(kicad_pcb
	(version 20260206)
	(generator "pcbnew")
	(generator_version "10.0")
	(general
		(thickness 1.6)
		(legacy_teardrops no)
	)
	(paper "A4")
	(layers
		(0 "F.Cu" signal "TOP")
		(4 "In1.Cu" signal "GND")
		(6 "In2.Cu" signal "VCC")
		(8 "In3.Cu" signal "VCC1")
		(10 "In4.Cu" signal "GND1")
		(12 "In5.Cu" signal "IN1")
		(14 "In6.Cu" signal "GND2")
		(16 "In7.Cu" signal "IN2")
		(18 "In8.Cu" signal "GND3")
		(20 "In9.Cu" signal "IN3")
		(22 "In10.Cu" signal "GND4")
		(24 "In11.Cu" signal "IN4")
		(26 "In12.Cu" signal "GND5")
		(28 "In13.Cu" signal "IN5")
		(30 "In14.Cu" signal "GND6")
		(32 "In15.Cu" signal "IN6")
		(34 "In16.Cu" signal "GND7")
		(2 "B.Cu" signal "BOTTOM")
		(9 "F.Adhes" user "F.Adhesive")
		(11 "B.Adhes" user "B.Adhesive")
		(13 "F.Paste" user "Package Geometry/Pastemask Top")
		(15 "B.Paste" user "Package Geometry/Pastemask Bottom")
		(5 "F.SilkS" user "Ref Des/Silkscreen Top")
		(7 "B.SilkS" user "Ref Des/Silkscreen Bottom")
		(1 "F.Mask" user "Board Geometry/Soldermask Top")
		(3 "B.Mask" user "Board Geometry/Soldermask Bottom")
		(17 "Dwgs.User" user "User.Drawings")
		(19 "Cmts.User" user "User.Comments")
		(21 "Eco1.User" user "User.Eco1")
		(23 "Eco2.User" user "User.Eco2")
		(25 "Edge.Cuts" user "Board Geometry/Outline")
		(27 "Margin" user)
		(31 "F.CrtYd" user "Package Geometry/Place Bound Top")
		(29 "B.CrtYd" user "Package Geometry/Place Bound Bottom")
		(35 "F.Fab" user "Ref Des/Assembly Top")
		(33 "B.Fab" user "Ref Des/Assembly Bottom")
	)
	(setup
		(pad_to_mask_clearance 0)
		(allow_soldermask_bridges_in_footprints no)
		(tenting
			(front yes)
			(back yes)
		)
		(covering
			(front no)
			(back no)
		)
		(plugging
			(front no)
			(back no)
		)
		(capping no)
		(filling no)
		(pcbplotparams
			(layerselection 0x00000000_00000000_55555555_5755f5ff)
			(plot_on_all_layers_selection 0x00000000_00000000_00000000_00000000)
			(disableapertmacros no)
			(usegerberextensions no)
			(usegerberattributes yes)
			(usegerberadvancedattributes yes)
			(creategerberjobfile yes)
			(dashed_line_dash_ratio 12)
			(dashed_line_gap_ratio 3)
			(svgprecision 4)
			(plotframeref no)
			(mode 1)
			(useauxorigin no)
			(pdf_front_fp_property_popups yes)
			(pdf_back_fp_property_popups yes)
			(pdf_metadata yes)
			(pdf_single_document no)
			(dxfpolygonmode yes)
			(dxfimperialunits yes)
			(dxfusepcbnewfont yes)
			(psnegative no)
			(psa4output no)
			(plot_black_and_white yes)
			(sketchpadsonfab no)
			(plotpadnumbers no)
			(hidednponfab no)
			(sketchdnponfab yes)
			(crossoutdnponfab yes)
			(subtractmaskfromsilk no)
			(outputformat 1)
			(mirror no)
			(drillshape 1)
			(scaleselection 1)
			(outputdirectory "")
		)
	)
	(gr_poly
		(pts
			(xy 53.023516 -417.065968) (xy 53.032744 -417.065564) (xy 53.049995 -417.059003) (xy 53.06379 -417.046743)
			(xy 53.072331 -417.030382) (xy 53.073808 -417.021264) (xy 53.073808 -394.27912) (xy 66.477388 -394.27912)
			(xy 66.525648 -394.32738) (xy 66.525648 -397.823885) (xy 71.348788 -397.823885) (xy 71.348792 -397.756458)
			(xy 71.356871 -397.689518) (xy 71.372911 -397.624026) (xy 71.396679 -397.560928) (xy 71.427833 -397.501131)
			(xy 71.465926 -397.445495) (xy 71.487792 -397.41983) (xy 71.4936 -397.412693) (xy 71.500108 -397.395496)
			(xy 71.500492 -397.386302) (xy 71.500492 -396.89405) (xy 71.50006 -396.884865) (xy 71.493562 -396.86768)
			(xy 71.487792 -396.860522) (xy 71.465918 -396.834865) (xy 71.427831 -396.779229) (xy 71.396681 -396.719431)
			(xy 71.372918 -396.656334) (xy 71.356883 -396.590844) (xy 71.348808 -396.523905) (xy 71.348809 -396.45648)
			(xy 71.356886 -396.389542) (xy 71.372922 -396.324052) (xy 71.396687 -396.260955) (xy 71.427838 -396.201158)
			(xy 71.465928 -396.145523) (xy 71.487792 -396.119858) (xy 71.493588 -396.112712) (xy 71.500103 -396.095522)
			(xy 71.500492 -396.08633) (xy 71.500492 -395.92885) (xy 71.501066 -395.918732) (xy 71.508769 -395.900021)
			(xy 71.523028 -395.885665) (xy 71.541686 -395.877836) (xy 71.5518 -395.877288) (xy 72.26808 -395.877288)
			(xy 72.278231 -395.877738) (xy 72.296981 -395.885524) (xy 72.311305 -395.899912) (xy 72.319007 -395.918697)
			(xy 72.319388 -395.92885) (xy 72.319388 -396.08633) (xy 72.319786 -396.095518) (xy 72.326308 -396.112703)
			(xy 72.332088 -396.119858) (xy 72.353943 -396.145531) (xy 72.392032 -396.201164) (xy 72.423184 -396.260959)
			(xy 72.446949 -396.324055) (xy 72.462986 -396.389543) (xy 72.471063 -396.456481) (xy 72.471064 -396.523904)
			(xy 72.462989 -396.590842) (xy 72.446954 -396.656331) (xy 72.42319 -396.719427) (xy 72.39204 -396.779223)
			(xy 72.353952 -396.834857) (xy 72.332088 -396.860522) (xy 72.326298 -396.867672) (xy 72.31978 -396.884859)
			(xy 72.319388 -396.89405) (xy 72.319388 -397.386302) (xy 72.3198 -397.395489) (xy 72.326313 -397.412673)
			(xy 72.332088 -397.41983) (xy 72.353915 -397.445526) (xy 72.392006 -397.501156) (xy 72.420766 -397.556355)
			(xy 73.54898 -397.556355) (xy 73.557023 -397.489534) (xy 73.572995 -397.424152) (xy 73.596666 -397.361148)
			(xy 73.627698 -397.301425) (xy 73.665645 -397.245838) (xy 73.687432 -397.220186) (xy 73.693221 -397.213036)
			(xy 73.69974 -397.195849) (xy 73.700132 -397.186658) (xy 73.700132 -397.028924) (xy 73.700542 -397.018767)
			(xy 73.708335 -397.000009) (xy 73.722736 -396.985684) (xy 73.741535 -396.977989) (xy 73.751694 -396.977616)
			(xy 74.467974 -396.977616) (xy 74.478096 -396.978147) (xy 74.496812 -396.985862) (xy 74.511169 -397.000134)
			(xy 74.518993 -397.018805) (xy 74.519536 -397.028924) (xy 74.519536 -397.186658) (xy 74.519981 -397.195841)
			(xy 74.526472 -397.213025) (xy 74.532236 -397.220186) (xy 74.554034 -397.24583) (xy 74.591984 -397.301417)
			(xy 74.623019 -397.361141) (xy 74.646692 -397.424147) (xy 74.662665 -397.48953) (xy 74.670709 -397.556354)
			(xy 74.670708 -397.623661) (xy 74.662662 -397.690484) (xy 74.646687 -397.755867) (xy 74.623012 -397.818872)
			(xy 74.620438 -397.823826) (xy 75.749084 -397.823826) (xy 75.749087 -397.756517) (xy 75.757136 -397.689691)
			(xy 75.773114 -397.624306) (xy 75.796793 -397.5613) (xy 75.827833 -397.501576) (xy 75.865789 -397.44599)
			(xy 75.88758 -397.420338) (xy 75.893383 -397.413197) (xy 75.899895 -397.396003) (xy 75.90028 -397.38681)
			(xy 75.90028 -396.893542) (xy 75.899854 -396.884356) (xy 75.893352 -396.867172) (xy 75.88758 -396.860014)
			(xy 75.865781 -396.83437) (xy 75.82783 -396.778784) (xy 75.796795 -396.719059) (xy 75.773121 -396.656054)
			(xy 75.757147 -396.59067) (xy 75.749104 -396.523846) (xy 75.749104 -396.456539) (xy 75.75715 -396.389715)
			(xy 75.773125 -396.324332) (xy 75.796801 -396.261327) (xy 75.827838 -396.201603) (xy 75.86579 -396.146018)
			(xy 75.88758 -396.120366) (xy 75.893371 -396.113217) (xy 75.89989 -396.096029) (xy 75.90028 -396.086838)
			(xy 75.90028 -395.92885) (xy 75.900706 -395.918676) (xy 75.908482 -395.899875) (xy 75.922868 -395.885487)
			(xy 75.941668 -395.877707) (xy 75.951842 -395.877288) (xy 76.668122 -395.877288) (xy 76.678301 -395.877647)
			(xy 76.697106 -395.885449) (xy 76.711492 -395.899855) (xy 76.719267 -395.91867) (xy 76.719684 -395.92885)
			(xy 76.719684 -396.086838) (xy 76.720079 -396.096027) (xy 76.726604 -396.113211) (xy 76.732384 -396.120366)
			(xy 76.754161 -396.146026) (xy 76.792109 -396.201612) (xy 76.823141 -396.261335) (xy 76.846814 -396.324338)
			(xy 76.862787 -396.389719) (xy 76.870831 -396.456541) (xy 76.870832 -396.523844) (xy 76.862789 -396.590666)
			(xy 76.846818 -396.656047) (xy 76.823147 -396.719051) (xy 76.792117 -396.778775) (xy 76.75417 -396.834362)
			(xy 76.732384 -396.860014) (xy 76.726597 -396.867166) (xy 76.720077 -396.884351) (xy 76.719684 -396.893542)
			(xy 76.719684 -397.38681) (xy 76.720093 -397.395997) (xy 76.726608 -397.413181) (xy 76.732384 -397.420338)
			(xy 76.754133 -397.446021) (xy 76.792082 -397.501604) (xy 76.820503 -397.556296) (xy 77.948748 -397.556296)
			(xy 77.956824 -397.489358) (xy 77.972859 -397.423869) (xy 77.996623 -397.360772) (xy 78.027774 -397.300977)
			(xy 78.065864 -397.245343) (xy 78.087728 -397.219678) (xy 78.09352 -397.21253) (xy 78.100037 -397.195341)
			(xy 78.100428 -397.18615) (xy 78.100428 -397.028924) (xy 78.100836 -397.0188) (xy 78.108582 -397.000091)
			(xy 78.122901 -396.985775) (xy 78.141611 -396.978034) (xy 78.151736 -396.977616) (xy 78.868016 -396.977616)
			(xy 78.878142 -396.978003) (xy 78.896849 -396.985759) (xy 78.911163 -397.000085) (xy 78.918905 -397.018798)
			(xy 78.919324 -397.028924) (xy 78.919324 -397.18615) (xy 78.919753 -397.195335) (xy 78.926253 -397.21252)
			(xy 78.932024 -397.219678) (xy 78.953897 -397.245336) (xy 78.991984 -397.300972) (xy 79.023133 -397.360769)
			(xy 79.046895 -397.423867) (xy 79.062929 -397.489357) (xy 79.071004 -397.556296) (xy 79.071003 -397.62372)
			(xy 79.062927 -397.690658) (xy 79.046891 -397.756147) (xy 79.023127 -397.819245) (xy 79.02071 -397.823885)
			(xy 80.148876 -397.823885) (xy 80.14888 -397.756458) (xy 80.156959 -397.689518) (xy 80.172998 -397.624027)
			(xy 80.196765 -397.560929) (xy 80.227919 -397.501131) (xy 80.266011 -397.445496) (xy 80.287876 -397.41983)
			(xy 80.293682 -397.412691) (xy 80.300192 -397.395496) (xy 80.300576 -397.386302) (xy 80.300576 -396.89405)
			(xy 80.300147 -396.884865) (xy 80.293647 -396.86768) (xy 80.287876 -396.860522) (xy 80.266003 -396.834864)
			(xy 80.227916 -396.779228) (xy 80.196767 -396.719431) (xy 80.173005 -396.656333) (xy 80.156971 -396.590843)
			(xy 80.148896 -396.523904) (xy 80.148897 -396.45648) (xy 80.156973 -396.389542) (xy 80.173009 -396.324053)
			(xy 80.196773 -396.260955) (xy 80.227924 -396.201159) (xy 80.266012 -396.145524) (xy 80.287876 -396.119858)
			(xy 80.29367 -396.112711) (xy 80.300187 -396.095522) (xy 80.300576 -396.08633) (xy 80.300576 -395.92885)
			(xy 80.301069 -395.918722) (xy 80.308787 -395.899995) (xy 80.323072 -395.885636) (xy 80.341759 -395.877821)
			(xy 80.351884 -395.877288) (xy 81.068164 -395.877288) (xy 81.078314 -395.877751) (xy 81.097063 -395.885532)
			(xy 81.111388 -395.899917) (xy 81.119091 -395.918698) (xy 81.119472 -395.92885) (xy 81.119472 -396.08633)
			(xy 81.119874 -396.095518) (xy 81.126394 -396.112702) (xy 81.132172 -396.119858) (xy 81.154027 -396.145531)
			(xy 81.192118 -396.201164) (xy 81.223271 -396.260959) (xy 81.247037 -396.324054) (xy 81.263074 -396.389543)
			(xy 81.271151 -396.456481) (xy 81.271152 -396.523904) (xy 81.263076 -396.590842) (xy 81.247041 -396.656331)
			(xy 81.223277 -396.719428) (xy 81.192126 -396.779223) (xy 81.154036 -396.834857) (xy 81.132172 -396.860522)
			(xy 81.12638 -396.86767) (xy 81.119863 -396.884859) (xy 81.119472 -396.89405) (xy 81.119472 -397.386302)
			(xy 81.119887 -397.395489) (xy 81.126398 -397.412673) (xy 81.132172 -397.41983) (xy 81.154 -397.445526)
			(xy 81.192091 -397.501155) (xy 81.220853 -397.556356) (xy 82.349068 -397.556356) (xy 82.357111 -397.489534)
			(xy 82.373082 -397.424153) (xy 82.396753 -397.361149) (xy 82.427783 -397.301425) (xy 82.46573 -397.245838)
			(xy 82.487516 -397.220186) (xy 82.493303 -397.213034) (xy 82.499823 -397.195849) (xy 82.500216 -397.186658)
			(xy 82.500216 -397.028924) (xy 82.500641 -397.018769) (xy 82.508432 -397.000014) (xy 82.522828 -396.98569)
			(xy 82.541621 -396.977992) (xy 82.551778 -396.977616) (xy 83.268058 -396.977616) (xy 83.278179 -396.97816)
			(xy 83.296895 -396.98587) (xy 83.311252 -397.000138) (xy 83.319076 -397.018806) (xy 83.31962 -397.028924)
			(xy 83.31962 -397.186658) (xy 83.320046 -397.195844) (xy 83.326548 -397.213028) (xy 83.33232 -397.220186)
			(xy 83.354119 -397.24583) (xy 83.39207 -397.301416) (xy 83.423105 -397.361141) (xy 83.446779 -397.424146)
			(xy 83.462753 -397.48953) (xy 83.470796 -397.556354) (xy 83.470796 -397.623661) (xy 83.46275 -397.690485)
			(xy 83.446775 -397.755868) (xy 83.423099 -397.818873) (xy 83.420495 -397.823884) (xy 84.548667 -397.823884)
			(xy 84.548671 -397.756458) (xy 84.55675 -397.689518) (xy 84.572788 -397.624028) (xy 84.596555 -397.560929)
			(xy 84.627708 -397.501132) (xy 84.665799 -397.445496) (xy 84.687664 -397.41983) (xy 84.693481 -397.412699)
			(xy 84.699982 -397.395497) (xy 84.700364 -397.386302) (xy 84.700364 -396.89405) (xy 84.699916 -396.884867)
			(xy 84.693427 -396.867683) (xy 84.687664 -396.860522) (xy 84.665791 -396.834864) (xy 84.627705 -396.779228)
			(xy 84.596557 -396.71943) (xy 84.572795 -396.656332) (xy 84.556761 -396.590843) (xy 84.548687 -396.523904)
			(xy 84.548688 -396.456481) (xy 84.556764 -396.389542) (xy 84.5728 -396.324053) (xy 84.596563 -396.260956)
			(xy 84.627713 -396.201159) (xy 84.665801 -396.145524) (xy 84.687664 -396.119858) (xy 84.693469 -396.112719)
			(xy 84.699977 -396.095523) (xy 84.700364 -396.08633) (xy 84.700364 -395.92885) (xy 84.700868 -395.918724)
			(xy 84.708584 -395.899999) (xy 84.722866 -395.88564) (xy 84.741548 -395.877823) (xy 84.751672 -395.877288)
			(xy 85.467952 -395.877288) (xy 85.478102 -395.877761) (xy 85.496851 -395.885538) (xy 85.511175 -395.899919)
			(xy 85.518879 -395.918699) (xy 85.51926 -395.92885) (xy 85.51926 -396.08633) (xy 85.519665 -396.095518)
			(xy 85.526183 -396.112701) (xy 85.53196 -396.119858) (xy 85.553816 -396.145531) (xy 85.591907 -396.201163)
			(xy 85.623061 -396.260958) (xy 85.646827 -396.324054) (xy 85.662864 -396.389543) (xy 85.670942 -396.456481)
			(xy 85.670943 -396.523904) (xy 85.662867 -396.590843) (xy 85.646832 -396.656332) (xy 85.623067 -396.719428)
			(xy 85.591915 -396.779224) (xy 85.553825 -396.834857) (xy 85.53196 -396.860522) (xy 85.526167 -396.867669)
			(xy 85.519651 -396.884858) (xy 85.51926 -396.89405) (xy 85.51926 -397.386302) (xy 85.519678 -397.395488)
			(xy 85.526187 -397.412672) (xy 85.53196 -397.41983) (xy 85.553788 -397.445525) (xy 85.591881 -397.501155)
			(xy 85.620612 -397.556296) (xy 86.748836 -397.556296) (xy 86.756911 -397.489358) (xy 86.772946 -397.423869)
			(xy 86.79671 -397.360773) (xy 86.82786 -397.300977) (xy 86.865948 -397.245343) (xy 86.887812 -397.219678)
			(xy 86.893602 -397.212528) (xy 86.90012 -397.195341) (xy 86.900512 -397.18615) (xy 86.900512 -397.028924)
			(xy 86.900936 -397.018802) (xy 86.908678 -397.000096) (xy 86.922993 -396.985781) (xy 86.941698 -396.978037)
			(xy 86.95182 -396.977616) (xy 87.6681 -396.977616) (xy 87.678224 -396.978016) (xy 87.696931 -396.985768)
			(xy 87.711246 -397.000089) (xy 87.718988 -397.018799) (xy 87.719408 -397.028924) (xy 87.719408 -397.18615)
			(xy 87.71984 -397.195335) (xy 87.726338 -397.21252) (xy 87.732108 -397.219678) (xy 87.753982 -397.245335)
			(xy 87.792069 -397.300971) (xy 87.823219 -397.360769) (xy 87.846982 -397.423866) (xy 87.863017 -397.489356)
			(xy 87.871092 -397.556295) (xy 87.871091 -397.62372) (xy 87.863014 -397.690658) (xy 87.846978 -397.756148)
			(xy 87.823213 -397.819245) (xy 87.820827 -397.823826) (xy 88.948962 -397.823826) (xy 88.948966 -397.756517)
			(xy 88.957014 -397.689692) (xy 88.972991 -397.624307) (xy 88.996669 -397.561301) (xy 89.027707 -397.501577)
			(xy 89.065661 -397.44599) (xy 89.087452 -397.420338) (xy 89.093264 -397.413204) (xy 89.099768 -397.396005)
			(xy 89.100152 -397.38681) (xy 89.100152 -396.893542) (xy 89.09971 -396.884358) (xy 89.093217 -396.867175)
			(xy 89.087452 -396.860014) (xy 89.065654 -396.83437) (xy 89.027704 -396.778783) (xy 88.996671 -396.719058)
			(xy 88.972998 -396.656053) (xy 88.957025 -396.590669) (xy 88.948982 -396.523846) (xy 88.948983 -396.456539)
			(xy 88.957028 -396.389716) (xy 88.973003 -396.324333) (xy 88.996677 -396.261328) (xy 89.027712 -396.201604)
			(xy 89.065663 -396.146018) (xy 89.087452 -396.120366) (xy 89.093252 -396.113223) (xy 89.099763 -396.096031)
			(xy 89.100152 -396.086838) (xy 89.100152 -395.92885) (xy 89.100605 -395.91868) (xy 89.108376 -395.899884)
			(xy 89.122753 -395.885496) (xy 89.141544 -395.877712) (xy 89.151714 -395.877288) (xy 89.867994 -395.877288)
			(xy 89.878171 -395.87767) (xy 89.896976 -395.885462) (xy 89.911362 -395.899861) (xy 89.919139 -395.918672)
			(xy 89.919556 -395.92885) (xy 89.919556 -396.086838) (xy 89.919958 -396.096026) (xy 89.926478 -396.11321)
			(xy 89.932256 -396.120366) (xy 89.954034 -396.146026) (xy 89.991983 -396.201611) (xy 90.023017 -396.261334)
			(xy 90.046691 -396.324337) (xy 90.062665 -396.389719) (xy 90.07071 -396.45654) (xy 90.070711 -396.523845)
			(xy 90.062667 -396.590667) (xy 90.046695 -396.656048) (xy 90.023023 -396.719052) (xy 89.991991 -396.778776)
			(xy 89.954043 -396.834362) (xy 89.932256 -396.860014) (xy 89.926465 -396.867163) (xy 89.919948 -396.884351)
			(xy 89.919556 -396.893542) (xy 89.919556 -397.38681) (xy 89.919971 -397.395996) (xy 89.926482 -397.41318)
			(xy 89.932256 -397.420338) (xy 89.954006 -397.446021) (xy 89.991957 -397.501603) (xy 90.020411 -397.556356)
			(xy 91.149156 -397.556356) (xy 91.157198 -397.489535) (xy 91.173169 -397.424153) (xy 91.196839 -397.361149)
			(xy 91.227869 -397.301426) (xy 91.265814 -397.245839) (xy 91.2876 -397.220186) (xy 91.293385 -397.213033)
			(xy 91.299907 -397.195848) (xy 91.3003 -397.186658) (xy 91.3003 -397.028924) (xy 91.300741 -397.018771)
			(xy 91.308529 -397.000019) (xy 91.32292 -396.985695) (xy 91.341708 -396.977995) (xy 91.351862 -396.977616)
			(xy 92.068142 -396.977616) (xy 92.078268 -396.978091) (xy 92.096986 -396.985829) (xy 92.11134 -397.000118)
			(xy 92.119162 -397.0188) (xy 92.119704 -397.028924) (xy 92.119704 -397.186658) (xy 92.120133 -397.195843)
			(xy 92.126634 -397.213028) (xy 92.132404 -397.220186) (xy 92.1542 -397.245831) (xy 92.192146 -397.301419)
			(xy 92.223176 -397.361144) (xy 92.246847 -397.42415) (xy 92.262818 -397.489532) (xy 92.27086 -397.556355)
			(xy 92.270859 -397.62366) (xy 92.262815 -397.690483) (xy 92.246842 -397.755865) (xy 92.22317 -397.81887)
			(xy 92.220595 -397.823825) (xy 115.349226 -397.823825) (xy 115.349229 -397.756518) (xy 115.357277 -397.689693)
			(xy 115.373253 -397.624309) (xy 115.396928 -397.561303) (xy 115.427964 -397.501578) (xy 115.465915 -397.445991)
			(xy 115.487704 -397.420338) (xy 115.49351 -397.413199) (xy 115.500019 -397.396004) (xy 115.500404 -397.38681)
			(xy 115.500404 -396.893542) (xy 115.499973 -396.884357) (xy 115.493474 -396.867173) (xy 115.487704 -396.860014)
			(xy 115.465908 -396.834369) (xy 115.427961 -396.778781) (xy 115.39693 -396.719056) (xy 115.37326 -396.656051)
			(xy 115.357288 -396.590668) (xy 115.349246 -396.523845) (xy 115.349247 -396.45654) (xy 115.357291 -396.389717)
			(xy 115.373264 -396.324335) (xy 115.396937 -396.26133) (xy 115.427969 -396.201606) (xy 115.465917 -396.146019)
			(xy 115.487704 -396.120366) (xy 115.493498 -396.113219) (xy 115.500014 -396.09603) (xy 115.500404 -396.086838)
			(xy 115.500404 -395.92885) (xy 115.500904 -395.918686) (xy 115.508666 -395.899899) (xy 115.523028 -395.885513)
			(xy 115.541803 -395.87772) (xy 115.551966 -395.877288) (xy 116.268246 -395.877288) (xy 116.278427 -395.877627)
			(xy 116.297232 -395.885437) (xy 116.311617 -395.899849) (xy 116.319392 -395.918668) (xy 116.319808 -395.92885)
			(xy 116.319808 -396.086838) (xy 116.320198 -396.096027) (xy 116.326725 -396.113212) (xy 116.332508 -396.120366)
			(xy 116.354288 -396.146026) (xy 116.39224 -396.20161) (xy 116.423277 -396.261332) (xy 116.446952 -396.324335)
			(xy 116.462928 -396.389717) (xy 116.470973 -396.45654) (xy 116.470974 -396.523845) (xy 116.46293 -396.590668)
			(xy 116.446957 -396.65605) (xy 116.423283 -396.719055) (xy 116.392248 -396.778777) (xy 116.354297 -396.834363)
			(xy 116.332508 -396.860014) (xy 116.326724 -396.867168) (xy 116.320202 -396.884352) (xy 116.319808 -396.893542)
			(xy 116.319808 -397.38681) (xy 116.320212 -397.395998) (xy 116.32673 -397.413182) (xy 116.332508 -397.420338)
			(xy 116.35426 -397.44602) (xy 116.392213 -397.501601) (xy 116.42064 -397.556296) (xy 117.548866 -397.556296)
			(xy 117.556942 -397.489357) (xy 117.572978 -397.423868) (xy 117.596743 -397.360771) (xy 117.627896 -397.300976)
			(xy 117.665987 -397.245342) (xy 117.687852 -397.219678) (xy 117.693647 -397.212532) (xy 117.700161 -397.195342)
			(xy 117.700552 -397.18615) (xy 117.700552 -397.028924) (xy 117.701103 -397.018823) (xy 117.708824 -397.000154)
			(xy 117.7231 -396.98586) (xy 117.741759 -396.978116) (xy 117.75186 -396.977616) (xy 118.46814 -396.977616)
			(xy 118.478253 -396.978053) (xy 118.496935 -396.985807) (xy 118.511229 -397.000118) (xy 118.51896 -397.01881)
			(xy 118.519448 -397.028924) (xy 118.519448 -397.18615) (xy 118.519894 -397.195333) (xy 118.526384 -397.212517)
			(xy 118.532148 -397.219678) (xy 118.554024 -397.245334) (xy 118.592115 -397.300969) (xy 118.623269 -397.360766)
			(xy 118.647035 -397.423864) (xy 118.663071 -397.489355) (xy 118.671147 -397.556295) (xy 118.671146 -397.62372)
			(xy 118.663068 -397.69066) (xy 118.64703 -397.75615) (xy 118.623262 -397.819248) (xy 118.620846 -397.823885)
			(xy 119.748994 -397.823885) (xy 119.748998 -397.756458) (xy 119.757077 -397.689517) (xy 119.773117 -397.624026)
			(xy 119.796885 -397.560928) (xy 119.828041 -397.50113) (xy 119.866134 -397.445495) (xy 119.888 -397.41983)
			(xy 119.893809 -397.412693) (xy 119.900316 -397.395496) (xy 119.9007 -397.386302) (xy 119.9007 -396.89405)
			(xy 119.900266 -396.884865) (xy 119.893769 -396.867681) (xy 119.888 -396.860522) (xy 119.866126 -396.834865)
			(xy 119.828038 -396.779229) (xy 119.796888 -396.719432) (xy 119.773124 -396.656334) (xy 119.757089 -396.590844)
			(xy 119.749014 -396.523905) (xy 119.749015 -396.45648) (xy 119.757092 -396.389541) (xy 119.773128 -396.324052)
			(xy 119.796894 -396.260954) (xy 119.828046 -396.201158) (xy 119.866135 -396.145523) (xy 119.888 -396.119858)
			(xy 119.893797 -396.112713) (xy 119.900311 -396.095522) (xy 119.9007 -396.08633) (xy 119.9007 -395.92885)
			(xy 119.901266 -395.918731) (xy 119.90897 -395.900019) (xy 119.923232 -395.885662) (xy 119.941893 -395.877834)
			(xy 119.952008 -395.877288) (xy 120.668288 -395.877288) (xy 120.67844 -395.877731) (xy 120.69719 -395.885521)
			(xy 120.711513 -395.899911) (xy 120.719215 -395.918696) (xy 120.719596 -395.92885) (xy 120.719596 -396.08633)
			(xy 120.719992 -396.095519) (xy 120.726516 -396.112703) (xy 120.732296 -396.119858) (xy 120.75415 -396.145531)
			(xy 120.79224 -396.201165) (xy 120.823391 -396.26096) (xy 120.847156 -396.324055) (xy 120.863192 -396.389544)
			(xy 120.871269 -396.456481) (xy 120.87127 -396.523904) (xy 120.863195 -396.590842) (xy 120.84716 -396.65633)
			(xy 120.823397 -396.719427) (xy 120.792247 -396.779223) (xy 120.75416 -396.834857) (xy 120.732296 -396.860522)
			(xy 120.726507 -396.867673) (xy 120.719988 -396.884859) (xy 120.719596 -396.89405) (xy 120.719596 -397.386302)
			(xy 120.720006 -397.395489) (xy 120.72652 -397.412673) (xy 120.732296 -397.41983) (xy 120.754123 -397.445526)
			(xy 120.792213 -397.501156) (xy 120.820972 -397.556355) (xy 121.949186 -397.556355) (xy 121.95723 -397.489533)
			(xy 121.973202 -397.424152) (xy 121.996873 -397.361148) (xy 122.027905 -397.301425) (xy 122.065853 -397.245838)
			(xy 122.08764 -397.220186) (xy 122.09343 -397.213036) (xy 122.099948 -397.195849) (xy 122.10034 -397.186658)
			(xy 122.10034 -397.028924) (xy 122.100742 -397.018766) (xy 122.108537 -397.000007) (xy 122.122941 -396.985681)
			(xy 122.141742 -396.977988) (xy 122.151902 -396.977616) (xy 122.868182 -396.977616) (xy 122.878305 -396.978141)
			(xy 122.897021 -396.985858) (xy 122.911377 -397.000132) (xy 122.919201 -397.018804) (xy 122.919744 -397.028924)
			(xy 122.919744 -397.186658) (xy 122.920187 -397.195841) (xy 122.926679 -397.213026) (xy 122.932444 -397.220186)
			(xy 122.954242 -397.24583) (xy 122.992192 -397.301417) (xy 123.023225 -397.361142) (xy 123.046898 -397.424147)
			(xy 123.062871 -397.489531) (xy 123.070915 -397.556354) (xy 123.070914 -397.623661) (xy 123.062868 -397.690484)
			(xy 123.046894 -397.755867) (xy 123.023219 -397.818872) (xy 123.020645 -397.823826) (xy 124.14929 -397.823826)
			(xy 124.149293 -397.756517) (xy 124.157342 -397.689691) (xy 124.17332 -397.624306) (xy 124.197 -397.5613)
			(xy 124.22804 -397.501575) (xy 124.265997 -397.44599) (xy 124.287788 -397.420338) (xy 124.293592 -397.413198)
			(xy 124.300103 -397.396004) (xy 124.300488 -397.38681) (xy 124.300488 -396.893542) (xy 124.30006 -396.884357)
			(xy 124.293559 -396.867172) (xy 124.287788 -396.860014) (xy 124.265989 -396.834371) (xy 124.228037 -396.778784)
			(xy 124.197002 -396.71906) (xy 124.173327 -396.656054) (xy 124.157354 -396.59067) (xy 124.14931 -396.523846)
			(xy 124.14931 -396.456539) (xy 124.157356 -396.389715) (xy 124.173332 -396.324332) (xy 124.197008 -396.261327)
			(xy 124.228045 -396.201603) (xy 124.265998 -396.146018) (xy 124.287788 -396.120366) (xy 124.29358 -396.113218)
			(xy 124.300098 -396.09603) (xy 124.300488 -396.086838) (xy 124.300488 -395.92885) (xy 124.300906 -395.918675)
			(xy 124.308684 -395.899872) (xy 124.323072 -395.885484) (xy 124.341875 -395.877706) (xy 124.35205 -395.877288)
			(xy 125.06833 -395.877288) (xy 125.07851 -395.87764) (xy 125.097315 -395.885445) (xy 125.1117 -395.899852)
			(xy 125.119475 -395.91867) (xy 125.119892 -395.92885) (xy 125.119892 -396.086838) (xy 125.120286 -396.096027)
			(xy 125.126811 -396.113211) (xy 125.132592 -396.120366) (xy 125.154369 -396.146027) (xy 125.192316 -396.201613)
			(xy 125.223348 -396.261335) (xy 125.24702 -396.324339) (xy 125.262993 -396.389719) (xy 125.271037 -396.456541)
			(xy 125.271038 -396.523844) (xy 125.262995 -396.590666) (xy 125.247025 -396.656047) (xy 125.223354 -396.719051)
			(xy 125.192324 -396.778774) (xy 125.154378 -396.834361) (xy 125.132592 -396.860014) (xy 125.126806 -396.867167)
			(xy 125.120285 -396.884351) (xy 125.119892 -396.893542) (xy 125.119892 -397.38681) (xy 125.120299 -397.395998)
			(xy 125.126815 -397.413182) (xy 125.132592 -397.420338) (xy 125.154341 -397.446021) (xy 125.192289 -397.501604)
			(xy 125.22071 -397.556296) (xy 126.348954 -397.556296) (xy 126.35703 -397.489357) (xy 126.373065 -397.423869)
			(xy 126.39683 -397.360772) (xy 126.427981 -397.300976) (xy 126.466071 -397.245343) (xy 126.487936 -397.219678)
			(xy 126.493729 -397.21253) (xy 126.500245 -397.195342) (xy 126.500636 -397.18615) (xy 126.500636 -397.028924)
			(xy 126.501036 -397.018799) (xy 126.508783 -397.000089) (xy 126.523105 -396.985772) (xy 126.541818 -396.978032)
			(xy 126.551944 -396.977616) (xy 127.268224 -396.977616) (xy 127.278336 -396.978066) (xy 127.297018 -396.985814)
			(xy 127.311313 -397.000122) (xy 127.319044 -397.018811) (xy 127.319532 -397.028924) (xy 127.319532 -397.18615)
			(xy 127.319981 -397.195333) (xy 127.326469 -397.212517) (xy 127.332232 -397.219678) (xy 127.354105 -397.245336)
			(xy 127.392191 -397.300972) (xy 127.423339 -397.36077) (xy 127.447102 -397.423867) (xy 127.463135 -397.489357)
			(xy 127.47121 -397.556296) (xy 127.471209 -397.623719) (xy 127.463133 -397.690658) (xy 127.447097 -397.756147)
			(xy 127.423333 -397.819244) (xy 127.420946 -397.823826) (xy 128.54908 -397.823826) (xy 128.549084 -397.756517)
			(xy 128.557132 -397.689691) (xy 128.57311 -397.624306) (xy 128.596789 -397.5613) (xy 128.627829 -397.501576)
			(xy 128.665785 -397.445989) (xy 128.687576 -397.420338) (xy 128.693379 -397.413197) (xy 128.69989 -397.396003)
			(xy 128.700276 -397.38681) (xy 128.700276 -396.893542) (xy 128.699851 -396.884356) (xy 128.693348 -396.867171)
			(xy 128.687576 -396.860014) (xy 128.665777 -396.83437) (xy 128.627826 -396.778784) (xy 128.596792 -396.719059)
			(xy 128.573118 -396.656053) (xy 128.557144 -396.59067) (xy 128.5491 -396.523846) (xy 128.549101 -396.456539)
			(xy 128.557147 -396.389715) (xy 128.573122 -396.324332) (xy 128.596798 -396.261327) (xy 128.627834 -396.201604)
			(xy 128.665787 -396.146018) (xy 128.687576 -396.120366) (xy 128.693367 -396.113216) (xy 128.699886 -396.096029)
			(xy 128.700276 -396.086838) (xy 128.700276 -395.92885) (xy 128.700706 -395.918677) (xy 128.708481 -395.899876)
			(xy 128.722866 -395.885488) (xy 128.741665 -395.877708) (xy 128.751838 -395.877288) (xy 129.468118 -395.877288)
			(xy 129.478297 -395.87765) (xy 129.497102 -395.885451) (xy 129.511487 -395.899856) (xy 129.519263 -395.91867)
			(xy 129.51968 -395.92885) (xy 129.51968 -396.086838) (xy 129.520076 -396.096027) (xy 129.5266 -396.113211)
			(xy 129.53238 -396.120366) (xy 129.554157 -396.146026) (xy 129.592105 -396.201612) (xy 129.623138 -396.261335)
			(xy 129.64681 -396.324338) (xy 129.662784 -396.389719) (xy 129.670828 -396.456541) (xy 129.670829 -396.523844)
			(xy 129.662786 -396.590666) (xy 129.646815 -396.656047) (xy 129.623144 -396.719051) (xy 129.592113 -396.778775)
			(xy 129.554167 -396.834362) (xy 129.53238 -396.860014) (xy 129.526593 -396.867166) (xy 129.520073 -396.884351)
			(xy 129.51968 -396.893542) (xy 129.51968 -397.38681) (xy 129.52009 -397.395997) (xy 129.526604 -397.413181)
			(xy 129.53238 -397.420338) (xy 129.55413 -397.446021) (xy 129.592078 -397.501604) (xy 129.620531 -397.556356)
			(xy 130.749274 -397.556356) (xy 130.757317 -397.489534) (xy 130.773288 -397.424152) (xy 130.796959 -397.361148)
			(xy 130.827991 -397.301425) (xy 130.865937 -397.245838) (xy 130.887724 -397.220186) (xy 130.893512 -397.213035)
			(xy 130.900031 -397.195849) (xy 130.900424 -397.186658) (xy 130.900424 -397.028924) (xy 130.900842 -397.018768)
			(xy 130.908634 -397.000012) (xy 130.923032 -396.985687) (xy 130.941828 -396.97799) (xy 130.951986 -396.977616)
			(xy 131.668266 -396.977616) (xy 131.678388 -396.978154) (xy 131.697103 -396.985866) (xy 131.71146 -397.000137)
			(xy 131.719284 -397.018806) (xy 131.719828 -397.028924) (xy 131.719828 -397.186658) (xy 131.720252 -397.195844)
			(xy 131.726756 -397.213029) (xy 131.732528 -397.220186) (xy 131.754326 -397.24583) (xy 131.792277 -397.301417)
			(xy 131.823312 -397.361141) (xy 131.846985 -397.424147) (xy 131.862959 -397.48953) (xy 131.871003 -397.556354)
			(xy 131.871002 -397.623661) (xy 131.862956 -397.690485) (xy 131.846981 -397.755868) (xy 131.823306 -397.818873)
			(xy 131.792269 -397.878596) (xy 131.754317 -397.934182) (xy 131.732528 -397.959834) (xy 131.726726 -397.966975)
			(xy 131.720217 -397.984169) (xy 131.719828 -397.993362) (xy 131.719828 -398.486884) (xy 131.720239 -398.496071)
			(xy 131.726751 -398.513256) (xy 131.732528 -398.520412) (xy 131.754352 -398.546034) (xy 131.792302 -398.601624)
			(xy 131.823336 -398.661352) (xy 131.847008 -398.72436) (xy 131.86298 -398.789746) (xy 131.871021 -398.856573)
			(xy 131.871018 -398.923881) (xy 131.86297 -398.990707) (xy 131.846992 -399.056092) (xy 131.823314 -399.119098)
			(xy 131.792274 -399.178822) (xy 131.754319 -399.234408) (xy 131.732528 -399.26006) (xy 131.726715 -399.267193)
			(xy 131.720212 -399.284393) (xy 131.719828 -399.293588) (xy 131.719828 -399.451576) (xy 131.719359 -399.461725)
			(xy 131.711577 -399.480472) (xy 131.697195 -399.494795) (xy 131.678417 -399.502501) (xy 131.668266 -399.502884)
			(xy 130.951986 -399.502884) (xy 130.941861 -399.502385) (xy 130.923145 -399.494657) (xy 130.90879 -399.480375)
			(xy 130.900967 -399.461698) (xy 130.900424 -399.451576) (xy 130.900424 -399.293588) (xy 130.900014 -399.284401)
			(xy 130.8935 -399.267217) (xy 130.887724 -399.26006) (xy 130.865972 -399.234378) (xy 130.828023 -399.178796)
			(xy 130.796989 -399.119076) (xy 130.773315 -399.056076) (xy 130.75734 -398.990697) (xy 130.749294 -398.923878)
			(xy 130.74929 -398.856576) (xy 130.757331 -398.789756) (xy 130.773299 -398.724376) (xy 130.796967 -398.661373)
			(xy 130.827996 -398.601651) (xy 130.865939 -398.546065) (xy 130.887724 -398.520412) (xy 130.893543 -398.513283)
			(xy 130.900044 -398.49608) (xy 130.900424 -398.486884) (xy 130.900424 -397.993362) (xy 130.900027 -397.984174)
			(xy 130.893504 -397.96699) (xy 130.887724 -397.959834) (xy 130.865946 -397.934174) (xy 130.827998 -397.878588)
			(xy 130.796965 -397.818865) (xy 130.773293 -397.755862) (xy 130.75732 -397.690481) (xy 130.749275 -397.62366)
			(xy 130.749274 -397.556356) (xy 129.620531 -397.556356) (xy 129.623112 -397.561323) (xy 129.646786 -397.624324)
			(xy 129.662761 -397.689702) (xy 129.670808 -397.756521) (xy 129.670811 -397.823822) (xy 129.662771 -397.890642)
			(xy 129.646803 -397.956022) (xy 129.623135 -398.019025) (xy 129.592108 -398.078747) (xy 129.554165 -398.134333)
			(xy 129.53238 -398.159986) (xy 129.526562 -398.167116) (xy 129.520061 -398.184318) (xy 129.51968 -398.193514)
			(xy 129.51968 -398.351502) (xy 129.519169 -398.361658) (xy 129.511397 -398.380423) (xy 129.497037 -398.394788)
			(xy 129.478274 -398.402565) (xy 129.468118 -398.403064) (xy 128.751838 -398.403064) (xy 128.741669 -398.402605)
			(xy 128.722876 -398.394833) (xy 128.70849 -398.380458) (xy 128.700703 -398.361671) (xy 128.700276 -398.351502)
			(xy 128.700276 -398.193514) (xy 128.699865 -398.184327) (xy 128.693352 -398.167142) (xy 128.687576 -398.159986)
			(xy 128.66575 -398.134365) (xy 128.627799 -398.078775) (xy 128.596766 -398.019048) (xy 128.573093 -397.956039)
			(xy 128.557122 -397.890652) (xy 128.54908 -397.823826) (xy 127.420946 -397.823826) (xy 127.392183 -397.879041)
			(xy 127.354095 -397.934676) (xy 127.332232 -397.960342) (xy 127.326427 -397.967481) (xy 127.319919 -397.984676)
			(xy 127.319532 -397.99387) (xy 127.319532 -398.486376) (xy 127.319969 -398.49556) (xy 127.326466 -398.512744)
			(xy 127.332232 -398.519904) (xy 127.35413 -398.545541) (xy 127.392216 -398.60118) (xy 127.423363 -398.66098)
			(xy 127.447124 -398.724081) (xy 127.463156 -398.789573) (xy 127.471228 -398.856514) (xy 127.471225 -398.92394)
			(xy 127.463146 -398.99088) (xy 127.447108 -399.056371) (xy 127.423341 -399.119469) (xy 127.392188 -399.179266)
			(xy 127.354097 -399.234902) (xy 127.332232 -399.260568) (xy 127.326416 -399.267699) (xy 127.319915 -399.284901)
			(xy 127.319532 -399.294096) (xy 127.319532 -399.451576) (xy 127.318996 -399.461679) (xy 127.311272 -399.480351)
			(xy 127.296991 -399.494645) (xy 127.278327 -399.502387) (xy 127.268224 -399.502884) (xy 126.551944 -399.502884)
			(xy 126.541822 -399.502447) (xy 126.523117 -399.494711) (xy 126.5088 -399.4804) (xy 126.501056 -399.461697)
			(xy 126.500636 -399.451576) (xy 126.500636 -399.294096) (xy 126.50022 -399.28491) (xy 126.49371 -399.267726)
			(xy 126.487936 -399.260568) (xy 126.466106 -399.234874) (xy 126.428014 -399.179245) (xy 126.39686 -399.119453)
			(xy 126.373092 -399.056359) (xy 126.357053 -398.990873) (xy 126.348974 -398.923938) (xy 126.34897 -398.856516)
			(xy 126.357043 -398.78958) (xy 126.373076 -398.724092) (xy 126.396838 -398.660997) (xy 126.427986 -398.601202)
			(xy 126.466073 -398.545569) (xy 126.487936 -398.519904) (xy 126.493718 -398.512749) (xy 126.50024 -398.495566)
			(xy 126.500636 -398.486376) (xy 126.500636 -397.99387) (xy 126.500232 -397.984682) (xy 126.493713 -397.967498)
			(xy 126.487936 -397.960342) (xy 126.466081 -397.934669) (xy 126.427989 -397.879037) (xy 126.396836 -397.819242)
			(xy 126.37307 -397.756146) (xy 126.357032 -397.690657) (xy 126.348955 -397.623719) (xy 126.348954 -397.556296)
			(xy 125.22071 -397.556296) (xy 125.223323 -397.561324) (xy 125.246996 -397.624324) (xy 125.262971 -397.689702)
			(xy 125.271018 -397.756521) (xy 125.271021 -397.823822) (xy 125.262981 -397.890642) (xy 125.247013 -397.956021)
			(xy 125.223346 -398.019024) (xy 125.192319 -398.078747) (xy 125.154377 -398.134334) (xy 125.132592 -398.159986)
			(xy 125.126775 -398.167117) (xy 125.120273 -398.184318) (xy 125.119892 -398.193514) (xy 125.119892 -398.351502)
			(xy 125.119369 -398.361656) (xy 125.111599 -398.38042) (xy 125.097243 -398.394784) (xy 125.078484 -398.402563)
			(xy 125.06833 -398.403064) (xy 124.35205 -398.403064) (xy 124.341882 -398.402595) (xy 124.323089 -398.394827)
			(xy 124.308702 -398.380455) (xy 124.300915 -398.36167) (xy 124.300488 -398.351502) (xy 124.300488 -398.193514)
			(xy 124.300074 -398.184327) (xy 124.293563 -398.167143) (xy 124.287788 -398.159986) (xy 124.265961 -398.134365)
			(xy 124.228011 -398.078775) (xy 124.196976 -398.019048) (xy 124.173304 -397.956039) (xy 124.157332 -397.890653)
			(xy 124.14929 -397.823826) (xy 123.020645 -397.823826) (xy 122.992184 -397.878596) (xy 122.954233 -397.934182)
			(xy 122.932444 -397.959834) (xy 122.926644 -397.966976) (xy 122.920133 -397.984169) (xy 122.919744 -397.993362)
			(xy 122.919744 -398.486884) (xy 122.920174 -398.496069) (xy 122.926675 -398.513253) (xy 122.932444 -398.520412)
			(xy 122.954268 -398.546035) (xy 122.992217 -398.601625) (xy 123.023249 -398.661352) (xy 123.046921 -398.724361)
			(xy 123.062892 -398.789747) (xy 123.070933 -398.856573) (xy 123.07093 -398.923881) (xy 123.062882 -398.990707)
			(xy 123.046905 -399.056091) (xy 123.023227 -399.119097) (xy 122.992189 -399.178822) (xy 122.954235 -399.234408)
			(xy 122.932444 -399.26006) (xy 122.926633 -399.267194) (xy 122.920128 -399.284393) (xy 122.919744 -399.293588)
			(xy 122.919744 -399.451576) (xy 122.91926 -399.461723) (xy 122.91148 -399.480467) (xy 122.897103 -399.494789)
			(xy 122.878331 -399.502498) (xy 122.868182 -399.502884) (xy 122.151902 -399.502884) (xy 122.141778 -399.502372)
			(xy 122.123062 -399.49465) (xy 122.108706 -399.480371) (xy 122.100883 -399.461697) (xy 122.10034 -399.451576)
			(xy 122.10034 -399.293588) (xy 122.099927 -399.284401) (xy 122.093414 -399.267217) (xy 122.08764 -399.26006)
			(xy 122.065888 -399.234379) (xy 122.027938 -399.178796) (xy 121.996903 -399.119077) (xy 121.973228 -399.056076)
			(xy 121.957253 -398.990698) (xy 121.949206 -398.923878) (xy 121.949202 -398.856576) (xy 121.957243 -398.789756)
			(xy 121.973212 -398.724376) (xy 121.996881 -398.661373) (xy 122.02791 -398.60165) (xy 122.065855 -398.546064)
			(xy 122.08764 -398.520412) (xy 122.093461 -398.513285) (xy 122.09996 -398.49608) (xy 122.10034 -398.486884)
			(xy 122.10034 -397.993362) (xy 122.099939 -397.984174) (xy 122.093418 -397.96699) (xy 122.08764 -397.959834)
			(xy 122.065862 -397.934174) (xy 122.027913 -397.878588) (xy 121.996879 -397.818866) (xy 121.973206 -397.755863)
			(xy 121.957232 -397.690481) (xy 121.949187 -397.62366) (xy 121.949186 -397.556355) (xy 120.820972 -397.556355)
			(xy 120.823365 -397.560948) (xy 120.847132 -397.624041) (xy 120.86317 -397.689526) (xy 120.871249 -397.756461)
			(xy 120.871253 -397.823882) (xy 120.86318 -397.890818) (xy 120.847149 -397.956305) (xy 120.823389 -398.0194)
			(xy 120.792242 -398.079195) (xy 120.754158 -398.134829) (xy 120.732296 -398.160494) (xy 120.726519 -398.167653)
			(xy 120.719993 -398.184833) (xy 120.719596 -398.194022) (xy 120.719596 -398.351502) (xy 120.719076 -398.361624)
			(xy 120.711354 -398.380339) (xy 120.697079 -398.394694) (xy 120.678408 -398.402519) (xy 120.668288 -398.403064)
			(xy 119.952008 -398.403064) (xy 119.94185 -398.402671) (xy 119.923091 -398.394871) (xy 119.908766 -398.380465)
			(xy 119.901072 -398.361662) (xy 119.9007 -398.351502) (xy 119.9007 -398.194022) (xy 119.900279 -398.184836)
			(xy 119.893773 -398.167651) (xy 119.888 -398.160494) (xy 119.866099 -398.13486) (xy 119.828011 -398.079221)
			(xy 119.796862 -398.01942) (xy 119.7731 -397.956319) (xy 119.757067 -397.890826) (xy 119.748994 -397.823885)
			(xy 118.620846 -397.823885) (xy 118.592108 -397.879044) (xy 118.554014 -397.934678) (xy 118.532148 -397.960342)
			(xy 118.526345 -397.967482) (xy 118.519835 -397.984677) (xy 118.519448 -397.99387) (xy 118.519448 -398.486376)
			(xy 118.519881 -398.495561) (xy 118.52638 -398.512745) (xy 118.532148 -398.519904) (xy 118.554049 -398.545539)
			(xy 118.59214 -398.601177) (xy 118.623292 -398.660977) (xy 118.647057 -398.724078) (xy 118.663091 -398.789571)
			(xy 118.671165 -398.856513) (xy 118.671162 -398.923941) (xy 118.663082 -398.990882) (xy 118.647041 -399.056374)
			(xy 118.62327 -399.119473) (xy 118.592112 -399.17927) (xy 118.554016 -399.234904) (xy 118.532148 -399.260568)
			(xy 118.526334 -399.2677) (xy 118.519831 -399.284901) (xy 118.519448 -399.294096) (xy 118.519448 -399.451576)
			(xy 118.518897 -399.461677) (xy 118.511176 -399.480346) (xy 118.4969 -399.49464) (xy 118.478241 -399.502384)
			(xy 118.46814 -399.502884) (xy 117.75186 -399.502884) (xy 117.741747 -399.502447) (xy 117.723065 -399.494693)
			(xy 117.708771 -399.480382) (xy 117.70104 -399.46169) (xy 117.700552 -399.451576) (xy 117.700552 -399.294096)
			(xy 117.700132 -399.28491) (xy 117.693624 -399.267726) (xy 117.687852 -399.260568) (xy 117.666022 -399.234874)
			(xy 117.627928 -399.179245) (xy 117.596773 -399.119453) (xy 117.573005 -399.05636) (xy 117.556965 -398.990874)
			(xy 117.548886 -398.923938) (xy 117.548882 -398.856516) (xy 117.556955 -398.789579) (xy 117.572989 -398.724092)
			(xy 117.596751 -398.660996) (xy 117.627901 -398.601201) (xy 117.665988 -398.545568) (xy 117.687852 -398.519904)
			(xy 117.693636 -398.51275) (xy 117.700157 -398.495566) (xy 117.700552 -398.486376) (xy 117.700552 -397.99387)
			(xy 117.700145 -397.984683) (xy 117.693628 -397.967499) (xy 117.687852 -397.960342) (xy 117.665996 -397.93467)
			(xy 117.627904 -397.879037) (xy 117.59675 -397.819243) (xy 117.572983 -397.756147) (xy 117.556945 -397.690658)
			(xy 117.548867 -397.623719) (xy 117.548866 -397.556296) (xy 116.42064 -397.556296) (xy 116.423251 -397.56132)
			(xy 116.446929 -397.624321) (xy 116.462906 -397.6897) (xy 116.470954 -397.75652) (xy 116.470957 -397.823823)
			(xy 116.462916 -397.890644) (xy 116.446945 -397.956025) (xy 116.423275 -398.019028) (xy 116.392243 -398.07875)
			(xy 116.354295 -398.134335) (xy 116.332508 -398.159986) (xy 116.326693 -398.167118) (xy 116.320189 -398.184319)
			(xy 116.319808 -398.193514) (xy 116.319808 -398.351502) (xy 116.319269 -398.361654) (xy 116.311503 -398.380415)
			(xy 116.297152 -398.394778) (xy 116.278398 -398.402561) (xy 116.268246 -398.403064) (xy 115.551966 -398.403064)
			(xy 115.541806 -398.402595) (xy 115.523037 -398.394809) (xy 115.508673 -398.380436) (xy 115.500899 -398.361662)
			(xy 115.500404 -398.351502) (xy 115.500404 -398.193514) (xy 115.499986 -398.184328) (xy 115.493478 -398.167143)
			(xy 115.487704 -398.159986) (xy 115.46588 -398.134364) (xy 115.427935 -398.078772) (xy 115.396905 -398.019044)
			(xy 115.373236 -397.956036) (xy 115.357267 -397.89065) (xy 115.349226 -397.823825) (xy 92.220595 -397.823825)
			(xy 92.192138 -397.878594) (xy 92.154191 -397.934181) (xy 92.132404 -397.959834) (xy 92.126611 -397.966982)
			(xy 92.120094 -397.98417) (xy 92.119704 -397.993362) (xy 92.119704 -398.486884) (xy 92.120121 -398.49607)
			(xy 92.12663 -398.513255) (xy 92.132404 -398.520412) (xy 92.154226 -398.546036) (xy 92.192171 -398.601627)
			(xy 92.2232 -398.661355) (xy 92.246869 -398.724363) (xy 92.262838 -398.789748) (xy 92.270879 -398.856574)
			(xy 92.270875 -398.923881) (xy 92.262828 -398.990705) (xy 92.246853 -399.056089) (xy 92.223178 -399.119094)
			(xy 92.192143 -399.178819) (xy 92.154193 -399.234407) (xy 92.132404 -399.26006) (xy 92.1266 -399.2672)
			(xy 92.12009 -399.284394) (xy 92.119704 -399.293588) (xy 92.119704 -399.451576) (xy 92.119259 -399.461728)
			(xy 92.111472 -399.480479) (xy 92.097082 -399.494803) (xy 92.078296 -399.502505) (xy 92.068142 -399.502884)
			(xy 91.351862 -399.502884) (xy 91.341736 -399.502405) (xy 91.323018 -399.494669) (xy 91.308664 -399.480381)
			(xy 91.300842 -399.4617) (xy 91.3003 -399.451576) (xy 91.3003 -399.293588) (xy 91.299895 -399.2844)
			(xy 91.293378 -399.267216) (xy 91.2876 -399.26006) (xy 91.265849 -399.234378) (xy 91.227901 -399.178795)
			(xy 91.196869 -399.119075) (xy 91.173196 -399.056075) (xy 91.157221 -398.990697) (xy 91.149175 -398.923878)
			(xy 91.149172 -398.856576) (xy 91.157212 -398.789757) (xy 91.17318 -398.724377) (xy 91.196847 -398.661374)
			(xy 91.227874 -398.601651) (xy 91.265816 -398.546065) (xy 91.2876 -398.520412) (xy 91.293416 -398.513281)
			(xy 91.299919 -398.49608) (xy 91.3003 -398.486884) (xy 91.3003 -397.993362) (xy 91.299908 -397.984173)
			(xy 91.293382 -397.966989) (xy 91.2876 -397.959834) (xy 91.265823 -397.934173) (xy 91.227877 -397.878587)
			(xy 91.196845 -397.818864) (xy 91.173174 -397.755861) (xy 91.157201 -397.69048) (xy 91.149157 -397.623659)
			(xy 91.149156 -397.556356) (xy 90.020411 -397.556356) (xy 90.022992 -397.561322) (xy 90.046667 -397.624323)
			(xy 90.062643 -397.689701) (xy 90.07069 -397.75652) (xy 90.070693 -397.823822) (xy 90.062653 -397.890643)
			(xy 90.046684 -397.956023) (xy 90.023015 -398.019026) (xy 89.991986 -398.078748) (xy 89.954041 -398.134334)
			(xy 89.932256 -398.159986) (xy 89.926435 -398.167114) (xy 89.919936 -398.184318) (xy 89.919556 -398.193514)
			(xy 89.919556 -398.351502) (xy 89.919138 -398.361674) (xy 89.911351 -398.38047) (xy 89.896964 -398.394855)
			(xy 89.878167 -398.402639) (xy 89.867994 -398.403064) (xy 89.151714 -398.403064) (xy 89.141544 -398.402625)
			(xy 89.122749 -398.394845) (xy 89.108364 -398.380464) (xy 89.100578 -398.361672) (xy 89.100152 -398.351502)
			(xy 89.100152 -398.193514) (xy 89.099724 -398.184329) (xy 89.093221 -398.167145) (xy 89.087452 -398.159986)
			(xy 89.065626 -398.134365) (xy 89.027678 -398.078774) (xy 88.996645 -398.019047) (xy 88.972974 -397.956038)
			(xy 88.957004 -397.890652) (xy 88.948962 -397.823826) (xy 87.820827 -397.823826) (xy 87.792062 -397.879042)
			(xy 87.753972 -397.934677) (xy 87.732108 -397.960342) (xy 87.726312 -397.967488) (xy 87.719797 -397.984678)
			(xy 87.719408 -397.99387) (xy 87.719408 -398.486376) (xy 87.719828 -398.495562) (xy 87.726335 -398.512747)
			(xy 87.732108 -398.519904) (xy 87.754007 -398.54554) (xy 87.792094 -398.601179) (xy 87.823243 -398.660979)
			(xy 87.847005 -398.72408) (xy 87.863037 -398.789573) (xy 87.87111 -398.856514) (xy 87.871107 -398.92394)
			(xy 87.863028 -398.990881) (xy 87.846989 -399.056372) (xy 87.823221 -399.11947) (xy 87.792066 -399.179267)
			(xy 87.753974 -399.234903) (xy 87.732108 -399.260568) (xy 87.726301 -399.267706) (xy 87.719792 -399.284902)
			(xy 87.719408 -399.294096) (xy 87.719408 -399.451576) (xy 87.718965 -399.461696) (xy 87.711226 -399.480398)
			(xy 87.696918 -399.494712) (xy 87.67822 -399.50246) (xy 87.6681 -399.502884) (xy 86.95182 -399.502884)
			(xy 86.941697 -399.502467) (xy 86.922991 -399.494723) (xy 86.908675 -399.480406) (xy 86.900932 -399.461699)
			(xy 86.900512 -399.451576) (xy 86.900512 -399.294096) (xy 86.900101 -399.284909) (xy 86.893587 -399.267725)
			(xy 86.887812 -399.260568) (xy 86.865983 -399.234874) (xy 86.827892 -399.179244) (xy 86.796739 -399.119452)
			(xy 86.772973 -399.056358) (xy 86.756934 -398.990873) (xy 86.748855 -398.923938) (xy 86.748852 -398.856516)
			(xy 86.756925 -398.78958) (xy 86.772957 -398.724093) (xy 86.796717 -398.660998) (xy 86.827865 -398.601203)
			(xy 86.86595 -398.545569) (xy 86.887812 -398.519904) (xy 86.893591 -398.512746) (xy 86.900116 -398.495565)
			(xy 86.900512 -398.486376) (xy 86.900512 -397.99387) (xy 86.900114 -397.984682) (xy 86.893592 -397.967497)
			(xy 86.887812 -397.960342) (xy 86.865957 -397.934669) (xy 86.827868 -397.879036) (xy 86.796716 -397.819241)
			(xy 86.772951 -397.756145) (xy 86.756914 -397.690657) (xy 86.748837 -397.623719) (xy 86.748836 -397.556296)
			(xy 85.620612 -397.556296) (xy 85.623035 -397.560946) (xy 85.646803 -397.624039) (xy 85.662842 -397.689525)
			(xy 85.670922 -397.756461) (xy 85.670925 -397.823882) (xy 85.662853 -397.890819) (xy 85.64682 -397.956306)
			(xy 85.623058 -398.019402) (xy 85.59191 -398.079196) (xy 85.553823 -398.134829) (xy 85.53196 -398.160494)
			(xy 85.526178 -398.16765) (xy 85.519656 -398.184832) (xy 85.51926 -398.194022) (xy 85.51926 -398.351502)
			(xy 85.518775 -398.361629) (xy 85.511047 -398.38035) (xy 85.49676 -398.394706) (xy 85.478076 -398.402525)
			(xy 85.467952 -398.403064) (xy 84.751672 -398.403064) (xy 84.741512 -398.402701) (xy 84.722752 -398.394889)
			(xy 84.708428 -398.380474) (xy 84.700736 -398.361665) (xy 84.700364 -398.351502) (xy 84.700364 -398.194022)
			(xy 84.699929 -398.184838) (xy 84.693431 -398.167654) (xy 84.687664 -398.160494) (xy 84.665764 -398.134859)
			(xy 84.627679 -398.079219) (xy 84.596532 -398.019419) (xy 84.572771 -397.956318) (xy 84.55674 -397.890825)
			(xy 84.548667 -397.823884) (xy 83.420495 -397.823884) (xy 83.392062 -397.878597) (xy 83.35411 -397.934182)
			(xy 83.33232 -397.959834) (xy 83.326529 -397.966983) (xy 83.32001 -397.984171) (xy 83.31962 -397.993362)
			(xy 83.31962 -398.486884) (xy 83.320033 -398.496071) (xy 83.326544 -398.513256) (xy 83.33232 -398.520412)
			(xy 83.354144 -398.546035) (xy 83.392095 -398.601624) (xy 83.423129 -398.661352) (xy 83.446801 -398.72436)
			(xy 83.462773 -398.789746) (xy 83.470815 -398.856573) (xy 83.470812 -398.923881) (xy 83.462763 -398.990707)
			(xy 83.446785 -399.056092) (xy 83.423107 -399.119098) (xy 83.392067 -399.178822) (xy 83.354111 -399.234408)
			(xy 83.33232 -399.26006) (xy 83.326518 -399.267201) (xy 83.320006 -399.284395) (xy 83.31962 -399.293588)
			(xy 83.31962 -399.451576) (xy 83.319159 -399.461726) (xy 83.311375 -399.480474) (xy 83.296991 -399.494798)
			(xy 83.27821 -399.502502) (xy 83.268058 -399.502884) (xy 82.551778 -399.502884) (xy 82.541653 -399.502392)
			(xy 82.522936 -399.494662) (xy 82.508581 -399.480378) (xy 82.500758 -399.461699) (xy 82.500216 -399.451576)
			(xy 82.500216 -399.293588) (xy 82.499808 -399.284401) (xy 82.493293 -399.267216) (xy 82.487516 -399.26006)
			(xy 82.465765 -399.234378) (xy 82.427816 -399.178795) (xy 82.396783 -399.119076) (xy 82.373109 -399.056075)
			(xy 82.357134 -398.990697) (xy 82.349088 -398.923878) (xy 82.349084 -398.856576) (xy 82.357125 -398.789756)
			(xy 82.373093 -398.724377) (xy 82.396761 -398.661374) (xy 82.427788 -398.601651) (xy 82.465731 -398.546065)
			(xy 82.487516 -398.520412) (xy 82.493334 -398.513282) (xy 82.499835 -398.49608) (xy 82.500216 -398.486884)
			(xy 82.500216 -397.993362) (xy 82.499821 -397.984173) (xy 82.493296 -397.966989) (xy 82.487516 -397.959834)
			(xy 82.465739 -397.934174) (xy 82.427791 -397.878588) (xy 82.396759 -397.818865) (xy 82.373086 -397.755862)
			(xy 82.357113 -397.690481) (xy 82.349069 -397.623659) (xy 82.349068 -397.556356) (xy 81.220853 -397.556356)
			(xy 81.223245 -397.560947) (xy 81.247013 -397.62404) (xy 81.263052 -397.689525) (xy 81.271131 -397.756461)
			(xy 81.271135 -397.823882) (xy 81.263062 -397.890818) (xy 81.24703 -397.956306) (xy 81.223269 -398.019401)
			(xy 81.192121 -398.079196) (xy 81.154035 -398.134829) (xy 81.132172 -398.160494) (xy 81.126392 -398.167651)
			(xy 81.119868 -398.184832) (xy 81.119472 -398.194022) (xy 81.119472 -398.351502) (xy 81.118975 -398.361627)
			(xy 81.111249 -398.380346) (xy 81.096966 -398.394702) (xy 81.078287 -398.402523) (xy 81.068164 -398.403064)
			(xy 80.351884 -398.403064) (xy 80.341724 -398.402691) (xy 80.322965 -398.394883) (xy 80.30864 -398.380471)
			(xy 80.300948 -398.361664) (xy 80.300576 -398.351502) (xy 80.300576 -398.194022) (xy 80.300161 -398.184835)
			(xy 80.293651 -398.16765) (xy 80.287876 -398.160494) (xy 80.265976 -398.134859) (xy 80.22789 -398.07922)
			(xy 80.196742 -398.019419) (xy 80.172981 -397.956318) (xy 80.156949 -397.890826) (xy 80.148876 -397.823885)
			(xy 79.02071 -397.823885) (xy 78.991976 -397.879041) (xy 78.953888 -397.934676) (xy 78.932024 -397.960342)
			(xy 78.92623 -397.967489) (xy 78.919713 -397.984678) (xy 78.919324 -397.99387) (xy 78.919324 -398.486376)
			(xy 78.91974 -398.495563) (xy 78.926249 -398.512747) (xy 78.932024 -398.519904) (xy 78.953922 -398.54554)
			(xy 78.992009 -398.60118) (xy 79.023156 -398.66098) (xy 79.046917 -398.724081) (xy 79.06295 -398.789573)
			(xy 79.071022 -398.856514) (xy 79.071019 -398.92394) (xy 79.06294 -398.99088) (xy 79.046901 -399.056371)
			(xy 79.023134 -399.119469) (xy 78.991981 -399.179267) (xy 78.953889 -399.234902) (xy 78.932024 -399.260568)
			(xy 78.926219 -399.267707) (xy 78.919709 -399.284902) (xy 78.919324 -399.294096) (xy 78.919324 -399.451576)
			(xy 78.918865 -399.461694) (xy 78.911129 -399.480393) (xy 78.896826 -399.494707) (xy 78.878134 -399.502457)
			(xy 78.868016 -399.502884) (xy 78.151736 -399.502884) (xy 78.141614 -399.502454) (xy 78.122908 -399.494715)
			(xy 78.108592 -399.480402) (xy 78.100848 -399.461698) (xy 78.100428 -399.451576) (xy 78.100428 -399.294096)
			(xy 78.100014 -399.284909) (xy 78.093502 -399.267725) (xy 78.087728 -399.260568) (xy 78.065898 -399.234874)
			(xy 78.027807 -399.179244) (xy 77.996653 -399.119452) (xy 77.972886 -399.056359) (xy 77.956847 -398.990873)
			(xy 77.948768 -398.923938) (xy 77.948764 -398.856516) (xy 77.956837 -398.78958) (xy 77.972869 -398.724093)
			(xy 77.996631 -398.660997) (xy 78.027779 -398.601202) (xy 78.065865 -398.545569) (xy 78.087728 -398.519904)
			(xy 78.093509 -398.512748) (xy 78.100032 -398.495566) (xy 78.100428 -398.486376) (xy 78.100428 -397.99387)
			(xy 78.100026 -397.984682) (xy 78.093506 -397.967498) (xy 78.087728 -397.960342) (xy 78.065873 -397.934669)
			(xy 78.027782 -397.879036) (xy 77.996629 -397.819241) (xy 77.972863 -397.756146) (xy 77.956826 -397.690657)
			(xy 77.948749 -397.623719) (xy 77.948748 -397.556296) (xy 76.820503 -397.556296) (xy 76.823115 -397.561323)
			(xy 76.846789 -397.624324) (xy 76.862764 -397.689702) (xy 76.870811 -397.756521) (xy 76.870814 -397.823822)
			(xy 76.862774 -397.890642) (xy 76.846806 -397.956022) (xy 76.823139 -398.019024) (xy 76.792111 -398.078747)
			(xy 76.754168 -398.134333) (xy 76.732384 -398.159986) (xy 76.726567 -398.167116) (xy 76.720065 -398.184318)
			(xy 76.719684 -398.193514) (xy 76.719684 -398.351502) (xy 76.719169 -398.361657) (xy 76.711398 -398.380422)
			(xy 76.697039 -398.394787) (xy 76.678277 -398.402565) (xy 76.668122 -398.403064) (xy 75.951842 -398.403064)
			(xy 75.941673 -398.402602) (xy 75.92288 -398.394831) (xy 75.908494 -398.380457) (xy 75.900707 -398.36167)
			(xy 75.90028 -398.351502) (xy 75.90028 -398.193514) (xy 75.899868 -398.184327) (xy 75.893356 -398.167142)
			(xy 75.88758 -398.159986) (xy 75.865754 -398.134365) (xy 75.827803 -398.078775) (xy 75.79677 -398.019048)
			(xy 75.773097 -397.956039) (xy 75.757126 -397.890653) (xy 75.749084 -397.823826) (xy 74.620438 -397.823826)
			(xy 74.591977 -397.878596) (xy 74.554025 -397.934182) (xy 74.532236 -397.959834) (xy 74.526435 -397.966975)
			(xy 74.519925 -397.984169) (xy 74.519536 -397.993362) (xy 74.519536 -398.486884) (xy 74.519968 -398.496069)
			(xy 74.526468 -398.513252) (xy 74.532236 -398.520412) (xy 74.55406 -398.546035) (xy 74.592009 -398.601625)
			(xy 74.623043 -398.661352) (xy 74.646714 -398.724361) (xy 74.662686 -398.789747) (xy 74.670727 -398.856573)
			(xy 74.670724 -398.923881) (xy 74.662676 -398.990707) (xy 74.646698 -399.056091) (xy 74.623021 -399.119097)
			(xy 74.591982 -399.178822) (xy 74.554027 -399.234408) (xy 74.532236 -399.26006) (xy 74.526424 -399.267194)
			(xy 74.51992 -399.284393) (xy 74.519536 -399.293588) (xy 74.519536 -399.451576) (xy 74.51906 -399.461724)
			(xy 74.511279 -399.480469) (xy 74.496899 -399.494792) (xy 74.478124 -399.502499) (xy 74.467974 -399.502884)
			(xy 73.751694 -399.502884) (xy 73.74157 -399.502379) (xy 73.722853 -399.494654) (xy 73.708498 -399.480373)
			(xy 73.700675 -399.461697) (xy 73.700132 -399.451576) (xy 73.700132 -399.293588) (xy 73.699721 -399.284401)
			(xy 73.693207 -399.267217) (xy 73.687432 -399.26006) (xy 73.66568 -399.234378) (xy 73.627731 -399.178796)
			(xy 73.596696 -399.119077) (xy 73.573022 -399.056076) (xy 73.557047 -398.990697) (xy 73.549 -398.923878)
			(xy 73.548996 -398.856576) (xy 73.557037 -398.789756) (xy 73.573006 -398.724376) (xy 73.596674 -398.661373)
			(xy 73.627703 -398.60165) (xy 73.665647 -398.546064) (xy 73.687432 -398.520412) (xy 73.693253 -398.513284)
			(xy 73.699752 -398.49608) (xy 73.700132 -398.486884) (xy 73.700132 -397.993362) (xy 73.699733 -397.984174)
			(xy 73.693211 -397.96699) (xy 73.687432 -397.959834) (xy 73.665654 -397.934174) (xy 73.627705 -397.878588)
			(xy 73.596672 -397.818866) (xy 73.572999 -397.755862) (xy 73.557026 -397.690481) (xy 73.548981 -397.62366)
			(xy 73.54898 -397.556355) (xy 72.420766 -397.556355) (xy 72.423159 -397.560948) (xy 72.446926 -397.62404)
			(xy 72.462964 -397.689526) (xy 72.471043 -397.756461) (xy 72.471047 -397.823882) (xy 72.462974 -397.890818)
			(xy 72.446942 -397.956305) (xy 72.423182 -398.0194) (xy 72.392035 -398.079195) (xy 72.35395 -398.134829)
			(xy 72.332088 -398.160494) (xy 72.32631 -398.167652) (xy 72.319785 -398.184833) (xy 72.319388 -398.194022)
			(xy 72.319388 -398.351502) (xy 72.318876 -398.361625) (xy 72.311153 -398.380341) (xy 72.296875 -398.394696)
			(xy 72.278201 -398.40252) (xy 72.26808 -398.403064) (xy 71.5518 -398.403064) (xy 71.541641 -398.402678)
			(xy 71.522882 -398.394875) (xy 71.508557 -398.380467) (xy 71.500864 -398.361663) (xy 71.500492 -398.351502)
			(xy 71.500492 -398.194022) (xy 71.500073 -398.184836) (xy 71.493566 -398.167651) (xy 71.487792 -398.160494)
			(xy 71.465891 -398.134859) (xy 71.427804 -398.07922) (xy 71.396655 -398.01942) (xy 71.372894 -397.956319)
			(xy 71.356861 -397.890826) (xy 71.348788 -397.823885) (xy 66.525648 -397.823885) (xy 66.525648 -401.723796)
			(xy 71.3488 -401.723796) (xy 71.348802 -401.656371) (xy 71.35688 -401.589431) (xy 71.372917 -401.523941)
			(xy 71.396683 -401.460843) (xy 71.427836 -401.401046) (xy 71.465927 -401.345411) (xy 71.487792 -401.319746)
			(xy 71.493593 -401.312604) (xy 71.500105 -401.295411) (xy 71.500492 -401.286218) (xy 71.500492 -400.793966)
			(xy 71.5001 -400.784777) (xy 71.493574 -400.767592) (xy 71.487792 -400.760438) (xy 71.465934 -400.734768)
			(xy 71.427846 -400.679134) (xy 71.396695 -400.619338) (xy 71.372931 -400.556242) (xy 71.356896 -400.490754)
			(xy 71.348819 -400.423816) (xy 71.348819 -400.356393) (xy 71.356894 -400.289455) (xy 71.372928 -400.223967)
			(xy 71.396692 -400.16087) (xy 71.427841 -400.101074) (xy 71.465929 -400.045439) (xy 71.487792 -400.019774)
			(xy 71.493581 -400.012623) (xy 71.500101 -399.995437) (xy 71.500492 -399.986246) (xy 71.500492 -399.828766)
			(xy 71.500997 -399.818643) (xy 71.508727 -399.79993) (xy 71.523007 -399.785577) (xy 71.54168 -399.77775)
			(xy 71.5518 -399.777204) (xy 72.26808 -399.777204) (xy 72.278233 -399.777638) (xy 72.296986 -399.785428)
			(xy 72.31131 -399.799821) (xy 72.31901 -399.818611) (xy 72.319388 -399.828766) (xy 72.319388 -399.986246)
			(xy 72.319827 -399.99543) (xy 72.326321 -400.012615) (xy 72.332088 -400.019774) (xy 72.353958 -400.045434)
			(xy 72.392048 -400.101069) (xy 72.423199 -400.160866) (xy 72.446963 -400.223963) (xy 72.462999 -400.289453)
			(xy 72.471074 -400.356392) (xy 72.471074 -400.423817) (xy 72.462997 -400.490756) (xy 72.44696 -400.556245)
			(xy 72.423195 -400.619342) (xy 72.392043 -400.679139) (xy 72.353953 -400.734773) (xy 72.332088 -400.760438)
			(xy 72.326291 -400.767583) (xy 72.319777 -400.784774) (xy 72.319388 -400.793966) (xy 72.319388 -401.286218)
			(xy 72.319792 -401.295406) (xy 72.32631 -401.31259) (xy 72.332088 -401.319746) (xy 72.353931 -401.345429)
			(xy 72.392021 -401.401061) (xy 72.423173 -401.460854) (xy 72.446939 -401.523949) (xy 72.462977 -401.589436)
			(xy 72.471054 -401.656372) (xy 72.471056 -401.723795) (xy 72.462982 -401.790732) (xy 72.446949 -401.85622)
			(xy 72.423187 -401.919316) (xy 72.392038 -401.979111) (xy 72.353951 -402.034745) (xy 72.332088 -402.06041)
			(xy 72.326303 -402.067564) (xy 72.319782 -402.084748) (xy 72.319388 -402.093938) (xy 72.319388 -402.251418)
			(xy 72.318889 -402.261542) (xy 72.311161 -402.280259) (xy 72.296879 -402.294614) (xy 72.278202 -402.302437)
			(xy 72.26808 -402.30298) (xy 71.5518 -402.30298) (xy 71.541643 -402.302578) (xy 71.522887 -402.294779)
			(xy 71.508563 -402.280376) (xy 71.500867 -402.261577) (xy 71.500492 -402.251418) (xy 71.500492 -402.093938)
			(xy 71.500065 -402.084753) (xy 71.493563 -402.067568) (xy 71.487792 -402.06041) (xy 71.465907 -402.034762)
			(xy 71.427819 -401.979125) (xy 71.39667 -401.919326) (xy 71.372907 -401.856227) (xy 71.356874 -401.790736)
			(xy 71.3488 -401.723796) (xy 66.525648 -401.723796) (xy 66.525648 -402.823818) (xy 73.54894 -402.823818)
			(xy 73.548944 -402.75651) (xy 73.556993 -402.689684) (xy 73.572971 -402.624299) (xy 73.596649 -402.561293)
			(xy 73.627687 -402.501568) (xy 73.665642 -402.44598) (xy 73.687432 -402.420328) (xy 73.693246 -402.413195)
			(xy 73.699749 -402.395995) (xy 73.700132 -402.3868) (xy 73.700132 -401.893532) (xy 73.699699 -401.884347)
			(xy 73.6932 -401.867163) (xy 73.687432 -401.860004) (xy 73.665625 -401.834368) (xy 73.627677 -401.778779)
			(xy 73.596645 -401.719053) (xy 73.572974 -401.656047) (xy 73.557002 -401.590662) (xy 73.54896 -401.523838)
			(xy 73.548962 -401.456532) (xy 73.557008 -401.389708) (xy 73.572982 -401.324325) (xy 73.596657 -401.261319)
			(xy 73.627692 -401.201595) (xy 73.665643 -401.146008) (xy 73.687432 -401.120356) (xy 73.693234 -401.113215)
			(xy 73.699745 -401.096021) (xy 73.700132 -401.086828) (xy 73.700132 -400.92884) (xy 73.700555 -400.918685)
			(xy 73.708343 -400.899927) (xy 73.722741 -400.885601) (xy 73.741537 -400.877906) (xy 73.751694 -400.877532)
			(xy 74.467974 -400.877532) (xy 74.478098 -400.878047) (xy 74.496817 -400.885765) (xy 74.511174 -400.900043)
			(xy 74.518996 -400.918719) (xy 74.519536 -400.92884) (xy 74.519536 -401.086828) (xy 74.519947 -401.096015)
			(xy 74.526462 -401.113198) (xy 74.532236 -401.120356) (xy 74.554005 -401.146024) (xy 74.591956 -401.201608)
			(xy 74.622991 -401.261329) (xy 74.646666 -401.324331) (xy 74.662641 -401.389712) (xy 74.670687 -401.456533)
			(xy 74.670689 -401.523837) (xy 74.662647 -401.590659) (xy 74.646675 -401.65604) (xy 74.623004 -401.719044)
			(xy 74.620565 -401.723737) (xy 75.749095 -401.723737) (xy 75.749097 -401.65643) (xy 75.757144 -401.589605)
			(xy 75.773121 -401.524221) (xy 75.796798 -401.461215) (xy 75.827836 -401.401492) (xy 75.86579 -401.345906)
			(xy 75.88758 -401.320254) (xy 75.893376 -401.313108) (xy 75.899892 -401.295918) (xy 75.90028 -401.286726)
			(xy 75.90028 -400.793458) (xy 75.899895 -400.784268) (xy 75.893364 -400.767084) (xy 75.88758 -400.75993)
			(xy 75.865797 -400.734274) (xy 75.827845 -400.678689) (xy 75.79681 -400.618966) (xy 75.773135 -400.555962)
			(xy 75.75716 -400.49058) (xy 75.749115 -400.423757) (xy 75.749114 -400.356452) (xy 75.757158 -400.289629)
			(xy 75.773132 -400.224247) (xy 75.796806 -400.161242) (xy 75.827841 -400.101519) (xy 75.865791 -400.045934)
			(xy 75.88758 -400.020282) (xy 75.893364 -400.013128) (xy 75.899887 -399.995944) (xy 75.90028 -399.986754)
			(xy 75.90028 -399.828766) (xy 75.900637 -399.818587) (xy 75.908441 -399.799783) (xy 75.922847 -399.785398)
			(xy 75.941662 -399.777622) (xy 75.951842 -399.777204) (xy 76.668122 -399.777204) (xy 76.678277 -399.777714)
			(xy 76.69704 -399.78549) (xy 76.711404 -399.79985) (xy 76.719183 -399.818611) (xy 76.719684 -399.828766)
			(xy 76.719684 -399.986754) (xy 76.72012 -399.995938) (xy 76.726616 -400.013123) (xy 76.732384 -400.020282)
			(xy 76.754177 -400.04593) (xy 76.792124 -400.101517) (xy 76.823156 -400.161242) (xy 76.846827 -400.224247)
			(xy 76.862799 -400.289629) (xy 76.870842 -400.356452) (xy 76.870842 -400.423757) (xy 76.862798 -400.49058)
			(xy 76.846825 -400.555962) (xy 76.823152 -400.618967) (xy 76.792119 -400.678691) (xy 76.754171 -400.734278)
			(xy 76.732384 -400.75993) (xy 76.72659 -400.767077) (xy 76.720074 -400.784266) (xy 76.719684 -400.793458)
			(xy 76.719684 -401.286726) (xy 76.720085 -401.295914) (xy 76.726605 -401.313098) (xy 76.732384 -401.320254)
			(xy 76.754149 -401.345924) (xy 76.792097 -401.401509) (xy 76.82313 -401.46123) (xy 76.846803 -401.524232)
			(xy 76.862777 -401.589612) (xy 76.870823 -401.656432) (xy 76.870825 -401.723735) (xy 76.862783 -401.790556)
			(xy 76.846813 -401.855936) (xy 76.823144 -401.91894) (xy 76.792114 -401.978663) (xy 76.75417 -402.03425)
			(xy 76.732384 -402.059902) (xy 76.726602 -402.067058) (xy 76.720079 -402.08424) (xy 76.719684 -402.09343)
			(xy 76.719684 -402.251418) (xy 76.719182 -402.261574) (xy 76.711406 -402.28034) (xy 76.697043 -402.294704)
			(xy 76.678278 -402.302481) (xy 76.668122 -402.30298) (xy 75.951842 -402.30298) (xy 75.941675 -402.302502)
			(xy 75.922885 -402.294734) (xy 75.908499 -402.280365) (xy 75.90071 -402.261584) (xy 75.90028 -402.251418)
			(xy 75.90028 -402.09343) (xy 75.89986 -402.084244) (xy 75.893354 -402.067059) (xy 75.88758 -402.059902)
			(xy 75.865769 -402.034268) (xy 75.827819 -401.97868) (xy 75.796784 -401.918954) (xy 75.773111 -401.855947)
			(xy 75.757138 -401.790562) (xy 75.749095 -401.723737) (xy 74.620565 -401.723737) (xy 74.591971 -401.778767)
			(xy 74.554023 -401.834352) (xy 74.532236 -401.860004) (xy 74.526447 -401.867155) (xy 74.51993 -401.884341)
			(xy 74.519536 -401.893532) (xy 74.519536 -402.3868) (xy 74.519961 -402.395985) (xy 74.526466 -402.413169)
			(xy 74.532236 -402.420328) (xy 74.553977 -402.446019) (xy 74.591929 -402.501599) (xy 74.622966 -402.561317)
			(xy 74.646642 -402.624317) (xy 74.662619 -402.689694) (xy 74.670668 -402.756513) (xy 74.670672 -402.823815)
			(xy 74.670664 -402.823878) (xy 77.948708 -402.823878) (xy 77.948713 -402.75645) (xy 77.956794 -402.689508)
			(xy 77.972835 -402.624016) (xy 77.996606 -402.560917) (xy 78.027764 -402.501119) (xy 78.06586 -402.445485)
			(xy 78.087728 -402.41982) (xy 78.093545 -402.412689) (xy 78.100047 -402.395488) (xy 78.100428 -402.386292)
			(xy 78.100428 -401.89404) (xy 78.099992 -401.884856) (xy 78.093496 -401.867671) (xy 78.087728 -401.860512)
			(xy 78.065843 -401.834863) (xy 78.027753 -401.779227) (xy 77.996602 -401.719429) (xy 77.972838 -401.65633)
			(xy 77.956803 -401.590838) (xy 77.948728 -401.523898) (xy 77.94873 -401.456472) (xy 77.956808 -401.389532)
			(xy 77.972847 -401.324041) (xy 77.996614 -401.260944) (xy 78.027769 -401.201147) (xy 78.065862 -401.145513)
			(xy 78.087728 -401.119848) (xy 78.093533 -401.112709) (xy 78.100042 -401.095514) (xy 78.100428 -401.08632)
			(xy 78.100428 -400.92884) (xy 78.10085 -400.918717) (xy 78.10859 -400.900009) (xy 78.122905 -400.885692)
			(xy 78.141613 -400.87795) (xy 78.151736 -400.877532) (xy 78.868016 -400.877532) (xy 78.878144 -400.877903)
			(xy 78.896854 -400.885663) (xy 78.911169 -400.899993) (xy 78.918908 -400.918712) (xy 78.919324 -400.92884)
			(xy 78.919324 -401.08632) (xy 78.919719 -401.095509) (xy 78.926243 -401.112693) (xy 78.932024 -401.119848)
			(xy 78.953867 -401.14553) (xy 78.991955 -401.201163) (xy 79.023105 -401.260957) (xy 79.04687 -401.324051)
			(xy 79.062906 -401.389538) (xy 79.070983 -401.456474) (xy 79.070985 -401.523896) (xy 79.062911 -401.590832)
			(xy 79.046879 -401.65632) (xy 79.023118 -401.719416) (xy 79.020837 -401.723796) (xy 80.148888 -401.723796)
			(xy 80.14889 -401.656371) (xy 80.156967 -401.589432) (xy 80.173004 -401.523942) (xy 80.19677 -401.460844)
			(xy 80.227922 -401.401047) (xy 80.266012 -401.345412) (xy 80.287876 -401.319746) (xy 80.293675 -401.312603)
			(xy 80.300189 -401.295411) (xy 80.300576 -401.286218) (xy 80.300576 -400.793966) (xy 80.300187 -400.784776)
			(xy 80.293659 -400.767592) (xy 80.287876 -400.760438) (xy 80.266019 -400.734767) (xy 80.227931 -400.679133)
			(xy 80.196782 -400.619337) (xy 80.173018 -400.556241) (xy 80.156983 -400.490753) (xy 80.148907 -400.423816)
			(xy 80.148907 -400.356393) (xy 80.156982 -400.289456) (xy 80.173016 -400.223967) (xy 80.196778 -400.160871)
			(xy 80.227927 -400.101075) (xy 80.266013 -400.04544) (xy 80.287876 -400.019774) (xy 80.293663 -400.012622)
			(xy 80.300184 -399.995437) (xy 80.300576 -399.986246) (xy 80.300576 -399.828766) (xy 80.301 -399.818633)
			(xy 80.308745 -399.799904) (xy 80.323051 -399.785548) (xy 80.341753 -399.777736) (xy 80.351884 -399.777204)
			(xy 81.068164 -399.777204) (xy 81.078316 -399.777651) (xy 81.097069 -399.785436) (xy 81.111393 -399.799825)
			(xy 81.119094 -399.818612) (xy 81.119472 -399.828766) (xy 81.119472 -399.986246) (xy 81.119914 -399.99543)
			(xy 81.126406 -400.012614) (xy 81.132172 -400.019774) (xy 81.154043 -400.045434) (xy 81.192133 -400.101069)
			(xy 81.223285 -400.160865) (xy 81.24705 -400.223963) (xy 81.263086 -400.289453) (xy 81.271162 -400.356392)
			(xy 81.271161 -400.423817) (xy 81.263085 -400.490756) (xy 81.247048 -400.556246) (xy 81.223282 -400.619343)
			(xy 81.192129 -400.679139) (xy 81.154037 -400.734773) (xy 81.132172 -400.760438) (xy 81.126373 -400.767581)
			(xy 81.11986 -400.784773) (xy 81.119472 -400.793966) (xy 81.119472 -401.286218) (xy 81.11988 -401.295405)
			(xy 81.126396 -401.312589) (xy 81.132172 -401.319746) (xy 81.154015 -401.345429) (xy 81.192107 -401.40106)
			(xy 81.22326 -401.460854) (xy 81.247026 -401.523948) (xy 81.263064 -401.589435) (xy 81.271142 -401.656372)
			(xy 81.271144 -401.723795) (xy 81.26307 -401.790732) (xy 81.247036 -401.85622) (xy 81.223273 -401.919316)
			(xy 81.192124 -401.979112) (xy 81.154036 -402.034745) (xy 81.132172 -402.06041) (xy 81.126385 -402.067562)
			(xy 81.119865 -402.084747) (xy 81.119472 -402.093938) (xy 81.119472 -402.251418) (xy 81.118989 -402.261544)
			(xy 81.111257 -402.280264) (xy 81.09697 -402.294619) (xy 81.078288 -402.30244) (xy 81.068164 -402.30298)
			(xy 80.351884 -402.30298) (xy 80.341726 -402.302591) (xy 80.32297 -402.294787) (xy 80.308646 -402.28038)
			(xy 80.30095 -402.261578) (xy 80.300576 -402.251418) (xy 80.300576 -402.093938) (xy 80.300153 -402.084752)
			(xy 80.293649 -402.067567) (xy 80.287876 -402.06041) (xy 80.265991 -402.034762) (xy 80.227905 -401.979125)
			(xy 80.196756 -401.919326) (xy 80.172994 -401.856227) (xy 80.156961 -401.790736) (xy 80.148888 -401.723796)
			(xy 79.020837 -401.723796) (xy 78.991971 -401.779212) (xy 78.953886 -401.834846) (xy 78.932024 -401.860512)
			(xy 78.926243 -401.867668) (xy 78.919718 -401.88485) (xy 78.919324 -401.89404) (xy 78.919324 -402.386292)
			(xy 78.919733 -402.395479) (xy 78.926247 -402.412664) (xy 78.932024 -402.41982) (xy 78.95384 -402.445525)
			(xy 78.991929 -402.501154) (xy 79.02308 -402.560945) (xy 79.046846 -402.624037) (xy 79.062884 -402.689521)
			(xy 79.070963 -402.756454) (xy 79.070968 -402.823818) (xy 82.349028 -402.823818) (xy 82.349032 -402.75651)
			(xy 82.357081 -402.689684) (xy 82.373058 -402.6243) (xy 82.396735 -402.561293) (xy 82.427773 -402.501568)
			(xy 82.465726 -402.44598) (xy 82.487516 -402.420328) (xy 82.493327 -402.413193) (xy 82.499833 -402.395995)
			(xy 82.500216 -402.3868) (xy 82.500216 -401.893532) (xy 82.499787 -401.884347) (xy 82.493286 -401.867163)
			(xy 82.487516 -401.860004) (xy 82.465709 -401.834368) (xy 82.427763 -401.778778) (xy 82.396731 -401.719052)
			(xy 82.373061 -401.656046) (xy 82.35709 -401.590662) (xy 82.349048 -401.523838) (xy 82.34905 -401.456532)
			(xy 82.357095 -401.389708) (xy 82.37307 -401.324325) (xy 82.396744 -401.26132) (xy 82.427778 -401.201596)
			(xy 82.465728 -401.146008) (xy 82.487516 -401.120356) (xy 82.493316 -401.113213) (xy 82.499828 -401.096021)
			(xy 82.500216 -401.086828) (xy 82.500216 -400.92884) (xy 82.500655 -400.918687) (xy 82.50844 -400.899932)
			(xy 82.522832 -400.885607) (xy 82.541623 -400.877908) (xy 82.551778 -400.877532) (xy 83.268058 -400.877532)
			(xy 83.278181 -400.878061) (xy 83.2969 -400.885773) (xy 83.311257 -400.900047) (xy 83.319079 -400.91872)
			(xy 83.31962 -400.92884) (xy 83.31962 -401.086828) (xy 83.320012 -401.096017) (xy 83.326538 -401.113202)
			(xy 83.33232 -401.120356) (xy 83.354089 -401.146024) (xy 83.392041 -401.201607) (xy 83.423078 -401.261328)
			(xy 83.446753 -401.324331) (xy 83.462729 -401.389711) (xy 83.470775 -401.456533) (xy 83.470777 -401.523837)
			(xy 83.462734 -401.590659) (xy 83.446762 -401.656041) (xy 83.42309 -401.719044) (xy 83.420621 -401.723796)
			(xy 84.548678 -401.723796) (xy 84.54868 -401.656371) (xy 84.556758 -401.589432) (xy 84.572795 -401.523942)
			(xy 84.59656 -401.460845) (xy 84.627711 -401.401047) (xy 84.6658 -401.345412) (xy 84.687664 -401.319746)
			(xy 84.693474 -401.312611) (xy 84.699979 -401.295412) (xy 84.700364 -401.286218) (xy 84.700364 -400.793966)
			(xy 84.699956 -400.784779) (xy 84.693439 -400.767595) (xy 84.687664 -400.760438) (xy 84.665807 -400.734767)
			(xy 84.627721 -400.679133) (xy 84.596572 -400.619337) (xy 84.572809 -400.556241) (xy 84.556774 -400.490753)
			(xy 84.548698 -400.423816) (xy 84.548698 -400.356393) (xy 84.556772 -400.289456) (xy 84.572806 -400.223968)
			(xy 84.596568 -400.160871) (xy 84.627716 -400.101075) (xy 84.665802 -400.04544) (xy 84.687664 -400.019774)
			(xy 84.693462 -400.01263) (xy 84.699974 -399.995438) (xy 84.700364 -399.986246) (xy 84.700364 -399.828766)
			(xy 84.700799 -399.818634) (xy 84.708543 -399.799908) (xy 84.722845 -399.785552) (xy 84.741542 -399.777738)
			(xy 84.751672 -399.777204) (xy 85.467952 -399.777204) (xy 85.478104 -399.777661) (xy 85.496856 -399.785442)
			(xy 85.511181 -399.799828) (xy 85.518881 -399.818613) (xy 85.51926 -399.828766) (xy 85.51926 -399.986246)
			(xy 85.519705 -399.995429) (xy 85.526196 -400.012613) (xy 85.53196 -400.019774) (xy 85.553831 -400.045434)
			(xy 85.591922 -400.101068) (xy 85.623075 -400.160865) (xy 85.646841 -400.223962) (xy 85.662877 -400.289453)
			(xy 85.670953 -400.356392) (xy 85.670952 -400.423817) (xy 85.662875 -400.490756) (xy 85.646838 -400.556246)
			(xy 85.623071 -400.619344) (xy 85.591918 -400.67914) (xy 85.553826 -400.734773) (xy 85.53196 -400.760438)
			(xy 85.52616 -400.76758) (xy 85.519648 -400.784773) (xy 85.51926 -400.793966) (xy 85.51926 -401.286218)
			(xy 85.51967 -401.295405) (xy 85.526185 -401.312589) (xy 85.53196 -401.319746) (xy 85.553804 -401.345428)
			(xy 85.591896 -401.40106) (xy 85.62305 -401.460853) (xy 85.646817 -401.523948) (xy 85.662855 -401.589435)
			(xy 85.670933 -401.656372) (xy 85.670935 -401.723795) (xy 85.662861 -401.790732) (xy 85.646827 -401.856221)
			(xy 85.623063 -401.919317) (xy 85.591913 -401.979112) (xy 85.553824 -402.034745) (xy 85.53196 -402.06041)
			(xy 85.526172 -402.067561) (xy 85.519653 -402.084747) (xy 85.51926 -402.093938) (xy 85.51926 -402.251418)
			(xy 85.518788 -402.261546) (xy 85.511055 -402.280268) (xy 85.496764 -402.294623) (xy 85.478078 -402.302442)
			(xy 85.467952 -402.30298) (xy 84.751672 -402.30298) (xy 84.741514 -402.302601) (xy 84.722757 -402.294792)
			(xy 84.708434 -402.280383) (xy 84.700738 -402.261579) (xy 84.700364 -402.251418) (xy 84.700364 -402.093938)
			(xy 84.699921 -402.084755) (xy 84.693429 -402.067571) (xy 84.687664 -402.06041) (xy 84.66578 -402.034762)
			(xy 84.627694 -401.979124) (xy 84.596546 -401.919325) (xy 84.572785 -401.856226) (xy 84.556752 -401.790735)
			(xy 84.548678 -401.723796) (xy 83.420621 -401.723796) (xy 83.392057 -401.778767) (xy 83.354108 -401.834352)
			(xy 83.33232 -401.860004) (xy 83.326542 -401.867162) (xy 83.320015 -401.884343) (xy 83.31962 -401.893532)
			(xy 83.31962 -402.3868) (xy 83.320026 -402.395988) (xy 83.326542 -402.413172) (xy 83.33232 -402.420328)
			(xy 83.354062 -402.446018) (xy 83.392015 -402.501598) (xy 83.423052 -402.561316) (xy 83.44673 -402.624316)
			(xy 83.462707 -402.689694) (xy 83.470756 -402.756513) (xy 83.47076 -402.823815) (xy 83.470752 -402.823878)
			(xy 86.748796 -402.823878) (xy 86.748801 -402.75645) (xy 86.756882 -402.689508) (xy 86.772922 -402.624016)
			(xy 86.796693 -402.560918) (xy 86.82785 -402.50112) (xy 86.865945 -402.445485) (xy 86.887812 -402.41982)
			(xy 86.893626 -402.412687) (xy 86.90013 -402.395487) (xy 86.900512 -402.386292) (xy 86.900512 -401.89404)
			(xy 86.90008 -401.884855) (xy 86.893581 -401.867671) (xy 86.887812 -401.860512) (xy 86.865928 -401.834863)
			(xy 86.827839 -401.779227) (xy 86.796689 -401.719428) (xy 86.772925 -401.656329) (xy 86.756891 -401.590838)
			(xy 86.748816 -401.523898) (xy 86.748818 -401.456472) (xy 86.756896 -401.389532) (xy 86.772934 -401.324042)
			(xy 86.796701 -401.260944) (xy 86.827855 -401.201148) (xy 86.865946 -401.145513) (xy 86.887812 -401.119848)
			(xy 86.893615 -401.112707) (xy 86.900125 -401.095513) (xy 86.900512 -401.08632) (xy 86.900512 -400.92884)
			(xy 86.900949 -400.918719) (xy 86.908686 -400.900014) (xy 86.922997 -400.885698) (xy 86.941699 -400.877953)
			(xy 86.95182 -400.877532) (xy 87.6681 -400.877532) (xy 87.678226 -400.877917) (xy 87.696936 -400.885671)
			(xy 87.711252 -400.899997) (xy 87.718991 -400.918713) (xy 87.719408 -400.92884) (xy 87.719408 -401.08632)
			(xy 87.719807 -401.095508) (xy 87.726328 -401.112693) (xy 87.732108 -401.119848) (xy 87.753952 -401.14553)
			(xy 87.792041 -401.201162) (xy 87.823192 -401.260956) (xy 87.846957 -401.324051) (xy 87.862994 -401.389538)
			(xy 87.871071 -401.456474) (xy 87.871073 -401.523896) (xy 87.862999 -401.590833) (xy 87.846966 -401.656321)
			(xy 87.823204 -401.719417) (xy 87.820954 -401.723737) (xy 115.349237 -401.723737) (xy 115.349239 -401.65643)
			(xy 115.357285 -401.589607) (xy 115.373259 -401.524224) (xy 115.396933 -401.461219) (xy 115.427967 -401.401494)
			(xy 115.465916 -401.345907) (xy 115.487704 -401.320254) (xy 115.493503 -401.313111) (xy 115.500016 -401.295919)
			(xy 115.500404 -401.286726) (xy 115.500404 -400.793458) (xy 115.500013 -400.784269) (xy 115.493486 -400.767085)
			(xy 115.487704 -400.75993) (xy 115.465923 -400.734273) (xy 115.427977 -400.678686) (xy 115.396945 -400.618963)
			(xy 115.373273 -400.555959) (xy 115.357301 -400.490578) (xy 115.349257 -400.423756) (xy 115.349256 -400.356453)
			(xy 115.357299 -400.289631) (xy 115.373271 -400.22425) (xy 115.396941 -400.161245) (xy 115.427972 -400.101522)
			(xy 115.465918 -400.045935) (xy 115.487704 -400.020282) (xy 115.493491 -400.01313) (xy 115.500011 -399.995945)
			(xy 115.500404 -399.986754) (xy 115.500404 -399.828766) (xy 115.500905 -399.81861) (xy 115.508684 -399.799847)
			(xy 115.523047 -399.785484) (xy 115.54181 -399.777705) (xy 115.551966 -399.777204) (xy 116.268246 -399.777204)
			(xy 116.278403 -399.777695) (xy 116.297166 -399.785478) (xy 116.311529 -399.799844) (xy 116.319307 -399.818609)
			(xy 116.319808 -399.828766) (xy 116.319808 -399.986754) (xy 116.320238 -399.995939) (xy 116.326738 -400.013124)
			(xy 116.332508 -400.020282) (xy 116.354303 -400.045929) (xy 116.392255 -400.101515) (xy 116.423291 -400.161238)
			(xy 116.446966 -400.224244) (xy 116.46294 -400.289627) (xy 116.470985 -400.356451) (xy 116.470984 -400.423758)
			(xy 116.462939 -400.490582) (xy 116.446963 -400.555965) (xy 116.423288 -400.61897) (xy 116.392251 -400.678693)
			(xy 116.354298 -400.734279) (xy 116.332508 -400.75993) (xy 116.326717 -400.767079) (xy 116.320199 -400.784267)
			(xy 116.319808 -400.793458) (xy 116.319808 -401.286726) (xy 116.320204 -401.295915) (xy 116.326727 -401.313099)
			(xy 116.332508 -401.320254) (xy 116.354276 -401.345923) (xy 116.392229 -401.401506) (xy 116.423266 -401.461227)
			(xy 116.446942 -401.524229) (xy 116.462918 -401.58961) (xy 116.470965 -401.656431) (xy 116.470967 -401.723736)
			(xy 116.462924 -401.790558) (xy 116.446952 -401.855939) (xy 116.423279 -401.918943) (xy 116.392246 -401.978666)
			(xy 116.354296 -402.034251) (xy 116.332508 -402.059902) (xy 116.326729 -402.06706) (xy 116.320204 -402.084241)
			(xy 116.319808 -402.09343) (xy 116.319808 -402.251418) (xy 116.319283 -402.261571) (xy 116.311511 -402.280332)
			(xy 116.297156 -402.294695) (xy 116.278399 -402.302477) (xy 116.268246 -402.30298) (xy 115.551966 -402.30298)
			(xy 115.541808 -402.302495) (xy 115.523042 -402.294713) (xy 115.508678 -402.280345) (xy 115.500902 -402.261576)
			(xy 115.500404 -402.251418) (xy 115.500404 -402.09343) (xy 115.499978 -402.084244) (xy 115.493475 -402.06706)
			(xy 115.487704 -402.059902) (xy 115.465896 -402.034267) (xy 115.42795 -401.978677) (xy 115.396919 -401.918951)
			(xy 115.373249 -401.855944) (xy 115.357279 -401.79056) (xy 115.349237 -401.723737) (xy 87.820954 -401.723737)
			(xy 87.792056 -401.779212) (xy 87.75397 -401.834847) (xy 87.732108 -401.860512) (xy 87.726325 -401.867667)
			(xy 87.719802 -401.88485) (xy 87.719408 -401.89404) (xy 87.719408 -402.386292) (xy 87.71982 -402.395479)
			(xy 87.726332 -402.412663) (xy 87.732108 -402.41982) (xy 87.753925 -402.445524) (xy 87.792014 -402.501153)
			(xy 87.823166 -402.560944) (xy 87.846933 -402.624036) (xy 87.862972 -402.68952) (xy 87.871051 -402.756454)
			(xy 87.871055 -402.823874) (xy 87.862984 -402.890809) (xy 87.846954 -402.956295) (xy 87.823196 -403.01939)
			(xy 87.792051 -403.079185) (xy 87.753969 -403.134819) (xy 87.732108 -403.160484) (xy 87.726294 -403.167617)
			(xy 87.71979 -403.184817) (xy 87.719408 -403.194012) (xy 87.719408 -403.351492) (xy 87.718978 -403.361613)
			(xy 87.711234 -403.380315) (xy 87.696922 -403.394629) (xy 87.678221 -403.402376) (xy 87.6681 -403.4028)
			(xy 86.95182 -403.4028) (xy 86.941699 -403.402368) (xy 86.922996 -403.394626) (xy 86.908681 -403.380315)
			(xy 86.900935 -403.361613) (xy 86.900512 -403.351492) (xy 86.900512 -403.194012) (xy 86.900093 -403.184826)
			(xy 86.893585 -403.167642) (xy 86.887812 -403.160484) (xy 86.8659 -403.134858) (xy 86.827812 -403.079218)
			(xy 86.796663 -403.019417) (xy 86.772901 -402.956315) (xy 86.756869 -402.890821) (xy 86.748796 -402.823878)
			(xy 83.470752 -402.823878) (xy 83.46272 -402.890635) (xy 83.446751 -402.956015) (xy 83.423082 -403.019018)
			(xy 83.392052 -403.07874) (xy 83.354106 -403.134324) (xy 83.33232 -403.159976) (xy 83.326511 -403.167113)
			(xy 83.320003 -403.18431) (xy 83.31962 -403.193504) (xy 83.31962 -403.351492) (xy 83.319172 -403.361643)
			(xy 83.311383 -403.380391) (xy 83.296995 -403.394714) (xy 83.278211 -403.402418) (xy 83.268058 -403.4028)
			(xy 82.551778 -403.4028) (xy 82.541655 -403.402293) (xy 82.522941 -403.394565) (xy 82.508586 -403.380286)
			(xy 82.500761 -403.361613) (xy 82.500216 -403.351492) (xy 82.500216 -403.193504) (xy 82.4998 -403.184318)
			(xy 82.49329 -403.167133) (xy 82.487516 -403.159976) (xy 82.465682 -403.134362) (xy 82.427736 -403.07877)
			(xy 82.396706 -403.019041) (xy 82.373037 -402.956031) (xy 82.357068 -402.890645) (xy 82.349028 -402.823818)
			(xy 79.070968 -402.823818) (xy 79.070968 -402.823874) (xy 79.062897 -402.890808) (xy 79.046867 -402.956294)
			(xy 79.023109 -403.019389) (xy 78.991966 -403.079184) (xy 78.953884 -403.134818) (xy 78.932024 -403.160484)
			(xy 78.926212 -403.167618) (xy 78.919706 -403.184817) (xy 78.919324 -403.194012) (xy 78.919324 -403.351492)
			(xy 78.918809 -403.361597) (xy 78.911078 -403.380271) (xy 78.896791 -403.394565) (xy 78.878121 -403.402304)
			(xy 78.868016 -403.4028) (xy 78.151736 -403.4028) (xy 78.141616 -403.402354) (xy 78.122913 -403.394618)
			(xy 78.108598 -403.38031) (xy 78.100851 -403.361612) (xy 78.100428 -403.351492) (xy 78.100428 -403.194012)
			(xy 78.100006 -403.184826) (xy 78.0935 -403.167642) (xy 78.087728 -403.160484) (xy 78.065816 -403.134858)
			(xy 78.027727 -403.079219) (xy 77.996577 -403.019417) (xy 77.972814 -402.956315) (xy 77.956781 -402.890821)
			(xy 77.948708 -402.823878) (xy 74.670664 -402.823878) (xy 74.662632 -402.890635) (xy 74.646664 -402.956014)
			(xy 74.622995 -403.019017) (xy 74.591966 -403.078739) (xy 74.554022 -403.134324) (xy 74.532236 -403.159976)
			(xy 74.526417 -403.167105) (xy 74.519917 -403.184308) (xy 74.519536 -403.193504) (xy 74.519536 -403.351492)
			(xy 74.519073 -403.361641) (xy 74.511286 -403.380386) (xy 74.496903 -403.394709) (xy 74.478125 -403.402415)
			(xy 74.467974 -403.4028) (xy 73.751694 -403.4028) (xy 73.741572 -403.402279) (xy 73.722858 -403.394557)
			(xy 73.708504 -403.380282) (xy 73.700678 -403.361611) (xy 73.700132 -403.351492) (xy 73.700132 -403.193504)
			(xy 73.699713 -403.184318) (xy 73.693205 -403.167134) (xy 73.687432 -403.159976) (xy 73.665597 -403.134363)
			(xy 73.62765 -403.07877) (xy 73.59662 -403.019041) (xy 73.57295 -402.956032) (xy 73.55698 -402.890645)
			(xy 73.54894 -402.823818) (xy 66.525648 -402.823818) (xy 66.525648 -405.623707) (xy 71.348811 -405.623707)
			(xy 71.348811 -405.556283) (xy 71.356888 -405.489345) (xy 71.372924 -405.423856) (xy 71.396688 -405.360759)
			(xy 71.427839 -405.300962) (xy 71.465928 -405.245327) (xy 71.487792 -405.219662) (xy 71.493586 -405.212515)
			(xy 71.500103 -405.195326) (xy 71.500492 -405.186134) (xy 71.500492 -404.693882) (xy 71.500092 -404.684694)
			(xy 71.493571 -404.667509) (xy 71.487792 -404.660354) (xy 71.46595 -404.634671) (xy 71.427861 -404.579039)
			(xy 71.39671 -404.519245) (xy 71.372945 -404.45615) (xy 71.356908 -404.390664) (xy 71.348831 -404.323727)
			(xy 71.348829 -404.256306) (xy 71.356902 -404.189369) (xy 71.372935 -404.123881) (xy 71.396696 -404.060785)
			(xy 71.427844 -404.00099) (xy 71.46593 -403.945355) (xy 71.487792 -403.91969) (xy 71.493574 -403.912535)
			(xy 71.500098 -403.895352) (xy 71.500492 -403.886162) (xy 71.500492 -403.728682) (xy 71.50101 -403.71856)
			(xy 71.508735 -403.699847) (xy 71.523011 -403.685493) (xy 71.541681 -403.677666) (xy 71.5518 -403.67712)
			(xy 72.26808 -403.67712) (xy 72.278235 -403.677538) (xy 72.296991 -403.685331) (xy 72.311316 -403.699729)
			(xy 72.319013 -403.718525) (xy 72.319388 -403.728682) (xy 72.319388 -403.886162) (xy 72.319819 -403.895347)
			(xy 72.326319 -403.912531) (xy 72.332088 -403.91969) (xy 72.353974 -403.945337) (xy 72.392063 -404.000974)
			(xy 72.423213 -404.060773) (xy 72.446977 -404.123872) (xy 72.463011 -404.189363) (xy 72.471085 -404.256304)
			(xy 72.471083 -404.323729) (xy 72.463005 -404.390669) (xy 72.446967 -404.45616) (xy 72.4232 -404.519258)
			(xy 72.392046 -404.579054) (xy 72.353954 -404.634689) (xy 72.332088 -404.660354) (xy 72.326285 -404.667494)
			(xy 72.319774 -404.684689) (xy 72.319388 -404.693882) (xy 72.319388 -405.186134) (xy 72.319784 -405.195323)
			(xy 72.326308 -405.212507) (xy 72.332088 -405.219662) (xy 72.353946 -405.245332) (xy 72.392036 -405.300965)
			(xy 72.423188 -405.360761) (xy 72.446953 -405.423857) (xy 72.462989 -405.489346) (xy 72.471066 -405.556284)
			(xy 72.471066 -405.623707) (xy 72.462991 -405.690645) (xy 72.446956 -405.756134) (xy 72.423191 -405.819231)
			(xy 72.392041 -405.879027) (xy 72.353952 -405.934661) (xy 72.332088 -405.960326) (xy 72.326297 -405.967475)
			(xy 72.319779 -405.984663) (xy 72.319388 -405.993854) (xy 72.319388 -406.151334) (xy 72.318902 -406.161459)
			(xy 72.311168 -406.180176) (xy 72.296883 -406.19453) (xy 72.278203 -406.202353) (xy 72.26808 -406.202896)
			(xy 71.5518 -406.202896) (xy 71.541645 -406.202478) (xy 71.522892 -406.194682) (xy 71.508569 -406.180284)
			(xy 71.50087 -406.161491) (xy 71.500492 -406.151334) (xy 71.500492 -405.993854) (xy 71.500058 -405.984669)
			(xy 71.493561 -405.967485) (xy 71.487792 -405.960326) (xy 71.465922 -405.934665) (xy 71.427834 -405.87903)
			(xy 71.396684 -405.819233) (xy 71.372921 -405.756136) (xy 71.356886 -405.690646) (xy 71.348811 -405.623707)
			(xy 66.525648 -405.623707) (xy 66.525648 -406.72373) (xy 73.548951 -406.72373) (xy 73.548954 -406.656422)
			(xy 73.557001 -406.589598) (xy 73.572978 -406.524214) (xy 73.596654 -406.461208) (xy 73.62769 -406.401483)
			(xy 73.665642 -406.345896) (xy 73.687432 -406.320244) (xy 73.693239 -406.313106) (xy 73.699747 -406.29591)
			(xy 73.700132 -406.286716) (xy 73.700132 -405.793448) (xy 73.699691 -405.784264) (xy 73.693198 -405.76708)
			(xy 73.687432 -405.75992) (xy 73.66564 -405.734271) (xy 73.627692 -405.678684) (xy 73.596659 -405.61896)
			(xy 73.572987 -405.555955) (xy 73.557015 -405.490572) (xy 73.548971 -405.42375) (xy 73.548971 -405.356444)
			(xy 73.557016 -405.289622) (xy 73.572989 -405.224239) (xy 73.596662 -405.161235) (xy 73.627695 -405.101511)
			(xy 73.665644 -405.045924) (xy 73.687432 -405.020272) (xy 73.693227 -405.013126) (xy 73.699742 -404.995936)
			(xy 73.700132 -404.986744) (xy 73.700132 -404.828756) (xy 73.700486 -404.818595) (xy 73.708302 -404.799836)
			(xy 73.72272 -404.785513) (xy 73.74153 -404.77782) (xy 73.751694 -404.777448) (xy 74.467974 -404.777448)
			(xy 74.4781 -404.777948) (xy 74.496822 -404.785669) (xy 74.51118 -404.799951) (xy 74.518998 -404.818633)
			(xy 74.519536 -404.828756) (xy 74.519536 -404.986744) (xy 74.519939 -404.995932) (xy 74.526459 -405.013115)
			(xy 74.532236 -405.020272) (xy 74.55402 -405.045927) (xy 74.591971 -405.101513) (xy 74.623006 -405.161235)
			(xy 74.64668 -405.22424) (xy 74.662654 -405.289622) (xy 74.670699 -405.356444) (xy 74.670699 -405.42375)
			(xy 74.662655 -405.490572) (xy 74.646682 -405.555955) (xy 74.623008 -405.618959) (xy 74.620571 -405.623649)
			(xy 75.749106 -405.623649) (xy 75.749107 -405.556342) (xy 75.757152 -405.489519) (xy 75.773127 -405.424136)
			(xy 75.796802 -405.361131) (xy 75.827839 -405.301407) (xy 75.865791 -405.245822) (xy 75.88758 -405.22017)
			(xy 75.893369 -405.21302) (xy 75.899889 -405.195833) (xy 75.90028 -405.186642) (xy 75.90028 -404.693374)
			(xy 75.899887 -404.684185) (xy 75.893362 -404.667001) (xy 75.88758 -404.659846) (xy 75.865813 -404.634177)
			(xy 75.827861 -404.578594) (xy 75.796824 -404.518873) (xy 75.773148 -404.45587) (xy 75.757173 -404.39049)
			(xy 75.749126 -404.323669) (xy 75.749124 -404.256365) (xy 75.757167 -404.189543) (xy 75.773138 -404.124161)
			(xy 75.796811 -404.061157) (xy 75.827844 -404.001435) (xy 75.865792 -403.94585) (xy 75.88758 -403.920198)
			(xy 75.893358 -403.913039) (xy 75.899884 -403.895859) (xy 75.90028 -403.88667) (xy 75.90028 -403.728682)
			(xy 75.90065 -403.718504) (xy 75.908449 -403.699701) (xy 75.922851 -403.685315) (xy 75.941664 -403.677538)
			(xy 75.951842 -403.67712) (xy 76.668122 -403.67712) (xy 76.678279 -403.677615) (xy 76.697045 -403.685393)
			(xy 76.711409 -403.699758) (xy 76.719186 -403.718525) (xy 76.719684 -403.728682) (xy 76.719684 -403.88667)
			(xy 76.720112 -403.895855) (xy 76.726614 -403.91304) (xy 76.732384 -403.920198) (xy 76.754193 -403.945833)
			(xy 76.792139 -404.001422) (xy 76.82317 -404.061148) (xy 76.846841 -404.124155) (xy 76.862812 -404.189539)
			(xy 76.870854 -404.256363) (xy 76.870852 -404.32367) (xy 76.862806 -404.390493) (xy 76.846831 -404.455877)
			(xy 76.823157 -404.518882) (xy 76.792122 -404.578606) (xy 76.754172 -404.634194) (xy 76.732384 -404.659846)
			(xy 76.726584 -404.666988) (xy 76.720072 -404.684181) (xy 76.719684 -404.693374) (xy 76.719684 -405.186642)
			(xy 76.720077 -405.195831) (xy 76.726603 -405.213015) (xy 76.732384 -405.22017) (xy 76.754165 -405.245827)
			(xy 76.792113 -405.301414) (xy 76.823145 -405.361137) (xy 76.846817 -405.42414) (xy 76.86279 -405.489522)
			(xy 76.870834 -405.556343) (xy 76.870835 -405.623648) (xy 76.862791 -405.690469) (xy 76.84682 -405.755851)
			(xy 76.823149 -405.818855) (xy 76.792117 -405.878579) (xy 76.754171 -405.934166) (xy 76.732384 -405.959818)
			(xy 76.726595 -405.966969) (xy 76.720077 -405.984155) (xy 76.719684 -405.993346) (xy 76.719684 -406.151334)
			(xy 76.719195 -406.161491) (xy 76.711414 -406.180257) (xy 76.697047 -406.19462) (xy 76.678279 -406.202397)
			(xy 76.668122 -406.202896) (xy 75.951842 -406.202896) (xy 75.941677 -406.202403) (xy 75.92289 -406.194638)
			(xy 75.908505 -406.180274) (xy 75.900712 -406.161498) (xy 75.90028 -406.151334) (xy 75.90028 -405.993346)
			(xy 75.899852 -405.984161) (xy 75.893351 -405.966976) (xy 75.88758 -405.959818) (xy 75.865785 -405.934171)
			(xy 75.827834 -405.878585) (xy 75.796799 -405.818861) (xy 75.773124 -405.755856) (xy 75.757151 -405.690472)
			(xy 75.749106 -405.623649) (xy 74.620571 -405.623649) (xy 74.591974 -405.678682) (xy 74.554024 -405.734268)
			(xy 74.532236 -405.75992) (xy 74.526441 -405.767066) (xy 74.519927 -405.784256) (xy 74.519536 -405.793448)
			(xy 74.519536 -406.286716) (xy 74.519953 -406.295902) (xy 74.526464 -406.313086) (xy 74.532236 -406.320244)
			(xy 74.553993 -406.345922) (xy 74.591944 -406.401504) (xy 74.62298 -406.461224) (xy 74.646656 -406.524225)
			(xy 74.662632 -406.589604) (xy 74.670679 -406.656424) (xy 74.670682 -406.723727) (xy 74.670675 -406.723789)
			(xy 77.94872 -406.723789) (xy 77.948723 -406.656363) (xy 77.956802 -406.589422) (xy 77.972842 -406.52393)
			(xy 77.996611 -406.460832) (xy 78.027767 -406.401035) (xy 78.065861 -406.345401) (xy 78.087728 -406.319736)
			(xy 78.093538 -406.3126) (xy 78.100044 -406.295402) (xy 78.100428 -406.286208) (xy 78.100428 -405.793956)
			(xy 78.100033 -405.784767) (xy 78.093508 -405.767584) (xy 78.087728 -405.760428) (xy 78.065859 -405.734766)
			(xy 78.027769 -405.679132) (xy 77.996617 -405.619336) (xy 77.972851 -405.556238) (xy 77.956815 -405.490748)
			(xy 77.948739 -405.423809) (xy 77.94874 -405.356385) (xy 77.956816 -405.289446) (xy 77.972853 -405.223956)
			(xy 77.996619 -405.160859) (xy 78.027772 -405.101063) (xy 78.065863 -405.045429) (xy 78.087728 -405.019764)
			(xy 78.093526 -405.01262) (xy 78.100039 -404.995428) (xy 78.100428 -404.986236) (xy 78.100428 -404.828756)
			(xy 78.10085 -404.818641) (xy 78.108607 -404.799956) (xy 78.122924 -404.785662) (xy 78.14162 -404.777934)
			(xy 78.151736 -404.777448) (xy 78.868016 -404.777448) (xy 78.878119 -404.777971) (xy 78.896788 -404.785704)
			(xy 78.91108 -404.799989) (xy 78.918823 -404.818653) (xy 78.919324 -404.828756) (xy 78.919324 -404.986236)
			(xy 78.919712 -404.995426) (xy 78.92624 -405.01261) (xy 78.932024 -405.019764) (xy 78.953883 -405.045433)
			(xy 78.99197 -405.101067) (xy 79.02312 -405.160863) (xy 79.046883 -405.22396) (xy 79.062918 -405.289448)
			(xy 79.070994 -405.356386) (xy 79.070995 -405.423808) (xy 79.062919 -405.490746) (xy 79.046885 -405.556235)
			(xy 79.023122 -405.619331) (xy 79.020843 -405.623707) (xy 80.148899 -405.623707) (xy 80.148899 -405.556284)
			(xy 80.156975 -405.489345) (xy 80.173011 -405.423856) (xy 80.196775 -405.360759) (xy 80.227925 -405.300963)
			(xy 80.266013 -405.245328) (xy 80.287876 -405.219662) (xy 80.293668 -405.212514) (xy 80.300186 -405.195326)
			(xy 80.300576 -405.186134) (xy 80.300576 -404.693882) (xy 80.30018 -404.684693) (xy 80.293657 -404.667509)
			(xy 80.287876 -404.660354) (xy 80.266034 -404.634671) (xy 80.227947 -404.579038) (xy 80.196796 -404.519244)
			(xy 80.173032 -404.45615) (xy 80.156996 -404.390663) (xy 80.148918 -404.323727) (xy 80.148917 -404.256306)
			(xy 80.15699 -404.189369) (xy 80.173022 -404.123882) (xy 80.196783 -404.060786) (xy 80.22793 -404.00099)
			(xy 80.266014 -403.945356) (xy 80.287876 -403.91969) (xy 80.293657 -403.912533) (xy 80.300182 -403.895352)
			(xy 80.300576 -403.886162) (xy 80.300576 -403.728682) (xy 80.301013 -403.71855) (xy 80.308753 -403.699821)
			(xy 80.323055 -403.685464) (xy 80.341754 -403.677652) (xy 80.351884 -403.67712) (xy 81.068164 -403.67712)
			(xy 81.078318 -403.677552) (xy 81.097074 -403.685339) (xy 81.111399 -403.699733) (xy 81.119096 -403.718526)
			(xy 81.119472 -403.728682) (xy 81.119472 -403.886162) (xy 81.119907 -403.895346) (xy 81.126404 -403.912531)
			(xy 81.132172 -403.91969) (xy 81.154059 -403.945337) (xy 81.192148 -404.000973) (xy 81.2233 -404.060772)
			(xy 81.247064 -404.123871) (xy 81.263099 -404.189363) (xy 81.271173 -404.256304) (xy 81.271171 -404.32373)
			(xy 81.263093 -404.39067) (xy 81.247054 -404.45616) (xy 81.223286 -404.519258) (xy 81.192131 -404.579055)
			(xy 81.154038 -404.634689) (xy 81.132172 -404.660354) (xy 81.126366 -404.667493) (xy 81.119858 -404.684688)
			(xy 81.119472 -404.693882) (xy 81.119472 -405.186134) (xy 81.119872 -405.195322) (xy 81.126393 -405.212506)
			(xy 81.132172 -405.219662) (xy 81.154031 -405.245332) (xy 81.192122 -405.300965) (xy 81.223274 -405.36076)
			(xy 81.24704 -405.423857) (xy 81.263077 -405.489345) (xy 81.271154 -405.556284) (xy 81.271154 -405.623707)
			(xy 81.263078 -405.690646) (xy 81.247043 -405.756135) (xy 81.223278 -405.819232) (xy 81.192126 -405.879027)
			(xy 81.154037 -405.934661) (xy 81.132172 -405.960326) (xy 81.126378 -405.967473) (xy 81.119862 -405.984662)
			(xy 81.119472 -405.993854) (xy 81.119472 -406.151334) (xy 81.119002 -406.161461) (xy 81.111265 -406.180181)
			(xy 81.096974 -406.194536) (xy 81.078289 -406.202356) (xy 81.068164 -406.202896) (xy 80.351884 -406.202896)
			(xy 80.341728 -406.202492) (xy 80.322975 -406.19469) (xy 80.308652 -406.180288) (xy 80.300953 -406.161492)
			(xy 80.300576 -406.151334) (xy 80.300576 -405.993854) (xy 80.300145 -405.984669) (xy 80.293646 -405.967484)
			(xy 80.287876 -405.960326) (xy 80.266007 -405.934665) (xy 80.22792 -405.879029) (xy 80.196771 -405.819232)
			(xy 80.173008 -405.756135) (xy 80.156974 -405.690646) (xy 80.148899 -405.623707) (xy 79.020843 -405.623707)
			(xy 78.991974 -405.679127) (xy 78.953887 -405.734762) (xy 78.932024 -405.760428) (xy 78.926236 -405.767579)
			(xy 78.919715 -405.784765) (xy 78.919324 -405.793956) (xy 78.919324 -406.286208) (xy 78.919725 -406.295396)
			(xy 78.926244 -406.312581) (xy 78.932024 -406.319736) (xy 78.953856 -406.345428) (xy 78.991944 -406.401059)
			(xy 79.023095 -406.460852) (xy 79.046859 -406.523945) (xy 79.062896 -406.589431) (xy 79.070974 -406.656366)
			(xy 79.070977 -406.72373) (xy 82.349039 -406.72373) (xy 82.349042 -406.656422) (xy 82.357089 -406.589598)
			(xy 82.373065 -406.524214) (xy 82.39674 -406.461209) (xy 82.427776 -406.401484) (xy 82.465727 -406.345896)
			(xy 82.487516 -406.320244) (xy 82.493321 -406.313105) (xy 82.49983 -406.29591) (xy 82.500216 -406.286716)
			(xy 82.500216 -405.793448) (xy 82.499779 -405.784264) (xy 82.493284 -405.767079) (xy 82.487516 -405.75992)
			(xy 82.465725 -405.734271) (xy 82.427778 -405.678683) (xy 82.396746 -405.618959) (xy 82.373074 -405.555954)
			(xy 82.357102 -405.490572) (xy 82.349059 -405.423749) (xy 82.349059 -405.356445) (xy 82.357103 -405.289622)
			(xy 82.373076 -405.22424) (xy 82.396748 -405.161235) (xy 82.427781 -405.101511) (xy 82.465729 -405.045924)
			(xy 82.487516 -405.020272) (xy 82.493309 -405.013124) (xy 82.499825 -404.995936) (xy 82.500216 -404.986744)
			(xy 82.500216 -404.828756) (xy 82.500586 -404.818597) (xy 82.508399 -404.799841) (xy 82.522811 -404.785518)
			(xy 82.541617 -404.777823) (xy 82.551778 -404.777448) (xy 83.268058 -404.777448) (xy 83.278183 -404.777961)
			(xy 83.296905 -404.785677) (xy 83.311263 -404.799955) (xy 83.319082 -404.818634) (xy 83.31962 -404.828756)
			(xy 83.31962 -404.986744) (xy 83.320004 -404.995934) (xy 83.326535 -405.013118) (xy 83.33232 -405.020272)
			(xy 83.354105 -405.045927) (xy 83.392057 -405.101512) (xy 83.423092 -405.161235) (xy 83.446767 -405.224239)
			(xy 83.462742 -405.289621) (xy 83.470787 -405.356444) (xy 83.470787 -405.42375) (xy 83.462743 -405.490573)
			(xy 83.446769 -405.555955) (xy 83.423095 -405.61896) (xy 83.420628 -405.623707) (xy 84.54869 -405.623707)
			(xy 84.54869 -405.556284) (xy 84.556766 -405.489346) (xy 84.572801 -405.423857) (xy 84.596564 -405.36076)
			(xy 84.627714 -405.300963) (xy 84.665801 -405.245328) (xy 84.687664 -405.219662) (xy 84.693467 -405.212522)
			(xy 84.699976 -405.195327) (xy 84.700364 -405.186134) (xy 84.700364 -404.693882) (xy 84.699948 -404.684696)
			(xy 84.693437 -404.667512) (xy 84.687664 -404.660354) (xy 84.665823 -404.63467) (xy 84.627736 -404.579038)
			(xy 84.596586 -404.519244) (xy 84.572822 -404.456149) (xy 84.556787 -404.390663) (xy 84.548709 -404.323727)
			(xy 84.548707 -404.256306) (xy 84.556781 -404.18937) (xy 84.572813 -404.123882) (xy 84.596573 -404.060787)
			(xy 84.627719 -404.000991) (xy 84.665803 -403.945356) (xy 84.687664 -403.91969) (xy 84.693455 -403.912541)
			(xy 84.699971 -403.895353) (xy 84.700364 -403.886162) (xy 84.700364 -403.728682) (xy 84.700812 -403.718551)
			(xy 84.70855 -403.699825) (xy 84.722849 -403.685468) (xy 84.741543 -403.677654) (xy 84.751672 -403.67712)
			(xy 85.467952 -403.67712) (xy 85.478105 -403.677561) (xy 85.496861 -403.685345) (xy 85.511186 -403.699736)
			(xy 85.518884 -403.718527) (xy 85.51926 -403.728682) (xy 85.51926 -403.886162) (xy 85.519698 -403.895346)
			(xy 85.526193 -403.91253) (xy 85.53196 -403.91969) (xy 85.553847 -403.945337) (xy 85.591938 -404.000973)
			(xy 85.62309 -404.060771) (xy 85.646854 -404.123871) (xy 85.66289 -404.189362) (xy 85.670964 -404.256303)
			(xy 85.670962 -404.32373) (xy 85.662884 -404.39067) (xy 85.646845 -404.456161) (xy 85.623076 -404.519259)
			(xy 85.591921 -404.579055) (xy 85.553827 -404.634689) (xy 85.53196 -404.660354) (xy 85.526153 -404.667492)
			(xy 85.519646 -404.684688) (xy 85.51926 -404.693882) (xy 85.51926 -405.186134) (xy 85.519663 -405.195322)
			(xy 85.526183 -405.212506) (xy 85.53196 -405.219662) (xy 85.553819 -405.245331) (xy 85.591911 -405.300964)
			(xy 85.623064 -405.36076) (xy 85.64683 -405.423856) (xy 85.662868 -405.489345) (xy 85.670945 -405.556284)
			(xy 85.670945 -405.623707) (xy 85.662869 -405.690646) (xy 85.646833 -405.756135) (xy 85.623068 -405.819232)
			(xy 85.591916 -405.879028) (xy 85.553825 -405.934661) (xy 85.53196 -405.960326) (xy 85.526165 -405.967472)
			(xy 85.51965 -405.984662) (xy 85.51926 -405.993854) (xy 85.51926 -406.151334) (xy 85.518801 -406.161463)
			(xy 85.511062 -406.180185) (xy 85.496768 -406.19454) (xy 85.478079 -406.202358) (xy 85.467952 -406.202896)
			(xy 84.751672 -406.202896) (xy 84.741516 -406.202501) (xy 84.722762 -406.194696) (xy 84.708439 -406.180291)
			(xy 84.700741 -406.161493) (xy 84.700364 -406.151334) (xy 84.700364 -405.993854) (xy 84.699914 -405.984671)
			(xy 84.693426 -405.967487) (xy 84.687664 -405.960326) (xy 84.665795 -405.934665) (xy 84.627709 -405.879029)
			(xy 84.596561 -405.819232) (xy 84.572799 -405.756135) (xy 84.556765 -405.690645) (xy 84.54869 -405.623707)
			(xy 83.420628 -405.623707) (xy 83.39206 -405.678683) (xy 83.354109 -405.734268) (xy 83.33232 -405.75992)
			(xy 83.326535 -405.767073) (xy 83.320013 -405.784258) (xy 83.31962 -405.793448) (xy 83.31962 -406.286716)
			(xy 83.320018 -406.295905) (xy 83.32654 -406.313089) (xy 83.33232 -406.320244) (xy 83.354077 -406.345921)
			(xy 83.39203 -406.401503) (xy 83.423067 -406.461223) (xy 83.446743 -406.524224) (xy 83.46272 -406.589604)
			(xy 83.470767 -406.656424) (xy 83.47077 -406.723728) (xy 83.470763 -406.723789) (xy 86.748808 -406.723789)
			(xy 86.748811 -406.656363) (xy 86.75689 -406.589422) (xy 86.772929 -406.523931) (xy 86.796697 -406.460833)
			(xy 86.827852 -406.401036) (xy 86.865946 -406.345401) (xy 86.887812 -406.319736) (xy 86.89362 -406.312599)
			(xy 86.900127 -406.295402) (xy 86.900512 -406.286208) (xy 86.900512 -405.793956) (xy 86.90012 -405.784767)
			(xy 86.893594 -405.767583) (xy 86.887812 -405.760428) (xy 86.865944 -405.734766) (xy 86.827854 -405.679131)
			(xy 86.796703 -405.619335) (xy 86.772939 -405.556238) (xy 86.756903 -405.490748) (xy 86.748827 -405.423809)
			(xy 86.748828 -405.356385) (xy 86.756904 -405.289446) (xy 86.77294 -405.223957) (xy 86.796706 -405.16086)
			(xy 86.827857 -405.101063) (xy 86.865947 -405.045429) (xy 86.887812 -405.019764) (xy 86.893608 -405.012618)
			(xy 86.900123 -404.995428) (xy 86.900512 -404.986236) (xy 86.900512 -404.828756) (xy 86.900949 -404.818643)
			(xy 86.908704 -404.799961) (xy 86.923015 -404.785668) (xy 86.941706 -404.777937) (xy 86.95182 -404.777448)
			(xy 87.6681 -404.777448) (xy 87.678202 -404.777984) (xy 87.696871 -404.785712) (xy 87.711163 -404.799993)
			(xy 87.718907 -404.818654) (xy 87.719408 -404.828756) (xy 87.719408 -404.986236) (xy 87.719799 -404.995425)
			(xy 87.726326 -405.01261) (xy 87.732108 -405.019764) (xy 87.753968 -405.045433) (xy 87.792056 -405.101067)
			(xy 87.823206 -405.160863) (xy 87.846971 -405.223959) (xy 87.863006 -405.289448) (xy 87.871082 -405.356385)
			(xy 87.871082 -405.423809) (xy 87.863007 -405.490746) (xy 87.846972 -405.556235) (xy 87.823209 -405.619332)
			(xy 87.792059 -405.679128) (xy 87.753971 -405.734763) (xy 87.732108 -405.760428) (xy 87.726318 -405.767578)
			(xy 87.719799 -405.784765) (xy 87.719408 -405.793956) (xy 87.719408 -406.286208) (xy 87.719813 -406.295396)
			(xy 87.72633 -406.31258) (xy 87.732108 -406.319736) (xy 87.75394 -406.345427) (xy 87.792029 -406.401058)
			(xy 87.823181 -406.460851) (xy 87.846947 -406.523944) (xy 87.862984 -406.58943) (xy 87.871062 -406.656365)
			(xy 87.871065 -406.723729) (xy 91.149127 -406.723729) (xy 91.14913 -406.656423) (xy 91.157177 -406.589598)
			(xy 91.173152 -406.524215) (xy 91.196827 -406.461209) (xy 91.227861 -406.401484) (xy 91.265812 -406.345897)
			(xy 91.2876 -406.320244) (xy 91.293403 -406.313103) (xy 91.299914 -406.295909) (xy 91.3003 -406.286716)
			(xy 91.3003 -405.793448) (xy 91.299867 -405.784263) (xy 91.293369 -405.767079) (xy 91.2876 -405.75992)
			(xy 91.26581 -405.734271) (xy 91.227863 -405.678683) (xy 91.196832 -405.618958) (xy 91.173162 -405.555954)
			(xy 91.15719 -405.490572) (xy 91.149147 -405.423749) (xy 91.149147 -405.356445) (xy 91.157191 -405.289622)
			(xy 91.173163 -405.224241) (xy 91.196835 -405.161236) (xy 91.227866 -405.101512) (xy 91.265813 -405.045925)
			(xy 91.2876 -405.020272) (xy 91.293391 -405.013123) (xy 91.299909 -404.995935) (xy 91.3003 -404.986744)
			(xy 91.3003 -404.828756) (xy 91.300686 -404.818599) (xy 91.308496 -404.799846) (xy 91.322903 -404.785524)
			(xy 91.341703 -404.777826) (xy 91.351862 -404.777448) (xy 92.068142 -404.777448) (xy 92.078272 -404.777892)
			(xy 92.096996 -404.785635) (xy 92.111351 -404.799934) (xy 92.119167 -404.818628) (xy 92.119704 -404.828756)
			(xy 92.119704 -404.986744) (xy 92.120092 -404.995934) (xy 92.126621 -405.013118) (xy 92.132404 -405.020272)
			(xy 92.154186 -405.045928) (xy 92.192133 -405.101515) (xy 92.223164 -405.161238) (xy 92.246835 -405.224242)
			(xy 92.262807 -405.289624) (xy 92.270851 -405.356445) (xy 92.270851 -405.423749) (xy 92.262808 -405.490571)
			(xy 92.246837 -405.555952) (xy 92.223166 -405.618956) (xy 92.192136 -405.67868) (xy 92.15419 -405.734267)
			(xy 92.132404 -405.75992) (xy 92.126617 -405.767072) (xy 92.120096 -405.784257) (xy 92.119704 -405.793448)
			(xy 92.119704 -406.286716) (xy 92.120106 -406.295904) (xy 92.126625 -406.313088) (xy 92.132404 -406.320244)
			(xy 92.154159 -406.345923) (xy 92.192106 -406.401506) (xy 92.223138 -406.461227) (xy 92.246811 -406.524228)
			(xy 92.262785 -406.589606) (xy 92.270831 -406.656425) (xy 92.270834 -406.723727) (xy 92.262793 -406.790546)
			(xy 92.246825 -406.855926) (xy 92.223158 -406.918929) (xy 92.192131 -406.978652) (xy 92.154188 -407.034239)
			(xy 92.132404 -407.059892) (xy 92.126629 -407.067052) (xy 92.120101 -407.084231) (xy 92.119704 -407.09342)
			(xy 92.119704 -407.251408) (xy 92.119285 -407.261562) (xy 92.111487 -407.280314) (xy 92.09709 -407.294637)
			(xy 92.078298 -407.302337) (xy 92.068142 -407.302716) (xy 91.351862 -407.302716) (xy 91.341727 -407.302303)
			(xy 91.322997 -407.294555) (xy 91.308641 -407.280246) (xy 91.30083 -407.261541) (xy 91.3003 -407.251408)
			(xy 91.3003 -407.09342) (xy 91.29988 -407.084234) (xy 91.293373 -407.067049) (xy 91.2876 -407.059892)
			(xy 91.265782 -407.034265) (xy 91.227837 -406.978674) (xy 91.196807 -406.918947) (xy 91.173138 -406.855939)
			(xy 91.157168 -406.790554) (xy 91.149127 -406.723729) (xy 87.871065 -406.723729) (xy 87.871065 -406.723786)
			(xy 87.862993 -406.790722) (xy 87.846961 -406.85621) (xy 87.823201 -406.919305) (xy 87.792054 -406.9791)
			(xy 87.75397 -407.034735) (xy 87.732108 -407.0604) (xy 87.72633 -407.067558) (xy 87.719804 -407.084739)
			(xy 87.719408 -407.093928) (xy 87.719408 -407.251408) (xy 87.718921 -407.261516) (xy 87.711183 -407.280193)
			(xy 87.696886 -407.294487) (xy 87.678208 -407.302223) (xy 87.6681 -407.302716) (xy 86.95182 -407.302716)
			(xy 86.941701 -407.302268) (xy 86.923001 -407.29453) (xy 86.908686 -407.280223) (xy 86.900937 -407.261527)
			(xy 86.900512 -407.251408) (xy 86.900512 -407.093928) (xy 86.900086 -407.084743) (xy 86.893583 -407.067558)
			(xy 86.887812 -407.0604) (xy 86.865916 -407.034761) (xy 86.827828 -406.979123) (xy 86.796678 -406.919323)
			(xy 86.772915 -406.856223) (xy 86.756881 -406.790731) (xy 86.748808 -406.723789) (xy 83.470763 -406.723789)
			(xy 83.462728 -406.790549) (xy 83.446757 -406.85593) (xy 83.423086 -406.918933) (xy 83.392055 -406.978655)
			(xy 83.354107 -407.03424) (xy 83.33232 -407.059892) (xy 83.326547 -407.067054) (xy 83.320017 -407.084231)
			(xy 83.31962 -407.09342) (xy 83.31962 -407.251408) (xy 83.319185 -407.26156) (xy 83.311391 -407.280309)
			(xy 83.296998 -407.294631) (xy 83.278212 -407.302334) (xy 83.268058 -407.302716) (xy 82.551778 -407.302716)
			(xy 82.541644 -407.30229) (xy 82.522914 -407.294547) (xy 82.508557 -407.280242) (xy 82.500747 -407.26154)
			(xy 82.500216 -407.251408) (xy 82.500216 -407.09342) (xy 82.499792 -407.084234) (xy 82.493288 -407.06705)
			(xy 82.487516 -407.059892) (xy 82.465698 -407.034265) (xy 82.427751 -406.978675) (xy 82.396721 -406.918947)
			(xy 82.373051 -406.85594) (xy 82.35708 -406.790555) (xy 82.349039 -406.72373) (xy 79.070977 -406.72373)
			(xy 79.070977 -406.723786) (xy 79.062905 -406.790722) (xy 79.046874 -406.856209) (xy 79.023114 -406.919304)
			(xy 78.991969 -406.9791) (xy 78.953885 -407.034734) (xy 78.932024 -407.0604) (xy 78.926248 -407.06756)
			(xy 78.91972 -407.084739) (xy 78.919324 -407.093928) (xy 78.919324 -407.251408) (xy 78.918822 -407.261514)
			(xy 78.911086 -407.280188) (xy 78.896795 -407.294482) (xy 78.878122 -407.30222) (xy 78.868016 -407.302716)
			(xy 78.151736 -407.302716) (xy 78.141618 -407.302255) (xy 78.122918 -407.294521) (xy 78.108603 -407.280219)
			(xy 78.100854 -407.261526) (xy 78.100428 -407.251408) (xy 78.100428 -407.093928) (xy 78.099998 -407.084743)
			(xy 78.093497 -407.067559) (xy 78.087728 -407.0604) (xy 78.065832 -407.034761) (xy 78.027742 -406.979124)
			(xy 77.996591 -406.919324) (xy 77.972828 -406.856224) (xy 77.956793 -406.790731) (xy 77.94872 -406.723789)
			(xy 74.670675 -406.723789) (xy 74.662641 -406.790548) (xy 74.64667 -406.855929) (xy 74.623 -406.918932)
			(xy 74.591969 -406.978655) (xy 74.554022 -407.03424) (xy 74.532236 -407.059892) (xy 74.526453 -407.067046)
			(xy 74.519932 -407.08423) (xy 74.519536 -407.09342) (xy 74.519536 -407.251408) (xy 74.519085 -407.261558)
			(xy 74.511294 -407.280304) (xy 74.496907 -407.294625) (xy 74.478126 -407.302331) (xy 74.467974 -407.302716)
			(xy 73.751694 -407.302716) (xy 73.741562 -407.302277) (xy 73.722832 -407.294539) (xy 73.708474 -407.280238)
			(xy 73.700663 -407.261538) (xy 73.700132 -407.251408) (xy 73.700132 -407.09342) (xy 73.699705 -407.084235)
			(xy 73.693202 -407.067051) (xy 73.687432 -407.059892) (xy 73.665613 -407.034266) (xy 73.627666 -406.978675)
			(xy 73.596634 -406.918948) (xy 73.572963 -406.85594) (xy 73.556993 -406.790555) (xy 73.548951 -406.72373)
			(xy 66.525648 -406.72373) (xy 66.525648 -409.523886) (xy 71.34879 -409.523886) (xy 71.348793 -409.45646)
			(xy 71.356872 -409.389519) (xy 71.372911 -409.324028) (xy 71.396679 -409.26093) (xy 71.427834 -409.201133)
			(xy 71.465926 -409.145497) (xy 71.487792 -409.119832) (xy 71.493599 -409.112694) (xy 71.500108 -409.095498)
			(xy 71.500492 -409.086304) (xy 71.500492 -408.594052) (xy 71.500059 -408.584867) (xy 71.493561 -408.567682)
			(xy 71.487792 -408.560524) (xy 71.46592 -408.534865) (xy 71.427833 -408.479229) (xy 71.396683 -408.419432)
			(xy 71.372919 -408.356335) (xy 71.356885 -408.290845) (xy 71.348809 -408.223906) (xy 71.34881 -408.156482)
			(xy 71.356887 -408.089543) (xy 71.372923 -408.024054) (xy 71.396688 -407.960957) (xy 71.427839 -407.90116)
			(xy 71.465928 -407.845525) (xy 71.487792 -407.81986) (xy 71.493587 -407.812714) (xy 71.500103 -407.795524)
			(xy 71.500492 -407.786332) (xy 71.500492 -407.628852) (xy 71.500946 -407.618741) (xy 71.508698 -407.600063)
			(xy 71.523004 -407.585771) (xy 71.541689 -407.578036) (xy 71.5518 -407.577544) (xy 72.26808 -407.577544)
			(xy 72.278181 -407.5781) (xy 72.296848 -407.585821) (xy 72.311141 -407.600095) (xy 72.318887 -407.618752)
			(xy 72.319388 -407.628852) (xy 72.319388 -407.786332) (xy 72.319785 -407.795521) (xy 72.326308 -407.812705)
			(xy 72.332088 -407.81986) (xy 72.353945 -407.845532) (xy 72.392034 -407.901165) (xy 72.423186 -407.96096)
			(xy 72.446951 -408.024056) (xy 72.462988 -408.089545) (xy 72.471064 -408.156482) (xy 72.471065 -408.223906)
			(xy 72.46299 -408.290844) (xy 72.446955 -408.356332) (xy 72.423191 -408.419429) (xy 72.39204 -408.479225)
			(xy 72.353952 -408.534859) (xy 72.332088 -408.560524) (xy 72.326297 -408.567673) (xy 72.31978 -408.584861)
			(xy 72.319388 -408.594052) (xy 72.319388 -409.086304) (xy 72.319799 -409.095491) (xy 72.326313 -409.112675)
			(xy 72.332088 -409.119832) (xy 72.353917 -409.145526) (xy 72.392008 -409.201156) (xy 72.423161 -409.260948)
			(xy 72.446927 -409.324042) (xy 72.462966 -409.389527) (xy 72.471045 -409.456462) (xy 72.471048 -409.523884)
			(xy 72.462975 -409.59082) (xy 72.446943 -409.656307) (xy 72.423183 -409.719402) (xy 72.392035 -409.779197)
			(xy 72.35395 -409.834831) (xy 72.332088 -409.860496) (xy 72.326309 -409.867654) (xy 72.319784 -409.884835)
			(xy 72.319388 -409.894024) (xy 72.319388 -410.051504) (xy 72.318987 -410.061628) (xy 72.311235 -410.080334)
			(xy 72.296914 -410.094649) (xy 72.278204 -410.102392) (xy 72.26808 -410.102812) (xy 71.5518 -410.102812)
			(xy 71.541693 -410.102315) (xy 71.523017 -410.09458) (xy 71.508723 -410.080286) (xy 71.500986 -410.061611)
			(xy 71.500492 -410.051504) (xy 71.500492 -409.894024) (xy 71.500072 -409.884838) (xy 71.493565 -409.867653)
			(xy 71.487792 -409.860496) (xy 71.465893 -409.83486) (xy 71.427806 -409.779221) (xy 71.396657 -409.719421)
			(xy 71.372895 -409.65632) (xy 71.356863 -409.590827) (xy 71.34879 -409.523886) (xy 66.525648 -409.523886)
			(xy 66.525648 -410.623641) (xy 73.548963 -410.623641) (xy 73.548964 -410.556335) (xy 73.55701 -410.489511)
			(xy 73.572984 -410.424128) (xy 73.596658 -410.361123) (xy 73.627693 -410.301399) (xy 73.665643 -410.245812)
			(xy 73.687432 -410.22016) (xy 73.693232 -410.213017) (xy 73.699744 -410.195825) (xy 73.700132 -410.186632)
			(xy 73.700132 -409.693364) (xy 73.699732 -409.684176) (xy 73.69321 -409.666992) (xy 73.687432 -409.659836)
			(xy 73.665656 -409.634174) (xy 73.627707 -409.578589) (xy 73.596674 -409.518867) (xy 73.573001 -409.455863)
			(xy 73.557027 -409.390482) (xy 73.548982 -409.323661) (xy 73.548981 -409.256357) (xy 73.557024 -409.189535)
			(xy 73.572995 -409.124154) (xy 73.596667 -409.06115) (xy 73.627698 -409.001427) (xy 73.665645 -408.94584)
			(xy 73.687432 -408.920188) (xy 73.69322 -408.913037) (xy 73.699739 -408.895851) (xy 73.700132 -408.88666)
			(xy 73.700132 -408.728672) (xy 73.700499 -408.718512) (xy 73.70831 -408.699753) (xy 73.722724 -408.685429)
			(xy 73.741532 -408.677736) (xy 73.751694 -408.677364) (xy 74.467974 -408.677364) (xy 74.478102 -408.677848)
			(xy 74.496827 -408.685572) (xy 74.511185 -408.69986) (xy 74.519001 -408.718546) (xy 74.519536 -408.728672)
			(xy 74.519536 -408.88666) (xy 74.51998 -408.895843) (xy 74.526472 -408.913027) (xy 74.532236 -408.920188)
			(xy 74.554036 -408.94583) (xy 74.591986 -409.001418) (xy 74.62302 -409.061142) (xy 74.646694 -409.124148)
			(xy 74.662666 -409.189532) (xy 74.67071 -409.256356) (xy 74.670709 -409.323662) (xy 74.662663 -409.390486)
			(xy 74.646688 -409.455869) (xy 74.623013 -409.518874) (xy 74.620439 -409.523827) (xy 75.749085 -409.523827)
			(xy 75.749088 -409.456519) (xy 75.757137 -409.389693) (xy 75.773115 -409.324308) (xy 75.796793 -409.261302)
			(xy 75.827833 -409.201578) (xy 75.865789 -409.145992) (xy 75.88758 -409.12034) (xy 75.893382 -409.113199)
			(xy 75.899894 -409.096005) (xy 75.90028 -409.086812) (xy 75.90028 -408.593544) (xy 75.899853 -408.584358)
			(xy 75.893352 -408.567174) (xy 75.88758 -408.560016) (xy 75.865783 -408.534371) (xy 75.827832 -408.478784)
			(xy 75.796797 -408.41906) (xy 75.773123 -408.356055) (xy 75.757149 -408.290671) (xy 75.749105 -408.223847)
			(xy 75.749106 -408.156541) (xy 75.757151 -408.089717) (xy 75.773126 -408.024334) (xy 75.796802 -407.961329)
			(xy 75.827838 -407.901605) (xy 75.865791 -407.84602) (xy 75.88758 -407.820368) (xy 75.89337 -407.813218)
			(xy 75.899889 -407.796031) (xy 75.90028 -407.78684) (xy 75.90028 -407.628852) (xy 75.900682 -407.618697)
			(xy 75.90849 -407.599948) (xy 75.922892 -407.585627) (xy 75.941685 -407.577925) (xy 75.951842 -407.577544)
			(xy 76.668122 -407.577544) (xy 76.678251 -407.578008) (xy 76.696973 -407.585744) (xy 76.711329 -407.600037)
			(xy 76.719147 -407.618726) (xy 76.719684 -407.628852) (xy 76.719684 -407.78684) (xy 76.720078 -407.796029)
			(xy 76.726603 -407.813213) (xy 76.732384 -407.820368) (xy 76.754163 -407.846027) (xy 76.792111 -407.901613)
			(xy 76.823143 -407.961336) (xy 76.846815 -408.024339) (xy 76.862788 -408.08972) (xy 76.870833 -408.156542)
			(xy 76.870833 -408.223846) (xy 76.86279 -408.290668) (xy 76.846819 -408.356049) (xy 76.823148 -408.419053)
			(xy 76.792117 -408.478777) (xy 76.754171 -408.534364) (xy 76.732384 -408.560016) (xy 76.726596 -408.567167)
			(xy 76.720077 -408.584353) (xy 76.719684 -408.593544) (xy 76.719684 -409.086812) (xy 76.720092 -409.095999)
			(xy 76.726607 -409.113184) (xy 76.732384 -409.12034) (xy 76.754135 -409.146022) (xy 76.792084 -409.201605)
			(xy 76.823117 -409.261324) (xy 76.846791 -409.324325) (xy 76.862766 -409.389703) (xy 76.870812 -409.456522)
			(xy 76.870816 -409.523824) (xy 76.862775 -409.590644) (xy 76.846807 -409.656023) (xy 76.823139 -409.719026)
			(xy 76.792112 -409.778749) (xy 76.754169 -409.834335) (xy 76.732384 -409.859988) (xy 76.726566 -409.867118)
			(xy 76.720065 -409.88432) (xy 76.719684 -409.893516) (xy 76.719684 -410.051504) (xy 76.719281 -410.06166)
			(xy 76.711481 -410.080416) (xy 76.697079 -410.09474) (xy 76.678281 -410.102436) (xy 76.668122 -410.102812)
			(xy 75.951842 -410.102812) (xy 75.941724 -410.10224) (xy 75.923014 -410.094536) (xy 75.908658 -410.080276)
			(xy 75.900828 -410.061618) (xy 75.90028 -410.051504) (xy 75.90028 -409.893516) (xy 75.899867 -409.884329)
			(xy 75.893356 -409.867144) (xy 75.88758 -409.859988) (xy 75.865756 -409.834365) (xy 75.827805 -409.778776)
			(xy 75.796771 -409.719048) (xy 75.773099 -409.65604) (xy 75.757127 -409.590654) (xy 75.749085 -409.523827)
			(xy 74.620439 -409.523827) (xy 74.591977 -409.578598) (xy 74.554025 -409.634184) (xy 74.532236 -409.659836)
			(xy 74.526434 -409.666977) (xy 74.519924 -409.684171) (xy 74.519536 -409.693364) (xy 74.519536 -410.186632)
			(xy 74.519945 -410.195819) (xy 74.526461 -410.213002) (xy 74.532236 -410.22016) (xy 74.554009 -410.245825)
			(xy 74.59196 -410.301409) (xy 74.622995 -410.36113) (xy 74.64667 -410.424133) (xy 74.662644 -410.489514)
			(xy 74.67069 -410.556336) (xy 74.670692 -410.62364) (xy 74.670685 -410.623701) (xy 77.948731 -410.623701)
			(xy 77.948732 -410.556275) (xy 77.95681 -410.489335) (xy 77.972848 -410.423845) (xy 77.996615 -410.360747)
			(xy 78.02777 -410.300951) (xy 78.065862 -410.245317) (xy 78.087728 -410.219652) (xy 78.093531 -410.212512)
			(xy 78.100041 -410.195317) (xy 78.100428 -410.186124) (xy 78.100428 -409.693872) (xy 78.100025 -409.684684)
			(xy 78.093506 -409.6675) (xy 78.087728 -409.660344) (xy 78.065875 -409.63467) (xy 78.027784 -409.579037)
			(xy 77.996631 -409.519242) (xy 77.972865 -409.456147) (xy 77.956828 -409.390658) (xy 77.948751 -409.323721)
			(xy 77.94875 -409.256297) (xy 77.956825 -409.189359) (xy 77.97286 -409.123871) (xy 77.996624 -409.060774)
			(xy 78.027775 -409.000979) (xy 78.065864 -408.945345) (xy 78.087728 -408.91968) (xy 78.093519 -408.912531)
			(xy 78.100036 -408.895343) (xy 78.100428 -408.886152) (xy 78.100428 -408.728672) (xy 78.100794 -408.718544)
			(xy 78.108556 -408.699835) (xy 78.122888 -408.68552) (xy 78.141608 -408.677781) (xy 78.151736 -408.677364)
			(xy 78.868016 -408.677364) (xy 78.878121 -408.677871) (xy 78.896793 -408.685608) (xy 78.911086 -408.699897)
			(xy 78.918826 -408.718567) (xy 78.919324 -408.728672) (xy 78.919324 -408.886152) (xy 78.919752 -408.895337)
			(xy 78.926253 -408.912522) (xy 78.932024 -408.91968) (xy 78.953899 -408.945336) (xy 78.991986 -409.000972)
			(xy 79.023135 -409.06077) (xy 79.046897 -409.123868) (xy 79.062931 -409.189358) (xy 79.071005 -409.256297)
			(xy 79.071004 -409.323721) (xy 79.062928 -409.39066) (xy 79.046892 -409.456149) (xy 79.023127 -409.519246)
			(xy 79.02071 -409.523886) (xy 80.148878 -409.523886) (xy 80.148881 -409.45646) (xy 80.15696 -409.38952)
			(xy 80.172999 -409.324029) (xy 80.196766 -409.260931) (xy 80.227919 -409.201133) (xy 80.266011 -409.145498)
			(xy 80.287876 -409.119832) (xy 80.293681 -409.112693) (xy 80.300191 -409.095498) (xy 80.300576 -409.086304)
			(xy 80.300576 -408.594052) (xy 80.300146 -408.584867) (xy 80.293647 -408.567682) (xy 80.287876 -408.560524)
			(xy 80.266005 -408.534865) (xy 80.227918 -408.479229) (xy 80.196769 -408.419432) (xy 80.173006 -408.356334)
			(xy 80.156972 -408.290844) (xy 80.148897 -408.223906) (xy 80.148898 -408.156482) (xy 80.156974 -408.089544)
			(xy 80.17301 -408.024055) (xy 80.196774 -407.960957) (xy 80.227924 -407.901161) (xy 80.266012 -407.845526)
			(xy 80.287876 -407.81986) (xy 80.293669 -407.812712) (xy 80.300187 -407.795524) (xy 80.300576 -407.786332)
			(xy 80.300576 -407.628852) (xy 80.301045 -407.618743) (xy 80.308794 -407.600069) (xy 80.323095 -407.585776)
			(xy 80.341775 -407.578039) (xy 80.351884 -407.577544) (xy 81.068164 -407.577544) (xy 81.078264 -407.578113)
			(xy 81.09693 -407.585829) (xy 81.111224 -407.600099) (xy 81.11897 -407.618753) (xy 81.119472 -407.628852)
			(xy 81.119472 -407.786332) (xy 81.119873 -407.79552) (xy 81.126394 -407.812704) (xy 81.132172 -407.81986)
			(xy 81.154029 -407.845531) (xy 81.19212 -407.901164) (xy 81.223273 -407.960959) (xy 81.247038 -408.024056)
			(xy 81.263075 -408.089544) (xy 81.271152 -408.156482) (xy 81.271153 -408.223906) (xy 81.263077 -408.290844)
			(xy 81.247042 -408.356333) (xy 81.223277 -408.41943) (xy 81.192126 -408.479225) (xy 81.154036 -408.534859)
			(xy 81.132172 -408.560524) (xy 81.126379 -408.567672) (xy 81.119863 -408.58486) (xy 81.119472 -408.594052)
			(xy 81.119472 -409.086304) (xy 81.119886 -409.095491) (xy 81.126398 -409.112675) (xy 81.132172 -409.119832)
			(xy 81.154002 -409.145526) (xy 81.192093 -409.201156) (xy 81.223247 -409.260948) (xy 81.247014 -409.324041)
			(xy 81.263053 -409.389527) (xy 81.271132 -409.456462) (xy 81.271136 -409.523884) (xy 81.263063 -409.59082)
			(xy 81.247031 -409.656307) (xy 81.223269 -409.719403) (xy 81.192121 -409.779198) (xy 81.154035 -409.834831)
			(xy 81.132172 -409.860496) (xy 81.126391 -409.867652) (xy 81.119868 -409.884834) (xy 81.119472 -409.894024)
			(xy 81.119472 -410.051504) (xy 81.119086 -410.06163) (xy 81.111332 -410.080339) (xy 81.097006 -410.094654)
			(xy 81.078291 -410.102394) (xy 81.068164 -410.102812) (xy 80.351884 -410.102812) (xy 80.341776 -410.102328)
			(xy 80.3231 -410.094587) (xy 80.308806 -410.08029) (xy 80.30107 -410.061612) (xy 80.300576 -410.051504)
			(xy 80.300576 -409.894024) (xy 80.30016 -409.884837) (xy 80.293651 -409.867653) (xy 80.287876 -409.860496)
			(xy 80.265978 -409.83486) (xy 80.227891 -409.77922) (xy 80.196744 -409.71942) (xy 80.172983 -409.656319)
			(xy 80.15695 -409.590827) (xy 80.148878 -409.523886) (xy 79.02071 -409.523886) (xy 78.991976 -409.579043)
			(xy 78.953888 -409.634678) (xy 78.932024 -409.660344) (xy 78.926229 -409.667491) (xy 78.919713 -409.68468)
			(xy 78.919324 -409.693872) (xy 78.919324 -410.186124) (xy 78.919717 -410.195313) (xy 78.926242 -410.212497)
			(xy 78.932024 -410.219652) (xy 78.953871 -410.245331) (xy 78.991959 -410.300964) (xy 79.023109 -410.360758)
			(xy 79.046873 -410.423853) (xy 79.062909 -410.489341) (xy 79.070986 -410.556277) (xy 79.070987 -410.623641)
			(xy 82.349051 -410.623641) (xy 82.349052 -410.556335) (xy 82.357097 -410.489512) (xy 82.373071 -410.424129)
			(xy 82.396745 -410.361124) (xy 82.427779 -410.3014) (xy 82.465728 -410.245812) (xy 82.487516 -410.22016)
			(xy 82.493314 -410.213016) (xy 82.499827 -410.195824) (xy 82.500216 -410.186632) (xy 82.500216 -409.693364)
			(xy 82.49982 -409.684175) (xy 82.493296 -409.666991) (xy 82.487516 -409.659836) (xy 82.465741 -409.634174)
			(xy 82.427793 -409.578588) (xy 82.39676 -409.518866) (xy 82.373088 -409.455863) (xy 82.357115 -409.390482)
			(xy 82.34907 -409.323661) (xy 82.349069 -409.256357) (xy 82.357112 -409.189536) (xy 82.373083 -409.124155)
			(xy 82.396753 -409.061151) (xy 82.427784 -409.001427) (xy 82.46573 -408.94584) (xy 82.487516 -408.920188)
			(xy 82.493302 -408.913035) (xy 82.499822 -408.89585) (xy 82.500216 -408.88666) (xy 82.500216 -408.728672)
			(xy 82.500599 -408.718514) (xy 82.508407 -408.699758) (xy 82.522815 -408.685435) (xy 82.541618 -408.677739)
			(xy 82.551778 -408.677364) (xy 83.268058 -408.677364) (xy 83.278185 -408.677862) (xy 83.29691 -408.68558)
			(xy 83.311268 -408.699864) (xy 83.319085 -408.718548) (xy 83.31962 -408.728672) (xy 83.31962 -408.88666)
			(xy 83.320045 -408.895846) (xy 83.326548 -408.913031) (xy 83.33232 -408.920188) (xy 83.354121 -408.94583)
			(xy 83.392072 -409.001417) (xy 83.423107 -409.061141) (xy 83.446781 -409.124147) (xy 83.462754 -409.189531)
			(xy 83.470798 -409.256356) (xy 83.470797 -409.323662) (xy 83.462751 -409.390487) (xy 83.446775 -409.45587)
			(xy 83.423099 -409.518875) (xy 83.420495 -409.523886) (xy 84.548669 -409.523886) (xy 84.548672 -409.45646)
			(xy 84.556751 -409.38952) (xy 84.572789 -409.324029) (xy 84.596556 -409.260931) (xy 84.627709 -409.201134)
			(xy 84.665799 -409.145498) (xy 84.687664 -409.119832) (xy 84.69348 -409.112701) (xy 84.699981 -409.095499)
			(xy 84.700364 -409.086304) (xy 84.700364 -408.594052) (xy 84.699915 -408.584869) (xy 84.693427 -408.567685)
			(xy 84.687664 -408.560524) (xy 84.665793 -408.534865) (xy 84.627707 -408.479228) (xy 84.596559 -408.419431)
			(xy 84.572797 -408.356334) (xy 84.556763 -408.290844) (xy 84.548688 -408.223906) (xy 84.548689 -408.156482)
			(xy 84.556765 -408.089544) (xy 84.5728 -408.024055) (xy 84.596564 -407.960958) (xy 84.627714 -407.901161)
			(xy 84.665801 -407.845526) (xy 84.687664 -407.81986) (xy 84.693468 -407.81272) (xy 84.699976 -407.795525)
			(xy 84.700364 -407.786332) (xy 84.700364 -407.628852) (xy 84.700845 -407.618745) (xy 84.708592 -407.600072)
			(xy 84.722889 -407.585781) (xy 84.741564 -407.578041) (xy 84.751672 -407.577544) (xy 85.467952 -407.577544)
			(xy 85.478051 -407.578123) (xy 85.496717 -407.585835) (xy 85.510806 -407.599896) (xy 98.75089 -407.599896)
			(xy 98.754894 -407.394708) (xy 98.766901 -407.189832) (xy 98.786892 -406.985581) (xy 98.814837 -406.782266)
			(xy 98.850693 -406.580195) (xy 98.894407 -406.379677) (xy 98.94591 -406.181018) (xy 99.005125 -405.984519)
			(xy 99.071961 -405.79048) (xy 99.146317 -405.599197) (xy 99.22808 -405.41096) (xy 99.317125 -405.226057)
			(xy 99.413316 -405.044769) (xy 99.516507 -404.867372) (xy 99.626541 -404.694135) (xy 99.74325 -404.525324)
			(xy 99.866456 -404.361195) (xy 99.995973 -404.201998) (xy 100.131602 -404.047976) (xy 100.273137 -403.899362)
			(xy 100.420362 -403.756384) (xy 100.573054 -403.619259) (xy 100.73098 -403.488195) (xy 100.893899 -403.363393)
			(xy 101.061564 -403.245043) (xy 101.233718 -403.133324) (xy 101.4101 -403.028407) (xy 101.590441 -402.930452)
			(xy 101.774467 -402.839608) (xy 101.961897 -402.756012) (xy 102.152446 -402.679793) (xy 102.345823 -402.611067)
			(xy 102.541735 -402.549938) (xy 102.739882 -402.496499) (xy 102.939964 -402.450832) (xy 103.141675 -402.413005)
			(xy 103.344708 -402.383078) (xy 103.548755 -402.361095) (xy 103.753504 -402.34709) (xy 103.958643 -402.341084)
			(xy 104.16386 -402.343086) (xy 104.368843 -402.353094) (xy 104.57328 -402.371091) (xy 104.776858 -402.397051)
			(xy 104.979269 -402.430934) (xy 105.180203 -402.472689) (xy 105.379356 -402.522252) (xy 105.576423 -402.579547)
			(xy 105.771105 -402.644487) (xy 105.963105 -402.716973) (xy 106.15213 -402.796896) (xy 106.209586 -402.823878)
			(xy 117.548826 -402.823878) (xy 117.548831 -402.75645) (xy 117.556912 -402.689507) (xy 117.572954 -402.624015)
			(xy 117.596726 -402.560916) (xy 117.627885 -402.501119) (xy 117.665983 -402.445484) (xy 117.687852 -402.41982)
			(xy 117.693671 -402.412691) (xy 117.700171 -402.395488) (xy 117.700552 -402.386292) (xy 117.700552 -401.89404)
			(xy 117.700111 -401.884856) (xy 117.693618 -401.867672) (xy 117.687852 -401.860512) (xy 117.665967 -401.834864)
			(xy 117.627875 -401.779228) (xy 117.596722 -401.71943) (xy 117.572957 -401.656331) (xy 117.556921 -401.590839)
			(xy 117.548846 -401.523898) (xy 117.548848 -401.456472) (xy 117.556927 -401.389531) (xy 117.572966 -401.32404)
			(xy 117.596735 -401.260943) (xy 117.627891 -401.201146) (xy 117.665985 -401.145512) (xy 117.687852 -401.119848)
			(xy 117.69366 -401.112711) (xy 117.700166 -401.095514) (xy 117.700552 -401.08632) (xy 117.700552 -400.92884)
			(xy 117.701117 -400.91874) (xy 117.708832 -400.900072) (xy 117.723105 -400.885777) (xy 117.741761 -400.878033)
			(xy 117.75186 -400.877532) (xy 118.46814 -400.877532) (xy 118.478255 -400.877953) (xy 118.49694 -400.88571)
			(xy 118.511235 -400.900027) (xy 118.518963 -400.918724) (xy 118.519448 -400.92884) (xy 118.519448 -401.08632)
			(xy 118.51986 -401.095507) (xy 118.526374 -401.11269) (xy 118.532148 -401.119848) (xy 118.553994 -401.145529)
			(xy 118.592087 -401.20116) (xy 118.623241 -401.260953) (xy 118.647009 -401.324048) (xy 118.663047 -401.389536)
			(xy 118.671126 -401.456473) (xy 118.671127 -401.523897) (xy 118.663053 -401.590834) (xy 118.647018 -401.656323)
			(xy 118.623254 -401.719419) (xy 118.620974 -401.723796) (xy 119.749006 -401.723796) (xy 119.749008 -401.656371)
			(xy 119.757086 -401.589431) (xy 119.773123 -401.523941) (xy 119.79689 -401.460843) (xy 119.828043 -401.401046)
			(xy 119.866135 -401.345411) (xy 119.888 -401.319746) (xy 119.893802 -401.312605) (xy 119.900313 -401.295411)
			(xy 119.9007 -401.286218) (xy 119.9007 -400.793966) (xy 119.900306 -400.784777) (xy 119.893781 -400.767593)
			(xy 119.888 -400.760438) (xy 119.866142 -400.734768) (xy 119.828053 -400.679134) (xy 119.796902 -400.619339)
			(xy 119.773138 -400.556242) (xy 119.757102 -400.490754) (xy 119.749025 -400.423816) (xy 119.749025 -400.356393)
			(xy 119.7571 -400.289455) (xy 119.773135 -400.223966) (xy 119.796898 -400.16087) (xy 119.828048 -400.101074)
			(xy 119.866136 -400.045439) (xy 119.888 -400.019774) (xy 119.89379 -400.012624) (xy 119.900309 -399.995437)
			(xy 119.9007 -399.986246) (xy 119.9007 -399.828766) (xy 119.901197 -399.818642) (xy 119.908929 -399.799928)
			(xy 119.923211 -399.785574) (xy 119.941887 -399.777749) (xy 119.952008 -399.777204) (xy 120.668288 -399.777204)
			(xy 120.678442 -399.777631) (xy 120.697195 -399.785424) (xy 120.711519 -399.799819) (xy 120.719218 -399.81861)
			(xy 120.719596 -399.828766) (xy 120.719596 -399.986246) (xy 120.720033 -399.99543) (xy 120.726528 -400.012615)
			(xy 120.732296 -400.019774) (xy 120.754166 -400.045434) (xy 120.792255 -400.101069) (xy 120.823405 -400.160866)
			(xy 120.847169 -400.223964) (xy 120.863205 -400.289454) (xy 120.87128 -400.356392) (xy 120.87128 -400.423817)
			(xy 120.863203 -400.490755) (xy 120.847167 -400.556245) (xy 120.823402 -400.619342) (xy 120.79225 -400.679138)
			(xy 120.75416 -400.734773) (xy 120.732296 -400.760438) (xy 120.7265 -400.767584) (xy 120.719985 -400.784774)
			(xy 120.719596 -400.793966) (xy 120.719596 -401.286218) (xy 120.719998 -401.295406) (xy 120.726517 -401.31259)
			(xy 120.732296 -401.319746) (xy 120.754138 -401.345429) (xy 120.792228 -401.401061) (xy 120.82338 -401.460855)
			(xy 120.847146 -401.523949) (xy 120.863183 -401.589436) (xy 120.87126 -401.656372) (xy 120.871262 -401.723794)
			(xy 120.863189 -401.790731) (xy 120.847155 -401.856219) (xy 120.823394 -401.919315) (xy 120.792245 -401.979111)
			(xy 120.754159 -402.034745) (xy 120.732296 -402.06041) (xy 120.726512 -402.067564) (xy 120.71999 -402.084748)
			(xy 120.719596 -402.093938) (xy 120.719596 -402.251418) (xy 120.719089 -402.261541) (xy 120.711362 -402.280256)
			(xy 120.697083 -402.294611) (xy 120.678409 -402.302436) (xy 120.668288 -402.30298) (xy 119.952008 -402.30298)
			(xy 119.941852 -402.302571) (xy 119.923096 -402.294775) (xy 119.908771 -402.280374) (xy 119.901075 -402.261576)
			(xy 119.9007 -402.251418) (xy 119.9007 -402.093938) (xy 119.900272 -402.084753) (xy 119.893771 -402.067568)
			(xy 119.888 -402.06041) (xy 119.866114 -402.034763) (xy 119.828026 -401.979126) (xy 119.796877 -401.919327)
			(xy 119.773114 -401.856228) (xy 119.75708 -401.790736) (xy 119.749006 -401.723796) (xy 118.620974 -401.723796)
			(xy 118.592102 -401.779215) (xy 118.554013 -401.834848) (xy 118.532148 -401.860512) (xy 118.526357 -401.867661)
			(xy 118.519841 -401.884849) (xy 118.519448 -401.89404) (xy 118.519448 -402.386292) (xy 118.519874 -402.395477)
			(xy 118.526378 -402.412661) (xy 118.532148 -402.41982) (xy 118.553967 -402.445523) (xy 118.59206 -402.501151)
			(xy 118.623216 -402.560942) (xy 118.646985 -402.624034) (xy 118.663025 -402.689519) (xy 118.671106 -402.756454)
			(xy 118.67111 -402.823818) (xy 121.949146 -402.823818) (xy 121.94915 -402.756509) (xy 121.957199 -402.689684)
			(xy 121.973177 -402.624299) (xy 121.996856 -402.561292) (xy 122.027895 -402.501567) (xy 122.065849 -402.44598)
			(xy 122.08764 -402.420328) (xy 122.093455 -402.413196) (xy 122.099958 -402.395995) (xy 122.10034 -402.3868)
			(xy 122.10034 -401.893532) (xy 122.099905 -401.884348) (xy 122.093408 -401.867164) (xy 122.08764 -401.860004)
			(xy 122.065832 -401.834368) (xy 122.027884 -401.778779) (xy 121.996852 -401.719054) (xy 121.97318 -401.656047)
			(xy 121.957208 -401.590663) (xy 121.949166 -401.523838) (xy 121.949168 -401.456532) (xy 121.957214 -401.389708)
			(xy 121.973189 -401.324324) (xy 121.996864 -401.261319) (xy 122.0279 -401.201595) (xy 122.065851 -401.146008)
			(xy 122.08764 -401.120356) (xy 122.093443 -401.113215) (xy 122.099953 -401.096021) (xy 122.10034 -401.086828)
			(xy 122.10034 -400.92884) (xy 122.100755 -400.918684) (xy 122.108545 -400.899924) (xy 122.122945 -400.885598)
			(xy 122.141743 -400.877904) (xy 122.151902 -400.877532) (xy 122.868182 -400.877532) (xy 122.878307 -400.878041)
			(xy 122.897026 -400.885761) (xy 122.911383 -400.900041) (xy 122.919204 -400.918718) (xy 122.919744 -400.92884)
			(xy 122.919744 -401.086828) (xy 122.920153 -401.096015) (xy 122.926669 -401.113199) (xy 122.932444 -401.120356)
			(xy 122.954212 -401.146024) (xy 122.992163 -401.201608) (xy 123.023198 -401.261329) (xy 123.046873 -401.324332)
			(xy 123.062848 -401.389712) (xy 123.070894 -401.456533) (xy 123.070895 -401.523837) (xy 123.062853 -401.590658)
			(xy 123.046882 -401.65604) (xy 123.02321 -401.719043) (xy 123.020771 -401.723737) (xy 124.149301 -401.723737)
			(xy 124.149303 -401.65643) (xy 124.15735 -401.589605) (xy 124.173327 -401.524221) (xy 124.197004 -401.461215)
			(xy 124.228043 -401.401491) (xy 124.265997 -401.345906) (xy 124.287788 -401.320254) (xy 124.293585 -401.313109)
			(xy 124.3001 -401.295918) (xy 124.300488 -401.286726) (xy 124.300488 -400.793458) (xy 124.300101 -400.784268)
			(xy 124.293572 -400.767084) (xy 124.287788 -400.75993) (xy 124.266005 -400.734274) (xy 124.228052 -400.678689)
			(xy 124.197016 -400.618966) (xy 124.173341 -400.555962) (xy 124.157366 -400.49058) (xy 124.149321 -400.423757)
			(xy 124.14932 -400.356452) (xy 124.157365 -400.289629) (xy 124.173338 -400.224246) (xy 124.197013 -400.161242)
			(xy 124.228048 -400.101519) (xy 124.265999 -400.045933) (xy 124.287788 -400.020282) (xy 124.293573 -400.013129)
			(xy 124.300095 -399.995944) (xy 124.300488 -399.986754) (xy 124.300488 -399.828766) (xy 124.300837 -399.818586)
			(xy 124.308643 -399.799781) (xy 124.323052 -399.785395) (xy 124.341869 -399.777621) (xy 124.35205 -399.777204)
			(xy 125.06833 -399.777204) (xy 125.078486 -399.777708) (xy 125.097249 -399.785486) (xy 125.111612 -399.799848)
			(xy 125.119391 -399.818611) (xy 125.119892 -399.828766) (xy 125.119892 -399.986754) (xy 125.120326 -399.995939)
			(xy 125.126823 -400.013123) (xy 125.132592 -400.020282) (xy 125.154385 -400.04593) (xy 125.192331 -400.101518)
			(xy 125.223363 -400.161242) (xy 125.247034 -400.224247) (xy 125.263005 -400.289629) (xy 125.271049 -400.356452)
			(xy 125.271048 -400.423757) (xy 125.263004 -400.490579) (xy 125.247031 -400.555962) (xy 125.223359 -400.618966)
			(xy 125.192327 -400.67869) (xy 125.154379 -400.734277) (xy 125.132592 -400.75993) (xy 125.126799 -400.767078)
			(xy 125.120283 -400.784266) (xy 125.119892 -400.793458) (xy 125.119892 -401.286726) (xy 125.120291 -401.295914)
			(xy 125.126813 -401.313099) (xy 125.132592 -401.320254) (xy 125.154357 -401.345924) (xy 125.192305 -401.401509)
			(xy 125.223337 -401.46123) (xy 125.24701 -401.524232) (xy 125.262983 -401.589612) (xy 125.271029 -401.656432)
			(xy 125.271031 -401.723735) (xy 125.262989 -401.790555) (xy 125.24702 -401.855936) (xy 125.223351 -401.918939)
			(xy 125.192322 -401.978663) (xy 125.154377 -402.034249) (xy 125.132592 -402.059902) (xy 125.126811 -402.067058)
			(xy 125.120287 -402.08424) (xy 125.119892 -402.09343) (xy 125.119892 -402.251418) (xy 125.119382 -402.261573)
			(xy 125.111608 -402.280337) (xy 125.097247 -402.294701) (xy 125.078485 -402.30248) (xy 125.06833 -402.30298)
			(xy 124.35205 -402.30298) (xy 124.341884 -402.302496) (xy 124.323094 -402.29473) (xy 124.308708 -402.280363)
			(xy 124.300918 -402.261584) (xy 124.300488 -402.251418) (xy 124.300488 -402.09343) (xy 124.300066 -402.084244)
			(xy 124.293561 -402.067059) (xy 124.287788 -402.059902) (xy 124.265977 -402.034268) (xy 124.228026 -401.97868)
			(xy 124.196991 -401.918955) (xy 124.173317 -401.855948) (xy 124.157344 -401.790563) (xy 124.149301 -401.723737)
			(xy 123.020771 -401.723737) (xy 122.992178 -401.778766) (xy 122.954231 -401.834352) (xy 122.932444 -401.860004)
			(xy 122.926656 -401.867155) (xy 122.920138 -401.884341) (xy 122.919744 -401.893532) (xy 122.919744 -402.3868)
			(xy 122.920167 -402.395986) (xy 122.926673 -402.413169) (xy 122.932444 -402.420328) (xy 122.954185 -402.446019)
			(xy 122.992136 -402.501599) (xy 123.023173 -402.561317) (xy 123.046849 -402.624317) (xy 123.062826 -402.689695)
			(xy 123.070874 -402.756513) (xy 123.070878 -402.823815) (xy 123.07087 -402.823878) (xy 126.348914 -402.823878)
			(xy 126.348919 -402.75645) (xy 126.357 -402.689508) (xy 126.373042 -402.624016) (xy 126.396813 -402.560916)
			(xy 126.427971 -402.501119) (xy 126.466068 -402.445485) (xy 126.487936 -402.41982) (xy 126.493754 -402.41269)
			(xy 126.500255 -402.395488) (xy 126.500636 -402.386292) (xy 126.500636 -401.89404) (xy 126.500198 -401.884856)
			(xy 126.493703 -401.867672) (xy 126.487936 -401.860512) (xy 126.466051 -401.834864) (xy 126.427961 -401.779227)
			(xy 126.396809 -401.719429) (xy 126.373044 -401.65633) (xy 126.357009 -401.590839) (xy 126.348934 -401.523898)
			(xy 126.348936 -401.456472) (xy 126.357014 -401.389532) (xy 126.373053 -401.324041) (xy 126.396821 -401.260943)
			(xy 126.427976 -401.201147) (xy 126.46607 -401.145513) (xy 126.487936 -401.119848) (xy 126.493742 -401.112709)
			(xy 126.50025 -401.095514) (xy 126.500636 -401.08632) (xy 126.500636 -400.92884) (xy 126.50105 -400.918716)
			(xy 126.508791 -400.900006) (xy 126.523109 -400.885689) (xy 126.54182 -400.877949) (xy 126.551944 -400.877532)
			(xy 127.268224 -400.877532) (xy 127.278352 -400.877897) (xy 127.297062 -400.885659) (xy 127.311377 -400.899991)
			(xy 127.319116 -400.918711) (xy 127.319532 -400.92884) (xy 127.319532 -401.08632) (xy 127.319948 -401.095506)
			(xy 127.326459 -401.11269) (xy 127.332232 -401.119848) (xy 127.354075 -401.14553) (xy 127.392162 -401.201163)
			(xy 127.423312 -401.260957) (xy 127.447076 -401.324052) (xy 127.463112 -401.389538) (xy 127.471189 -401.456474)
			(xy 127.471191 -401.523896) (xy 127.463117 -401.590832) (xy 127.447085 -401.65632) (xy 127.423324 -401.719415)
			(xy 127.421073 -401.723737) (xy 128.549092 -401.723737) (xy 128.549094 -401.65643) (xy 128.557141 -401.589605)
			(xy 128.573117 -401.524221) (xy 128.596794 -401.461216) (xy 128.627832 -401.401492) (xy 128.665786 -401.345906)
			(xy 128.687576 -401.320254) (xy 128.693372 -401.313108) (xy 128.699888 -401.295918) (xy 128.700276 -401.286726)
			(xy 128.700276 -400.793458) (xy 128.699891 -400.784268) (xy 128.69336 -400.767084) (xy 128.687576 -400.75993)
			(xy 128.665793 -400.734273) (xy 128.627842 -400.678688) (xy 128.596806 -400.618966) (xy 128.573131 -400.555962)
			(xy 128.557157 -400.49058) (xy 128.549112 -400.423757) (xy 128.549111 -400.356452) (xy 128.557155 -400.289629)
			(xy 128.573129 -400.224247) (xy 128.596802 -400.161242) (xy 128.627837 -400.101519) (xy 128.665788 -400.045934)
			(xy 128.687576 -400.020282) (xy 128.69336 -400.013128) (xy 128.699883 -399.995944) (xy 128.700276 -399.986754)
			(xy 128.700276 -399.828766) (xy 128.700637 -399.818587) (xy 128.70844 -399.799785) (xy 128.722845 -399.7854)
			(xy 128.741659 -399.777623) (xy 128.751838 -399.777204) (xy 129.468118 -399.777204) (xy 129.478273 -399.777718)
			(xy 129.497036 -399.785492) (xy 129.511399 -399.799851) (xy 129.519179 -399.818611) (xy 129.51968 -399.828766)
			(xy 129.51968 -399.986754) (xy 129.520117 -399.995938) (xy 129.526612 -400.013123) (xy 129.53238 -400.020282)
			(xy 129.554173 -400.045929) (xy 129.592121 -400.101517) (xy 129.623152 -400.161241) (xy 129.646824 -400.224247)
			(xy 129.662796 -400.289629) (xy 129.670839 -400.356452) (xy 129.670839 -400.423757) (xy 129.662794 -400.49058)
			(xy 129.646821 -400.555962) (xy 129.623149 -400.618967) (xy 129.592116 -400.678691) (xy 129.554168 -400.734278)
			(xy 129.53238 -400.75993) (xy 129.526586 -400.767077) (xy 129.52007 -400.784266) (xy 129.51968 -400.793458)
			(xy 129.51968 -401.286726) (xy 129.520082 -401.295914) (xy 129.526602 -401.313098) (xy 129.53238 -401.320254)
			(xy 129.554146 -401.345924) (xy 129.592094 -401.401508) (xy 129.623127 -401.46123) (xy 129.6468 -401.524232)
			(xy 129.662774 -401.589612) (xy 129.67082 -401.656432) (xy 129.670822 -401.723735) (xy 129.66278 -401.790556)
			(xy 129.64681 -401.855937) (xy 129.623141 -401.91894) (xy 129.592111 -401.978663) (xy 129.554166 -402.03425)
			(xy 129.53238 -402.059902) (xy 129.526598 -402.067057) (xy 129.520075 -402.08424) (xy 129.51968 -402.09343)
			(xy 129.51968 -402.251418) (xy 129.519182 -402.261575) (xy 129.511405 -402.280341) (xy 129.497041 -402.294705)
			(xy 129.478275 -402.302482) (xy 129.468118 -402.30298) (xy 128.751838 -402.30298) (xy 128.741671 -402.302505)
			(xy 128.722881 -402.294736) (xy 128.708495 -402.280366) (xy 128.700706 -402.261584) (xy 128.700276 -402.251418)
			(xy 128.700276 -402.09343) (xy 128.699857 -402.084244) (xy 128.69335 -402.067059) (xy 128.687576 -402.059902)
			(xy 128.665766 -402.034268) (xy 128.627815 -401.97868) (xy 128.596781 -401.918954) (xy 128.573108 -401.855947)
			(xy 128.557135 -401.790562) (xy 128.549092 -401.723737) (xy 127.421073 -401.723737) (xy 127.392178 -401.779211)
			(xy 127.354094 -401.834846) (xy 127.332232 -401.860512) (xy 127.32644 -401.86766) (xy 127.319924 -401.884849)
			(xy 127.319532 -401.89404) (xy 127.319532 -402.386292) (xy 127.319961 -402.395477) (xy 127.326463 -402.412661)
			(xy 127.332232 -402.41982) (xy 127.354048 -402.445525) (xy 127.392136 -402.501154) (xy 127.423287 -402.560945)
			(xy 127.447052 -402.624037) (xy 127.46309 -402.689521) (xy 127.471169 -402.756454) (xy 127.471174 -402.823818)
			(xy 130.749234 -402.823818) (xy 130.749238 -402.75651) (xy 130.757287 -402.689684) (xy 130.773265 -402.624299)
			(xy 130.796942 -402.561293) (xy 130.82798 -402.501568) (xy 130.865934 -402.44598) (xy 130.887724 -402.420328)
			(xy 130.893536 -402.413194) (xy 130.900041 -402.395995) (xy 130.900424 -402.3868) (xy 130.900424 -401.893532)
			(xy 130.899993 -401.884347) (xy 130.893493 -401.867163) (xy 130.887724 -401.860004) (xy 130.865917 -401.834368)
			(xy 130.82797 -401.778779) (xy 130.796938 -401.719053) (xy 130.773267 -401.656046) (xy 130.757296 -401.590662)
			(xy 130.749254 -401.523838) (xy 130.749256 -401.456532) (xy 130.757301 -401.389708) (xy 130.773276 -401.324325)
			(xy 130.79695 -401.26132) (xy 130.827985 -401.201595) (xy 130.865935 -401.146008) (xy 130.887724 -401.120356)
			(xy 130.893525 -401.113214) (xy 130.900036 -401.096021) (xy 130.900424 -401.086828) (xy 130.900424 -400.92884)
			(xy 130.900855 -400.918686) (xy 130.908642 -400.899929) (xy 130.923036 -400.885604) (xy 130.94183 -400.877907)
			(xy 130.951986 -400.877532) (xy 131.668266 -400.877532) (xy 131.67839 -400.878054) (xy 131.697108 -400.88577)
			(xy 131.711465 -400.900045) (xy 131.719287 -400.918719) (xy 131.719828 -400.92884) (xy 131.719828 -401.086828)
			(xy 131.720218 -401.096017) (xy 131.726745 -401.113202) (xy 131.732528 -401.120356) (xy 131.754297 -401.146024)
			(xy 131.792249 -401.201607) (xy 131.823285 -401.261328) (xy 131.84696 -401.324331) (xy 131.862935 -401.389712)
			(xy 131.870981 -401.456533) (xy 131.870983 -401.523837) (xy 131.862941 -401.590659) (xy 131.846969 -401.65604)
			(xy 131.823297 -401.719044) (xy 131.792264 -401.778767) (xy 131.754315 -401.834352) (xy 131.732528 -401.860004)
			(xy 131.726738 -401.867154) (xy 131.720222 -401.884341) (xy 131.719828 -401.893532) (xy 131.719828 -402.3868)
			(xy 131.720232 -402.395988) (xy 131.726749 -402.413173) (xy 131.732528 -402.420328) (xy 131.75427 -402.446019)
			(xy 131.792222 -402.501599) (xy 131.823259 -402.561317) (xy 131.846936 -402.624316) (xy 131.862913 -402.689694)
			(xy 131.870962 -402.756513) (xy 131.870966 -402.823815) (xy 131.862926 -402.890635) (xy 131.846957 -402.956015)
			(xy 131.823289 -403.019017) (xy 131.792259 -403.078739) (xy 131.754314 -403.134324) (xy 131.732528 -403.159976)
			(xy 131.726708 -403.167104) (xy 131.720209 -403.184308) (xy 131.719828 -403.193504) (xy 131.719828 -403.351492)
			(xy 131.719372 -403.361642) (xy 131.711585 -403.380389) (xy 131.697199 -403.394712) (xy 131.678418 -403.402417)
			(xy 131.668266 -403.4028) (xy 130.951986 -403.4028) (xy 130.941863 -403.402286) (xy 130.92315 -403.394561)
			(xy 130.908795 -403.380284) (xy 130.90097 -403.361612) (xy 130.900424 -403.351492) (xy 130.900424 -403.193504)
			(xy 130.900007 -403.184318) (xy 130.893498 -403.167133) (xy 130.887724 -403.159976) (xy 130.86589 -403.134362)
			(xy 130.827943 -403.07877) (xy 130.796913 -403.019041) (xy 130.773243 -402.956032) (xy 130.757274 -402.890645)
			(xy 130.749234 -402.823818) (xy 127.471174 -402.823818) (xy 127.471174 -402.823874) (xy 127.463103 -402.890808)
			(xy 127.447074 -402.956294) (xy 127.423316 -403.019389) (xy 127.392173 -403.079184) (xy 127.354092 -403.134818)
			(xy 127.332232 -403.160484) (xy 127.326409 -403.16761) (xy 127.319912 -403.184816) (xy 127.319532 -403.194012)
			(xy 127.319532 -403.351492) (xy 127.319009 -403.361596) (xy 127.31128 -403.380268) (xy 127.296995 -403.394562)
			(xy 127.278328 -403.402303) (xy 127.268224 -403.4028) (xy 126.551944 -403.4028) (xy 126.541824 -403.402348)
			(xy 126.523122 -403.394614) (xy 126.508806 -403.380308) (xy 126.501059 -403.361611) (xy 126.500636 -403.351492)
			(xy 126.500636 -403.194012) (xy 126.500212 -403.184826) (xy 126.493707 -403.167642) (xy 126.487936 -403.160484)
			(xy 126.466024 -403.134858) (xy 126.427934 -403.079219) (xy 126.396783 -403.019418) (xy 126.37302 -402.956315)
			(xy 126.356987 -402.890821) (xy 126.348914 -402.823878) (xy 123.07087 -402.823878) (xy 123.062839 -402.890634)
			(xy 123.04687 -402.956014) (xy 123.023202 -403.019017) (xy 122.992173 -403.078739) (xy 122.954229 -403.134324)
			(xy 122.932444 -403.159976) (xy 122.926626 -403.167106) (xy 122.920126 -403.184308) (xy 122.919744 -403.193504)
			(xy 122.919744 -403.351492) (xy 122.919273 -403.36164) (xy 122.911488 -403.380384) (xy 122.897107 -403.394706)
			(xy 122.878332 -403.402414) (xy 122.868182 -403.4028) (xy 122.151902 -403.4028) (xy 122.14178 -403.402273)
			(xy 122.123067 -403.394553) (xy 122.108712 -403.38028) (xy 122.100886 -403.361611) (xy 122.10034 -403.351492)
			(xy 122.10034 -403.193504) (xy 122.099919 -403.184318) (xy 122.093412 -403.167134) (xy 122.08764 -403.159976)
			(xy 122.065805 -403.134363) (xy 122.027857 -403.078771) (xy 121.996826 -403.019042) (xy 121.973156 -402.956032)
			(xy 121.957186 -402.890645) (xy 121.949146 -402.823818) (xy 118.67111 -402.823818) (xy 118.67111 -402.823874)
			(xy 118.663038 -402.89081) (xy 118.647006 -402.956297) (xy 118.623245 -403.019392) (xy 118.592097 -403.079187)
			(xy 118.554011 -403.13482) (xy 118.532148 -403.160484) (xy 118.526327 -403.167612) (xy 118.519828 -403.184816)
			(xy 118.519448 -403.194012) (xy 118.519448 -403.351492) (xy 118.51891 -403.361594) (xy 118.511183 -403.380263)
			(xy 118.496903 -403.394557) (xy 118.478242 -403.4023) (xy 118.46814 -403.4028) (xy 117.75186 -403.4028)
			(xy 117.741749 -403.402348) (xy 117.72307 -403.394597) (xy 117.708776 -403.38029) (xy 117.701043 -403.361604)
			(xy 117.700552 -403.351492) (xy 117.700552 -403.194012) (xy 117.700125 -403.184827) (xy 117.693622 -403.167643)
			(xy 117.687852 -403.160484) (xy 117.665939 -403.134859) (xy 117.627848 -403.07922) (xy 117.596697 -403.019418)
			(xy 117.572933 -402.956316) (xy 117.556899 -402.890822) (xy 117.548826 -402.823878) (xy 106.209586 -402.823878)
			(xy 106.337893 -402.884132) (xy 106.520111 -402.97855) (xy 106.698507 -403.080005) (xy 106.872808 -403.188344)
			(xy 107.04275 -403.3034) (xy 107.208073 -403.425) (xy 107.368526 -403.552957) (xy 107.523865 -403.687076)
			(xy 107.673852 -403.827155) (xy 107.81826 -403.972979) (xy 107.956868 -404.124325) (xy 108.089466 -404.280965)
			(xy 108.215852 -404.442659) (xy 108.335832 -404.609161) (xy 108.449225 -404.780217) (xy 108.555858 -404.955567)
			(xy 108.655568 -405.134944) (xy 108.748204 -405.318074) (xy 108.833624 -405.50468) (xy 108.882562 -405.623648)
			(xy 115.349248 -405.623648) (xy 115.349249 -405.556343) (xy 115.357293 -405.489521) (xy 115.373266 -405.424139)
			(xy 115.396938 -405.361134) (xy 115.42797 -405.30141) (xy 115.465917 -405.245823) (xy 115.487704 -405.22017)
			(xy 115.493496 -405.213022) (xy 115.500013 -405.195834) (xy 115.500404 -405.186642) (xy 115.500404 -404.693374)
			(xy 115.500006 -404.684186) (xy 115.493484 -404.667001) (xy 115.487704 -404.659846) (xy 115.465939 -404.634176)
			(xy 115.427992 -404.578591) (xy 115.396959 -404.51887) (xy 115.373287 -404.455868) (xy 115.357314 -404.390488)
			(xy 115.349268 -404.323668) (xy 115.349266 -404.256365) (xy 115.357308 -404.189545) (xy 115.373277 -404.124164)
			(xy 115.396946 -404.061161) (xy 115.427975 -404.001437) (xy 115.465919 -403.945851) (xy 115.487704 -403.920198)
			(xy 115.493484 -403.913041) (xy 115.500009 -403.89586) (xy 115.500404 -403.88667) (xy 115.500404 -403.728682)
			(xy 115.500918 -403.718527) (xy 115.508692 -403.699764) (xy 115.523051 -403.685401) (xy 115.541811 -403.677621)
			(xy 115.551966 -403.67712) (xy 116.268246 -403.67712) (xy 116.278404 -403.677595) (xy 116.297171 -403.685382)
			(xy 116.311534 -403.699752) (xy 116.31931 -403.718523) (xy 116.319808 -403.728682) (xy 116.319808 -403.88667)
			(xy 116.320231 -403.895856) (xy 116.326735 -403.91304) (xy 116.332508 -403.920198) (xy 116.354319 -403.945832)
			(xy 116.392271 -404.00142) (xy 116.423306 -404.061145) (xy 116.44698 -404.124152) (xy 116.462953 -404.189537)
			(xy 116.470996 -404.256363) (xy 116.470994 -404.32367) (xy 116.462947 -404.390495) (xy 116.44697 -404.455879)
			(xy 116.423292 -404.518885) (xy 116.392254 -404.578609) (xy 116.354299 -404.634195) (xy 116.332508 -404.659846)
			(xy 116.32671 -404.66699) (xy 116.320196 -404.684181) (xy 116.319808 -404.693374) (xy 116.319808 -405.186642)
			(xy 116.320196 -405.195832) (xy 116.326725 -405.213016) (xy 116.332508 -405.22017) (xy 116.354291 -405.245826)
			(xy 116.392244 -405.301411) (xy 116.42328 -405.361133) (xy 116.446956 -405.424137) (xy 116.462931 -405.48952)
			(xy 116.470976 -405.556343) (xy 116.470977 -405.623648) (xy 116.462932 -405.690471) (xy 116.446958 -405.755854)
			(xy 116.423284 -405.818858) (xy 116.392249 -405.878581) (xy 116.354297 -405.934167) (xy 116.332508 -405.959818)
			(xy 116.326722 -405.966971) (xy 116.320201 -405.984155) (xy 116.319808 -405.993346) (xy 116.319808 -406.151334)
			(xy 116.319296 -406.161488) (xy 116.311519 -406.180249) (xy 116.297159 -406.194612) (xy 116.2784 -406.202393)
			(xy 116.268246 -406.202896) (xy 115.551966 -406.202896) (xy 115.54181 -406.202395) (xy 115.523047 -406.194616)
			(xy 115.508684 -406.180253) (xy 115.500905 -406.16149) (xy 115.500404 -406.151334) (xy 115.500404 -405.993346)
			(xy 115.499971 -405.984161) (xy 115.493473 -405.966977) (xy 115.487704 -405.959818) (xy 115.465911 -405.93417)
			(xy 115.427965 -405.878582) (xy 115.396934 -405.818858) (xy 115.373263 -405.755853) (xy 115.357292 -405.69047)
			(xy 115.349248 -405.623648) (xy 108.882562 -405.623648) (xy 108.911698 -405.694476) (xy 108.982308 -405.887174)
			(xy 109.045345 -406.08248) (xy 109.100715 -406.280096) (xy 109.148332 -406.479723) (xy 109.188124 -406.681055)
			(xy 109.19485 -406.72379) (xy 117.548838 -406.72379) (xy 117.548841 -406.656362) (xy 117.55692 -406.589421)
			(xy 117.572961 -406.523929) (xy 117.596731 -406.460831) (xy 117.627888 -406.401034) (xy 117.665984 -406.3454)
			(xy 117.687852 -406.319736) (xy 117.693665 -406.312602) (xy 117.700168 -406.295403) (xy 117.700552 -406.286208)
			(xy 117.700552 -405.793956) (xy 117.700151 -405.784768) (xy 117.69363 -405.767585) (xy 117.687852 -405.760428)
			(xy 117.665982 -405.734767) (xy 117.62789 -405.679133) (xy 117.596737 -405.619337) (xy 117.572971 -405.556239)
			(xy 117.556934 -405.490749) (xy 117.548857 -405.42381) (xy 117.548858 -405.356384) (xy 117.556935 -405.289445)
			(xy 117.572972 -405.223955) (xy 117.596739 -405.160858) (xy 117.627893 -405.101062) (xy 117.665986 -405.045428)
			(xy 117.687852 -405.019764) (xy 117.693653 -405.012622) (xy 117.700164 -404.995429) (xy 117.700552 -404.986236)
			(xy 117.700552 -404.828756) (xy 117.701048 -404.81865) (xy 117.708791 -404.79998) (xy 117.723084 -404.785689)
			(xy 117.741754 -404.777947) (xy 117.75186 -404.777448) (xy 118.46814 -404.777448) (xy 118.478245 -404.777951)
			(xy 118.496914 -404.785692) (xy 118.511206 -404.799983) (xy 118.518948 -404.818651) (xy 118.519448 -404.828756)
			(xy 118.519448 -404.986236) (xy 118.519853 -404.995424) (xy 118.526372 -405.012607) (xy 118.532148 -405.019764)
			(xy 118.55401 -405.045432) (xy 118.592102 -405.101065) (xy 118.623256 -405.16086) (xy 118.647023 -405.223957)
			(xy 118.66306 -405.289446) (xy 118.671137 -405.356385) (xy 118.671137 -405.423809) (xy 118.663061 -405.490748)
			(xy 118.647024 -405.556238) (xy 118.623258 -405.619335) (xy 118.62098 -405.623708) (xy 119.749017 -405.623708)
			(xy 119.749017 -405.556283) (xy 119.757094 -405.489345) (xy 119.77313 -405.423855) (xy 119.796895 -405.360758)
			(xy 119.828046 -405.300962) (xy 119.866136 -405.245327) (xy 119.888 -405.219662) (xy 119.893795 -405.212516)
			(xy 119.900311 -405.195326) (xy 119.9007 -405.186134) (xy 119.9007 -404.693882) (xy 119.900298 -404.684694)
			(xy 119.893779 -404.66751) (xy 119.888 -404.660354) (xy 119.866158 -404.634671) (xy 119.828068 -404.579039)
			(xy 119.796917 -404.519245) (xy 119.773151 -404.456151) (xy 119.757114 -404.390664) (xy 119.749037 -404.323727)
			(xy 119.749035 -404.256306) (xy 119.757108 -404.189369) (xy 119.773141 -404.123881) (xy 119.796903 -404.060785)
			(xy 119.828051 -404.000989) (xy 119.866137 -403.945355) (xy 119.888 -403.91969) (xy 119.893783 -403.912535)
			(xy 119.900306 -403.895352) (xy 119.9007 -403.886162) (xy 119.9007 -403.728682) (xy 119.90121 -403.718559)
			(xy 119.908937 -403.699845) (xy 119.923215 -403.685491) (xy 119.941888 -403.677665) (xy 119.952008 -403.67712)
			(xy 120.668288 -403.67712) (xy 120.678444 -403.677532) (xy 120.6972 -403.685327) (xy 120.711524 -403.699727)
			(xy 120.719221 -403.718524) (xy 120.719596 -403.728682) (xy 120.719596 -403.886162) (xy 120.720025 -403.895347)
			(xy 120.726526 -403.912532) (xy 120.732296 -403.91969) (xy 120.754182 -403.945337) (xy 120.79227 -404.000974)
			(xy 120.82342 -404.060773) (xy 120.847183 -404.123872) (xy 120.863217 -404.189363) (xy 120.871291 -404.256304)
			(xy 120.871289 -404.323729) (xy 120.863211 -404.390669) (xy 120.847173 -404.456159) (xy 120.823407 -404.519257)
			(xy 120.792253 -404.579054) (xy 120.754161 -404.634689) (xy 120.732296 -404.660354) (xy 120.726494 -404.667495)
			(xy 120.719983 -404.684689) (xy 120.719596 -404.693882) (xy 120.719596 -405.186134) (xy 120.719991 -405.195323)
			(xy 120.726515 -405.212507) (xy 120.732296 -405.219662) (xy 120.754154 -405.245332) (xy 120.792243 -405.300966)
			(xy 120.823395 -405.360761) (xy 120.847159 -405.423858) (xy 120.863195 -405.489346) (xy 120.871272 -405.556284)
			(xy 120.871272 -405.623707) (xy 120.863197 -405.690645) (xy 120.847162 -405.756134) (xy 120.823398 -405.81923)
			(xy 120.792248 -405.879026) (xy 120.75416 -405.934661) (xy 120.732296 -405.960326) (xy 120.726505 -405.967475)
			(xy 120.719987 -405.984663) (xy 120.719596 -405.993854) (xy 120.719596 -406.151334) (xy 120.719102 -406.161458)
			(xy 120.71137 -406.180174) (xy 120.697087 -406.194527) (xy 120.67841 -406.202352) (xy 120.668288 -406.202896)
			(xy 119.952008 -406.202896) (xy 119.941854 -406.202472) (xy 119.923101 -406.194678) (xy 119.908777 -406.180282)
			(xy 119.901078 -406.16149) (xy 119.9007 -406.151334) (xy 119.9007 -405.993854) (xy 119.900264 -405.98467)
			(xy 119.893768 -405.967485) (xy 119.888 -405.960326) (xy 119.86613 -405.934666) (xy 119.828042 -405.87903)
			(xy 119.796891 -405.819234) (xy 119.773127 -405.756136) (xy 119.757092 -405.690646) (xy 119.749017 -405.623708)
			(xy 118.62098 -405.623708) (xy 118.592105 -405.67913) (xy 118.554014 -405.734764) (xy 118.532148 -405.760428)
			(xy 118.526351 -405.767572) (xy 118.519838 -405.784764) (xy 118.519448 -405.793956) (xy 118.519448 -406.286208)
			(xy 118.519866 -406.295394) (xy 118.526375 -406.312578) (xy 118.532148 -406.319736) (xy 118.553982 -406.345426)
			(xy 118.592075 -406.401056) (xy 118.62323 -406.460848) (xy 118.646999 -406.523942) (xy 118.663038 -406.589429)
			(xy 118.671117 -406.656365) (xy 118.67112 -406.72373) (xy 121.949157 -406.72373) (xy 121.94916 -406.656422)
			(xy 121.957208 -406.589597) (xy 121.973184 -406.524213) (xy 121.99686 -406.461207) (xy 122.027897 -406.401483)
			(xy 122.06585 -406.345896) (xy 122.08764 -406.320244) (xy 122.093448 -406.313107) (xy 122.099955 -406.29591)
			(xy 122.10034 -406.286716) (xy 122.10034 -405.793448) (xy 122.099898 -405.784264) (xy 122.093405 -405.76708)
			(xy 122.08764 -405.75992) (xy 122.065848 -405.734271) (xy 122.027899 -405.678684) (xy 121.996866 -405.61896)
			(xy 121.973194 -405.555955) (xy 121.957221 -405.490573) (xy 121.949177 -405.42375) (xy 121.949177 -405.356444)
			(xy 121.957222 -405.289621) (xy 121.973195 -405.224239) (xy 121.996869 -405.161234) (xy 122.027902 -405.101511)
			(xy 122.065852 -405.045924) (xy 122.08764 -405.020272) (xy 122.093436 -405.013127) (xy 122.09995 -404.995936)
			(xy 122.10034 -404.986744) (xy 122.10034 -404.828756) (xy 122.100686 -404.818594) (xy 122.108504 -404.799833)
			(xy 122.122924 -404.78551) (xy 122.141737 -404.777819) (xy 122.151902 -404.777448) (xy 122.868182 -404.777448)
			(xy 122.878309 -404.777941) (xy 122.897031 -404.785665) (xy 122.911388 -404.799949) (xy 122.919207 -404.818632)
			(xy 122.919744 -404.828756) (xy 122.919744 -404.986744) (xy 122.920145 -404.995932) (xy 122.926666 -405.013116)
			(xy 122.932444 -405.020272) (xy 122.954228 -405.045927) (xy 122.992178 -405.101513) (xy 123.023213 -405.161236)
			(xy 123.046886 -405.22424) (xy 123.06286 -405.289622) (xy 123.070905 -405.356444) (xy 123.070905 -405.42375)
			(xy 123.062861 -405.490572) (xy 123.046888 -405.555954) (xy 123.023215 -405.618959) (xy 123.020778 -405.623649)
			(xy 124.149312 -405.623649) (xy 124.149313 -405.556342) (xy 124.157358 -405.489518) (xy 124.173333 -405.424135)
			(xy 124.197009 -405.36113) (xy 124.228046 -405.301407) (xy 124.265998 -405.245822) (xy 124.287788 -405.22017)
			(xy 124.293578 -405.21302) (xy 124.300097 -405.195833) (xy 124.300488 -405.186642) (xy 124.300488 -404.693374)
			(xy 124.300093 -404.684185) (xy 124.293569 -404.667001) (xy 124.287788 -404.659846) (xy 124.26602 -404.634177)
			(xy 124.228068 -404.578594) (xy 124.197031 -404.518873) (xy 124.173355 -404.455871) (xy 124.157379 -404.39049)
			(xy 124.149332 -404.323669) (xy 124.14933 -404.256364) (xy 124.157373 -404.189542) (xy 124.173345 -404.124161)
			(xy 124.197017 -404.061157) (xy 124.228051 -404.001435) (xy 124.266 -403.945849) (xy 124.287788 -403.920198)
			(xy 124.293567 -403.91304) (xy 124.300092 -403.895859) (xy 124.300488 -403.88667) (xy 124.300488 -403.728682)
			(xy 124.30085 -403.718503) (xy 124.308651 -403.699698) (xy 124.323056 -403.685313) (xy 124.34187 -403.677537)
			(xy 124.35205 -403.67712) (xy 125.06833 -403.67712) (xy 125.078487 -403.677608) (xy 125.097254 -403.685389)
			(xy 125.111617 -403.699756) (xy 125.119394 -403.718524) (xy 125.119892 -403.728682) (xy 125.119892 -403.88667)
			(xy 125.120318 -403.895855) (xy 125.126821 -403.91304) (xy 125.132592 -403.920198) (xy 125.1544 -403.945833)
			(xy 125.192347 -404.001422) (xy 125.223377 -404.061149) (xy 125.247047 -404.124155) (xy 125.263018 -404.189539)
			(xy 125.27106 -404.256363) (xy 125.271058 -404.32367) (xy 125.263012 -404.390493) (xy 125.247038 -404.455876)
			(xy 125.223364 -404.518882) (xy 125.19233 -404.578606) (xy 125.15438 -404.634193) (xy 125.132592 -404.659846)
			(xy 125.126792 -404.666989) (xy 125.12028 -404.684181) (xy 125.119892 -404.693374) (xy 125.119892 -405.186642)
			(xy 125.120284 -405.195831) (xy 125.12681 -405.213015) (xy 125.132592 -405.22017) (xy 125.154373 -405.245827)
			(xy 125.19232 -405.301414) (xy 125.223352 -405.361137) (xy 125.247023 -405.424141) (xy 125.262996 -405.489522)
			(xy 125.27104 -405.556343) (xy 125.271041 -405.623647) (xy 125.262998 -405.690469) (xy 125.247026 -405.755851)
			(xy 125.223355 -405.818855) (xy 125.192325 -405.878578) (xy 125.154378 -405.934165) (xy 125.132592 -405.959818)
			(xy 125.126804 -405.96697) (xy 125.120285 -405.984155) (xy 125.119892 -405.993346) (xy 125.119892 -406.151334)
			(xy 125.119395 -406.16149) (xy 125.111615 -406.180254) (xy 125.097251 -406.194617) (xy 125.078486 -406.202396)
			(xy 125.06833 -406.202896) (xy 124.35205 -406.202896) (xy 124.341886 -406.202396) (xy 124.323099 -406.194634)
			(xy 124.308713 -406.180272) (xy 124.30092 -406.161497) (xy 124.300488 -406.151334) (xy 124.300488 -405.993346)
			(xy 124.300059 -405.984161) (xy 124.293559 -405.966976) (xy 124.287788 -405.959818) (xy 124.265993 -405.934171)
			(xy 124.228041 -405.878585) (xy 124.197005 -405.818861) (xy 124.173331 -405.755856) (xy 124.157357 -405.690473)
			(xy 124.149312 -405.623649) (xy 123.020778 -405.623649) (xy 122.992181 -405.678682) (xy 122.954232 -405.734268)
			(xy 122.932444 -405.75992) (xy 122.92665 -405.767066) (xy 122.920135 -405.784256) (xy 122.919744 -405.793448)
			(xy 122.919744 -406.286716) (xy 122.920159 -406.295902) (xy 122.926671 -406.313086) (xy 122.932444 -406.320244)
			(xy 122.954201 -406.345922) (xy 122.992152 -406.401504) (xy 123.023187 -406.461224) (xy 123.046862 -406.524225)
			(xy 123.062838 -406.589605) (xy 123.070885 -406.656425) (xy 123.070888 -406.723727) (xy 123.070881 -406.723789)
			(xy 126.348926 -406.723789) (xy 126.348929 -406.656363) (xy 126.357008 -406.589421) (xy 126.373048 -406.52393)
			(xy 126.396818 -406.460832) (xy 126.427974 -406.401035) (xy 126.466069 -406.345401) (xy 126.487936 -406.319736)
			(xy 126.493747 -406.312601) (xy 126.500252 -406.295403) (xy 126.500636 -406.286208) (xy 126.500636 -405.793956)
			(xy 126.500239 -405.784768) (xy 126.493715 -405.767584) (xy 126.487936 -405.760428) (xy 126.466067 -405.734767)
			(xy 126.427976 -405.679132) (xy 126.396823 -405.619336) (xy 126.373058 -405.556239) (xy 126.357022 -405.490749)
			(xy 126.348945 -405.423809) (xy 126.348946 -405.356385) (xy 126.357023 -405.289445) (xy 126.37306 -405.223956)
			(xy 126.396826 -405.160859) (xy 126.427979 -405.101062) (xy 126.466071 -405.045429) (xy 126.487936 -405.019764)
			(xy 126.493735 -405.012621) (xy 126.500247 -404.995429) (xy 126.500636 -404.986236) (xy 126.500636 -404.828756)
			(xy 126.50105 -404.81864) (xy 126.508809 -404.799954) (xy 126.523128 -404.785659) (xy 126.541827 -404.777933)
			(xy 126.551944 -404.777448) (xy 127.268224 -404.777448) (xy 127.278328 -404.777964) (xy 127.296997 -404.7857)
			(xy 127.311289 -404.799986) (xy 127.319032 -404.818652) (xy 127.319532 -404.828756) (xy 127.319532 -404.986236)
			(xy 127.31994 -404.995423) (xy 127.326457 -405.012607) (xy 127.332232 -405.019764) (xy 127.354091 -405.045433)
			(xy 127.392178 -405.101068) (xy 127.423327 -405.160864) (xy 127.44709 -405.22396) (xy 127.463125 -405.289448)
			(xy 127.4712 -405.356386) (xy 127.471201 -405.423808) (xy 127.463126 -405.490746) (xy 127.447092 -405.556234)
			(xy 127.423329 -405.619331) (xy 127.42108 -405.623649) (xy 128.549103 -405.623649) (xy 128.549104 -405.556342)
			(xy 128.557149 -405.489519) (xy 128.573124 -405.424136) (xy 128.596799 -405.361131) (xy 128.627835 -405.301407)
			(xy 128.665787 -405.245822) (xy 128.687576 -405.22017) (xy 128.693365 -405.213019) (xy 128.699885 -405.195833)
			(xy 128.700276 -405.186642) (xy 128.700276 -404.693374) (xy 128.699884 -404.684185) (xy 128.693358 -404.667)
			(xy 128.687576 -404.659846) (xy 128.665809 -404.634177) (xy 128.627857 -404.578593) (xy 128.596821 -404.518873)
			(xy 128.573145 -404.45587) (xy 128.557169 -404.39049) (xy 128.549123 -404.323669) (xy 128.549121 -404.256365)
			(xy 128.557164 -404.189543) (xy 128.573135 -404.124161) (xy 128.596807 -404.061158) (xy 128.62784 -404.001435)
			(xy 128.665789 -403.94585) (xy 128.687576 -403.920198) (xy 128.693353 -403.913039) (xy 128.69988 -403.895859)
			(xy 128.700276 -403.88667) (xy 128.700276 -403.728682) (xy 128.70065 -403.718505) (xy 128.708448 -403.699702)
			(xy 128.722849 -403.685317) (xy 128.74166 -403.677539) (xy 128.751838 -403.67712) (xy 129.468118 -403.67712)
			(xy 129.478275 -403.677618) (xy 129.497041 -403.685395) (xy 129.511405 -403.699759) (xy 129.519182 -403.718525)
			(xy 129.51968 -403.728682) (xy 129.51968 -403.88667) (xy 129.520109 -403.895855) (xy 129.52661 -403.913039)
			(xy 129.53238 -403.920198) (xy 129.554189 -403.945833) (xy 129.592136 -404.001422) (xy 129.623167 -404.061148)
			(xy 129.646838 -404.124155) (xy 129.662809 -404.189539) (xy 129.670851 -404.256363) (xy 129.670849 -404.32367)
			(xy 129.662803 -404.390494) (xy 129.646828 -404.455877) (xy 129.623154 -404.518882) (xy 129.592119 -404.578606)
			(xy 129.554169 -404.634194) (xy 129.53238 -404.659846) (xy 129.526579 -404.666988) (xy 129.520068 -404.684181)
			(xy 129.51968 -404.693374) (xy 129.51968 -405.186642) (xy 129.520074 -405.195831) (xy 129.5266 -405.213015)
			(xy 129.53238 -405.22017) (xy 129.554161 -405.245827) (xy 129.592109 -405.301413) (xy 129.623142 -405.361136)
			(xy 129.646814 -405.42414) (xy 129.662787 -405.489522) (xy 129.670831 -405.556343) (xy 129.670832 -405.623648)
			(xy 129.662788 -405.690469) (xy 129.646817 -405.755851) (xy 129.623145 -405.818855) (xy 129.592114 -405.878579)
			(xy 129.554167 -405.934166) (xy 129.53238 -405.959818) (xy 129.526591 -405.966968) (xy 129.520072 -405.984155)
			(xy 129.51968 -405.993346) (xy 129.51968 -406.151334) (xy 129.519195 -406.161492) (xy 129.511413 -406.180258)
			(xy 129.497045 -406.194622) (xy 129.478276 -406.202398) (xy 129.468118 -406.202896) (xy 128.751838 -406.202896)
			(xy 128.741673 -406.202406) (xy 128.722886 -406.19464) (xy 128.708501 -406.180275) (xy 128.700708 -406.161498)
			(xy 128.700276 -406.151334) (xy 128.700276 -405.993346) (xy 128.699849 -405.984161) (xy 128.693347 -405.966976)
			(xy 128.687576 -405.959818) (xy 128.665781 -405.934171) (xy 128.62783 -405.878585) (xy 128.596795 -405.818861)
			(xy 128.573121 -405.755856) (xy 128.557148 -405.690472) (xy 128.549103 -405.623649) (xy 127.42108 -405.623649)
			(xy 127.392181 -405.679127) (xy 127.354095 -405.734762) (xy 127.332232 -405.760428) (xy 127.326433 -405.767571)
			(xy 127.319922 -405.784763) (xy 127.319532 -405.793956) (xy 127.319532 -406.286208) (xy 127.319954 -406.295394)
			(xy 127.326461 -406.312577) (xy 127.332232 -406.319736) (xy 127.354063 -406.345428) (xy 127.392151 -406.401059)
			(xy 127.423301 -406.460852) (xy 127.447066 -406.523945) (xy 127.463103 -406.589431) (xy 127.471181 -406.656366)
			(xy 127.471183 -406.72373) (xy 130.749245 -406.72373) (xy 130.749248 -406.656422) (xy 130.757295 -406.589598)
			(xy 130.773271 -406.524214) (xy 130.796947 -406.461208) (xy 130.827983 -406.401484) (xy 130.865935 -406.345896)
			(xy 130.887724 -406.320244) (xy 130.89353 -406.313105) (xy 130.900038 -406.29591) (xy 130.900424 -406.286716)
			(xy 130.900424 -405.793448) (xy 130.899985 -405.784264) (xy 130.893491 -405.76708) (xy 130.887724 -405.75992)
			(xy 130.865933 -405.734271) (xy 130.827985 -405.678684) (xy 130.796953 -405.61896) (xy 130.773281 -405.555955)
			(xy 130.757309 -405.490572) (xy 130.749265 -405.42375) (xy 130.749265 -405.356444) (xy 130.75731 -405.289622)
			(xy 130.773283 -405.22424) (xy 130.796955 -405.161235) (xy 130.827988 -405.101511) (xy 130.865936 -405.045924)
			(xy 130.887724 -405.020272) (xy 130.893518 -405.013125) (xy 130.900033 -404.995936) (xy 130.900424 -404.986744)
			(xy 130.900424 -404.828756) (xy 130.900786 -404.818596) (xy 130.908601 -404.799838) (xy 130.923016 -404.785515)
			(xy 130.941823 -404.777822) (xy 130.951986 -404.777448) (xy 131.668266 -404.777448) (xy 131.678391 -404.777955)
			(xy 131.697113 -404.785673) (xy 131.711471 -404.799953) (xy 131.71929 -404.818633) (xy 131.719828 -404.828756)
			(xy 131.719828 -404.986744) (xy 131.720211 -404.995934) (xy 131.726743 -405.013119) (xy 131.732528 -405.020272)
			(xy 131.754313 -405.045927) (xy 131.792264 -405.101512) (xy 131.823299 -405.161235) (xy 131.846974 -405.224239)
			(xy 131.862948 -405.289622) (xy 131.870993 -405.356444) (xy 131.870993 -405.42375) (xy 131.862949 -405.490573)
			(xy 131.846975 -405.555955) (xy 131.823302 -405.618959) (xy 131.792267 -405.678683) (xy 131.754316 -405.734268)
			(xy 131.732528 -405.75992) (xy 131.726732 -405.767065) (xy 131.720219 -405.784256) (xy 131.719828 -405.793448)
			(xy 131.719828 -406.286716) (xy 131.720224 -406.295905) (xy 131.726747 -406.313089) (xy 131.732528 -406.320244)
			(xy 131.754285 -406.345922) (xy 131.792237 -406.401504) (xy 131.823274 -406.461223) (xy 131.84695 -406.524225)
			(xy 131.862926 -406.589604) (xy 131.870973 -406.656424) (xy 131.870976 -406.723728) (xy 131.862934 -406.790548)
			(xy 131.846964 -406.855929) (xy 131.823293 -406.918933) (xy 131.792262 -406.978655) (xy 131.754315 -407.03424)
			(xy 131.732528 -407.059892) (xy 131.726744 -407.067045) (xy 131.720224 -407.08423) (xy 131.719828 -407.09342)
			(xy 131.719828 -407.251408) (xy 131.719385 -407.261559) (xy 131.711592 -407.280306) (xy 131.697203 -407.294628)
			(xy 131.678419 -407.302333) (xy 131.668266 -407.302716) (xy 130.951986 -407.302716) (xy 130.941853 -407.302283)
			(xy 130.923123 -407.294543) (xy 130.908766 -407.28024) (xy 130.900955 -407.261539) (xy 130.900424 -407.251408)
			(xy 130.900424 -407.09342) (xy 130.899999 -407.084235) (xy 130.893495 -407.06705) (xy 130.887724 -407.059892)
			(xy 130.865905 -407.034266) (xy 130.827958 -406.978675) (xy 130.796927 -406.918948) (xy 130.773257 -406.85594)
			(xy 130.757287 -406.790555) (xy 130.749245 -406.72373) (xy 127.471183 -406.72373) (xy 127.471183 -406.723786)
			(xy 127.463111 -406.790722) (xy 127.44708 -406.856209) (xy 127.423321 -406.919304) (xy 127.392176 -406.9791)
			(xy 127.354093 -407.034734) (xy 127.332232 -407.0604) (xy 127.326445 -407.067551) (xy 127.319926 -407.084737)
			(xy 127.319532 -407.093928) (xy 127.319532 -407.251408) (xy 127.319022 -407.261513) (xy 127.311288 -407.280185)
			(xy 127.296999 -407.294479) (xy 127.278329 -407.302219) (xy 127.268224 -407.302716) (xy 126.551944 -407.302716)
			(xy 126.541826 -407.302248) (xy 126.523127 -407.294518) (xy 126.508812 -407.280217) (xy 126.501062 -407.261525)
			(xy 126.500636 -407.251408) (xy 126.500636 -407.093928) (xy 126.500204 -407.084743) (xy 126.493705 -407.067559)
			(xy 126.487936 -407.0604) (xy 126.466039 -407.034761) (xy 126.427949 -406.979124) (xy 126.396798 -406.919324)
			(xy 126.373034 -406.856224) (xy 126.357 -406.790731) (xy 126.348926 -406.723789) (xy 123.070881 -406.723789)
			(xy 123.062847 -406.790548) (xy 123.046877 -406.855929) (xy 123.023207 -406.918932) (xy 122.992176 -406.978654)
			(xy 122.95423 -407.03424) (xy 122.932444 -407.059892) (xy 122.926661 -407.067047) (xy 122.92014 -407.08423)
			(xy 122.919744 -407.09342) (xy 122.919744 -407.251408) (xy 122.919286 -407.261557) (xy 122.911496 -407.280301)
			(xy 122.897111 -407.294623) (xy 122.878333 -407.30233) (xy 122.868182 -407.302716) (xy 122.151902 -407.302716)
			(xy 122.14177 -407.30227) (xy 122.123041 -407.294535) (xy 122.108683 -407.280236) (xy 122.100871 -407.261538)
			(xy 122.10034 -407.251408) (xy 122.10034 -407.09342) (xy 122.099911 -407.084235) (xy 122.09341 -407.067051)
			(xy 122.08764 -407.059892) (xy 122.065821 -407.034266) (xy 122.027873 -406.978676) (xy 121.996841 -406.918949)
			(xy 121.97317 -406.855941) (xy 121.957199 -406.790555) (xy 121.949157 -406.72373) (xy 118.67112 -406.72373)
			(xy 118.67112 -406.723787) (xy 118.663047 -406.790724) (xy 118.647013 -406.856212) (xy 118.62325 -406.919308)
			(xy 118.5921 -406.979103) (xy 118.554012 -407.034736) (xy 118.532148 -407.0604) (xy 118.526362 -407.067553)
			(xy 118.519843 -407.084738) (xy 118.519448 -407.093928) (xy 118.519448 -407.251408) (xy 118.518922 -407.261511)
			(xy 118.511191 -407.28018) (xy 118.496907 -407.294473) (xy 118.478243 -407.302216) (xy 118.46814 -407.302716)
			(xy 117.75186 -407.302716) (xy 117.741751 -407.302248) (xy 117.723075 -407.2945) (xy 117.708782 -407.280198)
			(xy 117.701046 -407.261518) (xy 117.700552 -407.251408) (xy 117.700552 -407.093928) (xy 117.700117 -407.084744)
			(xy 117.693619 -407.06756) (xy 117.687852 -407.0604) (xy 117.665955 -407.034762) (xy 117.627864 -406.979124)
			(xy 117.596711 -406.919325) (xy 117.572947 -406.856225) (xy 117.556912 -406.790732) (xy 117.548838 -406.72379)
			(xy 109.19485 -406.72379) (xy 109.220031 -406.883787) (xy 109.244004 -407.087609) (xy 109.260006 -407.292212)
			(xy 109.268013 -407.497282) (xy 109.268514 -407.599896) (xy 109.268013 -407.70251) (xy 109.260006 -407.90758)
			(xy 109.244004 -408.112183) (xy 109.220031 -408.316005) (xy 109.188124 -408.518737) (xy 109.148332 -408.720069)
			(xy 109.100715 -408.919696) (xy 109.045345 -409.117312) (xy 108.982308 -409.312618) (xy 108.911698 -409.505316)
			(xy 108.904083 -409.523827) (xy 115.349227 -409.523827) (xy 115.349231 -409.456519) (xy 115.357278 -409.389695)
			(xy 115.373254 -409.324311) (xy 115.396929 -409.261305) (xy 115.427964 -409.20158) (xy 115.465915 -409.145993)
			(xy 115.487704 -409.12034) (xy 115.493509 -409.113201) (xy 115.500019 -409.096006) (xy 115.500404 -409.086812)
			(xy 115.500404 -408.593544) (xy 115.499972 -408.584359) (xy 115.493473 -408.567175) (xy 115.487704 -408.560016)
			(xy 115.465909 -408.53437) (xy 115.427963 -408.478782) (xy 115.396932 -408.419057) (xy 115.373261 -408.356052)
			(xy 115.35729 -408.290669) (xy 115.349247 -408.223846) (xy 115.349248 -408.156541) (xy 115.357292 -408.089719)
			(xy 115.373265 -408.024337) (xy 115.396937 -407.961332) (xy 115.427969 -407.901608) (xy 115.465917 -407.846021)
			(xy 115.487704 -407.820368) (xy 115.493497 -407.81322) (xy 115.500014 -407.796032) (xy 115.500404 -407.78684)
			(xy 115.500404 -407.628852) (xy 115.500783 -407.618694) (xy 115.508595 -407.59994) (xy 115.523004 -407.585618)
			(xy 115.541806 -407.577921) (xy 115.551966 -407.577544) (xy 116.268246 -407.577544) (xy 116.278376 -407.577989)
			(xy 116.297099 -407.585733) (xy 116.311454 -407.600031) (xy 116.319271 -407.618724) (xy 116.319808 -407.628852)
			(xy 116.319808 -407.78684) (xy 116.320197 -407.79603) (xy 116.326725 -407.813214) (xy 116.332508 -407.820368)
			(xy 116.354289 -407.846026) (xy 116.392242 -407.90161) (xy 116.423279 -407.961333) (xy 116.446954 -408.024336)
			(xy 116.462929 -408.089718) (xy 116.470975 -408.156541) (xy 116.470976 -408.223847) (xy 116.462931 -408.29067)
			(xy 116.446958 -408.356052) (xy 116.423283 -408.419056) (xy 116.392248 -408.478779) (xy 116.354297 -408.534365)
			(xy 116.332508 -408.560016) (xy 116.326723 -408.56717) (xy 116.320201 -408.584354) (xy 116.319808 -408.593544)
			(xy 116.319808 -409.086812) (xy 116.320211 -409.096) (xy 116.326729 -409.113184) (xy 116.332508 -409.12034)
			(xy 116.354262 -409.146021) (xy 116.392215 -409.201602) (xy 116.423253 -409.261321) (xy 116.44693 -409.324322)
			(xy 116.462907 -409.389701) (xy 116.470955 -409.456521) (xy 116.470958 -409.523825) (xy 116.462917 -409.590646)
			(xy 116.446946 -409.656026) (xy 116.423275 -409.71903) (xy 116.392243 -409.778752) (xy 116.354295 -409.834337)
			(xy 116.332508 -409.859988) (xy 116.326692 -409.86712) (xy 116.320189 -409.884321) (xy 116.319808 -409.893516)
			(xy 116.319808 -410.051504) (xy 116.319382 -410.061657) (xy 116.311586 -410.080408) (xy 116.297191 -410.094731)
			(xy 116.278401 -410.102432) (xy 116.268246 -410.102812) (xy 115.551966 -410.102812) (xy 115.541844 -410.102303)
			(xy 115.523131 -410.094574) (xy 115.508778 -410.080295) (xy 115.500951 -410.061624) (xy 115.500404 -410.051504)
			(xy 115.500404 -409.893516) (xy 115.499985 -409.88433) (xy 115.493477 -409.867145) (xy 115.487704 -409.859988)
			(xy 115.465882 -409.834364) (xy 115.427937 -409.778773) (xy 115.396907 -409.719045) (xy 115.373238 -409.656037)
			(xy 115.357268 -409.590652) (xy 115.349227 -409.523827) (xy 108.904083 -409.523827) (xy 108.833624 -409.695112)
			(xy 108.748204 -409.881718) (xy 108.655568 -410.064848) (xy 108.555858 -410.244225) (xy 108.449225 -410.419575)
			(xy 108.335832 -410.590631) (xy 108.312002 -410.623701) (xy 117.548849 -410.623701) (xy 117.54885 -410.556275)
			(xy 117.556929 -410.489335) (xy 117.572967 -410.423844) (xy 117.596736 -410.360746) (xy 117.627891 -410.30095)
			(xy 117.665985 -410.245316) (xy 117.687852 -410.219652) (xy 117.693658 -410.212514) (xy 117.700166 -410.195318)
			(xy 117.700552 -410.186124) (xy 117.700552 -409.693872) (xy 117.700144 -409.684685) (xy 117.693627 -409.667501)
			(xy 117.687852 -409.660344) (xy 117.665998 -409.63467) (xy 117.627906 -409.579038) (xy 117.596751 -409.519243)
			(xy 117.572984 -409.456148) (xy 117.556946 -409.390659) (xy 117.548869 -409.323721) (xy 117.548868 -409.256297)
			(xy 117.556943 -409.189359) (xy 117.572979 -409.12387) (xy 117.596744 -409.060773) (xy 117.627896 -409.000978)
			(xy 117.665987 -408.945344) (xy 117.687852 -408.91968) (xy 117.693646 -408.912533) (xy 117.700161 -408.895344)
			(xy 117.700552 -408.886152) (xy 117.700552 -408.728672) (xy 117.701061 -408.718567) (xy 117.708799 -408.699898)
			(xy 117.723088 -408.685606) (xy 117.741756 -408.677863) (xy 117.75186 -408.677364) (xy 118.46814 -408.677364)
			(xy 118.478247 -408.677852) (xy 118.496919 -408.685596) (xy 118.511211 -408.699891) (xy 118.518951 -408.718565)
			(xy 118.519448 -408.728672) (xy 118.519448 -408.886152) (xy 118.519893 -408.895335) (xy 118.526384 -408.912519)
			(xy 118.532148 -408.91968) (xy 118.554026 -408.945335) (xy 118.592117 -409.000969) (xy 118.62327 -409.060767)
			(xy 118.647036 -409.123865) (xy 118.663072 -409.189356) (xy 118.671148 -409.256296) (xy 118.671147 -409.323722)
			(xy 118.663069 -409.390662) (xy 118.647031 -409.456152) (xy 118.623263 -409.51925) (xy 118.620848 -409.523886)
			(xy 119.748996 -409.523886) (xy 119.748999 -409.45646) (xy 119.757078 -409.389519) (xy 119.773118 -409.324028)
			(xy 119.796886 -409.26093) (xy 119.828041 -409.201132) (xy 119.866134 -409.145497) (xy 119.888 -409.119832)
			(xy 119.893808 -409.112695) (xy 119.900316 -409.095498) (xy 119.9007 -409.086304) (xy 119.9007 -408.594052)
			(xy 119.900265 -408.584867) (xy 119.893769 -408.567683) (xy 119.888 -408.560524) (xy 119.866128 -408.534865)
			(xy 119.82804 -408.47923) (xy 119.796889 -408.419433) (xy 119.773126 -408.356335) (xy 119.757091 -408.290845)
			(xy 119.749015 -408.223906) (xy 119.749016 -408.156482) (xy 119.757093 -408.089543) (xy 119.773129 -408.024054)
			(xy 119.796894 -407.960956) (xy 119.828046 -407.90116) (xy 119.866136 -407.845525) (xy 119.888 -407.81986)
			(xy 119.893796 -407.812714) (xy 119.900311 -407.795524) (xy 119.9007 -407.786332) (xy 119.9007 -407.628852)
			(xy 119.901146 -407.61874) (xy 119.908899 -407.600061) (xy 119.923208 -407.585768) (xy 119.941896 -407.578035)
			(xy 119.952008 -407.577544) (xy 120.668288 -407.577544) (xy 120.678389 -407.578094) (xy 120.697056 -407.585817)
			(xy 120.71135 -407.600093) (xy 120.719095 -407.618752) (xy 120.719596 -407.628852) (xy 120.719596 -407.786332)
			(xy 120.719991 -407.795521) (xy 120.726515 -407.812705) (xy 120.732296 -407.81986) (xy 120.754152 -407.845532)
			(xy 120.792241 -407.901165) (xy 120.823393 -407.96096) (xy 120.847158 -408.024056) (xy 120.863194 -408.089545)
			(xy 120.87127 -408.156482) (xy 120.871271 -408.223906) (xy 120.863196 -408.290843) (xy 120.847161 -408.356332)
			(xy 120.823398 -408.419429) (xy 120.792248 -408.479225) (xy 120.75416 -408.534859) (xy 120.732296 -408.560524)
			(xy 120.726506 -408.567674) (xy 120.719988 -408.584861) (xy 120.719596 -408.594052) (xy 120.719596 -409.086304)
			(xy 120.720005 -409.095491) (xy 120.72652 -409.112675) (xy 120.732296 -409.119832) (xy 120.754125 -409.145526)
			(xy 120.792215 -409.201157) (xy 120.823367 -409.260949) (xy 120.847134 -409.324042) (xy 120.863172 -409.389527)
			(xy 120.871251 -409.456463) (xy 120.871254 -409.523883) (xy 120.863181 -409.590819) (xy 120.84715 -409.656306)
			(xy 120.823389 -409.719402) (xy 120.792243 -409.779197) (xy 120.754158 -409.834831) (xy 120.732296 -409.860496)
			(xy 120.726518 -409.867654) (xy 120.719992 -409.884835) (xy 120.719596 -409.894024) (xy 120.719596 -410.051504)
			(xy 120.719187 -410.061627) (xy 120.711437 -410.080332) (xy 120.697118 -410.094646) (xy 120.678411 -410.10239)
			(xy 120.668288 -410.102812) (xy 119.952008 -410.102812) (xy 119.941888 -410.102378) (xy 119.923186 -410.094634)
			(xy 119.908872 -410.080324) (xy 119.901125 -410.061624) (xy 119.9007 -410.051504) (xy 119.9007 -409.894024)
			(xy 119.900278 -409.884838) (xy 119.893773 -409.867654) (xy 119.888 -409.860496) (xy 119.866101 -409.83486)
			(xy 119.828013 -409.779221) (xy 119.796864 -409.719421) (xy 119.773102 -409.65632) (xy 119.757069 -409.590828)
			(xy 119.748996 -409.523886) (xy 118.620848 -409.523886) (xy 118.592108 -409.579046) (xy 118.554015 -409.63468)
			(xy 118.532148 -409.660344) (xy 118.526344 -409.667484) (xy 118.519835 -409.684679) (xy 118.519448 -409.693872)
			(xy 118.519448 -410.186124) (xy 118.519858 -410.195311) (xy 118.526373 -410.212495) (xy 118.532148 -410.219652)
			(xy 118.553998 -410.245329) (xy 118.592091 -410.300961) (xy 118.623245 -410.360755) (xy 118.647012 -410.42385)
			(xy 118.663051 -410.489338) (xy 118.671128 -410.556276) (xy 118.67113 -410.623641) (xy 121.949169 -410.623641)
			(xy 121.94917 -410.556335) (xy 121.957216 -410.489511) (xy 121.97319 -410.424128) (xy 121.996865 -410.361123)
			(xy 122.0279 -410.301399) (xy 122.065851 -410.245812) (xy 122.08764 -410.22016) (xy 122.093441 -410.213018)
			(xy 122.099952 -410.195825) (xy 122.10034 -410.186632) (xy 122.10034 -409.693364) (xy 122.099938 -409.684176)
			(xy 122.093418 -409.666992) (xy 122.08764 -409.659836) (xy 122.065864 -409.634174) (xy 122.027915 -409.578589)
			(xy 121.996881 -409.518867) (xy 121.973208 -409.455864) (xy 121.957234 -409.390483) (xy 121.949189 -409.323661)
			(xy 121.949188 -409.256357) (xy 121.957231 -409.189535) (xy 121.973202 -409.124154) (xy 121.996874 -409.06115)
			(xy 122.027906 -409.001427) (xy 122.065853 -408.94584) (xy 122.08764 -408.920188) (xy 122.093429 -408.913038)
			(xy 122.099947 -408.895851) (xy 122.10034 -408.88666) (xy 122.10034 -408.728672) (xy 122.100699 -408.718511)
			(xy 122.108512 -408.69975) (xy 122.122928 -408.685426) (xy 122.141738 -408.677735) (xy 122.151902 -408.677364)
			(xy 122.868182 -408.677364) (xy 122.878311 -408.677842) (xy 122.897036 -408.685568) (xy 122.911394 -408.699858)
			(xy 122.919209 -408.718546) (xy 122.919744 -408.728672) (xy 122.919744 -408.88666) (xy 122.920186 -408.895844)
			(xy 122.926679 -408.913028) (xy 122.932444 -408.920188) (xy 122.954244 -408.94583) (xy 122.992193 -409.001418)
			(xy 123.023227 -409.061143) (xy 123.0469 -409.124148) (xy 123.062873 -409.189532) (xy 123.070916 -409.256356)
			(xy 123.070915 -409.323662) (xy 123.062869 -409.390486) (xy 123.046895 -409.455869) (xy 123.02322 -409.518874)
			(xy 123.020646 -409.523827) (xy 124.149291 -409.523827) (xy 124.149295 -409.456519) (xy 124.157343 -409.389693)
			(xy 124.173321 -409.324308) (xy 124.197 -409.261302) (xy 124.22804 -409.201577) (xy 124.265997 -409.145992)
			(xy 124.287788 -409.12034) (xy 124.293591 -409.113199) (xy 124.300102 -409.096005) (xy 124.300488 -409.086812)
			(xy 124.300488 -408.593544) (xy 124.300059 -408.584359) (xy 124.293559 -408.567174) (xy 124.287788 -408.560016)
			(xy 124.265991 -408.534371) (xy 124.228039 -408.478785) (xy 124.197004 -408.419061) (xy 124.173329 -408.356055)
			(xy 124.157355 -408.290671) (xy 124.149311 -408.223847) (xy 124.149312 -408.156541) (xy 124.157357 -408.089717)
			(xy 124.173333 -408.024333) (xy 124.197008 -407.961328) (xy 124.228045 -407.901605) (xy 124.265998 -407.84602)
			(xy 124.287788 -407.820368) (xy 124.293579 -407.813219) (xy 124.300097 -407.796031) (xy 124.300488 -407.78684)
			(xy 124.300488 -407.628852) (xy 124.300882 -407.618696) (xy 124.308691 -407.599945) (xy 124.323096 -407.585624)
			(xy 124.341892 -407.577924) (xy 124.35205 -407.577544) (xy 125.06833 -407.577544) (xy 125.078459 -407.578002)
			(xy 125.097182 -407.58574) (xy 125.111537 -407.600035) (xy 125.119355 -407.618725) (xy 125.119892 -407.628852)
			(xy 125.119892 -407.78684) (xy 125.120285 -407.796029) (xy 125.126811 -407.813213) (xy 125.132592 -407.820368)
			(xy 125.154371 -407.846027) (xy 125.192318 -407.901613) (xy 125.22335 -407.961336) (xy 125.247022 -408.02434)
			(xy 125.262994 -408.089721) (xy 125.271039 -408.156542) (xy 125.271039 -408.223846) (xy 125.262997 -408.290667)
			(xy 125.247025 -408.356049) (xy 125.223355 -408.419053) (xy 125.192324 -408.478776) (xy 125.154378 -408.534363)
			(xy 125.132592 -408.560016) (xy 125.126805 -408.567168) (xy 125.120285 -408.584353) (xy 125.119892 -408.593544)
			(xy 125.119892 -409.086812) (xy 125.120298 -409.096) (xy 125.126815 -409.113184) (xy 125.132592 -409.12034)
			(xy 125.154343 -409.146022) (xy 125.192291 -409.201605) (xy 125.223324 -409.261324) (xy 125.246998 -409.324325)
			(xy 125.262972 -409.389703) (xy 125.271019 -409.456522) (xy 125.271022 -409.523824) (xy 125.262982 -409.590643)
			(xy 125.247014 -409.656023) (xy 125.223347 -409.719026) (xy 125.192319 -409.778749) (xy 125.154377 -409.834336)
			(xy 125.132592 -409.859988) (xy 125.126775 -409.867118) (xy 125.120273 -409.88432) (xy 125.119892 -409.893516)
			(xy 125.119892 -410.051504) (xy 125.119481 -410.061659) (xy 125.111683 -410.080413) (xy 125.097283 -410.094737)
			(xy 125.078487 -410.102435) (xy 125.06833 -410.102812) (xy 124.35205 -410.102812) (xy 124.341933 -410.102234)
			(xy 124.323223 -410.094532) (xy 124.308867 -410.080274) (xy 124.301036 -410.061618) (xy 124.300488 -410.051504)
			(xy 124.300488 -409.893516) (xy 124.300073 -409.884329) (xy 124.293563 -409.867145) (xy 124.287788 -409.859988)
			(xy 124.265963 -409.834366) (xy 124.228013 -409.778776) (xy 124.196978 -409.719049) (xy 124.173305 -409.65604)
			(xy 124.157333 -409.590654) (xy 124.149291 -409.523827) (xy 123.020646 -409.523827) (xy 122.992184 -409.578598)
			(xy 122.954233 -409.634184) (xy 122.932444 -409.659836) (xy 122.926643 -409.666978) (xy 122.920132 -409.684171)
			(xy 122.919744 -409.693364) (xy 122.919744 -410.186632) (xy 122.920151 -410.195819) (xy 122.926668 -410.213003)
			(xy 122.932444 -410.22016) (xy 122.954216 -410.245825) (xy 122.992167 -410.301409) (xy 123.023202 -410.361131)
			(xy 123.046876 -410.424134) (xy 123.062851 -410.489514) (xy 123.070896 -410.556336) (xy 123.070898 -410.62364)
			(xy 123.070891 -410.623701) (xy 126.348937 -410.623701) (xy 126.348938 -410.556275) (xy 126.357016 -410.489335)
			(xy 126.373055 -410.423845) (xy 126.396822 -410.360747) (xy 126.427977 -410.300951) (xy 126.46607 -410.245317)
			(xy 126.487936 -410.219652) (xy 126.49374 -410.212512) (xy 126.500249 -410.195317) (xy 126.500636 -410.186124)
			(xy 126.500636 -409.693872) (xy 126.500231 -409.684684) (xy 126.493713 -409.667501) (xy 126.487936 -409.660344)
			(xy 126.466083 -409.63467) (xy 126.427991 -409.579037) (xy 126.396838 -409.519243) (xy 126.373071 -409.456147)
			(xy 126.357034 -409.390659) (xy 126.348957 -409.323721) (xy 126.348956 -409.256297) (xy 126.357031 -409.189359)
			(xy 126.373066 -409.12387) (xy 126.396831 -409.060774) (xy 126.427982 -409.000978) (xy 126.466071 -408.945345)
			(xy 126.487936 -408.91968) (xy 126.493728 -408.912532) (xy 126.500245 -408.895343) (xy 126.500636 -408.886152)
			(xy 126.500636 -408.728672) (xy 126.500994 -408.718543) (xy 126.508758 -408.699832) (xy 126.523093 -408.685517)
			(xy 126.541815 -408.67778) (xy 126.551944 -408.677364) (xy 127.268224 -408.677364) (xy 127.27833 -408.677864)
			(xy 127.297002 -408.685603) (xy 127.311294 -408.699895) (xy 127.319035 -408.718566) (xy 127.319532 -408.728672)
			(xy 127.319532 -408.886152) (xy 127.31998 -408.895335) (xy 127.326469 -408.912519) (xy 127.332232 -408.91968)
			(xy 127.354107 -408.945336) (xy 127.392193 -409.000973) (xy 127.423341 -409.06077) (xy 127.447103 -409.123868)
			(xy 127.463137 -409.189358) (xy 127.471211 -409.256297) (xy 127.47121 -409.323721) (xy 127.463134 -409.39066)
			(xy 127.447098 -409.456149) (xy 127.423334 -409.519246) (xy 127.420948 -409.523827) (xy 128.549082 -409.523827)
			(xy 128.549085 -409.456519) (xy 128.557133 -409.389693) (xy 128.573111 -409.324308) (xy 128.59679 -409.261302)
			(xy 128.627829 -409.201578) (xy 128.665785 -409.145991) (xy 128.687576 -409.12034) (xy 128.693378 -409.113198)
			(xy 128.69989 -409.096005) (xy 128.700276 -409.086812) (xy 128.700276 -408.593544) (xy 128.69985 -408.584358)
			(xy 128.693348 -408.567174) (xy 128.687576 -408.560016) (xy 128.665779 -408.534371) (xy 128.627828 -408.478784)
			(xy 128.596793 -408.41906) (xy 128.573119 -408.356055) (xy 128.557146 -408.290671) (xy 128.549102 -408.223847)
			(xy 128.549103 -408.156541) (xy 128.557148 -408.089717) (xy 128.573123 -408.024334) (xy 128.596798 -407.961329)
			(xy 128.627835 -407.901605) (xy 128.665787 -407.84602) (xy 128.687576 -407.820368) (xy 128.693366 -407.813218)
			(xy 128.699885 -407.796031) (xy 128.700276 -407.78684) (xy 128.700276 -407.628852) (xy 128.700682 -407.618698)
			(xy 128.708489 -407.599949) (xy 128.72289 -407.585628) (xy 128.741682 -407.577926) (xy 128.751838 -407.577544)
			(xy 129.468118 -407.577544) (xy 129.478246 -407.578012) (xy 129.496969 -407.585746) (xy 129.511325 -407.600038)
			(xy 129.519143 -407.618726) (xy 129.51968 -407.628852) (xy 129.51968 -407.78684) (xy 129.520075 -407.796029)
			(xy 129.5266 -407.813213) (xy 129.53238 -407.820368) (xy 129.554159 -407.846027) (xy 129.592107 -407.901613)
			(xy 129.62314 -407.961336) (xy 129.646812 -408.024339) (xy 129.662785 -408.08972) (xy 129.67083 -408.156542)
			(xy 129.67083 -408.223846) (xy 129.662787 -408.290668) (xy 129.646816 -408.356049) (xy 129.623145 -408.419053)
			(xy 129.592113 -408.478777) (xy 129.554167 -408.534364) (xy 129.53238 -408.560016) (xy 129.526592 -408.567167)
			(xy 129.520073 -408.584353) (xy 129.51968 -408.593544) (xy 129.51968 -409.086812) (xy 129.520089 -409.095999)
			(xy 129.526604 -409.113183) (xy 129.53238 -409.12034) (xy 129.554131 -409.146022) (xy 129.59208 -409.201604)
			(xy 129.623114 -409.261324) (xy 129.646788 -409.324325) (xy 129.662763 -409.389703) (xy 129.670809 -409.456522)
			(xy 129.670813 -409.523824) (xy 129.662772 -409.590644) (xy 129.646804 -409.656024) (xy 129.623136 -409.719026)
			(xy 129.592108 -409.778749) (xy 129.554165 -409.834335) (xy 129.53238 -409.859988) (xy 129.526561 -409.867117)
			(xy 129.52006 -409.88432) (xy 129.51968 -409.893516) (xy 129.51968 -410.051504) (xy 129.519281 -410.061661)
			(xy 129.511481 -410.080417) (xy 129.497077 -410.094741) (xy 129.478277 -410.102437) (xy 129.468118 -410.102812)
			(xy 128.751838 -410.102812) (xy 128.74172 -410.102244) (xy 128.72301 -410.094538) (xy 128.708654 -410.080277)
			(xy 128.700824 -410.061618) (xy 128.700276 -410.051504) (xy 128.700276 -409.893516) (xy 128.699864 -409.884329)
			(xy 128.693352 -409.867144) (xy 128.687576 -409.859988) (xy 128.665751 -409.834366) (xy 128.627801 -409.778776)
			(xy 128.596768 -409.719048) (xy 128.573095 -409.65604) (xy 128.557124 -409.590654) (xy 128.549082 -409.523827)
			(xy 127.420948 -409.523827) (xy 127.392184 -409.579043) (xy 127.354096 -409.634678) (xy 127.332232 -409.660344)
			(xy 127.326426 -409.667482) (xy 127.319919 -409.684678) (xy 127.319532 -409.693872) (xy 127.319532 -410.186124)
			(xy 127.319946 -410.19531) (xy 127.326459 -410.212494) (xy 127.332232 -410.219652) (xy 127.354079 -410.245331)
			(xy 127.392166 -410.300964) (xy 127.423316 -410.360759) (xy 127.44708 -410.423854) (xy 127.463115 -410.489341)
			(xy 127.471192 -410.556277) (xy 127.471193 -410.623641) (xy 130.749257 -410.623641) (xy 130.749258 -410.556335)
			(xy 130.757303 -410.489512) (xy 130.773278 -410.424129) (xy 130.796952 -410.361123) (xy 130.827986 -410.301399)
			(xy 130.865936 -410.245812) (xy 130.887724 -410.22016) (xy 130.893523 -410.213017) (xy 130.900035 -410.195825)
			(xy 130.900424 -410.186632) (xy 130.900424 -409.693364) (xy 130.900026 -409.684176) (xy 130.893503 -409.666992)
			(xy 130.887724 -409.659836) (xy 130.865948 -409.634174) (xy 130.828 -409.578589) (xy 130.796967 -409.518866)
			(xy 130.773294 -409.455863) (xy 130.757321 -409.390482) (xy 130.749276 -409.323661) (xy 130.749275 -409.256357)
			(xy 130.757318 -409.189536) (xy 130.773289 -409.124154) (xy 130.79696 -409.06115) (xy 130.827991 -409.001427)
			(xy 130.865937 -408.94584) (xy 130.887724 -408.920188) (xy 130.893511 -408.913036) (xy 130.900031 -408.895851)
			(xy 130.900424 -408.88666) (xy 130.900424 -408.728672) (xy 130.900799 -408.718513) (xy 130.908608 -408.699755)
			(xy 130.92302 -408.685432) (xy 130.941825 -408.677738) (xy 130.951986 -408.677364) (xy 131.668266 -408.677364)
			(xy 131.678393 -408.677855) (xy 131.697118 -408.685576) (xy 131.711477 -408.699862) (xy 131.719293 -408.718547)
			(xy 131.719828 -408.728672) (xy 131.719828 -408.88666) (xy 131.720251 -408.895846) (xy 131.726755 -408.913031)
			(xy 131.732528 -408.920188) (xy 131.754328 -408.94583) (xy 131.792279 -409.001417) (xy 131.823314 -409.061142)
			(xy 131.846987 -409.124148) (xy 131.86296 -409.189532) (xy 131.871004 -409.256356) (xy 131.871003 -409.323662)
			(xy 131.862957 -409.390486) (xy 131.846982 -409.45587) (xy 131.823306 -409.518875) (xy 131.79227 -409.578598)
			(xy 131.754317 -409.634184) (xy 131.732528 -409.659836) (xy 131.726725 -409.666976) (xy 131.720216 -409.684171)
			(xy 131.719828 -409.693364) (xy 131.719828 -410.186632) (xy 131.720217 -410.195822) (xy 131.726745 -410.213006)
			(xy 131.732528 -410.22016) (xy 131.754301 -410.245825) (xy 131.792252 -410.301409) (xy 131.823288 -410.36113)
			(xy 131.846963 -410.424133) (xy 131.862938 -410.489514) (xy 131.870984 -410.556336) (xy 131.870986 -410.62364)
			(xy 131.862943 -410.690462) (xy 131.84697 -410.755844) (xy 131.823298 -410.818848) (xy 131.792265 -410.878571)
			(xy 131.754316 -410.934156) (xy 131.732528 -410.959808) (xy 131.726737 -410.966957) (xy 131.720221 -410.984145)
			(xy 131.719828 -410.993336) (xy 131.719828 -411.151324) (xy 131.719399 -411.161476) (xy 131.7116 -411.180224)
			(xy 131.697207 -411.194545) (xy 131.67842 -411.202249) (xy 131.668266 -411.202632) (xy 130.951986 -411.202632)
			(xy 130.941855 -411.202184) (xy 130.923128 -411.194446) (xy 130.908772 -411.180148) (xy 130.900958 -411.161453)
			(xy 130.900424 -411.151324) (xy 130.900424 -410.993336) (xy 130.899991 -410.984151) (xy 130.893493 -410.966967)
			(xy 130.887724 -410.959808) (xy 130.865921 -410.934169) (xy 130.827974 -410.87858) (xy 130.796942 -410.818855)
			(xy 130.773271 -410.755848) (xy 130.757299 -410.690465) (xy 130.749257 -410.623641) (xy 127.471193 -410.623641)
			(xy 127.471193 -410.623699) (xy 127.463119 -410.690635) (xy 127.447087 -410.756123) (xy 127.423326 -410.819219)
			(xy 127.392179 -410.879015) (xy 127.354094 -410.93465) (xy 127.332232 -410.960316) (xy 127.326438 -410.967463)
			(xy 127.319924 -410.984652) (xy 127.319532 -410.993844) (xy 127.319532 -411.151324) (xy 127.319035 -411.16143)
			(xy 127.311296 -411.180103) (xy 127.297003 -411.194396) (xy 127.27833 -411.202135) (xy 127.268224 -411.202632)
			(xy 126.551944 -411.202632) (xy 126.541828 -411.202149) (xy 126.523132 -411.194421) (xy 126.508817 -411.180125)
			(xy 126.501065 -411.161439) (xy 126.500636 -411.151324) (xy 126.500636 -410.993844) (xy 126.500196 -410.98466)
			(xy 126.493702 -410.967476) (xy 126.487936 -410.960316) (xy 126.466055 -410.934664) (xy 126.427964 -410.879029)
			(xy 126.396812 -410.819231) (xy 126.373048 -410.756132) (xy 126.357012 -410.690641) (xy 126.348937 -410.623701)
			(xy 123.070891 -410.623701) (xy 123.062855 -410.690462) (xy 123.046883 -410.755843) (xy 123.023211 -410.818847)
			(xy 122.992179 -410.87857) (xy 122.954231 -410.934156) (xy 122.932444 -410.959808) (xy 122.926655 -410.966958)
			(xy 122.920137 -410.984145) (xy 122.919744 -410.993336) (xy 122.919744 -411.151324) (xy 122.919299 -411.161474)
			(xy 122.911504 -411.180219) (xy 122.897115 -411.19454) (xy 122.878334 -411.202246) (xy 122.868182 -411.202632)
			(xy 122.151902 -411.202632) (xy 122.141772 -411.202171) (xy 122.123046 -411.194439) (xy 122.108688 -411.180144)
			(xy 122.100874 -411.161452) (xy 122.10034 -411.151324) (xy 122.10034 -410.993336) (xy 122.099903 -410.984152)
			(xy 122.093407 -410.966968) (xy 122.08764 -410.959808) (xy 122.065836 -410.934169) (xy 122.027888 -410.878581)
			(xy 121.996855 -410.818855) (xy 121.973183 -410.755849) (xy 121.957211 -410.690465) (xy 121.949169 -410.623641)
			(xy 118.67113 -410.623641) (xy 118.67113 -410.6237) (xy 118.663055 -410.690638) (xy 118.647019 -410.756127)
			(xy 118.623255 -410.819223) (xy 118.592103 -410.879018) (xy 118.554013 -410.934652) (xy 118.532148 -410.960316)
			(xy 118.526356 -410.967464) (xy 118.51984 -410.984653) (xy 118.519448 -410.993844) (xy 118.519448 -411.151324)
			(xy 118.518936 -411.161428) (xy 118.511199 -411.180098) (xy 118.496911 -411.19439) (xy 118.478244 -411.202133)
			(xy 118.46814 -411.202632) (xy 117.75186 -411.202632) (xy 117.741753 -411.202148) (xy 117.72308 -411.194404)
			(xy 117.708787 -411.180107) (xy 117.701048 -411.161431) (xy 117.700552 -411.151324) (xy 117.700552 -410.993844)
			(xy 117.700109 -410.984661) (xy 117.693617 -410.967477) (xy 117.687852 -410.960316) (xy 117.66597 -410.934665)
			(xy 117.627879 -410.879029) (xy 117.596726 -410.819232) (xy 117.57296 -410.756133) (xy 117.556924 -410.690642)
			(xy 117.548849 -410.623701) (xy 108.312002 -410.623701) (xy 108.215852 -410.757133) (xy 108.089466 -410.918827)
			(xy 107.956868 -411.075467) (xy 107.81826 -411.226813) (xy 107.673852 -411.372637) (xy 107.523865 -411.512716)
			(xy 107.368526 -411.646835) (xy 107.208073 -411.774792) (xy 107.04275 -411.896392) (xy 106.872808 -412.011448)
			(xy 106.698507 -412.119787) (xy 106.520111 -412.221242) (xy 106.337893 -412.31566) (xy 106.15213 -412.402896)
			(xy 105.963105 -412.482819) (xy 105.771105 -412.555305) (xy 105.576423 -412.620245) (xy 105.379356 -412.67754)
			(xy 105.180203 -412.727103) (xy 104.979269 -412.768858) (xy 104.776858 -412.802741) (xy 104.57328 -412.828701)
			(xy 104.368843 -412.846698) (xy 104.16386 -412.856706) (xy 103.958643 -412.858708) (xy 103.753504 -412.852702)
			(xy 103.548755 -412.838697) (xy 103.344708 -412.816714) (xy 103.141675 -412.786787) (xy 102.939964 -412.74896)
			(xy 102.739882 -412.703293) (xy 102.541735 -412.649854) (xy 102.345823 -412.588725) (xy 102.152446 -412.519999)
			(xy 101.961897 -412.44378) (xy 101.774467 -412.360184) (xy 101.590441 -412.26934) (xy 101.4101 -412.171385)
			(xy 101.233718 -412.066468) (xy 101.061564 -411.954749) (xy 100.893899 -411.836399) (xy 100.73098 -411.711597)
			(xy 100.573054 -411.580533) (xy 100.420362 -411.443408) (xy 100.273137 -411.30043) (xy 100.131602 -411.151816)
			(xy 99.995973 -410.997794) (xy 99.866456 -410.838597) (xy 99.74325 -410.674468) (xy 99.626541 -410.505657)
			(xy 99.516507 -410.33242) (xy 99.413316 -410.155023) (xy 99.317125 -409.973735) (xy 99.22808 -409.788832)
			(xy 99.146317 -409.600595) (xy 99.071961 -409.409312) (xy 99.005125 -409.215273) (xy 98.94591 -409.018774)
			(xy 98.894407 -408.820115) (xy 98.850693 -408.619597) (xy 98.814837 -408.417526) (xy 98.786892 -408.214211)
			(xy 98.766901 -408.00996) (xy 98.754894 -407.805084) (xy 98.75089 -407.599896) (xy 85.510806 -407.599896)
			(xy 85.511012 -407.600102) (xy 85.518758 -407.618754) (xy 85.51926 -407.628852) (xy 85.51926 -407.786332)
			(xy 85.519664 -407.79552) (xy 85.526183 -407.812703) (xy 85.53196 -407.81986) (xy 85.553818 -407.845531)
			(xy 85.591909 -407.901164) (xy 85.623062 -407.960959) (xy 85.646829 -408.024055) (xy 85.662866 -408.089544)
			(xy 85.670943 -408.156482) (xy 85.670944 -408.223906) (xy 85.662868 -408.290844) (xy 85.646832 -408.356333)
			(xy 85.623067 -408.41943) (xy 85.591915 -408.479226) (xy 85.553825 -408.534859) (xy 85.53196 -408.560524)
			(xy 85.526166 -408.567671) (xy 85.519651 -408.58486) (xy 85.51926 -408.594052) (xy 85.51926 -409.086304)
			(xy 85.519677 -409.09549) (xy 85.526187 -409.112674) (xy 85.53196 -409.119832) (xy 85.55379 -409.145526)
			(xy 85.591882 -409.201155) (xy 85.623037 -409.260947) (xy 85.646805 -409.32404) (xy 85.662844 -409.389526)
			(xy 85.670923 -409.456462) (xy 85.670927 -409.523884) (xy 85.662854 -409.59082) (xy 85.646821 -409.656308)
			(xy 85.623059 -409.719403) (xy 85.59191 -409.779198) (xy 85.553823 -409.834831) (xy 85.53196 -409.860496)
			(xy 85.526178 -409.867651) (xy 85.519655 -409.884834) (xy 85.51926 -409.894024) (xy 85.51926 -410.051504)
			(xy 85.518886 -410.061632) (xy 85.511129 -410.080343) (xy 85.496799 -410.094659) (xy 85.47808 -410.102396)
			(xy 85.467952 -410.102812) (xy 84.751672 -410.102812) (xy 84.741563 -410.102338) (xy 84.722886 -410.094594)
			(xy 84.708593 -410.080293) (xy 84.700857 -410.061613) (xy 84.700364 -410.051504) (xy 84.700364 -409.894024)
			(xy 84.699928 -409.88484) (xy 84.693431 -409.867656) (xy 84.687664 -409.860496) (xy 84.665766 -409.834859)
			(xy 84.627681 -409.77922) (xy 84.596534 -409.719419) (xy 84.572773 -409.656319) (xy 84.556741 -409.590827)
			(xy 84.548669 -409.523886) (xy 83.420495 -409.523886) (xy 83.392063 -409.578599) (xy 83.35411 -409.634184)
			(xy 83.33232 -409.659836) (xy 83.326528 -409.666985) (xy 83.32001 -409.684172) (xy 83.31962 -409.693364)
			(xy 83.31962 -410.186632) (xy 83.32001 -410.195821) (xy 83.326537 -410.213006) (xy 83.33232 -410.22016)
			(xy 83.354093 -410.245825) (xy 83.392045 -410.301408) (xy 83.423081 -410.36113) (xy 83.446757 -410.424133)
			(xy 83.462732 -410.489514) (xy 83.470778 -410.556336) (xy 83.47078 -410.62364) (xy 83.470773 -410.623701)
			(xy 86.748819 -410.623701) (xy 86.74882 -410.556275) (xy 86.756898 -410.489336) (xy 86.772936 -410.423846)
			(xy 86.796702 -410.360748) (xy 86.827855 -410.300952) (xy 86.865947 -410.245317) (xy 86.887812 -410.219652)
			(xy 86.893613 -410.21251) (xy 86.900125 -410.195317) (xy 86.900512 -410.186124) (xy 86.900512 -409.693872)
			(xy 86.900113 -409.684684) (xy 86.893591 -409.6675) (xy 86.887812 -409.660344) (xy 86.865959 -409.634669)
			(xy 86.82787 -409.579036) (xy 86.796718 -409.519242) (xy 86.772952 -409.456146) (xy 86.756916 -409.390658)
			(xy 86.748839 -409.32372) (xy 86.748837 -409.256298) (xy 86.756912 -409.18936) (xy 86.772947 -409.123871)
			(xy 86.79671 -409.060775) (xy 86.82786 -409.000979) (xy 86.865948 -408.945345) (xy 86.887812 -408.91968)
			(xy 86.893601 -408.912529) (xy 86.90012 -408.895343) (xy 86.900512 -408.886152) (xy 86.900512 -408.728672)
			(xy 86.900962 -408.71856) (xy 86.908711 -408.699879) (xy 86.923019 -408.685585) (xy 86.941708 -408.677853)
			(xy 86.95182 -408.677364) (xy 87.6681 -408.677364) (xy 87.678204 -408.677884) (xy 87.696876 -408.685615)
			(xy 87.711169 -408.699901) (xy 87.71891 -408.718568) (xy 87.719408 -408.728672) (xy 87.719408 -408.886152)
			(xy 87.719839 -408.895337) (xy 87.726338 -408.912522) (xy 87.732108 -408.91968) (xy 87.753983 -408.945336)
			(xy 87.792071 -409.000972) (xy 87.823221 -409.060769) (xy 87.846984 -409.123867) (xy 87.863019 -409.189358)
			(xy 87.871093 -409.256297) (xy 87.871092 -409.323721) (xy 87.863015 -409.39066) (xy 87.846979 -409.45615)
			(xy 87.823214 -409.519247) (xy 87.792062 -409.579044) (xy 87.753972 -409.634679) (xy 87.732108 -409.660344)
			(xy 87.726311 -409.667489) (xy 87.719796 -409.68468) (xy 87.719408 -409.693872) (xy 87.719408 -410.186124)
			(xy 87.719805 -410.195313) (xy 87.726328 -410.212497) (xy 87.732108 -410.219652) (xy 87.753956 -410.24533)
			(xy 87.792045 -410.300963) (xy 87.823196 -410.360758) (xy 87.84696 -410.423853) (xy 87.862997 -410.48934)
			(xy 87.871074 -410.556277) (xy 87.871075 -410.623641) (xy 91.149138 -410.623641) (xy 91.14914 -410.556335)
			(xy 91.157185 -410.489512) (xy 91.173158 -410.42413) (xy 91.196831 -410.361125) (xy 91.227864 -410.3014)
			(xy 91.265813 -410.245813) (xy 91.2876 -410.22016) (xy 91.293396 -410.213014) (xy 91.299911 -410.195824)
			(xy 91.3003 -410.186632) (xy 91.3003 -409.693364) (xy 91.299907 -409.684175) (xy 91.293382 -409.666991)
			(xy 91.2876 -409.659836) (xy 91.265825 -409.634174) (xy 91.227879 -409.578588) (xy 91.196847 -409.518865)
			(xy 91.173175 -409.455862) (xy 91.157203 -409.390482) (xy 91.149158 -409.323661) (xy 91.149157 -409.256357)
			(xy 91.157199 -409.189536) (xy 91.17317 -409.124155) (xy 91.19684 -409.061151) (xy 91.227869 -409.001428)
			(xy 91.265814 -408.945841) (xy 91.2876 -408.920188) (xy 91.293384 -408.913034) (xy 91.299906 -408.89585)
			(xy 91.3003 -408.88666) (xy 91.3003 -408.728672) (xy 91.300699 -408.718516) (xy 91.308503 -408.699763)
			(xy 91.322907 -408.685441) (xy 91.341704 -408.677742) (xy 91.351862 -408.677364) (xy 92.068142 -408.677364)
			(xy 92.078274 -408.677793) (xy 92.097001 -408.685539) (xy 92.111357 -408.699843) (xy 92.11917 -408.718542)
			(xy 92.119704 -408.728672) (xy 92.119704 -408.88666) (xy 92.120132 -408.895845) (xy 92.126633 -408.91303)
			(xy 92.132404 -408.920188) (xy 92.154202 -408.945831) (xy 92.192148 -409.00142) (xy 92.223178 -409.061145)
			(xy 92.246848 -409.124151) (xy 92.262819 -409.189534) (xy 92.270862 -409.256356) (xy 92.270861 -409.323662)
			(xy 92.262816 -409.390484) (xy 92.246843 -409.455867) (xy 92.223171 -409.518871) (xy 92.192139 -409.578596)
			(xy 92.154191 -409.634183) (xy 92.132404 -409.659836) (xy 92.12661 -409.666983) (xy 92.120094 -409.684172)
			(xy 92.119704 -409.693364) (xy 92.119704 -410.186632) (xy 92.120098 -410.195821) (xy 92.126623 -410.213005)
			(xy 92.132404 -410.22016) (xy 92.154175 -410.245826) (xy 92.192121 -410.301411) (xy 92.223153 -410.361133)
			(xy 92.246825 -410.424136) (xy 92.262797 -410.489516) (xy 92.270842 -410.556336) (xy 92.270844 -410.623639)
			(xy 92.262802 -410.69046) (xy 92.246832 -410.755841) (xy 92.223163 -410.818845) (xy 92.192134 -410.878568)
			(xy 92.154189 -410.934155) (xy 92.132404 -410.959808) (xy 92.126622 -410.966964) (xy 92.120098 -410.984146)
			(xy 92.119704 -410.993336) (xy 92.119704 -411.151324) (xy 92.119298 -411.161479) (xy 92.111495 -411.180231)
			(xy 92.097094 -411.194554) (xy 92.078299 -411.202253) (xy 92.068142 -411.202632) (xy 91.351862 -411.202632)
			(xy 91.341729 -411.202204) (xy 91.323002 -411.194458) (xy 91.308646 -411.180154) (xy 91.300833 -411.161455)
			(xy 91.3003 -411.151324) (xy 91.3003 -410.993336) (xy 91.299873 -410.984151) (xy 91.293371 -410.966966)
			(xy 91.2876 -410.959808) (xy 91.265798 -410.934168) (xy 91.227852 -410.878579) (xy 91.196822 -410.818853)
			(xy 91.173151 -410.755847) (xy 91.157181 -410.690464) (xy 91.149138 -410.623641) (xy 87.871075 -410.623641)
			(xy 87.871075 -410.623699) (xy 87.863001 -410.690636) (xy 87.846967 -410.756124) (xy 87.823205 -410.81922)
			(xy 87.792057 -410.879016) (xy 87.753971 -410.934651) (xy 87.732108 -410.960316) (xy 87.726323 -410.96747)
			(xy 87.719801 -410.984654) (xy 87.719408 -410.993844) (xy 87.719408 -411.151324) (xy 87.718935 -411.161433)
			(xy 87.711191 -411.180111) (xy 87.69689 -411.194404) (xy 87.67821 -411.20214) (xy 87.6681 -411.202632)
			(xy 86.95182 -411.202632) (xy 86.941716 -411.202099) (xy 86.923045 -411.194374) (xy 86.90875 -411.180092)
			(xy 86.901009 -411.161427) (xy 86.900512 -411.151324) (xy 86.900512 -410.993844) (xy 86.900078 -410.984659)
			(xy 86.893581 -410.967475) (xy 86.887812 -410.960316) (xy 86.865932 -410.934664) (xy 86.827843 -410.879028)
			(xy 86.796692 -410.81923) (xy 86.772928 -410.756131) (xy 86.756894 -410.69064) (xy 86.748819 -410.623701)
			(xy 83.470773 -410.623701) (xy 83.462736 -410.690462) (xy 83.446764 -410.755844) (xy 83.423091 -410.818848)
			(xy 83.392058 -410.878571) (xy 83.354108 -410.934156) (xy 83.33232 -410.959808) (xy 83.32654 -410.966965)
			(xy 83.320015 -410.984146) (xy 83.31962 -410.993336) (xy 83.31962 -411.151324) (xy 83.319199 -411.161477)
			(xy 83.311399 -411.180226) (xy 83.297003 -411.194548) (xy 83.278213 -411.202251) (xy 83.268058 -411.202632)
			(xy 82.551778 -411.202632) (xy 82.541646 -411.202191) (xy 82.522919 -411.194451) (xy 82.508563 -411.18015)
			(xy 82.500749 -411.161454) (xy 82.500216 -411.151324) (xy 82.500216 -410.993336) (xy 82.499785 -410.984151)
			(xy 82.493285 -410.966967) (xy 82.487516 -410.959808) (xy 82.465713 -410.934169) (xy 82.427766 -410.87858)
			(xy 82.396735 -410.818854) (xy 82.373064 -410.755848) (xy 82.357093 -410.690465) (xy 82.349051 -410.623641)
			(xy 79.070987 -410.623641) (xy 79.070987 -410.623699) (xy 79.062913 -410.690636) (xy 79.04688 -410.756124)
			(xy 79.023119 -410.81922) (xy 78.991971 -410.879016) (xy 78.953886 -410.93465) (xy 78.932024 -410.960316)
			(xy 78.926241 -410.967471) (xy 78.919717 -410.984654) (xy 78.919324 -410.993844) (xy 78.919324 -411.151324)
			(xy 78.918835 -411.161431) (xy 78.911094 -411.180106) (xy 78.896799 -411.194399) (xy 78.878123 -411.202137)
			(xy 78.868016 -411.202632) (xy 78.151736 -411.202632) (xy 78.14162 -411.202155) (xy 78.122923 -411.194425)
			(xy 78.108609 -411.180127) (xy 78.100857 -411.16144) (xy 78.100428 -411.151324) (xy 78.100428 -410.993844)
			(xy 78.09999 -410.98466) (xy 78.093495 -410.967476) (xy 78.087728 -410.960316) (xy 78.065847 -410.934664)
			(xy 78.027757 -410.879028) (xy 77.996606 -410.819231) (xy 77.972841 -410.756132) (xy 77.956806 -410.690641)
			(xy 77.948731 -410.623701) (xy 74.670685 -410.623701) (xy 74.662649 -410.690462) (xy 74.646677 -410.755844)
			(xy 74.623005 -410.818848) (xy 74.591972 -410.87857) (xy 74.554023 -410.934156) (xy 74.532236 -410.959808)
			(xy 74.526446 -410.966957) (xy 74.519929 -410.984145) (xy 74.519536 -410.993336) (xy 74.519536 -411.151324)
			(xy 74.519099 -411.161475) (xy 74.511302 -411.180221) (xy 74.496911 -411.194542) (xy 74.478127 -411.202248)
			(xy 74.467974 -411.202632) (xy 73.751694 -411.202632) (xy 73.741563 -411.202177) (xy 73.722837 -411.194442)
			(xy 73.70848 -411.180146) (xy 73.700666 -411.161452) (xy 73.700132 -411.151324) (xy 73.700132 -410.993336)
			(xy 73.699697 -410.984152) (xy 73.6932 -410.966967) (xy 73.687432 -410.959808) (xy 73.665629 -410.934169)
			(xy 73.627681 -410.87858) (xy 73.596649 -410.818855) (xy 73.572977 -410.755849) (xy 73.557005 -410.690465)
			(xy 73.548963 -410.623641) (xy 66.525648 -410.623641) (xy 66.525648 -417.018724) (xy 66.526774 -417.028227)
			(xy 66.535085 -417.04545) (xy 66.549098 -417.058464) (xy 66.566888 -417.065481) (xy 66.576448 -417.065968)
			(xy 140.97254 -417.065968) (xy 140.98212 -417.065577) (xy 140.999954 -417.058578) (xy 141.013983 -417.04553)
			(xy 141.022255 -417.02825) (xy 141.02334 -417.018724) (xy 141.02334 -394.305282) (xy 141.023816 -394.293169)
			(xy 141.031307 -394.270131) (xy 141.045549 -394.250535) (xy 141.065149 -394.236298) (xy 141.088189 -394.228813)
			(xy 141.100302 -394.22832) (xy 154.426158 -394.22832) (xy 154.57678 -394.378688) (xy 154.57678 -397.823825)
			(xy 159.349135 -397.823825) (xy 159.349138 -397.756518) (xy 159.357186 -397.689693) (xy 159.373162 -397.624309)
			(xy 159.396838 -397.561303) (xy 159.427875 -397.501578) (xy 159.465827 -397.44599) (xy 159.487616 -397.420338)
			(xy 159.493423 -397.4132) (xy 159.499931 -397.396004) (xy 159.500316 -397.38681) (xy 159.500316 -396.893542)
			(xy 159.499882 -396.884357) (xy 159.493384 -396.867173) (xy 159.487616 -396.860014) (xy 159.465819 -396.83437)
			(xy 159.427872 -396.778782) (xy 159.396841 -396.719057) (xy 159.373169 -396.656051) (xy 159.357198 -396.590668)
			(xy 159.349155 -396.523845) (xy 159.349156 -396.45654) (xy 159.3572 -396.389717) (xy 159.373174 -396.324334)
			(xy 159.396847 -396.26133) (xy 159.42788 -396.201606) (xy 159.465828 -396.146018) (xy 159.487616 -396.120366)
			(xy 159.493411 -396.11322) (xy 159.499926 -396.09603) (xy 159.500316 -396.086838) (xy 159.500316 -395.92885)
			(xy 159.500804 -395.918684) (xy 159.508569 -395.899895) (xy 159.522934 -395.885509) (xy 159.541713 -395.877718)
			(xy 159.551878 -395.877288) (xy 160.268158 -395.877288) (xy 160.278333 -395.877699) (xy 160.297136 -395.88548)
			(xy 160.311525 -395.89987) (xy 160.319302 -395.918675) (xy 160.31972 -395.92885) (xy 160.31972 -396.086838)
			(xy 160.320108 -396.096028) (xy 160.326637 -396.113212) (xy 160.33242 -396.120366) (xy 160.354199 -396.146026)
			(xy 160.392151 -396.20161) (xy 160.423187 -396.261332) (xy 160.446862 -396.324336) (xy 160.462837 -396.389718)
			(xy 160.470882 -396.45654) (xy 160.470883 -396.523845) (xy 160.46284 -396.590668) (xy 160.446866 -396.65605)
			(xy 160.423193 -396.719054) (xy 160.392159 -396.778777) (xy 160.354208 -396.834362) (xy 160.33242 -396.860014)
			(xy 160.326637 -396.867169) (xy 160.320114 -396.884352) (xy 160.31972 -396.893542) (xy 160.31972 -397.38681)
			(xy 160.320121 -397.395998) (xy 160.326641 -397.413183) (xy 160.33242 -397.420338) (xy 160.354172 -397.44602)
			(xy 160.392124 -397.501601) (xy 160.420549 -397.556296) (xy 161.5488 -397.556296) (xy 161.556874 -397.489359)
			(xy 161.572908 -397.423871) (xy 161.596669 -397.360775) (xy 161.627817 -397.300979) (xy 161.665902 -397.245344)
			(xy 161.687764 -397.219678) (xy 161.69356 -397.212533) (xy 161.700073 -397.195342) (xy 161.700464 -397.18615)
			(xy 161.700464 -397.028924) (xy 161.701004 -397.018821) (xy 161.708727 -397.00015) (xy 161.723007 -396.985856)
			(xy 161.74167 -396.978114) (xy 161.751772 -396.977616) (xy 162.468052 -396.977616) (xy 162.478173 -396.978056)
			(xy 162.496879 -396.985791) (xy 162.511195 -397.000101) (xy 162.51894 -397.018803) (xy 162.51936 -397.028924)
			(xy 162.51936 -397.18615) (xy 162.519803 -397.195333) (xy 162.526295 -397.212518) (xy 162.53206 -397.219678)
			(xy 162.553935 -397.245334) (xy 162.592026 -397.300969) (xy 162.623179 -397.360766) (xy 162.646944 -397.423864)
			(xy 162.66298 -397.489355) (xy 162.671056 -397.556295) (xy 162.671055 -397.62372) (xy 162.662977 -397.69066)
			(xy 162.64694 -397.75615) (xy 162.623173 -397.819247) (xy 162.620757 -397.823885) (xy 163.748903 -397.823885)
			(xy 163.748907 -397.756458) (xy 163.756987 -397.689517) (xy 163.773027 -397.624026) (xy 163.796796 -397.560927)
			(xy 163.827951 -397.50113) (xy 163.866045 -397.445495) (xy 163.887912 -397.41983) (xy 163.893722 -397.412694)
			(xy 163.900228 -397.395497) (xy 163.900612 -397.386302) (xy 163.900612 -396.89405) (xy 163.900175 -396.884866)
			(xy 163.89368 -396.867681) (xy 163.887912 -396.860522) (xy 163.866038 -396.834865) (xy 163.827949 -396.77923)
			(xy 163.796798 -396.719432) (xy 163.773034 -396.656334) (xy 163.756998 -396.590844) (xy 163.748923 -396.523905)
			(xy 163.748924 -396.45648) (xy 163.757001 -396.389541) (xy 163.773038 -396.324051) (xy 163.796804 -396.260954)
			(xy 163.827956 -396.201157) (xy 163.866047 -396.145523) (xy 163.887912 -396.119858) (xy 163.89371 -396.112714)
			(xy 163.900224 -396.095523) (xy 163.900612 -396.08633) (xy 163.900612 -395.92885) (xy 163.901167 -395.91873)
			(xy 163.908873 -395.900015) (xy 163.923138 -395.885658) (xy 163.941803 -395.877832) (xy 163.95192 -395.877288)
			(xy 164.6682 -395.877288) (xy 164.678353 -395.877721) (xy 164.697103 -395.885515) (xy 164.711426 -395.899908)
			(xy 164.719127 -395.918695) (xy 164.719508 -395.92885) (xy 164.719508 -396.08633) (xy 164.719902 -396.095519)
			(xy 164.726426 -396.112703) (xy 164.732208 -396.119858) (xy 164.754062 -396.145531) (xy 164.79215 -396.201165)
			(xy 164.823301 -396.26096) (xy 164.847065 -396.324056) (xy 164.863101 -396.389544) (xy 164.871178 -396.456481)
			(xy 164.871179 -396.523904) (xy 164.863104 -396.590841) (xy 164.84707 -396.65633) (xy 164.823307 -396.719426)
			(xy 164.792158 -396.779222) (xy 164.754071 -396.834857) (xy 164.732208 -396.860522) (xy 164.726421 -396.867674)
			(xy 164.7199 -396.884859) (xy 164.719508 -396.89405) (xy 164.719508 -397.386302) (xy 164.719915 -397.395489)
			(xy 164.726431 -397.412674) (xy 164.732208 -397.41983) (xy 164.754034 -397.445526) (xy 164.792124 -397.501156)
			(xy 164.823276 -397.560948) (xy 164.846898 -397.62366) (xy 165.949096 -397.62366) (xy 165.949096 -397.556355)
			(xy 165.957139 -397.489533) (xy 165.973111 -397.424151) (xy 165.996783 -397.361147) (xy 166.027816 -397.301424)
			(xy 166.065765 -397.245838) (xy 166.087552 -397.220186) (xy 166.093343 -397.213037) (xy 166.09986 -397.195849)
			(xy 166.100252 -397.186658) (xy 166.100252 -397.028924) (xy 166.10074 -397.018777) (xy 166.108519 -397.000035)
			(xy 166.122895 -396.985712) (xy 166.141666 -396.978003) (xy 166.151814 -396.977616) (xy 166.868094 -396.977616)
			(xy 166.878217 -396.978131) (xy 166.896934 -396.985852) (xy 166.911289 -397.000129) (xy 166.919113 -397.018803)
			(xy 166.919656 -397.028924) (xy 166.919656 -397.186658) (xy 166.920096 -397.195842) (xy 166.92659 -397.213026)
			(xy 166.932356 -397.220186) (xy 166.954154 -397.24583) (xy 166.992103 -397.301417) (xy 167.023136 -397.361142)
			(xy 167.046808 -397.424148) (xy 167.062781 -397.489531) (xy 167.070824 -397.556355) (xy 167.070823 -397.62366)
			(xy 167.062778 -397.690484) (xy 167.046804 -397.755867) (xy 167.02313 -397.818872) (xy 167.020556 -397.823825)
			(xy 168.149223 -397.823825) (xy 168.149226 -397.756518) (xy 168.157274 -397.689693) (xy 168.17325 -397.624309)
			(xy 168.196925 -397.561304) (xy 168.22796 -397.501579) (xy 168.265911 -397.445991) (xy 168.2877 -397.420338)
			(xy 168.293505 -397.413199) (xy 168.300015 -397.396004) (xy 168.3004 -397.38681) (xy 168.3004 -396.893542)
			(xy 168.29997 -396.884357) (xy 168.29347 -396.867172) (xy 168.2877 -396.860014) (xy 168.265904 -396.834369)
			(xy 168.227958 -396.778781) (xy 168.196927 -396.719056) (xy 168.173256 -396.656051) (xy 168.157285 -396.590668)
			(xy 168.149243 -396.523845) (xy 168.149244 -396.45654) (xy 168.157288 -396.389717) (xy 168.173261 -396.324335)
			(xy 168.196933 -396.26133) (xy 168.227965 -396.201606) (xy 168.265913 -396.146019) (xy 168.2877 -396.120366)
			(xy 168.293494 -396.113219) (xy 168.30001 -396.09603) (xy 168.3004 -396.086838) (xy 168.3004 -395.92885)
			(xy 168.300904 -395.918686) (xy 168.308665 -395.8999) (xy 168.323026 -395.885515) (xy 168.341799 -395.877721)
			(xy 168.351962 -395.877288) (xy 169.068242 -395.877288) (xy 169.078423 -395.877631) (xy 169.097228 -395.885439)
			(xy 169.111613 -395.89985) (xy 169.119388 -395.918669) (xy 169.119804 -395.92885) (xy 169.119804 -396.086838)
			(xy 169.120195 -396.096027) (xy 169.126722 -396.113212) (xy 169.132504 -396.120366) (xy 169.154281 -396.146027)
			(xy 169.192227 -396.201613) (xy 169.223258 -396.261336) (xy 169.24693 -396.324339) (xy 169.262902 -396.38972)
			(xy 169.270946 -396.456541) (xy 169.270947 -396.523844) (xy 169.262905 -396.590665) (xy 169.246934 -396.656047)
			(xy 169.223264 -396.71905) (xy 169.192235 -396.778774) (xy 169.15429 -396.834361) (xy 169.132504 -396.860014)
			(xy 169.126719 -396.867168) (xy 169.120197 -396.884352) (xy 169.119804 -396.893542) (xy 169.119804 -397.38681)
			(xy 169.120209 -397.395998) (xy 169.126726 -397.413182) (xy 169.132504 -397.420338) (xy 169.154253 -397.446021)
			(xy 169.1922 -397.501604) (xy 169.22062 -397.556296) (xy 170.348863 -397.556296) (xy 170.356939 -397.489357)
			(xy 170.372975 -397.423868) (xy 170.39674 -397.360771) (xy 170.427892 -397.300976) (xy 170.465983 -397.245342)
			(xy 170.487848 -397.219678) (xy 170.493642 -397.212531) (xy 170.500157 -397.195342) (xy 170.500548 -397.18615)
			(xy 170.500548 -397.028924) (xy 170.501103 -397.018823) (xy 170.508823 -397.000155) (xy 170.523098 -396.985862)
			(xy 170.541756 -396.978117) (xy 170.551856 -396.977616) (xy 171.268136 -396.977616) (xy 171.278249 -396.978056)
			(xy 171.296931 -396.985808) (xy 171.311225 -397.000119) (xy 171.318956 -397.01881) (xy 171.319444 -397.028924)
			(xy 171.319444 -397.18615) (xy 171.319891 -397.195333) (xy 171.326381 -397.212517) (xy 171.332144 -397.219678)
			(xy 171.35402 -397.245334) (xy 171.392112 -397.300969) (xy 171.423265 -397.360766) (xy 171.447031 -397.423864)
			(xy 171.463068 -397.489355) (xy 171.471144 -397.556295) (xy 171.471143 -397.62372) (xy 171.463065 -397.69066)
			(xy 171.447027 -397.756151) (xy 171.423259 -397.819248) (xy 171.420874 -397.823826) (xy 172.54899 -397.823826)
			(xy 172.548993 -397.756517) (xy 172.557042 -397.689691) (xy 172.57302 -397.624306) (xy 172.5967 -397.5613)
			(xy 172.62774 -397.501575) (xy 172.665697 -397.44599) (xy 172.687488 -397.420338) (xy 172.693292 -397.413198)
			(xy 172.699803 -397.396004) (xy 172.700188 -397.38681) (xy 172.700188 -396.893542) (xy 172.69976 -396.884357)
			(xy 172.693259 -396.867172) (xy 172.687488 -396.860014) (xy 172.665689 -396.834371) (xy 172.627737 -396.778784)
			(xy 172.596702 -396.71906) (xy 172.573027 -396.656054) (xy 172.557054 -396.59067) (xy 172.54901 -396.523846)
			(xy 172.54901 -396.456539) (xy 172.557056 -396.389715) (xy 172.573032 -396.324332) (xy 172.596708 -396.261327)
			(xy 172.627745 -396.201603) (xy 172.665698 -396.146018) (xy 172.687488 -396.120366) (xy 172.69328 -396.113218)
			(xy 172.699798 -396.09603) (xy 172.700188 -396.086838) (xy 172.700188 -395.92885) (xy 172.700606 -395.918675)
			(xy 172.708384 -395.899872) (xy 172.722772 -395.885484) (xy 172.741575 -395.877706) (xy 172.75175 -395.877288)
			(xy 173.46803 -395.877288) (xy 173.47821 -395.87764) (xy 173.497015 -395.885445) (xy 173.5114 -395.899852)
			(xy 173.519175 -395.91867) (xy 173.519592 -395.92885) (xy 173.519592 -396.086838) (xy 173.519986 -396.096027)
			(xy 173.526511 -396.113211) (xy 173.532292 -396.120366) (xy 173.554069 -396.146027) (xy 173.592016 -396.201613)
			(xy 173.623048 -396.261335) (xy 173.64672 -396.324339) (xy 173.662693 -396.389719) (xy 173.670737 -396.456541)
			(xy 173.670738 -396.523844) (xy 173.662695 -396.590666) (xy 173.646725 -396.656047) (xy 173.623054 -396.719051)
			(xy 173.592024 -396.778774) (xy 173.554078 -396.834361) (xy 173.532292 -396.860014) (xy 173.526506 -396.867167)
			(xy 173.519985 -396.884351) (xy 173.519592 -396.893542) (xy 173.519592 -397.38681) (xy 173.519999 -397.395998)
			(xy 173.526515 -397.413182) (xy 173.532292 -397.420338) (xy 173.554041 -397.446021) (xy 173.591989 -397.501604)
			(xy 173.620441 -397.556355) (xy 174.749183 -397.556355) (xy 174.757226 -397.489534) (xy 174.773198 -397.424152)
			(xy 174.796869 -397.361148) (xy 174.827901 -397.301424) (xy 174.865849 -397.245838) (xy 174.887636 -397.220186)
			(xy 174.893426 -397.213036) (xy 174.899944 -397.195849) (xy 174.900336 -397.186658) (xy 174.900336 -397.028924)
			(xy 174.900742 -397.018767) (xy 174.908536 -397.000008) (xy 174.922939 -396.985682) (xy 174.941739 -396.977988)
			(xy 174.951898 -396.977616) (xy 175.668178 -396.977616) (xy 175.6783 -396.978144) (xy 175.697017 -396.98586)
			(xy 175.711373 -397.000133) (xy 175.719197 -397.018805) (xy 175.71974 -397.028924) (xy 175.71974 -397.186658)
			(xy 175.720184 -397.195841) (xy 175.726675 -397.213025) (xy 175.73244 -397.220186) (xy 175.754238 -397.24583)
			(xy 175.792188 -397.301417) (xy 175.823222 -397.361142) (xy 175.846895 -397.424147) (xy 175.862868 -397.489531)
			(xy 175.870912 -397.556354) (xy 175.870911 -397.623661) (xy 175.862865 -397.690484) (xy 175.846891 -397.755867)
			(xy 175.823216 -397.818872) (xy 175.79218 -397.878596) (xy 175.754229 -397.934182) (xy 175.73244 -397.959834)
			(xy 175.726639 -397.966976) (xy 175.720129 -397.984169) (xy 175.71974 -397.993362) (xy 175.71974 -398.486884)
			(xy 175.720171 -398.496069) (xy 175.726672 -398.513253) (xy 175.73244 -398.520412) (xy 175.754264 -398.546035)
			(xy 175.792213 -398.601625) (xy 175.823246 -398.661352) (xy 175.846918 -398.724361) (xy 175.862889 -398.789747)
			(xy 175.87093 -398.856573) (xy 175.870927 -398.923881) (xy 175.862879 -398.990707) (xy 175.846902 -399.056091)
			(xy 175.823224 -399.119097) (xy 175.792185 -399.178822) (xy 175.754231 -399.234408) (xy 175.73244 -399.26006)
			(xy 175.726628 -399.267194) (xy 175.720124 -399.284393) (xy 175.71974 -399.293588) (xy 175.71974 -399.451576)
			(xy 175.71926 -399.461724) (xy 175.71148 -399.480468) (xy 175.697101 -399.494791) (xy 175.678327 -399.502498)
			(xy 175.668178 -399.502884) (xy 174.951898 -399.502884) (xy 174.941774 -399.502376) (xy 174.923058 -399.494652)
			(xy 174.908702 -399.480372) (xy 174.900879 -399.461697) (xy 174.900336 -399.451576) (xy 174.900336 -399.293588)
			(xy 174.899924 -399.284401) (xy 174.893411 -399.267217) (xy 174.887636 -399.26006) (xy 174.865884 -399.234379)
			(xy 174.827934 -399.178796) (xy 174.7969 -399.119077) (xy 174.773225 -399.056076) (xy 174.75725 -398.990697)
			(xy 174.749203 -398.923878) (xy 174.749199 -398.856576) (xy 174.75724 -398.789756) (xy 174.773209 -398.724376)
			(xy 174.796878 -398.661373) (xy 174.827906 -398.60165) (xy 174.865851 -398.546064) (xy 174.887636 -398.520412)
			(xy 174.893457 -398.513284) (xy 174.899956 -398.49608) (xy 174.900336 -398.486884) (xy 174.900336 -397.993362)
			(xy 174.899936 -397.984174) (xy 174.893414 -397.96699) (xy 174.887636 -397.959834) (xy 174.865858 -397.934174)
			(xy 174.827909 -397.878588) (xy 174.796876 -397.818866) (xy 174.773202 -397.755863) (xy 174.757229 -397.690481)
			(xy 174.749184 -397.62366) (xy 174.749183 -397.556355) (xy 173.620441 -397.556355) (xy 173.623023 -397.561324)
			(xy 173.646696 -397.624324) (xy 173.662671 -397.689702) (xy 173.670718 -397.756521) (xy 173.670721 -397.823822)
			(xy 173.662681 -397.890642) (xy 173.646713 -397.956021) (xy 173.623046 -398.019024) (xy 173.592019 -398.078747)
			(xy 173.554077 -398.134334) (xy 173.532292 -398.159986) (xy 173.526475 -398.167117) (xy 173.519973 -398.184318)
			(xy 173.519592 -398.193514) (xy 173.519592 -398.351502) (xy 173.519069 -398.361656) (xy 173.511299 -398.38042)
			(xy 173.496943 -398.394784) (xy 173.478184 -398.402563) (xy 173.46803 -398.403064) (xy 172.75175 -398.403064)
			(xy 172.741582 -398.402595) (xy 172.722789 -398.394827) (xy 172.708402 -398.380455) (xy 172.700615 -398.36167)
			(xy 172.700188 -398.351502) (xy 172.700188 -398.193514) (xy 172.699774 -398.184327) (xy 172.693263 -398.167143)
			(xy 172.687488 -398.159986) (xy 172.665661 -398.134365) (xy 172.627711 -398.078775) (xy 172.596676 -398.019048)
			(xy 172.573004 -397.956039) (xy 172.557032 -397.890653) (xy 172.54899 -397.823826) (xy 171.420874 -397.823826)
			(xy 171.392104 -397.879044) (xy 171.354011 -397.934678) (xy 171.332144 -397.960342) (xy 171.32634 -397.967482)
			(xy 171.319831 -397.984677) (xy 171.319444 -397.99387) (xy 171.319444 -398.486376) (xy 171.319878 -398.49556)
			(xy 171.326376 -398.512744) (xy 171.332144 -398.519904) (xy 171.354045 -398.545539) (xy 171.392137 -398.601177)
			(xy 171.423289 -398.660976) (xy 171.447054 -398.724077) (xy 171.463088 -398.789571) (xy 171.471162 -398.856513)
			(xy 171.471159 -398.923941) (xy 171.463078 -398.990883) (xy 171.447037 -399.056374) (xy 171.423267 -399.119473)
			(xy 171.392109 -399.17927) (xy 171.354012 -399.234904) (xy 171.332144 -399.260568) (xy 171.326329 -399.2677)
			(xy 171.319827 -399.284901) (xy 171.319444 -399.294096) (xy 171.319444 -399.451576) (xy 171.318896 -399.461678)
			(xy 171.311175 -399.480347) (xy 171.296897 -399.494641) (xy 171.278237 -399.502385) (xy 171.268136 -399.502884)
			(xy 170.551856 -399.502884) (xy 170.541742 -399.50245) (xy 170.52306 -399.494695) (xy 170.508766 -399.480383)
			(xy 170.501036 -399.46169) (xy 170.500548 -399.451576) (xy 170.500548 -399.294096) (xy 170.500129 -399.28491)
			(xy 170.49362 -399.267726) (xy 170.487848 -399.260568) (xy 170.466018 -399.234874) (xy 170.427925 -399.179245)
			(xy 170.39677 -399.119453) (xy 170.373001 -399.05636) (xy 170.356962 -398.990874) (xy 170.348883 -398.923938)
			(xy 170.348879 -398.856516) (xy 170.356952 -398.789579) (xy 170.372985 -398.724092) (xy 170.396748 -398.660996)
			(xy 170.427897 -398.601201) (xy 170.465984 -398.545568) (xy 170.487848 -398.519904) (xy 170.493631 -398.51275)
			(xy 170.500153 -398.495566) (xy 170.500548 -398.486376) (xy 170.500548 -397.99387) (xy 170.500141 -397.984683)
			(xy 170.493624 -397.967499) (xy 170.487848 -397.960342) (xy 170.465992 -397.934669) (xy 170.4279 -397.879037)
			(xy 170.396746 -397.819242) (xy 170.372979 -397.756146) (xy 170.356942 -397.690658) (xy 170.348864 -397.623719)
			(xy 170.348863 -397.556296) (xy 169.22062 -397.556296) (xy 169.223233 -397.561324) (xy 169.246906 -397.624324)
			(xy 169.26288 -397.689702) (xy 169.270927 -397.756521) (xy 169.27093 -397.823822) (xy 169.26289 -397.890641)
			(xy 169.246923 -397.956021) (xy 169.223256 -398.019024) (xy 169.19223 -398.078746) (xy 169.154288 -398.134333)
			(xy 169.132504 -398.159986) (xy 169.126689 -398.167118) (xy 169.120185 -398.184319) (xy 169.119804 -398.193514)
			(xy 169.119804 -398.351502) (xy 169.119269 -398.361655) (xy 169.111502 -398.380416) (xy 169.097149 -398.394779)
			(xy 169.078394 -398.402561) (xy 169.068242 -398.403064) (xy 168.351962 -398.403064) (xy 168.341802 -398.402598)
			(xy 168.323032 -398.394811) (xy 168.308669 -398.380437) (xy 168.300895 -398.361662) (xy 168.3004 -398.351502)
			(xy 168.3004 -398.193514) (xy 168.299983 -398.184328) (xy 168.293474 -398.167143) (xy 168.2877 -398.159986)
			(xy 168.265876 -398.134364) (xy 168.227931 -398.078772) (xy 168.196902 -398.019044) (xy 168.173233 -397.956036)
			(xy 168.157263 -397.89065) (xy 168.149223 -397.823825) (xy 167.020556 -397.823825) (xy 166.992095 -397.878596)
			(xy 166.954145 -397.934182) (xy 166.932356 -397.959834) (xy 166.926557 -397.966977) (xy 166.920045 -397.984169)
			(xy 166.919656 -397.993362) (xy 166.919656 -398.486884) (xy 166.920084 -398.496069) (xy 166.926586 -398.513253)
			(xy 166.932356 -398.520412) (xy 166.954179 -398.546035) (xy 166.992127 -398.601625) (xy 167.023159 -398.661353)
			(xy 167.04683 -398.724361) (xy 167.062801 -398.789747) (xy 167.070842 -398.856573) (xy 167.070839 -398.923881)
			(xy 167.062791 -398.990706) (xy 167.046814 -399.05609) (xy 167.023137 -399.119097) (xy 166.9921 -399.178821)
			(xy 166.954146 -399.234408) (xy 166.932356 -399.26006) (xy 166.926546 -399.267195) (xy 166.92004 -399.284394)
			(xy 166.919656 -399.293588) (xy 166.919656 -399.451576) (xy 166.91916 -399.461722) (xy 166.911383 -399.480463)
			(xy 166.89701 -399.494785) (xy 166.878241 -399.502496) (xy 166.868094 -399.502884) (xy 166.151814 -399.502884)
			(xy 166.141691 -399.502363) (xy 166.122975 -399.494644) (xy 166.108619 -399.480369) (xy 166.100795 -399.461696)
			(xy 166.100252 -399.451576) (xy 166.100252 -399.293588) (xy 166.099836 -399.284402) (xy 166.093325 -399.267218)
			(xy 166.087552 -399.26006) (xy 166.065799 -399.234379) (xy 166.027849 -399.178797) (xy 165.996813 -399.119077)
			(xy 165.973138 -399.056077) (xy 165.957162 -398.990698) (xy 165.949115 -398.923878) (xy 165.949111 -398.856576)
			(xy 165.957152 -398.789755) (xy 165.973122 -398.724375) (xy 165.996791 -398.661372) (xy 166.027821 -398.60165)
			(xy 166.065766 -398.546064) (xy 166.087552 -398.520412) (xy 166.093375 -398.513286) (xy 166.099872 -398.49608)
			(xy 166.100252 -398.486884) (xy 166.100252 -397.993362) (xy 166.099848 -397.984174) (xy 166.093329 -397.966991)
			(xy 166.087552 -397.959834) (xy 166.065774 -397.934174) (xy 166.027824 -397.878589) (xy 165.99679 -397.818866)
			(xy 165.973116 -397.755863) (xy 165.957142 -397.690482) (xy 165.949096 -397.62366) (xy 164.846898 -397.62366)
			(xy 164.847042 -397.624041) (xy 164.863079 -397.689526) (xy 164.871158 -397.756461) (xy 164.871162 -397.823882)
			(xy 164.86309 -397.890817) (xy 164.847058 -397.956304) (xy 164.823299 -398.019399) (xy 164.792153 -398.079195)
			(xy 164.754069 -398.134829) (xy 164.732208 -398.160494) (xy 164.726432 -398.167654) (xy 164.719905 -398.184833)
			(xy 164.719508 -398.194022) (xy 164.719508 -398.351502) (xy 164.718976 -398.361623) (xy 164.711257 -398.380335)
			(xy 164.696985 -398.394689) (xy 164.678318 -398.402517) (xy 164.6682 -398.403064) (xy 163.95192 -398.403064)
			(xy 163.941763 -398.402661) (xy 163.923004 -398.394866) (xy 163.908678 -398.380462) (xy 163.900984 -398.361662)
			(xy 163.900612 -398.351502) (xy 163.900612 -398.194022) (xy 163.900188 -398.184836) (xy 163.893684 -398.167652)
			(xy 163.887912 -398.160494) (xy 163.86601 -398.13486) (xy 163.827922 -398.079221) (xy 163.796772 -398.019421)
			(xy 163.77301 -397.95632) (xy 163.756976 -397.890827) (xy 163.748903 -397.823885) (xy 162.620757 -397.823885)
			(xy 162.592019 -397.879044) (xy 162.553926 -397.934677) (xy 162.53206 -397.960342) (xy 162.526258 -397.967483)
			(xy 162.519748 -397.984677) (xy 162.51936 -397.99387) (xy 162.51936 -398.486376) (xy 162.51979 -398.495561)
			(xy 162.526291 -398.512745) (xy 162.53206 -398.519904) (xy 162.553961 -398.545539) (xy 162.592051 -398.601177)
			(xy 162.623202 -398.660977) (xy 162.646966 -398.724078) (xy 162.663 -398.789571) (xy 162.671074 -398.856513)
			(xy 162.671071 -398.923941) (xy 162.662991 -398.990882) (xy 162.64695 -399.056374) (xy 162.62318 -399.119472)
			(xy 162.592023 -399.179269) (xy 162.553928 -399.234903) (xy 162.53206 -399.260568) (xy 162.526247 -399.267701)
			(xy 162.519743 -399.284901) (xy 162.51936 -399.294096) (xy 162.51936 -399.451576) (xy 162.518964 -399.461702)
			(xy 162.511216 -399.480413) (xy 162.496893 -399.494729) (xy 162.478178 -399.502468) (xy 162.468052 -399.502884)
			(xy 161.751772 -399.502884) (xy 161.741659 -399.502438) (xy 161.722978 -399.494688) (xy 161.708683 -399.480379)
			(xy 161.700952 -399.461689) (xy 161.700464 -399.451576) (xy 161.700464 -399.294096) (xy 161.700041 -399.28491)
			(xy 161.693535 -399.267727) (xy 161.687764 -399.260568) (xy 161.665937 -399.234873) (xy 161.627849 -399.179242)
			(xy 161.596699 -399.119449) (xy 161.572934 -399.056357) (xy 161.556897 -398.990871) (xy 161.548819 -398.923937)
			(xy 161.548816 -398.856517) (xy 161.556888 -398.789582) (xy 161.572918 -398.724095) (xy 161.596677 -398.661)
			(xy 161.627821 -398.601205) (xy 161.665903 -398.54557) (xy 161.687764 -398.519904) (xy 161.693549 -398.512751)
			(xy 161.700069 -398.495566) (xy 161.700464 -398.486376) (xy 161.700464 -397.99387) (xy 161.700054 -397.984683)
			(xy 161.693538 -397.9675) (xy 161.687764 -397.960342) (xy 161.665911 -397.934668) (xy 161.627824 -397.879034)
			(xy 161.596675 -397.819239) (xy 161.572912 -397.756143) (xy 161.556877 -397.690655) (xy 161.548801 -397.623719)
			(xy 161.5488 -397.556296) (xy 160.420549 -397.556296) (xy 160.423161 -397.561321) (xy 160.446838 -397.624321)
			(xy 160.462815 -397.6897) (xy 160.470863 -397.75652) (xy 160.470866 -397.823823) (xy 160.462825 -397.890644)
			(xy 160.446855 -397.956024) (xy 160.423185 -398.019027) (xy 160.392154 -398.078749) (xy 160.354207 -398.134334)
			(xy 160.33242 -398.159986) (xy 160.326607 -398.16712) (xy 160.320101 -398.184319) (xy 160.31972 -398.193514)
			(xy 160.31972 -398.351502) (xy 160.319337 -398.361679) (xy 160.311543 -398.380482) (xy 160.297145 -398.394868)
			(xy 160.278335 -398.402645) (xy 160.268158 -398.403064) (xy 159.551878 -398.403064) (xy 159.541719 -398.402585)
			(xy 159.52295 -398.394804) (xy 159.508585 -398.380433) (xy 159.500811 -398.361661) (xy 159.500316 -398.351502)
			(xy 159.500316 -398.193514) (xy 159.499895 -398.184328) (xy 159.493388 -398.167144) (xy 159.487616 -398.159986)
			(xy 159.465792 -398.134364) (xy 159.427845 -398.078773) (xy 159.396815 -398.019045) (xy 159.373145 -397.956036)
			(xy 159.357176 -397.890651) (xy 159.349135 -397.823825) (xy 154.57678 -397.823825) (xy 154.57678 -401.723737)
			(xy 159.349146 -401.723737) (xy 159.349148 -401.65643) (xy 159.357194 -401.589607) (xy 159.373169 -401.524223)
			(xy 159.396843 -401.461218) (xy 159.427878 -401.401494) (xy 159.465828 -401.345906) (xy 159.487616 -401.320254)
			(xy 159.493416 -401.313112) (xy 159.499928 -401.295919) (xy 159.500316 -401.286726) (xy 159.500316 -400.793458)
			(xy 159.499923 -400.784269) (xy 159.493397 -400.767085) (xy 159.487616 -400.75993) (xy 159.465835 -400.734273)
			(xy 159.427887 -400.678686) (xy 159.396855 -400.618963) (xy 159.373183 -400.55596) (xy 159.35721 -400.490578)
			(xy 159.349166 -400.423757) (xy 159.349165 -400.356452) (xy 159.357209 -400.289631) (xy 159.37318 -400.224249)
			(xy 159.396851 -400.161245) (xy 159.427883 -400.101521) (xy 159.465829 -400.045934) (xy 159.487616 -400.020282)
			(xy 159.493405 -400.013131) (xy 159.499923 -399.995945) (xy 159.500316 -399.986754) (xy 159.500316 -399.828766)
			(xy 159.500805 -399.818609) (xy 159.508586 -399.799843) (xy 159.522953 -399.78548) (xy 159.541721 -399.777703)
			(xy 159.551878 -399.777204) (xy 160.268158 -399.777204) (xy 160.278323 -399.777697) (xy 160.29711 -399.785462)
			(xy 160.311495 -399.799826) (xy 160.319288 -399.818602) (xy 160.31972 -399.828766) (xy 160.31972 -399.986754)
			(xy 160.320148 -399.995939) (xy 160.326649 -400.013124) (xy 160.33242 -400.020282) (xy 160.354215 -400.045929)
			(xy 160.392166 -400.101515) (xy 160.423201 -400.161239) (xy 160.446876 -400.224244) (xy 160.462849 -400.289628)
			(xy 160.470894 -400.356451) (xy 160.470893 -400.423758) (xy 160.462848 -400.490581) (xy 160.446873 -400.555964)
			(xy 160.423198 -400.618969) (xy 160.392161 -400.678693) (xy 160.354209 -400.734278) (xy 160.33242 -400.75993)
			(xy 160.326631 -400.76708) (xy 160.320111 -400.784267) (xy 160.31972 -400.793458) (xy 160.31972 -401.286726)
			(xy 160.320113 -401.295915) (xy 160.326638 -401.313099) (xy 160.33242 -401.320254) (xy 160.354187 -401.345923)
			(xy 160.392139 -401.401506) (xy 160.423176 -401.461227) (xy 160.446852 -401.52423) (xy 160.462827 -401.58961)
			(xy 160.470874 -401.656431) (xy 160.470876 -401.723735) (xy 160.462833 -401.790557) (xy 160.446862 -401.855939)
			(xy 160.423189 -401.918943) (xy 160.392156 -401.978665) (xy 160.354208 -402.03425) (xy 160.33242 -402.059902)
			(xy 160.326642 -402.067061) (xy 160.320116 -402.084241) (xy 160.31972 -402.09343) (xy 160.31972 -402.251418)
			(xy 160.31935 -402.261596) (xy 160.311551 -402.280399) (xy 160.297149 -402.294785) (xy 160.278336 -402.302562)
			(xy 160.268158 -402.30298) (xy 159.551878 -402.30298) (xy 159.541721 -402.302485) (xy 159.522955 -402.294707)
			(xy 159.508591 -402.280342) (xy 159.500814 -402.261575) (xy 159.500316 -402.251418) (xy 159.500316 -402.09343)
			(xy 159.499888 -402.084245) (xy 159.493386 -402.06706) (xy 159.487616 -402.059902) (xy 159.465807 -402.034267)
			(xy 159.427861 -401.978678) (xy 159.39683 -401.918952) (xy 159.373159 -401.855945) (xy 159.357188 -401.790561)
			(xy 159.349146 -401.723737) (xy 154.57678 -401.723737) (xy 154.57678 -402.823877) (xy 161.54876 -402.823877)
			(xy 161.548765 -402.756451) (xy 161.556845 -402.68951) (xy 161.572884 -402.624018) (xy 161.596652 -402.56092)
			(xy 161.627806 -402.501122) (xy 161.665898 -402.445486) (xy 161.687764 -402.41982) (xy 161.693585 -402.412692)
			(xy 161.700083 -402.395488) (xy 161.700464 -402.386292) (xy 161.700464 -401.89404) (xy 161.70002 -401.884857)
			(xy 161.693528 -401.867673) (xy 161.687764 -401.860512) (xy 161.665882 -401.834862) (xy 161.627796 -401.779225)
			(xy 161.596648 -401.719426) (xy 161.572887 -401.656327) (xy 161.556854 -401.590837) (xy 161.54878 -401.523897)
			(xy 161.548782 -401.456473) (xy 161.556859 -401.389534) (xy 161.572896 -401.324044) (xy 161.59666 -401.260946)
			(xy 161.627811 -401.201149) (xy 161.6659 -401.145514) (xy 161.687764 -401.119848) (xy 161.693573 -401.112712)
			(xy 161.700078 -401.095514) (xy 161.700464 -401.08632) (xy 161.700464 -400.92884) (xy 161.700948 -400.918725)
			(xy 161.708676 -400.900029) (xy 161.722972 -400.885714) (xy 161.741657 -400.877961) (xy 161.751772 -400.877532)
			(xy 162.468052 -400.877532) (xy 162.478175 -400.877956) (xy 162.496884 -400.885694) (xy 162.511201 -400.900009)
			(xy 162.518942 -400.918717) (xy 162.51936 -400.92884) (xy 162.51936 -401.08632) (xy 162.519769 -401.095507)
			(xy 162.526285 -401.112691) (xy 162.53206 -401.119848) (xy 162.553906 -401.145529) (xy 162.591998 -401.20116)
			(xy 162.623151 -401.260954) (xy 162.646919 -401.324049) (xy 162.662957 -401.389536) (xy 162.671035 -401.456474)
			(xy 162.671037 -401.523896) (xy 162.662962 -401.590834) (xy 162.646927 -401.656323) (xy 162.623164 -401.719419)
			(xy 162.620884 -401.723796) (xy 163.748915 -401.723796) (xy 163.748917 -401.656371) (xy 163.756995 -401.589431)
			(xy 163.773033 -401.52394) (xy 163.7968 -401.460842) (xy 163.827954 -401.401046) (xy 163.866046 -401.345411)
			(xy 163.887912 -401.319746) (xy 163.893715 -401.312606) (xy 163.900226 -401.295411) (xy 163.900612 -401.286218)
			(xy 163.900612 -400.793966) (xy 163.900216 -400.784777) (xy 163.893692 -400.767593) (xy 163.887912 -400.760438)
			(xy 163.866054 -400.734768) (xy 163.827964 -400.679135) (xy 163.796812 -400.619339) (xy 163.773047 -400.556243)
			(xy 163.757011 -400.490754) (xy 163.748934 -400.423816) (xy 163.748934 -400.356393) (xy 163.757009 -400.289455)
			(xy 163.773044 -400.223966) (xy 163.796809 -400.160869) (xy 163.827959 -400.101073) (xy 163.866048 -400.045439)
			(xy 163.887912 -400.019774) (xy 163.893703 -400.012625) (xy 163.900221 -399.995437) (xy 163.900612 -399.986246)
			(xy 163.900612 -399.828766) (xy 163.901098 -399.818641) (xy 163.908832 -399.799924) (xy 163.923117 -399.78557)
			(xy 163.941797 -399.777747) (xy 163.95192 -399.777204) (xy 164.6682 -399.777204) (xy 164.678355 -399.777622)
			(xy 164.697108 -399.785418) (xy 164.711431 -399.799816) (xy 164.71913 -399.818609) (xy 164.719508 -399.828766)
			(xy 164.719508 -399.986246) (xy 164.719942 -399.995431) (xy 164.726439 -400.012615) (xy 164.732208 -400.019774)
			(xy 164.754078 -400.045435) (xy 164.792166 -400.10107) (xy 164.823316 -400.160867) (xy 164.847079 -400.223964)
			(xy 164.863114 -400.289454) (xy 164.871189 -400.356393) (xy 164.871189 -400.423817) (xy 164.863112 -400.490755)
			(xy 164.847076 -400.556244) (xy 164.823312 -400.619341) (xy 164.792161 -400.679138) (xy 164.754072 -400.734773)
			(xy 164.732208 -400.760438) (xy 164.726414 -400.767585) (xy 164.719897 -400.784774) (xy 164.719508 -400.793966)
			(xy 164.719508 -401.286218) (xy 164.719908 -401.295406) (xy 164.726429 -401.312591) (xy 164.732208 -401.319746)
			(xy 164.75405 -401.345429) (xy 164.792139 -401.401061) (xy 164.82329 -401.460855) (xy 164.847055 -401.52395)
			(xy 164.863092 -401.589436) (xy 164.871169 -401.656373) (xy 164.871171 -401.723794) (xy 164.863098 -401.790731)
			(xy 164.847065 -401.856219) (xy 164.823304 -401.919315) (xy 164.792156 -401.97911) (xy 164.75407 -402.034745)
			(xy 164.732208 -402.06041) (xy 164.726426 -402.067565) (xy 164.719902 -402.084748) (xy 164.719508 -402.093938)
			(xy 164.719508 -402.251418) (xy 164.71899 -402.26154) (xy 164.711265 -402.280253) (xy 164.696989 -402.294607)
			(xy 164.678319 -402.302434) (xy 164.6682 -402.30298) (xy 163.95192 -402.30298) (xy 163.941765 -402.302562)
			(xy 163.923009 -402.294769) (xy 163.908684 -402.280371) (xy 163.900987 -402.261575) (xy 163.900612 -402.251418)
			(xy 163.900612 -402.093938) (xy 163.900181 -402.084753) (xy 163.893681 -402.067569) (xy 163.887912 -402.06041)
			(xy 163.866026 -402.034763) (xy 163.827937 -401.979126) (xy 163.796787 -401.919327) (xy 163.773023 -401.856228)
			(xy 163.756989 -401.790737) (xy 163.748915 -401.723796) (xy 162.620884 -401.723796) (xy 162.592013 -401.779214)
			(xy 162.553924 -401.834847) (xy 162.53206 -401.860512) (xy 162.526271 -401.867662) (xy 162.519753 -401.884849)
			(xy 162.51936 -401.89404) (xy 162.51936 -402.386292) (xy 162.519783 -402.395478) (xy 162.526289 -402.412662)
			(xy 162.53206 -402.41982) (xy 162.553878 -402.445523) (xy 162.591971 -402.501152) (xy 162.623126 -402.560942)
			(xy 162.646895 -402.624034) (xy 162.662935 -402.689519) (xy 162.671015 -402.756454) (xy 162.671019 -402.823818)
			(xy 165.949055 -402.823818) (xy 165.94906 -402.756509) (xy 165.957109 -402.689683) (xy 165.973087 -402.624298)
			(xy 165.996766 -402.561292) (xy 166.027805 -402.501567) (xy 166.065761 -402.44598) (xy 166.087552 -402.420328)
			(xy 166.093368 -402.413197) (xy 166.09987 -402.395995) (xy 166.100252 -402.3868) (xy 166.100252 -401.893532)
			(xy 166.099815 -401.884348) (xy 166.093319 -401.867164) (xy 166.087552 -401.860004) (xy 166.065744 -401.834368)
			(xy 166.027795 -401.77878) (xy 165.996762 -401.719054) (xy 165.97309 -401.656047) (xy 165.957118 -401.590663)
			(xy 165.949075 -401.523838) (xy 165.949077 -401.456532) (xy 165.957123 -401.389707) (xy 165.973098 -401.324324)
			(xy 165.996774 -401.261318) (xy 166.02781 -401.201594) (xy 166.065762 -401.146008) (xy 166.087552 -401.120356)
			(xy 166.093356 -401.113216) (xy 166.099865 -401.096021) (xy 166.100252 -401.086828) (xy 166.100252 -400.92884)
			(xy 166.100754 -400.918694) (xy 166.108527 -400.899952) (xy 166.122899 -400.885629) (xy 166.141667 -400.87792)
			(xy 166.151814 -400.877532) (xy 166.868094 -400.877532) (xy 166.878219 -400.878031) (xy 166.896939 -400.885756)
			(xy 166.911295 -400.900038) (xy 166.919116 -400.918717) (xy 166.919656 -400.92884) (xy 166.919656 -401.086828)
			(xy 166.920063 -401.096015) (xy 166.92658 -401.113199) (xy 166.932356 -401.120356) (xy 166.954124 -401.146024)
			(xy 166.992074 -401.201608) (xy 167.023108 -401.26133) (xy 167.046782 -401.324332) (xy 167.062757 -401.389712)
			(xy 167.070803 -401.456533) (xy 167.070804 -401.523837) (xy 167.062762 -401.590658) (xy 167.046791 -401.656039)
			(xy 167.02312 -401.719043) (xy 167.020682 -401.723736) (xy 168.149234 -401.723736) (xy 168.149236 -401.65643)
			(xy 168.157282 -401.589607) (xy 168.173256 -401.524224) (xy 168.19693 -401.461219) (xy 168.227963 -401.401494)
			(xy 168.265912 -401.345907) (xy 168.2877 -401.320254) (xy 168.293499 -401.31311) (xy 168.300012 -401.295919)
			(xy 168.3004 -401.286726) (xy 168.3004 -400.793458) (xy 168.30001 -400.784269) (xy 168.293482 -400.767084)
			(xy 168.2877 -400.75993) (xy 168.265919 -400.734272) (xy 168.227973 -400.678686) (xy 168.196942 -400.618963)
			(xy 168.17327 -400.555959) (xy 168.157298 -400.490578) (xy 168.149254 -400.423756) (xy 168.149253 -400.356453)
			(xy 168.157296 -400.289631) (xy 168.173267 -400.22425) (xy 168.196938 -400.161246) (xy 168.227968 -400.101522)
			(xy 168.265914 -400.045935) (xy 168.2877 -400.020282) (xy 168.293487 -400.01313) (xy 168.300007 -399.995945)
			(xy 168.3004 -399.986754) (xy 168.3004 -399.828766) (xy 168.300905 -399.818611) (xy 168.308683 -399.799848)
			(xy 168.323045 -399.785485) (xy 168.341807 -399.777705) (xy 168.351962 -399.777204) (xy 169.068242 -399.777204)
			(xy 169.078398 -399.777698) (xy 169.097162 -399.78548) (xy 169.111524 -399.799845) (xy 169.119303 -399.81861)
			(xy 169.119804 -399.828766) (xy 169.119804 -399.986754) (xy 169.120235 -399.995939) (xy 169.126734 -400.013124)
			(xy 169.132504 -400.020282) (xy 169.154296 -400.04593) (xy 169.192242 -400.101518) (xy 169.223273 -400.161243)
			(xy 169.246943 -400.224248) (xy 169.262915 -400.28963) (xy 169.270958 -400.356452) (xy 169.270957 -400.423757)
			(xy 169.262913 -400.490579) (xy 169.246941 -400.555961) (xy 169.223269 -400.618966) (xy 169.192237 -400.67869)
			(xy 169.154291 -400.734277) (xy 169.132504 -400.75993) (xy 169.126713 -400.767079) (xy 169.120195 -400.784267)
			(xy 169.119804 -400.793458) (xy 169.119804 -401.286726) (xy 169.1202 -401.295915) (xy 169.126723 -401.313099)
			(xy 169.132504 -401.320254) (xy 169.154269 -401.345925) (xy 169.192215 -401.401509) (xy 169.223247 -401.461231)
			(xy 169.246919 -401.524233) (xy 169.262893 -401.589612) (xy 169.270938 -401.656432) (xy 169.27094 -401.723735)
			(xy 169.262899 -401.790555) (xy 169.246929 -401.855936) (xy 169.223261 -401.918939) (xy 169.192232 -401.978662)
			(xy 169.154289 -402.034249) (xy 169.132504 -402.059902) (xy 169.126725 -402.067059) (xy 169.1202 -402.084241)
			(xy 169.119804 -402.09343) (xy 169.119804 -402.251418) (xy 169.119283 -402.261572) (xy 169.11151 -402.280333)
			(xy 169.097154 -402.294697) (xy 169.078396 -402.302478) (xy 169.068242 -402.30298) (xy 168.351962 -402.30298)
			(xy 168.341804 -402.302498) (xy 168.323037 -402.294715) (xy 168.308674 -402.280346) (xy 168.300898 -402.261576)
			(xy 168.3004 -402.251418) (xy 168.3004 -402.09343) (xy 168.299975 -402.084244) (xy 168.293472 -402.06706)
			(xy 168.2877 -402.059902) (xy 168.265892 -402.034267) (xy 168.227946 -401.978677) (xy 168.196916 -401.918951)
			(xy 168.173246 -401.855944) (xy 168.157276 -401.79056) (xy 168.149234 -401.723736) (xy 167.020682 -401.723736)
			(xy 166.992089 -401.778766) (xy 166.954142 -401.834352) (xy 166.932356 -401.860004) (xy 166.92657 -401.867156)
			(xy 166.92005 -401.884342) (xy 166.919656 -401.893532) (xy 166.919656 -402.3868) (xy 166.920076 -402.395986)
			(xy 166.926584 -402.41317) (xy 166.932356 -402.420328) (xy 166.954097 -402.446019) (xy 166.992047 -402.5016)
			(xy 167.023083 -402.561318) (xy 167.046758 -402.624317) (xy 167.062735 -402.689695) (xy 167.070783 -402.756513)
			(xy 167.070787 -402.823815) (xy 167.070779 -402.823878) (xy 170.348823 -402.823878) (xy 170.348828 -402.75645)
			(xy 170.356909 -402.689507) (xy 170.372951 -402.624015) (xy 170.396723 -402.560916) (xy 170.427882 -402.501119)
			(xy 170.465979 -402.445484) (xy 170.487848 -402.41982) (xy 170.493667 -402.412691) (xy 170.500167 -402.395488)
			(xy 170.500548 -402.386292) (xy 170.500548 -401.89404) (xy 170.500108 -401.884856) (xy 170.493614 -401.867672)
			(xy 170.487848 -401.860512) (xy 170.465963 -401.834864) (xy 170.427871 -401.779228) (xy 170.396719 -401.71943)
			(xy 170.372954 -401.656331) (xy 170.356918 -401.590839) (xy 170.348843 -401.523898) (xy 170.348845 -401.456472)
			(xy 170.356924 -401.389531) (xy 170.372963 -401.324041) (xy 170.396731 -401.260943) (xy 170.427887 -401.201146)
			(xy 170.465981 -401.145512) (xy 170.487848 -401.119848) (xy 170.493655 -401.112711) (xy 170.500162 -401.095514)
			(xy 170.500548 -401.08632) (xy 170.500548 -400.92884) (xy 170.501117 -400.91874) (xy 170.508832 -400.900073)
			(xy 170.523102 -400.885779) (xy 170.541757 -400.878033) (xy 170.551856 -400.877532) (xy 171.268136 -400.877532)
			(xy 171.278265 -400.877887) (xy 171.296975 -400.885653) (xy 171.311289 -400.899989) (xy 171.319028 -400.918711)
			(xy 171.319444 -400.92884) (xy 171.319444 -401.08632) (xy 171.319857 -401.095507) (xy 171.32637 -401.11269)
			(xy 171.332144 -401.119848) (xy 171.35399 -401.145528) (xy 171.392083 -401.20116) (xy 171.423238 -401.260953)
			(xy 171.447006 -401.324048) (xy 171.463044 -401.389536) (xy 171.471123 -401.456473) (xy 171.471124 -401.523897)
			(xy 171.46305 -401.590834) (xy 171.447015 -401.656323) (xy 171.42325 -401.719419) (xy 171.421001 -401.723737)
			(xy 172.549001 -401.723737) (xy 172.549003 -401.65643) (xy 172.55705 -401.589605) (xy 172.573027 -401.524221)
			(xy 172.596704 -401.461215) (xy 172.627743 -401.401491) (xy 172.665697 -401.345906) (xy 172.687488 -401.320254)
			(xy 172.693285 -401.313109) (xy 172.6998 -401.295918) (xy 172.700188 -401.286726) (xy 172.700188 -400.793458)
			(xy 172.699801 -400.784268) (xy 172.693272 -400.767084) (xy 172.687488 -400.75993) (xy 172.665705 -400.734274)
			(xy 172.627752 -400.678689) (xy 172.596716 -400.618966) (xy 172.573041 -400.555962) (xy 172.557066 -400.49058)
			(xy 172.549021 -400.423757) (xy 172.54902 -400.356452) (xy 172.557065 -400.289629) (xy 172.573038 -400.224246)
			(xy 172.596713 -400.161242) (xy 172.627748 -400.101519) (xy 172.665699 -400.045933) (xy 172.687488 -400.020282)
			(xy 172.693273 -400.013129) (xy 172.699795 -399.995944) (xy 172.700188 -399.986754) (xy 172.700188 -399.828766)
			(xy 172.700537 -399.818586) (xy 172.708343 -399.799781) (xy 172.722752 -399.785395) (xy 172.741569 -399.777621)
			(xy 172.75175 -399.777204) (xy 173.46803 -399.777204) (xy 173.478186 -399.777708) (xy 173.496949 -399.785486)
			(xy 173.511312 -399.799848) (xy 173.519091 -399.818611) (xy 173.519592 -399.828766) (xy 173.519592 -399.986754)
			(xy 173.520026 -399.995939) (xy 173.526523 -400.013123) (xy 173.532292 -400.020282) (xy 173.554085 -400.04593)
			(xy 173.592031 -400.101518) (xy 173.623063 -400.161242) (xy 173.646734 -400.224247) (xy 173.662705 -400.289629)
			(xy 173.670749 -400.356452) (xy 173.670748 -400.423757) (xy 173.662704 -400.490579) (xy 173.646731 -400.555962)
			(xy 173.623059 -400.618966) (xy 173.592027 -400.67869) (xy 173.554079 -400.734277) (xy 173.532292 -400.75993)
			(xy 173.526499 -400.767078) (xy 173.519983 -400.784266) (xy 173.519592 -400.793458) (xy 173.519592 -401.286726)
			(xy 173.519991 -401.295914) (xy 173.526513 -401.313099) (xy 173.532292 -401.320254) (xy 173.554057 -401.345924)
			(xy 173.592005 -401.401509) (xy 173.623037 -401.46123) (xy 173.64671 -401.524232) (xy 173.662683 -401.589612)
			(xy 173.670729 -401.656432) (xy 173.670731 -401.723735) (xy 173.662689 -401.790555) (xy 173.64672 -401.855936)
			(xy 173.623051 -401.918939) (xy 173.592022 -401.978663) (xy 173.554077 -402.034249) (xy 173.532292 -402.059902)
			(xy 173.526511 -402.067058) (xy 173.519987 -402.08424) (xy 173.519592 -402.09343) (xy 173.519592 -402.251418)
			(xy 173.519082 -402.261573) (xy 173.511308 -402.280337) (xy 173.496947 -402.294701) (xy 173.478185 -402.30248)
			(xy 173.46803 -402.30298) (xy 172.75175 -402.30298) (xy 172.741584 -402.302496) (xy 172.722794 -402.29473)
			(xy 172.708408 -402.280363) (xy 172.700618 -402.261584) (xy 172.700188 -402.251418) (xy 172.700188 -402.09343)
			(xy 172.699766 -402.084244) (xy 172.693261 -402.067059) (xy 172.687488 -402.059902) (xy 172.665677 -402.034268)
			(xy 172.627726 -401.97868) (xy 172.596691 -401.918955) (xy 172.573017 -401.855948) (xy 172.557044 -401.790563)
			(xy 172.549001 -401.723737) (xy 171.421001 -401.723737) (xy 171.392099 -401.779215) (xy 171.354009 -401.834848)
			(xy 171.332144 -401.860512) (xy 171.326353 -401.867661) (xy 171.319836 -401.884849) (xy 171.319444 -401.89404)
			(xy 171.319444 -402.386292) (xy 171.31987 -402.395477) (xy 171.326374 -402.412661) (xy 171.332144 -402.41982)
			(xy 171.353963 -402.445523) (xy 171.392057 -402.501151) (xy 171.423213 -402.560941) (xy 171.446982 -402.624033)
			(xy 171.463022 -402.689518) (xy 171.471103 -402.756453) (xy 171.471107 -402.823818) (xy 174.749143 -402.823818)
			(xy 174.749147 -402.75651) (xy 174.757196 -402.689684) (xy 174.773174 -402.624299) (xy 174.796852 -402.561292)
			(xy 174.827891 -402.501567) (xy 174.865845 -402.44598) (xy 174.887636 -402.420328) (xy 174.89345 -402.413195)
			(xy 174.899953 -402.395995) (xy 174.900336 -402.3868) (xy 174.900336 -401.893532) (xy 174.899902 -401.884348)
			(xy 174.893404 -401.867163) (xy 174.887636 -401.860004) (xy 174.865829 -401.834368) (xy 174.827881 -401.778779)
			(xy 174.796848 -401.719053) (xy 174.773177 -401.656047) (xy 174.757205 -401.590663) (xy 174.749163 -401.523838)
			(xy 174.749165 -401.456532) (xy 174.757211 -401.389708) (xy 174.773186 -401.324324) (xy 174.796861 -401.261319)
			(xy 174.827896 -401.201595) (xy 174.865847 -401.146008) (xy 174.887636 -401.120356) (xy 174.893438 -401.113215)
			(xy 174.899949 -401.096021) (xy 174.900336 -401.086828) (xy 174.900336 -400.92884) (xy 174.900755 -400.918684)
			(xy 174.908544 -400.899926) (xy 174.922943 -400.8856) (xy 174.94174 -400.877905) (xy 174.951898 -400.877532)
			(xy 175.668178 -400.877532) (xy 175.678302 -400.878044) (xy 175.697022 -400.885763) (xy 175.711378 -400.900042)
			(xy 175.7192 -400.918718) (xy 175.71974 -400.92884) (xy 175.71974 -401.086828) (xy 175.72015 -401.096015)
			(xy 175.726665 -401.113198) (xy 175.73244 -401.120356) (xy 175.754209 -401.146024) (xy 175.792159 -401.201608)
			(xy 175.823195 -401.261329) (xy 175.846869 -401.324331) (xy 175.862844 -401.389712) (xy 175.870891 -401.456533)
			(xy 175.870892 -401.523837) (xy 175.86285 -401.590658) (xy 175.846878 -401.65604) (xy 175.823207 -401.719044)
			(xy 175.792175 -401.778766) (xy 175.754227 -401.834352) (xy 175.73244 -401.860004) (xy 175.726652 -401.867155)
			(xy 175.720134 -401.884341) (xy 175.71974 -401.893532) (xy 175.71974 -402.3868) (xy 175.720164 -402.395985)
			(xy 175.726669 -402.413169) (xy 175.73244 -402.420328) (xy 175.754181 -402.446019) (xy 175.792133 -402.501599)
			(xy 175.823169 -402.561317) (xy 175.846846 -402.624317) (xy 175.862823 -402.689694) (xy 175.870871 -402.756513)
			(xy 175.870875 -402.823815) (xy 175.862835 -402.890634) (xy 175.846867 -402.956014) (xy 175.823199 -403.019017)
			(xy 175.79217 -403.078739) (xy 175.754225 -403.134324) (xy 175.73244 -403.159976) (xy 175.726621 -403.167105)
			(xy 175.720122 -403.184308) (xy 175.71974 -403.193504) (xy 175.71974 -403.351492) (xy 175.719273 -403.361641)
			(xy 175.711487 -403.380385) (xy 175.697105 -403.394707) (xy 175.678328 -403.402415) (xy 175.668178 -403.4028)
			(xy 174.951898 -403.4028) (xy 174.941776 -403.402276) (xy 174.923063 -403.394555) (xy 174.908708 -403.380281)
			(xy 174.900882 -403.361611) (xy 174.900336 -403.351492) (xy 174.900336 -403.193504) (xy 174.899916 -403.184318)
			(xy 174.893408 -403.167134) (xy 174.887636 -403.159976) (xy 174.865801 -403.134363) (xy 174.827854 -403.078771)
			(xy 174.796823 -403.019042) (xy 174.773153 -402.956032) (xy 174.757183 -402.890645) (xy 174.749143 -402.823818)
			(xy 171.471107 -402.823818) (xy 171.471107 -402.823874) (xy 171.463035 -402.89081) (xy 171.447003 -402.956298)
			(xy 171.423242 -403.019393) (xy 171.392094 -403.079187) (xy 171.354007 -403.13482) (xy 171.332144 -403.160484)
			(xy 171.326322 -403.167611) (xy 171.319824 -403.184816) (xy 171.319444 -403.194012) (xy 171.319444 -403.351492)
			(xy 171.318909 -403.361595) (xy 171.311183 -403.380264) (xy 171.296901 -403.394558) (xy 171.278238 -403.402301)
			(xy 171.268136 -403.4028) (xy 170.551856 -403.4028) (xy 170.541744 -403.402351) (xy 170.523065 -403.394599)
			(xy 170.508772 -403.380291) (xy 170.501039 -403.361604) (xy 170.500548 -403.351492) (xy 170.500548 -403.194012)
			(xy 170.500121 -403.184827) (xy 170.493618 -403.167643) (xy 170.487848 -403.160484) (xy 170.465935 -403.134858)
			(xy 170.427845 -403.079219) (xy 170.396693 -403.019418) (xy 170.37293 -402.956316) (xy 170.356896 -402.890822)
			(xy 170.348823 -402.823878) (xy 167.070779 -402.823878) (xy 167.062748 -402.890634) (xy 167.04678 -402.956014)
			(xy 167.023112 -403.019016) (xy 166.992084 -403.078738) (xy 166.954141 -403.134324) (xy 166.932356 -403.159976)
			(xy 166.926539 -403.167107) (xy 166.920038 -403.184308) (xy 166.919656 -403.193504) (xy 166.919656 -403.351492)
			(xy 166.919173 -403.361639) (xy 166.911391 -403.38038) (xy 166.897014 -403.394702) (xy 166.878242 -403.402412)
			(xy 166.868094 -403.4028) (xy 166.151814 -403.4028) (xy 166.141693 -403.402263) (xy 166.12298 -403.394547)
			(xy 166.108624 -403.380277) (xy 166.100798 -403.36161) (xy 166.100252 -403.351492) (xy 166.100252 -403.193504)
			(xy 166.099828 -403.184318) (xy 166.093323 -403.167135) (xy 166.087552 -403.159976) (xy 166.065717 -403.134363)
			(xy 166.027768 -403.078771) (xy 165.996736 -403.019042) (xy 165.973066 -402.956033) (xy 165.957096 -402.890646)
			(xy 165.949055 -402.823818) (xy 162.671019 -402.823818) (xy 162.671019 -402.823874) (xy 162.662948 -402.89081)
			(xy 162.646916 -402.956297) (xy 162.623155 -403.019392) (xy 162.592008 -403.079187) (xy 162.553923 -403.13482)
			(xy 162.53206 -403.160484) (xy 162.52624 -403.167613) (xy 162.51974 -403.184816) (xy 162.51936 -403.194012)
			(xy 162.51936 -403.351492) (xy 162.518976 -403.361619) (xy 162.511224 -403.38033) (xy 162.496896 -403.394646)
			(xy 162.478179 -403.402384) (xy 162.468052 -403.4028) (xy 161.751772 -403.4028) (xy 161.741661 -403.402338)
			(xy 161.722983 -403.394591) (xy 161.708689 -403.380287) (xy 161.700955 -403.361603) (xy 161.700464 -403.351492)
			(xy 161.700464 -403.194012) (xy 161.700034 -403.184827) (xy 161.693532 -403.167643) (xy 161.687764 -403.160484)
			(xy 161.665854 -403.134857) (xy 161.627769 -403.079216) (xy 161.596623 -403.019414) (xy 161.572863 -402.956313)
			(xy 161.556832 -402.890819) (xy 161.54876 -402.823877) (xy 154.57678 -402.823877) (xy 154.57678 -405.623648)
			(xy 159.349158 -405.623648) (xy 159.349158 -405.556343) (xy 159.357202 -405.48952) (xy 159.373175 -405.424138)
			(xy 159.396848 -405.361133) (xy 159.427881 -405.301409) (xy 159.465829 -405.245822) (xy 159.487616 -405.22017)
			(xy 159.49341 -405.213023) (xy 159.499926 -405.195834) (xy 159.500316 -405.186642) (xy 159.500316 -404.693374)
			(xy 159.499915 -404.684186) (xy 159.493395 -404.667002) (xy 159.487616 -404.659846) (xy 159.465851 -404.634176)
			(xy 159.427903 -404.578591) (xy 159.39687 -404.51887) (xy 159.373197 -404.455868) (xy 159.357223 -404.390488)
			(xy 159.349177 -404.323668) (xy 159.349175 -404.256365) (xy 159.357217 -404.189544) (xy 159.373187 -404.124164)
			(xy 159.396856 -404.06116) (xy 159.427886 -404.001437) (xy 159.46583 -403.94585) (xy 159.487616 -403.920198)
			(xy 159.493398 -403.913042) (xy 159.499921 -403.89586) (xy 159.500316 -403.88667) (xy 159.500316 -403.728682)
			(xy 159.500818 -403.718526) (xy 159.508594 -403.69976) (xy 159.522957 -403.685396) (xy 159.541722 -403.677619)
			(xy 159.551878 -403.67712) (xy 160.268158 -403.67712) (xy 160.278325 -403.677598) (xy 160.297115 -403.685366)
			(xy 160.311501 -403.699735) (xy 160.31929 -403.718516) (xy 160.31972 -403.728682) (xy 160.31972 -403.88667)
			(xy 160.32014 -403.895856) (xy 160.326646 -403.913041) (xy 160.33242 -403.920198) (xy 160.354231 -403.945832)
			(xy 160.392181 -404.00142) (xy 160.423216 -404.061146) (xy 160.446889 -404.124153) (xy 160.462862 -404.189538)
			(xy 160.470905 -404.256363) (xy 160.470903 -404.32367) (xy 160.462856 -404.390495) (xy 160.446879 -404.455879)
			(xy 160.423202 -404.518885) (xy 160.392164 -404.578608) (xy 160.35421 -404.634194) (xy 160.33242 -404.659846)
			(xy 160.326624 -404.666992) (xy 160.320108 -404.684182) (xy 160.31972 -404.693374) (xy 160.31972 -405.186642)
			(xy 160.320105 -405.195832) (xy 160.326636 -405.213016) (xy 160.33242 -405.22017) (xy 160.354203 -405.245826)
			(xy 160.392155 -405.301411) (xy 160.42319 -405.361134) (xy 160.446865 -405.424138) (xy 160.46284 -405.48952)
			(xy 160.470885 -405.556343) (xy 160.470886 -405.623648) (xy 160.462842 -405.690471) (xy 160.446868 -405.755853)
			(xy 160.423194 -405.818858) (xy 160.392159 -405.878581) (xy 160.354209 -405.934166) (xy 160.33242 -405.959818)
			(xy 160.326636 -405.966972) (xy 160.320113 -405.984156) (xy 160.31972 -405.993346) (xy 160.31972 -406.151334)
			(xy 160.319363 -406.161513) (xy 160.311559 -406.180317) (xy 160.297153 -406.194702) (xy 160.278338 -406.202478)
			(xy 160.268158 -406.202896) (xy 159.551878 -406.202896) (xy 159.541723 -406.202386) (xy 159.52296 -406.19461)
			(xy 159.508596 -406.18025) (xy 159.500817 -406.161489) (xy 159.500316 -406.151334) (xy 159.500316 -405.993346)
			(xy 159.49988 -405.984162) (xy 159.493384 -405.966977) (xy 159.487616 -405.959818) (xy 159.465823 -405.93417)
			(xy 159.427876 -405.878583) (xy 159.396844 -405.818858) (xy 159.373173 -405.755853) (xy 159.357201 -405.690471)
			(xy 159.349158 -405.623648) (xy 154.57678 -405.623648) (xy 154.57678 -406.723789) (xy 161.548771 -406.723789)
			(xy 161.548774 -406.656363) (xy 161.556853 -406.589423) (xy 161.572891 -406.523933) (xy 161.596657 -406.460835)
			(xy 161.627809 -406.401038) (xy 161.665899 -406.345402) (xy 161.687764 -406.319736) (xy 161.693578 -406.312604)
			(xy 161.70008 -406.295403) (xy 161.700464 -406.286208) (xy 161.700464 -405.793956) (xy 161.700061 -405.784768)
			(xy 161.693541 -405.767585) (xy 161.687764 -405.760428) (xy 161.665897 -405.734765) (xy 161.627811 -405.67913)
			(xy 161.596663 -405.619333) (xy 161.5729 -405.556236) (xy 161.556866 -405.490747) (xy 161.548791 -405.423809)
			(xy 161.548792 -405.356385) (xy 161.556867 -405.289447) (xy 161.572902 -405.223959) (xy 161.596665 -405.160862)
			(xy 161.627814 -405.101065) (xy 161.665901 -405.04543) (xy 161.687764 -405.019764) (xy 161.693566 -405.012623)
			(xy 161.700076 -404.995429) (xy 161.700464 -404.986236) (xy 161.700464 -404.828756) (xy 161.700948 -404.818649)
			(xy 161.708694 -404.799977) (xy 161.72299 -404.785685) (xy 161.741665 -404.777945) (xy 161.751772 -404.777448)
			(xy 162.468052 -404.777448) (xy 162.478165 -404.777954) (xy 162.496858 -404.785677) (xy 162.511172 -404.799965)
			(xy 162.518928 -404.818644) (xy 162.51936 -404.828756) (xy 162.51936 -404.986236) (xy 162.519762 -404.995424)
			(xy 162.526282 -405.012608) (xy 162.53206 -405.019764) (xy 162.553921 -405.045432) (xy 162.592013 -405.101065)
			(xy 162.623166 -405.16086) (xy 162.646932 -405.223957) (xy 162.662969 -405.289446) (xy 162.671046 -405.356385)
			(xy 162.671046 -405.423809) (xy 162.66297 -405.490748) (xy 162.646934 -405.556237) (xy 162.623168 -405.619334)
			(xy 162.620889 -405.623708) (xy 163.748926 -405.623708) (xy 163.748926 -405.556283) (xy 163.757003 -405.489344)
			(xy 163.77304 -405.423855) (xy 163.796805 -405.360758) (xy 163.827957 -405.300961) (xy 163.866047 -405.245327)
			(xy 163.887912 -405.219662) (xy 163.893709 -405.212517) (xy 163.900223 -405.195326) (xy 163.900612 -405.186134)
			(xy 163.900612 -404.693882) (xy 163.900208 -404.684694) (xy 163.89369 -404.66751) (xy 163.887912 -404.660354)
			(xy 163.866069 -404.634671) (xy 163.827979 -404.579039) (xy 163.796827 -404.519246) (xy 163.773061 -404.456151)
			(xy 163.757023 -404.390664) (xy 163.748946 -404.323728) (xy 163.748944 -404.256305) (xy 163.757018 -404.189368)
			(xy 163.773051 -404.12388) (xy 163.796813 -404.060784) (xy 163.827962 -404.000989) (xy 163.866049 -403.945355)
			(xy 163.887912 -403.91969) (xy 163.893697 -403.912536) (xy 163.900218 -403.895352) (xy 163.900612 -403.886162)
			(xy 163.900612 -403.728682) (xy 163.901111 -403.718558) (xy 163.908839 -403.699841) (xy 163.923121 -403.685486)
			(xy 163.941798 -403.677663) (xy 163.95192 -403.67712) (xy 164.6682 -403.67712) (xy 164.678357 -403.677522)
			(xy 164.697113 -403.685321) (xy 164.711437 -403.699724) (xy 164.719133 -403.718523) (xy 164.719508 -403.728682)
			(xy 164.719508 -403.886162) (xy 164.719935 -403.895347) (xy 164.726437 -403.912532) (xy 164.732208 -403.91969)
			(xy 164.754093 -403.945338) (xy 164.792181 -404.000975) (xy 164.82333 -404.060774) (xy 164.847093 -404.123873)
			(xy 164.863126 -404.189364) (xy 164.8712 -404.256304) (xy 164.871198 -404.323729) (xy 164.86312 -404.390669)
			(xy 164.847083 -404.456159) (xy 164.823317 -404.519257) (xy 164.792164 -404.579054) (xy 164.754073 -404.634689)
			(xy 164.732208 -404.660354) (xy 164.726407 -404.667496) (xy 164.719895 -404.684689) (xy 164.719508 -404.693882)
			(xy 164.719508 -405.186134) (xy 164.7199 -405.195323) (xy 164.726426 -405.212508) (xy 164.732208 -405.219662)
			(xy 164.754066 -405.245332) (xy 164.792154 -405.300966) (xy 164.823305 -405.360762) (xy 164.847069 -405.423858)
			(xy 164.863104 -405.489346) (xy 164.871181 -405.556284) (xy 164.871181 -405.623707) (xy 164.863106 -405.690645)
			(xy 164.847072 -405.756133) (xy 164.823308 -405.81923) (xy 164.792159 -405.879026) (xy 164.754071 -405.934661)
			(xy 164.732208 -405.960326) (xy 164.726419 -405.967477) (xy 164.719899 -405.984663) (xy 164.719508 -405.993854)
			(xy 164.719508 -406.151334) (xy 164.719003 -406.161457) (xy 164.711273 -406.18017) (xy 164.696993 -406.194523)
			(xy 164.67832 -406.20235) (xy 164.6682 -406.202896) (xy 163.95192 -406.202896) (xy 163.941767 -406.202462)
			(xy 163.923014 -406.194672) (xy 163.90869 -406.180279) (xy 163.90099 -406.161489) (xy 163.900612 -406.151334)
			(xy 163.900612 -405.993854) (xy 163.900173 -405.98467) (xy 163.893679 -405.967485) (xy 163.887912 -405.960326)
			(xy 163.866042 -405.934666) (xy 163.827952 -405.879031) (xy 163.796801 -405.819234) (xy 163.773037 -405.756137)
			(xy 163.757001 -405.690647) (xy 163.748926 -405.623708) (xy 162.620889 -405.623708) (xy 162.592016 -405.67913)
			(xy 162.553925 -405.734763) (xy 162.53206 -405.760428) (xy 162.526264 -405.767573) (xy 162.51975 -405.784764)
			(xy 162.51936 -405.793956) (xy 162.51936 -406.286208) (xy 162.519775 -406.295394) (xy 162.526286 -406.312578)
			(xy 162.53206 -406.319736) (xy 162.553894 -406.345426) (xy 162.591986 -406.401056) (xy 162.623141 -406.460849)
			(xy 162.646908 -406.523942) (xy 162.662947 -406.589429) (xy 162.671026 -406.656365) (xy 162.671029 -406.72373)
			(xy 165.949066 -406.72373) (xy 165.949069 -406.656422) (xy 165.957117 -406.589597) (xy 165.973094 -406.524213)
			(xy 165.996771 -406.461207) (xy 166.027808 -406.401483) (xy 166.065762 -406.345896) (xy 166.087552 -406.320244)
			(xy 166.093361 -406.313108) (xy 166.099867 -406.29591) (xy 166.100252 -406.286716) (xy 166.100252 -405.793448)
			(xy 166.099807 -405.784265) (xy 166.093316 -405.767081) (xy 166.087552 -405.75992) (xy 166.06576 -405.734271)
			(xy 166.027811 -405.678685) (xy 165.996777 -405.618961) (xy 165.973104 -405.555956) (xy 165.957131 -405.490573)
			(xy 165.949087 -405.42375) (xy 165.949087 -405.356444) (xy 165.957132 -405.289621) (xy 165.973105 -405.224239)
			(xy 165.996779 -405.161234) (xy 166.027814 -405.10151) (xy 166.065764 -405.045924) (xy 166.087552 -405.020272)
			(xy 166.093349 -405.013128) (xy 166.099862 -404.995936) (xy 166.100252 -404.986744) (xy 166.100252 -404.828756)
			(xy 166.100685 -404.818605) (xy 166.108486 -404.799861) (xy 166.122878 -404.785541) (xy 166.141661 -404.777834)
			(xy 166.151814 -404.777448) (xy 166.868094 -404.777448) (xy 166.878221 -404.777932) (xy 166.896944 -404.785659)
			(xy 166.911301 -404.799946) (xy 166.919119 -404.818631) (xy 166.919656 -404.828756) (xy 166.919656 -404.986744)
			(xy 166.920055 -404.995932) (xy 166.926578 -405.013116) (xy 166.932356 -405.020272) (xy 166.95414 -405.045927)
			(xy 166.992089 -405.101513) (xy 167.023123 -405.161236) (xy 167.046796 -405.22424) (xy 167.062769 -405.289622)
			(xy 167.070814 -405.356445) (xy 167.070814 -405.423749) (xy 167.06277 -405.490572) (xy 167.046798 -405.555954)
			(xy 167.023125 -405.618958) (xy 167.020688 -405.623648) (xy 168.149245 -405.623648) (xy 168.149246 -405.556343)
			(xy 168.15729 -405.489521) (xy 168.173263 -405.424139) (xy 168.196934 -405.361134) (xy 168.227966 -405.30141)
			(xy 168.265913 -405.245823) (xy 168.2877 -405.22017) (xy 168.293492 -405.213021) (xy 168.300009 -405.195834)
			(xy 168.3004 -405.186642) (xy 168.3004 -404.693374) (xy 168.300003 -404.684185) (xy 168.29348 -404.667001)
			(xy 168.2877 -404.659846) (xy 168.265935 -404.634176) (xy 168.227988 -404.578591) (xy 168.196956 -404.518869)
			(xy 168.173284 -404.455867) (xy 168.15731 -404.390488) (xy 168.149265 -404.323668) (xy 168.149263 -404.256365)
			(xy 168.157305 -404.189545) (xy 168.173274 -404.124164) (xy 168.196943 -404.061161) (xy 168.227971 -404.001438)
			(xy 168.265915 -403.945851) (xy 168.2877 -403.920198) (xy 168.29348 -403.913041) (xy 168.300005 -403.89586)
			(xy 168.3004 -403.88667) (xy 168.3004 -403.728682) (xy 168.300917 -403.718528) (xy 168.308691 -403.699765)
			(xy 168.323049 -403.685402) (xy 168.341808 -403.677621) (xy 168.351962 -403.67712) (xy 169.068242 -403.67712)
			(xy 169.0784 -403.677599) (xy 169.097167 -403.685383) (xy 169.11153 -403.699753) (xy 169.119306 -403.718524)
			(xy 169.119804 -403.728682) (xy 169.119804 -403.88667) (xy 169.120228 -403.895856) (xy 169.126732 -403.91304)
			(xy 169.132504 -403.920198) (xy 169.154312 -403.945833) (xy 169.192257 -404.001423) (xy 169.223287 -404.061149)
			(xy 169.246957 -404.124156) (xy 169.262927 -404.18954) (xy 169.270969 -404.256364) (xy 169.270967 -404.32367)
			(xy 169.262921 -404.390493) (xy 169.246947 -404.455876) (xy 169.223274 -404.518881) (xy 169.19224 -404.578606)
			(xy 169.154292 -404.634193) (xy 169.132504 -404.659846) (xy 169.126706 -404.66699) (xy 169.120192 -404.684181)
			(xy 169.119804 -404.693374) (xy 169.119804 -405.186642) (xy 169.120193 -405.195832) (xy 169.126721 -405.213016)
			(xy 169.132504 -405.22017) (xy 169.154284 -405.245828) (xy 169.192231 -405.301414) (xy 169.223262 -405.361137)
			(xy 169.246933 -405.424141) (xy 169.262905 -405.489522) (xy 169.270949 -405.556344) (xy 169.27095 -405.623647)
			(xy 169.262907 -405.690469) (xy 169.246936 -405.75585) (xy 169.223266 -405.818854) (xy 169.192235 -405.878578)
			(xy 169.15429 -405.934165) (xy 169.132504 -405.959818) (xy 169.126718 -405.966971) (xy 169.120197 -405.984155)
			(xy 169.119804 -405.993346) (xy 169.119804 -406.151334) (xy 169.119296 -406.161489) (xy 169.111518 -406.180251)
			(xy 169.097157 -406.194613) (xy 169.078397 -406.202394) (xy 169.068242 -406.202896) (xy 168.351962 -406.202896)
			(xy 168.341806 -406.202399) (xy 168.323042 -406.194618) (xy 168.30868 -406.180254) (xy 168.300901 -406.16149)
			(xy 168.3004 -406.151334) (xy 168.3004 -405.993346) (xy 168.299968 -405.984161) (xy 168.293469 -405.966977)
			(xy 168.2877 -405.959818) (xy 168.265908 -405.93417) (xy 168.227961 -405.878582) (xy 168.196931 -405.818858)
			(xy 168.17326 -405.755853) (xy 168.157289 -405.69047) (xy 168.149245 -405.623648) (xy 167.020688 -405.623648)
			(xy 166.992092 -405.678681) (xy 166.954143 -405.734268) (xy 166.932356 -405.75992) (xy 166.926563 -405.767067)
			(xy 166.920047 -405.784256) (xy 166.919656 -405.793448) (xy 166.919656 -406.286716) (xy 166.920068 -406.295903)
			(xy 166.926582 -406.313087) (xy 166.932356 -406.320244) (xy 166.954112 -406.345922) (xy 166.992062 -406.401505)
			(xy 167.023097 -406.461225) (xy 167.046772 -406.524226) (xy 167.062747 -406.589605) (xy 167.070794 -406.656425)
			(xy 167.070797 -406.723727) (xy 167.070789 -406.72379) (xy 170.348835 -406.72379) (xy 170.348838 -406.656362)
			(xy 170.356917 -406.589421) (xy 170.372958 -406.52393) (xy 170.396728 -406.460831) (xy 170.427885 -406.401034)
			(xy 170.46598 -406.3454) (xy 170.487848 -406.319736) (xy 170.49366 -406.312602) (xy 170.500164 -406.295403)
			(xy 170.500548 -406.286208) (xy 170.500548 -405.793956) (xy 170.500148 -405.784768) (xy 170.493626 -405.767584)
			(xy 170.487848 -405.760428) (xy 170.465978 -405.734767) (xy 170.427887 -405.679133) (xy 170.396733 -405.619337)
			(xy 170.372967 -405.556239) (xy 170.356931 -405.490749) (xy 170.348854 -405.423809) (xy 170.348855 -405.356385)
			(xy 170.356932 -405.289445) (xy 170.372969 -405.223955) (xy 170.396736 -405.160858) (xy 170.42789 -405.101062)
			(xy 170.465982 -405.045428) (xy 170.487848 -405.019764) (xy 170.493648 -405.012622) (xy 170.500159 -404.995429)
			(xy 170.500548 -404.986236) (xy 170.500548 -404.828756) (xy 170.501048 -404.818651) (xy 170.50879 -404.799982)
			(xy 170.523082 -404.78569) (xy 170.541751 -404.777948) (xy 170.551856 -404.777448) (xy 171.268136 -404.777448)
			(xy 171.278241 -404.777954) (xy 171.29691 -404.785694) (xy 171.311201 -404.799984) (xy 171.318944 -404.818651)
			(xy 171.319444 -404.828756) (xy 171.319444 -404.986236) (xy 171.31985 -404.995423) (xy 171.326368 -405.012607)
			(xy 171.332144 -405.019764) (xy 171.354006 -405.045432) (xy 171.392099 -405.101064) (xy 171.423253 -405.16086)
			(xy 171.447019 -405.223956) (xy 171.463057 -405.289446) (xy 171.471134 -405.356385) (xy 171.471134 -405.423809)
			(xy 171.463058 -405.490748) (xy 171.447021 -405.556238) (xy 171.423255 -405.619335) (xy 171.421007 -405.623649)
			(xy 172.549012 -405.623649) (xy 172.549013 -405.556342) (xy 172.557058 -405.489518) (xy 172.573033 -405.424135)
			(xy 172.596709 -405.36113) (xy 172.627746 -405.301407) (xy 172.665698 -405.245822) (xy 172.687488 -405.22017)
			(xy 172.693278 -405.21302) (xy 172.699797 -405.195833) (xy 172.700188 -405.186642) (xy 172.700188 -404.693374)
			(xy 172.699793 -404.684185) (xy 172.693269 -404.667001) (xy 172.687488 -404.659846) (xy 172.66572 -404.634177)
			(xy 172.627768 -404.578594) (xy 172.596731 -404.518873) (xy 172.573055 -404.455871) (xy 172.557079 -404.39049)
			(xy 172.549032 -404.323669) (xy 172.54903 -404.256364) (xy 172.557073 -404.189542) (xy 172.573045 -404.124161)
			(xy 172.596717 -404.061157) (xy 172.627751 -404.001435) (xy 172.6657 -403.945849) (xy 172.687488 -403.920198)
			(xy 172.693267 -403.91304) (xy 172.699792 -403.895859) (xy 172.700188 -403.88667) (xy 172.700188 -403.728682)
			(xy 172.70055 -403.718503) (xy 172.708351 -403.699698) (xy 172.722756 -403.685313) (xy 172.74157 -403.677537)
			(xy 172.75175 -403.67712) (xy 173.46803 -403.67712) (xy 173.478187 -403.677608) (xy 173.496954 -403.685389)
			(xy 173.511317 -403.699756) (xy 173.519094 -403.718524) (xy 173.519592 -403.728682) (xy 173.519592 -403.88667)
			(xy 173.520018 -403.895855) (xy 173.526521 -403.91304) (xy 173.532292 -403.920198) (xy 173.5541 -403.945833)
			(xy 173.592047 -404.001422) (xy 173.623077 -404.061149) (xy 173.646747 -404.124155) (xy 173.662718 -404.189539)
			(xy 173.67076 -404.256363) (xy 173.670758 -404.32367) (xy 173.662712 -404.390493) (xy 173.646738 -404.455876)
			(xy 173.623064 -404.518882) (xy 173.59203 -404.578606) (xy 173.55408 -404.634193) (xy 173.532292 -404.659846)
			(xy 173.526492 -404.666989) (xy 173.51998 -404.684181) (xy 173.519592 -404.693374) (xy 173.519592 -405.186642)
			(xy 173.519984 -405.195831) (xy 173.52651 -405.213015) (xy 173.532292 -405.22017) (xy 173.554073 -405.245827)
			(xy 173.59202 -405.301414) (xy 173.623052 -405.361137) (xy 173.646723 -405.424141) (xy 173.662696 -405.489522)
			(xy 173.67074 -405.556343) (xy 173.670741 -405.623647) (xy 173.662698 -405.690469) (xy 173.646726 -405.755851)
			(xy 173.623055 -405.818855) (xy 173.592025 -405.878578) (xy 173.554078 -405.934165) (xy 173.532292 -405.959818)
			(xy 173.526504 -405.96697) (xy 173.519985 -405.984155) (xy 173.519592 -405.993346) (xy 173.519592 -406.151334)
			(xy 173.519095 -406.16149) (xy 173.511315 -406.180254) (xy 173.496951 -406.194617) (xy 173.478186 -406.202396)
			(xy 173.46803 -406.202896) (xy 172.75175 -406.202896) (xy 172.741586 -406.202396) (xy 172.722799 -406.194634)
			(xy 172.708413 -406.180272) (xy 172.70062 -406.161497) (xy 172.700188 -406.151334) (xy 172.700188 -405.993346)
			(xy 172.699759 -405.984161) (xy 172.693259 -405.966976) (xy 172.687488 -405.959818) (xy 172.665693 -405.934171)
			(xy 172.627741 -405.878585) (xy 172.596705 -405.818861) (xy 172.573031 -405.755856) (xy 172.557057 -405.690473)
			(xy 172.549012 -405.623649) (xy 171.421007 -405.623649) (xy 171.392102 -405.67913) (xy 171.35401 -405.734764)
			(xy 171.332144 -405.760428) (xy 171.326346 -405.767572) (xy 171.319834 -405.784764) (xy 171.319444 -405.793956)
			(xy 171.319444 -406.286208) (xy 171.319863 -406.295394) (xy 171.326372 -406.312578) (xy 171.332144 -406.319736)
			(xy 171.353978 -406.345426) (xy 171.392072 -406.401056) (xy 171.423227 -406.460848) (xy 171.446996 -406.523942)
			(xy 171.463035 -406.589428) (xy 171.471114 -406.656365) (xy 171.471117 -406.72373) (xy 174.749154 -406.72373)
			(xy 174.749157 -406.656422) (xy 174.757205 -406.589597) (xy 174.773181 -406.524213) (xy 174.796857 -406.461208)
			(xy 174.827894 -406.401483) (xy 174.865846 -406.345896) (xy 174.887636 -406.320244) (xy 174.893443 -406.313107)
			(xy 174.899951 -406.29591) (xy 174.900336 -406.286716) (xy 174.900336 -405.793448) (xy 174.899895 -405.784264)
			(xy 174.893402 -405.76708) (xy 174.887636 -405.75992) (xy 174.865844 -405.734271) (xy 174.827896 -405.678684)
			(xy 174.796863 -405.61896) (xy 174.77319 -405.555955) (xy 174.757218 -405.490573) (xy 174.749174 -405.42375)
			(xy 174.749174 -405.356444) (xy 174.757219 -405.289621) (xy 174.773192 -405.224239) (xy 174.796865 -405.161234)
			(xy 174.827899 -405.101511) (xy 174.865848 -405.045924) (xy 174.887636 -405.020272) (xy 174.893432 -405.013126)
			(xy 174.899946 -404.995936) (xy 174.900336 -404.986744) (xy 174.900336 -404.828756) (xy 174.900686 -404.818594)
			(xy 174.908503 -404.799834) (xy 174.922922 -404.785511) (xy 174.941734 -404.77782) (xy 174.951898 -404.777448)
			(xy 175.668178 -404.777448) (xy 175.678304 -404.777945) (xy 175.697027 -404.785667) (xy 175.711384 -404.79995)
			(xy 175.719202 -404.818632) (xy 175.71974 -404.828756) (xy 175.71974 -404.986744) (xy 175.720142 -404.995932)
			(xy 175.726663 -405.013115) (xy 175.73244 -405.020272) (xy 175.754224 -405.045927) (xy 175.792175 -405.101513)
			(xy 175.823209 -405.161236) (xy 175.846883 -405.22424) (xy 175.862857 -405.289622) (xy 175.870902 -405.356444)
			(xy 175.870902 -405.42375) (xy 175.862858 -405.490572) (xy 175.846885 -405.555954) (xy 175.823212 -405.618959)
			(xy 175.792178 -405.678682) (xy 175.754228 -405.734268) (xy 175.73244 -405.75992) (xy 175.726645 -405.767066)
			(xy 175.720131 -405.784256) (xy 175.71974 -405.793448) (xy 175.71974 -406.286716) (xy 175.720156 -406.295902)
			(xy 175.726667 -406.313086) (xy 175.73244 -406.320244) (xy 175.754197 -406.345922) (xy 175.792148 -406.401504)
			(xy 175.823184 -406.461224) (xy 175.846859 -406.524225) (xy 175.862835 -406.589604) (xy 175.870882 -406.656424)
			(xy 175.870885 -406.723727) (xy 175.862844 -406.790548) (xy 175.846873 -406.855929) (xy 175.823203 -406.918932)
			(xy 175.792173 -406.978655) (xy 175.754226 -407.03424) (xy 175.73244 -407.059892) (xy 175.726657 -407.067046)
			(xy 175.720136 -407.08423) (xy 175.71974 -407.09342) (xy 175.71974 -407.251408) (xy 175.719286 -407.261558)
			(xy 175.711495 -407.280302) (xy 175.697109 -407.294624) (xy 175.678329 -407.302331) (xy 175.668178 -407.302716)
			(xy 174.951898 -407.302716) (xy 174.941766 -407.302274) (xy 174.923036 -407.294537) (xy 174.908679 -407.280237)
			(xy 174.900867 -407.261538) (xy 174.900336 -407.251408) (xy 174.900336 -407.09342) (xy 174.899908 -407.084235)
			(xy 174.893406 -407.067051) (xy 174.887636 -407.059892) (xy 174.865817 -407.034266) (xy 174.827869 -406.978676)
			(xy 174.796837 -406.918948) (xy 174.773167 -406.85594) (xy 174.757196 -406.790555) (xy 174.749154 -406.72373)
			(xy 171.471117 -406.72373) (xy 171.471117 -406.723787) (xy 171.463044 -406.790724) (xy 171.44701 -406.856212)
			(xy 171.423247 -406.919308) (xy 171.392097 -406.979103) (xy 171.354008 -407.034736) (xy 171.332144 -407.0604)
			(xy 171.326358 -407.067552) (xy 171.319839 -407.084738) (xy 171.319444 -407.093928) (xy 171.319444 -407.251408)
			(xy 171.318922 -407.261512) (xy 171.31119 -407.280182) (xy 171.296905 -407.294475) (xy 171.278239 -407.302217)
			(xy 171.268136 -407.302716) (xy 170.551856 -407.302716) (xy 170.541746 -407.302251) (xy 170.52307 -407.294502)
			(xy 170.508778 -407.280199) (xy 170.501042 -407.261518) (xy 170.500548 -407.251408) (xy 170.500548 -407.093928)
			(xy 170.500114 -407.084744) (xy 170.493616 -407.067559) (xy 170.487848 -407.0604) (xy 170.465951 -407.034762)
			(xy 170.42786 -406.979124) (xy 170.396708 -406.919325) (xy 170.372944 -406.856224) (xy 170.356909 -406.790732)
			(xy 170.348835 -406.72379) (xy 167.070789 -406.72379) (xy 167.062756 -406.790548) (xy 167.046786 -406.855928)
			(xy 167.023117 -406.918931) (xy 166.992087 -406.978654) (xy 166.954142 -407.03424) (xy 166.932356 -407.059892)
			(xy 166.926575 -407.067048) (xy 166.920052 -407.08423) (xy 166.919656 -407.09342) (xy 166.919656 -407.251408)
			(xy 166.919186 -407.261556) (xy 166.911398 -407.280297) (xy 166.897017 -407.294618) (xy 166.878243 -407.302328)
			(xy 166.868094 -407.302716) (xy 166.151814 -407.302716) (xy 166.141683 -407.302261) (xy 166.122954 -407.294529)
			(xy 166.108595 -407.280233) (xy 166.100783 -407.261537) (xy 166.100252 -407.251408) (xy 166.100252 -407.09342)
			(xy 166.099821 -407.084235) (xy 166.093321 -407.067051) (xy 166.087552 -407.059892) (xy 166.065732 -407.034266)
			(xy 166.027784 -406.978676) (xy 165.996751 -406.918949) (xy 165.973079 -406.855941) (xy 165.957108 -406.790556)
			(xy 165.949066 -406.72373) (xy 162.671029 -406.72373) (xy 162.671029 -406.723787) (xy 162.662956 -406.790724)
			(xy 162.646923 -406.856212) (xy 162.62316 -406.919307) (xy 162.592011 -406.979102) (xy 162.553923 -407.034735)
			(xy 162.53206 -407.0604) (xy 162.526276 -407.067554) (xy 162.519755 -407.084738) (xy 162.51936 -407.093928)
			(xy 162.51936 -407.251408) (xy 162.518989 -407.261536) (xy 162.511231 -407.280247) (xy 162.4969 -407.294563)
			(xy 162.47818 -407.3023) (xy 162.468052 -407.302716) (xy 161.751772 -407.302716) (xy 161.741663 -407.302238)
			(xy 161.722988 -407.294494) (xy 161.708694 -407.280196) (xy 161.700958 -407.261517) (xy 161.700464 -407.251408)
			(xy 161.700464 -407.093928) (xy 161.700026 -407.084744) (xy 161.69353 -407.06756) (xy 161.687764 -407.0604)
			(xy 161.66587 -407.03476) (xy 161.627784 -406.979121) (xy 161.596637 -406.919321) (xy 161.572876 -406.856221)
			(xy 161.556844 -406.790729) (xy 161.548771 -406.723789) (xy 154.57678 -406.723789) (xy 154.57678 -409.523827)
			(xy 159.349136 -409.523827) (xy 159.34914 -409.456519) (xy 159.357187 -409.389695) (xy 159.373163 -409.324311)
			(xy 159.396839 -409.261305) (xy 159.427875 -409.20158) (xy 159.465827 -409.145992) (xy 159.487616 -409.12034)
			(xy 159.493422 -409.113202) (xy 159.499931 -409.096006) (xy 159.500316 -409.086812) (xy 159.500316 -408.593544)
			(xy 159.499881 -408.58436) (xy 159.493384 -408.567175) (xy 159.487616 -408.560016) (xy 159.465821 -408.53437)
			(xy 159.427874 -408.478782) (xy 159.396842 -408.419058) (xy 159.373171 -408.356052) (xy 159.357199 -408.29067)
			(xy 159.349156 -408.223847) (xy 159.349157 -408.156541) (xy 159.357201 -408.089719) (xy 159.373175 -408.024336)
			(xy 159.396847 -407.961331) (xy 159.42788 -407.901607) (xy 159.465828 -407.84602) (xy 159.487616 -407.820368)
			(xy 159.49341 -407.813221) (xy 159.499926 -407.796032) (xy 159.500316 -407.78684) (xy 159.500316 -407.628852)
			(xy 159.500683 -407.618693) (xy 159.508497 -407.599936) (xy 159.522911 -407.585614) (xy 159.541716 -407.577919)
			(xy 159.551878 -407.577544) (xy 160.268158 -407.577544) (xy 160.278283 -407.578061) (xy 160.297003 -407.585776)
			(xy 160.311361 -407.600053) (xy 160.319181 -407.61873) (xy 160.31972 -407.628852) (xy 160.31972 -407.78684)
			(xy 160.320107 -407.79603) (xy 160.326636 -407.813214) (xy 160.33242 -407.820368) (xy 160.354201 -407.846026)
			(xy 160.392153 -407.901611) (xy 160.423189 -407.961333) (xy 160.446864 -408.024337) (xy 160.462838 -408.089719)
			(xy 160.470884 -408.156541) (xy 160.470885 -408.223847) (xy 160.462841 -408.290669) (xy 160.446867 -408.356052)
			(xy 160.423194 -408.419056) (xy 160.392159 -408.478779) (xy 160.354208 -408.534364) (xy 160.33242 -408.560016)
			(xy 160.326636 -408.567171) (xy 160.320113 -408.584354) (xy 160.31972 -408.593544) (xy 160.31972 -409.086812)
			(xy 160.32012 -409.096) (xy 160.32664 -409.113185) (xy 160.33242 -409.12034) (xy 160.354174 -409.146021)
			(xy 160.392126 -409.201602) (xy 160.423163 -409.261321) (xy 160.44684 -409.324322) (xy 160.462817 -409.389701)
			(xy 160.470864 -409.456521) (xy 160.470867 -409.523824) (xy 160.462826 -409.590645) (xy 160.446856 -409.656026)
			(xy 160.423185 -409.719029) (xy 160.392154 -409.778751) (xy 160.354207 -409.834336) (xy 160.33242 -409.859988)
			(xy 160.326606 -409.867121) (xy 160.320101 -409.884321) (xy 160.31972 -409.893516) (xy 160.31972 -410.051504)
			(xy 160.319282 -410.061656) (xy 160.311489 -410.080404) (xy 160.297098 -410.094727) (xy 160.278312 -410.10243)
			(xy 160.268158 -410.102812) (xy 159.551878 -410.102812) (xy 159.541756 -410.102293) (xy 159.523044 -410.094568)
			(xy 159.508691 -410.080292) (xy 159.500863 -410.061623) (xy 159.500316 -410.051504) (xy 159.500316 -409.893516)
			(xy 159.499894 -409.88433) (xy 159.493388 -409.867146) (xy 159.487616 -409.859988) (xy 159.465794 -409.834365)
			(xy 159.427847 -409.778774) (xy 159.396817 -409.719046) (xy 159.373147 -409.656038) (xy 159.357177 -409.590652)
			(xy 159.349136 -409.523827) (xy 154.57678 -409.523827) (xy 154.57678 -410.6237) (xy 161.548783 -410.6237)
			(xy 161.548784 -410.556276) (xy 161.556861 -410.489337) (xy 161.572897 -410.423848) (xy 161.596662 -410.36075)
			(xy 161.627812 -410.300953) (xy 161.6659 -410.245318) (xy 161.687764 -410.219652) (xy 161.693571 -410.212515)
			(xy 161.700078 -410.195318) (xy 161.700464 -410.186124) (xy 161.700464 -409.693872) (xy 161.700053 -409.684685)
			(xy 161.693538 -409.667502) (xy 161.687764 -409.660344) (xy 161.665913 -409.634668) (xy 161.627826 -409.579035)
			(xy 161.596677 -409.519239) (xy 161.572914 -409.456144) (xy 161.556879 -409.390657) (xy 161.548802 -409.32372)
			(xy 161.548801 -409.256298) (xy 161.556875 -409.189361) (xy 161.572909 -409.123873) (xy 161.59667 -409.060777)
			(xy 161.627817 -409.000981) (xy 161.665902 -408.945346) (xy 161.687764 -408.91968) (xy 161.693559 -408.912534)
			(xy 161.700073 -408.895344) (xy 161.700464 -408.886152) (xy 161.700464 -408.728672) (xy 161.700961 -408.718566)
			(xy 161.708701 -408.699894) (xy 161.722994 -408.685601) (xy 161.741666 -408.677861) (xy 161.751772 -408.677364)
			(xy 162.468052 -408.677364) (xy 162.478167 -408.677854) (xy 162.496863 -408.68558) (xy 162.511177 -408.699874)
			(xy 162.518931 -408.718558) (xy 162.51936 -408.728672) (xy 162.51936 -408.886152) (xy 162.519802 -408.895336)
			(xy 162.526295 -408.91252) (xy 162.53206 -408.91968) (xy 162.553937 -408.945335) (xy 162.592028 -409.00097)
			(xy 162.623181 -409.060767) (xy 162.646946 -409.123866) (xy 162.662982 -409.189356) (xy 162.671057 -409.256296)
			(xy 162.671056 -409.323722) (xy 162.662978 -409.390662) (xy 162.64694 -409.456152) (xy 162.623173 -409.519249)
			(xy 162.620757 -409.523886) (xy 163.748905 -409.523886) (xy 163.748908 -409.45646) (xy 163.756988 -409.389519)
			(xy 163.773027 -409.324027) (xy 163.796796 -409.260929) (xy 163.827952 -409.201132) (xy 163.866045 -409.145497)
			(xy 163.887912 -409.119832) (xy 163.893721 -409.112696) (xy 163.900228 -409.095498) (xy 163.900612 -409.086304)
			(xy 163.900612 -408.594052) (xy 163.900174 -408.584868) (xy 163.893679 -408.567683) (xy 163.887912 -408.560524)
			(xy 163.86604 -408.534865) (xy 163.82795 -408.47923) (xy 163.796799 -408.419433) (xy 163.773035 -408.356335)
			(xy 163.757 -408.290845) (xy 163.748925 -408.223906) (xy 163.748925 -408.156482) (xy 163.757002 -408.089543)
			(xy 163.773039 -408.024053) (xy 163.796804 -407.960956) (xy 163.827957 -407.901159) (xy 163.866047 -407.845525)
			(xy 163.887912 -407.81986) (xy 163.893709 -407.812715) (xy 163.900223 -407.795524) (xy 163.900612 -407.786332)
			(xy 163.900612 -407.628852) (xy 163.901046 -407.618739) (xy 163.908802 -407.600057) (xy 163.923114 -407.585764)
			(xy 163.941806 -407.578033) (xy 163.95192 -407.577544) (xy 164.6682 -407.577544) (xy 164.678302 -407.578084)
			(xy 164.696969 -407.585811) (xy 164.711262 -407.60009) (xy 164.719007 -407.618751) (xy 164.719508 -407.628852)
			(xy 164.719508 -407.786332) (xy 164.719901 -407.795521) (xy 164.726426 -407.812705) (xy 164.732208 -407.81986)
			(xy 164.754064 -407.845532) (xy 164.792152 -407.901166) (xy 164.823303 -407.960961) (xy 164.847067 -408.024057)
			(xy 164.863103 -408.089545) (xy 164.871179 -408.156483) (xy 164.87118 -408.223905) (xy 164.863105 -408.290843)
			(xy 164.847071 -408.356332) (xy 164.823308 -408.419428) (xy 164.792158 -408.479224) (xy 164.754071 -408.534859)
			(xy 164.732208 -408.560524) (xy 164.72642 -408.567675) (xy 164.7199 -408.584861) (xy 164.719508 -408.594052)
			(xy 164.719508 -409.086304) (xy 164.719915 -409.095492) (xy 164.726431 -409.112676) (xy 164.732208 -409.119832)
			(xy 164.754036 -409.145527) (xy 164.792126 -409.201157) (xy 164.823277 -409.260949) (xy 164.847043 -409.324042)
			(xy 164.863081 -409.389528) (xy 164.87116 -409.456463) (xy 164.871163 -409.523883) (xy 164.863091 -409.590819)
			(xy 164.847059 -409.656306) (xy 164.8233 -409.719401) (xy 164.792153 -409.779196) (xy 164.75407 -409.834831)
			(xy 164.732208 -409.860496) (xy 164.726432 -409.867656) (xy 164.719905 -409.884835) (xy 164.719508 -409.894024)
			(xy 164.719508 -410.051504) (xy 164.719018 -410.061612) (xy 164.711281 -410.080289) (xy 164.696985 -410.094583)
			(xy 164.678308 -410.102319) (xy 164.6682 -410.102812) (xy 163.95192 -410.102812) (xy 163.9418 -410.102368)
			(xy 163.923099 -410.094629) (xy 163.908785 -410.080321) (xy 163.901037 -410.061624) (xy 163.900612 -410.051504)
			(xy 163.900612 -409.894024) (xy 163.900188 -409.884838) (xy 163.893683 -409.867654) (xy 163.887912 -409.860496)
			(xy 163.866012 -409.83486) (xy 163.827924 -409.779222) (xy 163.796774 -409.719422) (xy 163.773011 -409.656321)
			(xy 163.756978 -409.590828) (xy 163.748905 -409.523886) (xy 162.620757 -409.523886) (xy 162.592019 -409.579046)
			(xy 162.553926 -409.634679) (xy 162.53206 -409.660344) (xy 162.526257 -409.667485) (xy 162.519747 -409.684679)
			(xy 162.51936 -409.693872) (xy 162.51936 -410.186124) (xy 162.519768 -410.195311) (xy 162.526284 -410.212495)
			(xy 162.53206 -410.219652) (xy 162.55391 -410.24533) (xy 162.592001 -410.300961) (xy 162.623155 -410.360755)
			(xy 162.646922 -410.423851) (xy 162.66296 -410.489339) (xy 162.671038 -410.556276) (xy 162.671039 -410.623641)
			(xy 165.949078 -410.623641) (xy 165.949079 -410.556335) (xy 165.957125 -410.489511) (xy 165.9731 -410.424127)
			(xy 165.996775 -410.361122) (xy 166.027811 -410.301398) (xy 166.065763 -410.245812) (xy 166.087552 -410.22016)
			(xy 166.093354 -410.213019) (xy 166.099864 -410.195825) (xy 166.100252 -410.186632) (xy 166.100252 -409.693364)
			(xy 166.099847 -409.684176) (xy 166.093328 -409.666993) (xy 166.087552 -409.659836) (xy 166.065776 -409.634174)
			(xy 166.027826 -409.578589) (xy 165.996791 -409.518867) (xy 165.973117 -409.455864) (xy 165.957143 -409.390483)
			(xy 165.949098 -409.323661) (xy 165.949097 -409.256357) (xy 165.95714 -409.189535) (xy 165.973112 -409.124153)
			(xy 165.996784 -409.061149) (xy 166.027817 -409.001426) (xy 166.065765 -408.94584) (xy 166.087552 -408.920188)
			(xy 166.093343 -408.913039) (xy 166.099859 -408.895851) (xy 166.100252 -408.88666) (xy 166.100252 -408.728672)
			(xy 166.100698 -408.718522) (xy 166.108493 -408.699778) (xy 166.122882 -408.685458) (xy 166.141662 -408.67775)
			(xy 166.151814 -408.677364) (xy 166.868094 -408.677364) (xy 166.878223 -408.677832) (xy 166.896949 -408.685562)
			(xy 166.911306 -408.699855) (xy 166.919121 -408.718545) (xy 166.919656 -408.728672) (xy 166.919656 -408.88666)
			(xy 166.920095 -408.895844) (xy 166.92659 -408.913028) (xy 166.932356 -408.920188) (xy 166.954156 -408.94583)
			(xy 166.992105 -409.001418) (xy 167.023138 -409.061143) (xy 167.04681 -409.124149) (xy 167.062782 -409.189532)
			(xy 167.070826 -409.256356) (xy 167.070824 -409.323662) (xy 167.062779 -409.390486) (xy 167.046805 -409.455869)
			(xy 167.02313 -409.518874) (xy 167.020557 -409.523826) (xy 168.149224 -409.523826) (xy 168.149228 -409.456519)
			(xy 168.157275 -409.389695) (xy 168.17325 -409.324311) (xy 168.196925 -409.261305) (xy 168.227961 -409.201581)
			(xy 168.265911 -409.145993) (xy 168.2877 -409.12034) (xy 168.293505 -409.1132) (xy 168.300014 -409.096006)
			(xy 168.3004 -409.086812) (xy 168.3004 -408.593544) (xy 168.299969 -408.584359) (xy 168.29347 -408.567174)
			(xy 168.2877 -408.560016) (xy 168.265906 -408.53437) (xy 168.22796 -408.478782) (xy 168.196929 -408.419057)
			(xy 168.173258 -408.356052) (xy 168.157287 -408.290669) (xy 168.149244 -408.223846) (xy 168.149245 -408.156542)
			(xy 168.157289 -408.089719) (xy 168.173262 -408.024337) (xy 168.196934 -407.961332) (xy 168.227966 -407.901608)
			(xy 168.265913 -407.846021) (xy 168.2877 -407.820368) (xy 168.293493 -407.81322) (xy 168.30001 -407.796032)
			(xy 168.3004 -407.78684) (xy 168.3004 -407.628852) (xy 168.300782 -407.618695) (xy 168.308594 -407.599941)
			(xy 168.323002 -407.58562) (xy 168.341802 -407.577922) (xy 168.351962 -407.577544) (xy 169.068242 -407.577544)
			(xy 169.078372 -407.577992) (xy 169.097095 -407.585735) (xy 169.11145 -407.600032) (xy 169.119267 -407.618724)
			(xy 169.119804 -407.628852) (xy 169.119804 -407.78684) (xy 169.120194 -407.796029) (xy 169.126721 -407.813214)
			(xy 169.132504 -407.820368) (xy 169.154283 -407.846027) (xy 169.192229 -407.901614) (xy 169.22326 -407.961337)
			(xy 169.246931 -408.02434) (xy 169.262904 -408.089721) (xy 169.270948 -408.156542) (xy 169.270948 -408.223846)
			(xy 169.262906 -408.290667) (xy 169.246935 -408.356048) (xy 169.223265 -408.419052) (xy 169.192235 -408.478776)
			(xy 169.15429 -408.534363) (xy 169.132504 -408.560016) (xy 169.126719 -408.567169) (xy 169.120197 -408.584354)
			(xy 169.119804 -408.593544) (xy 169.119804 -409.086812) (xy 169.120208 -409.096) (xy 169.126726 -409.113184)
			(xy 169.132504 -409.12034) (xy 169.154255 -409.146022) (xy 169.192202 -409.201605) (xy 169.223235 -409.261325)
			(xy 169.246908 -409.324325) (xy 169.262882 -409.389704) (xy 169.270928 -409.456522) (xy 169.270931 -409.523824)
			(xy 169.262891 -409.590643) (xy 169.246924 -409.656023) (xy 169.223257 -409.719026) (xy 169.19223 -409.778748)
			(xy 169.154288 -409.834335) (xy 169.132504 -409.859988) (xy 169.126688 -409.86712) (xy 169.120185 -409.88432)
			(xy 169.119804 -409.893516) (xy 169.119804 -410.051504) (xy 169.119382 -410.061658) (xy 169.111586 -410.08041)
			(xy 169.097189 -410.094733) (xy 169.078398 -410.102433) (xy 169.068242 -410.102812) (xy 168.351962 -410.102812)
			(xy 168.341839 -410.102306) (xy 168.323127 -410.094575) (xy 168.308774 -410.080296) (xy 168.300947 -410.061624)
			(xy 168.3004 -410.051504) (xy 168.3004 -409.893516) (xy 168.299982 -409.88433) (xy 168.293474 -409.867145)
			(xy 168.2877 -409.859988) (xy 168.265878 -409.834364) (xy 168.227933 -409.778773) (xy 168.196903 -409.719045)
			(xy 168.173234 -409.656037) (xy 168.157265 -409.590652) (xy 168.149224 -409.523826) (xy 167.020557 -409.523826)
			(xy 166.992095 -409.578598) (xy 166.954145 -409.634184) (xy 166.932356 -409.659836) (xy 166.926556 -409.666979)
			(xy 166.920045 -409.684171) (xy 166.919656 -409.693364) (xy 166.919656 -410.186632) (xy 166.920061 -410.19582)
			(xy 166.926579 -410.213003) (xy 166.932356 -410.22016) (xy 166.954128 -410.245825) (xy 166.992078 -410.30141)
			(xy 167.023112 -410.361131) (xy 167.046786 -410.424134) (xy 167.06276 -410.489515) (xy 167.070805 -410.556336)
			(xy 167.070807 -410.62364) (xy 167.0708 -410.623701) (xy 170.348846 -410.623701) (xy 170.348847 -410.556275)
			(xy 170.356926 -410.489335) (xy 170.372964 -410.423844) (xy 170.396732 -410.360747) (xy 170.427888 -410.30095)
			(xy 170.465981 -410.245316) (xy 170.487848 -410.219652) (xy 170.493653 -410.212513) (xy 170.500162 -410.195318)
			(xy 170.500548 -410.186124) (xy 170.500548 -409.693872) (xy 170.50014 -409.684685) (xy 170.493624 -409.667501)
			(xy 170.487848 -409.660344) (xy 170.465994 -409.63467) (xy 170.427902 -409.579038) (xy 170.396748 -409.519243)
			(xy 170.372981 -409.456147) (xy 170.356943 -409.390659) (xy 170.348866 -409.323721) (xy 170.348865 -409.256297)
			(xy 170.35694 -409.189359) (xy 170.372976 -409.12387) (xy 170.396741 -409.060773) (xy 170.427893 -409.000978)
			(xy 170.465983 -408.945344) (xy 170.487848 -408.91968) (xy 170.493642 -408.912533) (xy 170.500157 -408.895344)
			(xy 170.500548 -408.886152) (xy 170.500548 -408.728672) (xy 170.501061 -408.718568) (xy 170.508798 -408.699899)
			(xy 170.523086 -408.685607) (xy 170.541752 -408.677864) (xy 170.551856 -408.677364) (xy 171.268136 -408.677364)
			(xy 171.278243 -408.677855) (xy 171.296915 -408.685598) (xy 171.311207 -408.699892) (xy 171.318947 -408.718565)
			(xy 171.319444 -408.728672) (xy 171.319444 -408.886152) (xy 171.31989 -408.895335) (xy 171.32638 -408.912519)
			(xy 171.332144 -408.91968) (xy 171.354022 -408.945335) (xy 171.392114 -409.000969) (xy 171.423267 -409.060766)
			(xy 171.447033 -409.123865) (xy 171.463069 -409.189356) (xy 171.471145 -409.256296) (xy 171.471144 -409.323722)
			(xy 171.463066 -409.390662) (xy 171.447028 -409.456152) (xy 171.42326 -409.51925) (xy 171.420875 -409.523827)
			(xy 172.548991 -409.523827) (xy 172.548995 -409.456519) (xy 172.557043 -409.389693) (xy 172.573021 -409.324308)
			(xy 172.5967 -409.261302) (xy 172.62774 -409.201577) (xy 172.665697 -409.145992) (xy 172.687488 -409.12034)
			(xy 172.693291 -409.113199) (xy 172.699802 -409.096005) (xy 172.700188 -409.086812) (xy 172.700188 -408.593544)
			(xy 172.699759 -408.584359) (xy 172.693259 -408.567174) (xy 172.687488 -408.560016) (xy 172.665691 -408.534371)
			(xy 172.627739 -408.478785) (xy 172.596704 -408.419061) (xy 172.573029 -408.356055) (xy 172.557055 -408.290671)
			(xy 172.549011 -408.223847) (xy 172.549012 -408.156541) (xy 172.557057 -408.089717) (xy 172.573033 -408.024333)
			(xy 172.596708 -407.961328) (xy 172.627745 -407.901605) (xy 172.665698 -407.84602) (xy 172.687488 -407.820368)
			(xy 172.693279 -407.813219) (xy 172.699797 -407.796031) (xy 172.700188 -407.78684) (xy 172.700188 -407.628852)
			(xy 172.700582 -407.618696) (xy 172.708391 -407.599945) (xy 172.722796 -407.585624) (xy 172.741592 -407.577924)
			(xy 172.75175 -407.577544) (xy 173.46803 -407.577544) (xy 173.478159 -407.578002) (xy 173.496882 -407.58574)
			(xy 173.511237 -407.600035) (xy 173.519055 -407.618725) (xy 173.519592 -407.628852) (xy 173.519592 -407.78684)
			(xy 173.519985 -407.796029) (xy 173.526511 -407.813213) (xy 173.532292 -407.820368) (xy 173.554071 -407.846027)
			(xy 173.592018 -407.901613) (xy 173.62305 -407.961336) (xy 173.646722 -408.02434) (xy 173.662694 -408.089721)
			(xy 173.670739 -408.156542) (xy 173.670739 -408.223846) (xy 173.662697 -408.290667) (xy 173.646725 -408.356049)
			(xy 173.623055 -408.419053) (xy 173.592024 -408.478776) (xy 173.554078 -408.534363) (xy 173.532292 -408.560016)
			(xy 173.526505 -408.567168) (xy 173.519985 -408.584353) (xy 173.519592 -408.593544) (xy 173.519592 -409.086812)
			(xy 173.519998 -409.096) (xy 173.526515 -409.113184) (xy 173.532292 -409.12034) (xy 173.554043 -409.146022)
			(xy 173.591991 -409.201605) (xy 173.623024 -409.261324) (xy 173.646698 -409.324325) (xy 173.662672 -409.389703)
			(xy 173.670719 -409.456522) (xy 173.670722 -409.523824) (xy 173.662682 -409.590643) (xy 173.646714 -409.656023)
			(xy 173.623047 -409.719026) (xy 173.592019 -409.778749) (xy 173.554077 -409.834336) (xy 173.532292 -409.859988)
			(xy 173.526475 -409.867118) (xy 173.519973 -409.88432) (xy 173.519592 -409.893516) (xy 173.519592 -410.051504)
			(xy 173.519181 -410.061659) (xy 173.511383 -410.080413) (xy 173.496983 -410.094737) (xy 173.478187 -410.102435)
			(xy 173.46803 -410.102812) (xy 172.75175 -410.102812) (xy 172.741633 -410.102234) (xy 172.722923 -410.094532)
			(xy 172.708567 -410.080274) (xy 172.700736 -410.061618) (xy 172.700188 -410.051504) (xy 172.700188 -409.893516)
			(xy 172.699773 -409.884329) (xy 172.693263 -409.867145) (xy 172.687488 -409.859988) (xy 172.665663 -409.834366)
			(xy 172.627713 -409.778776) (xy 172.596678 -409.719049) (xy 172.573005 -409.65604) (xy 172.557033 -409.590654)
			(xy 172.548991 -409.523827) (xy 171.420875 -409.523827) (xy 171.392104 -409.579046) (xy 171.354011 -409.63468)
			(xy 171.332144 -409.660344) (xy 171.326339 -409.667483) (xy 171.319831 -409.684679) (xy 171.319444 -409.693872)
			(xy 171.319444 -410.186124) (xy 171.319855 -410.195311) (xy 171.32637 -410.212494) (xy 171.332144 -410.219652)
			(xy 171.353994 -410.245329) (xy 171.392087 -410.300961) (xy 171.423242 -410.360755) (xy 171.447009 -410.42385)
			(xy 171.463047 -410.489338) (xy 171.471125 -410.556276) (xy 171.471127 -410.623641) (xy 174.749166 -410.623641)
			(xy 174.749167 -410.556335) (xy 174.757213 -410.489511) (xy 174.773187 -410.424128) (xy 174.796862 -410.361123)
			(xy 174.827897 -410.301399) (xy 174.865847 -410.245812) (xy 174.887636 -410.22016) (xy 174.893437 -410.213018)
			(xy 174.899948 -410.195825) (xy 174.900336 -410.186632) (xy 174.900336 -409.693364) (xy 174.899935 -409.684176)
			(xy 174.893414 -409.666992) (xy 174.887636 -409.659836) (xy 174.86586 -409.634174) (xy 174.827911 -409.578589)
			(xy 174.796878 -409.518867) (xy 174.773205 -409.455863) (xy 174.757231 -409.390482) (xy 174.749186 -409.323661)
			(xy 174.749185 -409.256357) (xy 174.757228 -409.189535) (xy 174.773199 -409.124154) (xy 174.79687 -409.06115)
			(xy 174.827902 -409.001427) (xy 174.865849 -408.94584) (xy 174.887636 -408.920188) (xy 174.893425 -408.913037)
			(xy 174.899943 -408.895851) (xy 174.900336 -408.88666) (xy 174.900336 -408.728672) (xy 174.900699 -408.718512)
			(xy 174.908511 -408.699752) (xy 174.922926 -408.685428) (xy 174.941735 -408.677736) (xy 174.951898 -408.677364)
			(xy 175.668178 -408.677364) (xy 175.678306 -408.677845) (xy 175.697032 -408.68557) (xy 175.711389 -408.699859)
			(xy 175.719205 -408.718546) (xy 175.71974 -408.728672) (xy 175.71974 -408.88666) (xy 175.720183 -408.895843)
			(xy 175.726675 -408.913028) (xy 175.73244 -408.920188) (xy 175.75424 -408.94583) (xy 175.79219 -409.001418)
			(xy 175.823224 -409.061142) (xy 175.846897 -409.124148) (xy 175.862869 -409.189532) (xy 175.870913 -409.256356)
			(xy 175.870912 -409.323662) (xy 175.862866 -409.390486) (xy 175.846891 -409.455869) (xy 175.823216 -409.518874)
			(xy 175.792181 -409.578598) (xy 175.754229 -409.634184) (xy 175.73244 -409.659836) (xy 175.726638 -409.666977)
			(xy 175.720128 -409.684171) (xy 175.71974 -409.693364) (xy 175.71974 -410.186632) (xy 175.720148 -410.195819)
			(xy 175.726665 -410.213003) (xy 175.73244 -410.22016) (xy 175.754213 -410.245825) (xy 175.792163 -410.301409)
			(xy 175.823198 -410.361131) (xy 175.846873 -410.424134) (xy 175.862848 -410.489514) (xy 175.870893 -410.556336)
			(xy 175.870895 -410.62364) (xy 175.862852 -410.690462) (xy 175.84688 -410.755843) (xy 175.823208 -410.818847)
			(xy 175.792176 -410.87857) (xy 175.754227 -410.934156) (xy 175.73244 -410.959808) (xy 175.72665 -410.966958)
			(xy 175.720133 -410.984145) (xy 175.71974 -410.993336) (xy 175.71974 -411.151324) (xy 175.719299 -411.161475)
			(xy 175.711503 -411.18022) (xy 175.697113 -411.194541) (xy 175.678331 -411.202247) (xy 175.668178 -411.202632)
			(xy 174.951898 -411.202632) (xy 174.941768 -411.202174) (xy 174.923041 -411.194441) (xy 174.908684 -411.180145)
			(xy 174.90087 -411.161452) (xy 174.900336 -411.151324) (xy 174.900336 -410.993336) (xy 174.8999 -410.984152)
			(xy 174.893403 -410.966968) (xy 174.887636 -410.959808) (xy 174.865833 -410.934169) (xy 174.827884 -410.87858)
			(xy 174.796852 -410.818855) (xy 174.77318 -410.755849) (xy 174.757208 -410.690465) (xy 174.749166 -410.623641)
			(xy 171.471127 -410.623641) (xy 171.471127 -410.6237) (xy 171.463052 -410.690638) (xy 171.447016 -410.756127)
			(xy 171.423251 -410.819223) (xy 171.392099 -410.879019) (xy 171.354009 -410.934652) (xy 171.332144 -410.960316)
			(xy 171.326351 -410.967464) (xy 171.319836 -410.984653) (xy 171.319444 -410.993844) (xy 171.319444 -411.151324)
			(xy 171.318936 -411.161429) (xy 171.311198 -411.180099) (xy 171.296909 -411.194392) (xy 171.278241 -411.202133)
			(xy 171.268136 -411.202632) (xy 170.551856 -411.202632) (xy 170.541748 -411.202152) (xy 170.523075 -411.194405)
			(xy 170.508783 -411.180108) (xy 170.501044 -411.161432) (xy 170.500548 -411.151324) (xy 170.500548 -410.993844)
			(xy 170.500106 -410.98466) (xy 170.493613 -410.967476) (xy 170.487848 -410.960316) (xy 170.465967 -410.934665)
			(xy 170.427875 -410.879029) (xy 170.396723 -410.819232) (xy 170.372957 -410.756133) (xy 170.356921 -410.690641)
			(xy 170.348846 -410.623701) (xy 167.0708 -410.623701) (xy 167.062764 -410.690461) (xy 167.046793 -410.755843)
			(xy 167.023122 -410.818847) (xy 166.99209 -410.87857) (xy 166.954143 -410.934156) (xy 166.932356 -410.959808)
			(xy 166.926568 -410.966959) (xy 166.920049 -410.984145) (xy 166.919656 -410.993336) (xy 166.919656 -411.151324)
			(xy 166.919199 -411.161473) (xy 166.911406 -411.180215) (xy 166.897021 -411.194535) (xy 166.878245 -411.202244)
			(xy 166.868094 -411.202632) (xy 166.151814 -411.202632) (xy 166.141685 -411.202161) (xy 166.122959 -411.194433)
			(xy 166.108601 -411.180141) (xy 166.100786 -411.161451) (xy 166.100252 -411.151324) (xy 166.100252 -410.993336)
			(xy 166.099813 -410.984152) (xy 166.093318 -410.966968) (xy 166.087552 -410.959808) (xy 166.065748 -410.934169)
			(xy 166.027799 -410.878581) (xy 165.996765 -410.818856) (xy 165.973093 -410.75585) (xy 165.957121 -410.690466)
			(xy 165.949078 -410.623641) (xy 162.671039 -410.623641) (xy 162.671039 -410.6237) (xy 162.662964 -410.690637)
			(xy 162.646929 -410.756126) (xy 162.623165 -410.819223) (xy 162.592014 -410.879018) (xy 162.553924 -410.934651)
			(xy 162.53206 -410.960316) (xy 162.526269 -410.967465) (xy 162.519752 -410.984653) (xy 162.51936 -410.993844)
			(xy 162.51936 -411.151324) (xy 162.519003 -411.161453) (xy 162.511239 -411.180165) (xy 162.496904 -411.19448)
			(xy 162.478182 -411.202217) (xy 162.468052 -411.202632) (xy 161.751772 -411.202632) (xy 161.741665 -411.202139)
			(xy 161.722993 -411.194398) (xy 161.7087 -411.180104) (xy 161.700961 -411.161431) (xy 161.700464 -411.151324)
			(xy 161.700464 -410.993844) (xy 161.700019 -410.984661) (xy 161.693528 -410.967477) (xy 161.687764 -410.960316)
			(xy 161.665886 -410.934663) (xy 161.6278 -410.879026) (xy 161.596652 -410.819228) (xy 161.57289 -410.756129)
			(xy 161.556857 -410.690639) (xy 161.548783 -410.6237) (xy 154.57678 -410.6237) (xy 154.57678 -417.021264)
			(xy 154.57824 -417.030391) (xy 154.586758 -417.046776) (xy 154.600563 -417.059042) (xy 154.617837 -417.065574)
			(xy 154.627072 -417.065968) (xy 200.481184 -417.065968) (xy 200.514313 -417.065397) (xy 200.579932 -417.056209)
			(xy 200.643641 -417.038009) (xy 200.704211 -417.011147) (xy 200.760469 -416.976145) (xy 200.811329 -416.933677)
			(xy 200.83399 -416.909504) (xy 200.889199 -416.849276) (xy 201.004414 -416.733405) (xy 201.124876 -416.622999)
			(xy 201.250326 -416.518295) (xy 201.380495 -416.419518) (xy 201.515101 -416.32688) (xy 201.653857 -416.240581)
			(xy 201.796463 -416.160806) (xy 201.942614 -416.087726) (xy 202.091994 -416.021499) (xy 202.244284 -415.962267)
			(xy 202.399156 -415.910157) (xy 202.556276 -415.865281) (xy 202.715308 -415.827736) (xy 202.875909 -415.797602)
			(xy 203.037734 -415.774945) (xy 203.200435 -415.759812) (xy 203.363662 -415.752236) (xy 203.445364 -415.751772)
			(xy 271.794478 -415.751772) (xy 271.87618 -415.752242) (xy 272.039408 -415.759815) (xy 272.202109 -415.774945)
			(xy 272.363935 -415.797601) (xy 272.524536 -415.827733) (xy 272.683568 -415.865277) (xy 272.840689 -415.910151)
			(xy 272.995561 -415.96226) (xy 273.147852 -416.021492) (xy 273.297233 -416.087719) (xy 273.443384 -416.160798)
			(xy 273.585991 -416.240574) (xy 273.724746 -416.326873) (xy 273.859353 -416.419511) (xy 273.989521 -416.518289)
			(xy 274.11497 -416.622994) (xy 274.235432 -416.733401) (xy 274.350646 -416.849273) (xy 274.405852 -416.909504)
			(xy 274.428514 -416.933679) (xy 274.479371 -416.976152) (xy 274.535629 -417.011162) (xy 274.596198 -417.03803)
			(xy 274.659908 -417.056238) (xy 274.725528 -417.065434) (xy 274.758658 -417.065968) (xy 313.023504 -417.065968)
			(xy 313.032722 -417.06555) (xy 313.049945 -417.058972) (xy 313.063715 -417.046711) (xy 313.072237 -417.030362)
			(xy 313.073796 -417.021264) (xy 313.073796 -394.27912) (xy 326.479662 -394.27912) (xy 326.525636 -394.325094)
			(xy 326.525636 -397.823826) (xy 330.929171 -397.823826) (xy 330.929175 -397.756517) (xy 330.937223 -397.689692)
			(xy 330.953201 -397.624307) (xy 330.976879 -397.561301) (xy 331.007918 -397.501576) (xy 331.045873 -397.44599)
			(xy 331.067664 -397.420338) (xy 331.073477 -397.413205) (xy 331.07998 -397.396005) (xy 331.080364 -397.38681)
			(xy 331.080364 -396.893542) (xy 331.079919 -396.884359) (xy 331.073428 -396.867175) (xy 331.067664 -396.860014)
			(xy 331.045866 -396.83437) (xy 331.007916 -396.778783) (xy 330.976881 -396.719059) (xy 330.953208 -396.656053)
			(xy 330.937235 -396.59067) (xy 330.929191 -396.523846) (xy 330.929192 -396.456539) (xy 330.937238 -396.389716)
			(xy 330.953213 -396.324333) (xy 330.976888 -396.261328) (xy 331.007923 -396.201604) (xy 331.045875 -396.146018)
			(xy 331.067664 -396.120366) (xy 331.073465 -396.113225) (xy 331.079975 -396.096031) (xy 331.080364 -396.086838)
			(xy 331.080364 -395.92885) (xy 331.080805 -395.918678) (xy 331.088579 -395.89988) (xy 331.10296 -395.885492)
			(xy 331.121755 -395.87771) (xy 331.131926 -395.877288) (xy 331.848206 -395.877288) (xy 331.858384 -395.87766)
			(xy 331.877189 -395.885456) (xy 331.891575 -395.899859) (xy 331.899351 -395.918671) (xy 331.899768 -395.92885)
			(xy 331.899768 -396.086838) (xy 331.900167 -396.096026) (xy 331.906689 -396.11321) (xy 331.912468 -396.120366)
			(xy 331.934246 -396.146026) (xy 331.972195 -396.201612) (xy 332.003228 -396.261334) (xy 332.026901 -396.324338)
			(xy 332.042874 -396.389719) (xy 332.050919 -396.45654) (xy 332.05092 -396.523845) (xy 332.042877 -396.590666)
			(xy 332.026905 -396.656048) (xy 332.003234 -396.719052) (xy 331.972202 -396.778775) (xy 331.934255 -396.834362)
			(xy 331.912468 -396.860014) (xy 331.906679 -396.867164) (xy 331.90016 -396.884351) (xy 331.899768 -396.893542)
			(xy 331.899768 -397.38681) (xy 331.90018 -397.395997) (xy 331.906693 -397.413181) (xy 331.912468 -397.420338)
			(xy 331.934218 -397.446021) (xy 331.972167 -397.501603) (xy 332.00059 -397.556296) (xy 333.128836 -397.556296)
			(xy 333.136911 -397.489358) (xy 333.152946 -397.423869) (xy 333.17671 -397.360773) (xy 333.20786 -397.300977)
			(xy 333.245948 -397.245343) (xy 333.267812 -397.219678) (xy 333.273602 -397.212528) (xy 333.28012 -397.195341)
			(xy 333.280512 -397.18615) (xy 333.280512 -397.028924) (xy 333.280936 -397.018802) (xy 333.288678 -397.000096)
			(xy 333.302993 -396.985781) (xy 333.321698 -396.978037) (xy 333.33182 -396.977616) (xy 334.0481 -396.977616)
			(xy 334.058224 -396.978016) (xy 334.076931 -396.985768) (xy 334.091246 -397.000089) (xy 334.098988 -397.018799)
			(xy 334.099408 -397.028924) (xy 334.099408 -397.18615) (xy 334.09984 -397.195335) (xy 334.106338 -397.21252)
			(xy 334.112108 -397.219678) (xy 334.133982 -397.245335) (xy 334.172069 -397.300971) (xy 334.203219 -397.360769)
			(xy 334.226982 -397.423866) (xy 334.243017 -397.489356) (xy 334.251092 -397.556295) (xy 334.251091 -397.62372)
			(xy 334.243014 -397.690658) (xy 334.226978 -397.756148) (xy 334.203213 -397.819245) (xy 334.200796 -397.823884)
			(xy 335.328964 -397.823884) (xy 335.328968 -397.756459) (xy 335.337047 -397.689518) (xy 335.353085 -397.624028)
			(xy 335.376852 -397.560929) (xy 335.408005 -397.501132) (xy 335.446095 -397.445496) (xy 335.46796 -397.41983)
			(xy 335.473776 -397.412699) (xy 335.480277 -397.395497) (xy 335.48066 -397.386302) (xy 335.48066 -396.89405)
			(xy 335.480213 -396.884867) (xy 335.473723 -396.867683) (xy 335.46796 -396.860522) (xy 335.446088 -396.834864)
			(xy 335.408002 -396.779228) (xy 335.376854 -396.71943) (xy 335.353092 -396.656332) (xy 335.337058 -396.590843)
			(xy 335.328984 -396.523904) (xy 335.328985 -396.456481) (xy 335.337061 -396.389542) (xy 335.353096 -396.324053)
			(xy 335.37686 -396.260956) (xy 335.40801 -396.201159) (xy 335.446097 -396.145524) (xy 335.46796 -396.119858)
			(xy 335.473764 -396.112719) (xy 335.480273 -396.095523) (xy 335.48066 -396.08633) (xy 335.48066 -395.92885)
			(xy 335.481168 -395.918724) (xy 335.488883 -395.9) (xy 335.503164 -395.885642) (xy 335.521845 -395.877824)
			(xy 335.531968 -395.877288) (xy 336.248248 -395.877288) (xy 336.258404 -395.877682) (xy 336.277155 -395.885491)
			(xy 336.291476 -395.899896) (xy 336.299176 -395.918692) (xy 336.299556 -395.92885) (xy 336.299556 -396.08633)
			(xy 336.299962 -396.095517) (xy 336.30648 -396.112701) (xy 336.312256 -396.119858) (xy 336.334112 -396.145531)
			(xy 336.372204 -396.201163) (xy 336.403357 -396.260958) (xy 336.427124 -396.324054) (xy 336.443161 -396.389542)
			(xy 336.451239 -396.456481) (xy 336.45124 -396.523904) (xy 336.443164 -396.590843) (xy 336.427128 -396.656332)
			(xy 336.403363 -396.719428) (xy 336.372211 -396.779224) (xy 336.334121 -396.834858) (xy 336.312256 -396.860522)
			(xy 336.306462 -396.867669) (xy 336.299947 -396.884858) (xy 336.299556 -396.89405) (xy 336.299556 -397.386302)
			(xy 336.299975 -397.395488) (xy 336.306484 -397.412672) (xy 336.312256 -397.41983) (xy 336.334084 -397.445525)
			(xy 336.372177 -397.501154) (xy 336.40094 -397.556356) (xy 337.529156 -397.556356) (xy 337.537198 -397.489535)
			(xy 337.553169 -397.424153) (xy 337.576839 -397.361149) (xy 337.607869 -397.301426) (xy 337.645814 -397.245839)
			(xy 337.6676 -397.220186) (xy 337.673385 -397.213033) (xy 337.679907 -397.195848) (xy 337.6803 -397.186658)
			(xy 337.6803 -397.028924) (xy 337.680741 -397.018771) (xy 337.688529 -397.000019) (xy 337.70292 -396.985695)
			(xy 337.721708 -396.977995) (xy 337.731862 -396.977616) (xy 338.448142 -396.977616) (xy 338.458268 -396.978091)
			(xy 338.476986 -396.985829) (xy 338.49134 -397.000118) (xy 338.499162 -397.0188) (xy 338.499704 -397.028924)
			(xy 338.499704 -397.186658) (xy 338.500133 -397.195843) (xy 338.506634 -397.213028) (xy 338.512404 -397.220186)
			(xy 338.5342 -397.245831) (xy 338.572146 -397.301419) (xy 338.603176 -397.361144) (xy 338.626847 -397.42415)
			(xy 338.642818 -397.489532) (xy 338.65086 -397.556355) (xy 338.650859 -397.62366) (xy 338.642815 -397.690483)
			(xy 338.626842 -397.755865) (xy 338.60317 -397.81887) (xy 338.600595 -397.823826) (xy 339.729259 -397.823826)
			(xy 339.729263 -397.756517) (xy 339.737311 -397.689692) (xy 339.753288 -397.624308) (xy 339.776965 -397.561301)
			(xy 339.808004 -397.501577) (xy 339.845958 -397.44599) (xy 339.867748 -397.420338) (xy 339.873559 -397.413204)
			(xy 339.880064 -397.396005) (xy 339.880448 -397.38681) (xy 339.880448 -396.893542) (xy 339.880007 -396.884358)
			(xy 339.873513 -396.867174) (xy 339.867748 -396.860014) (xy 339.84595 -396.83437) (xy 339.808001 -396.778783)
			(xy 339.776968 -396.719058) (xy 339.753295 -396.656052) (xy 339.737322 -396.590669) (xy 339.729279 -396.523845)
			(xy 339.72928 -396.456539) (xy 339.737325 -396.389716) (xy 339.753299 -396.324333) (xy 339.776974 -396.261328)
			(xy 339.808009 -396.201604) (xy 339.845959 -396.146018) (xy 339.867748 -396.120366) (xy 339.873547 -396.113223)
			(xy 339.880059 -396.096031) (xy 339.880448 -396.086838) (xy 339.880448 -395.92885) (xy 339.880905 -395.91868)
			(xy 339.888675 -395.899885) (xy 339.903051 -395.885498) (xy 339.921841 -395.877713) (xy 339.93201 -395.877288)
			(xy 340.64829 -395.877288) (xy 340.658467 -395.877673) (xy 340.677271 -395.885464) (xy 340.691658 -395.899862)
			(xy 340.699435 -395.918672) (xy 340.699852 -395.92885) (xy 340.699852 -396.086838) (xy 340.700255 -396.096026)
			(xy 340.706775 -396.113209) (xy 340.712552 -396.120366) (xy 340.73433 -396.146026) (xy 340.77228 -396.201611)
			(xy 340.803314 -396.261334) (xy 340.826988 -396.324337) (xy 340.842962 -396.389718) (xy 340.851007 -396.45654)
			(xy 340.851007 -396.523845) (xy 340.842964 -396.590667) (xy 340.826992 -396.656048) (xy 340.80332 -396.719053)
			(xy 340.772287 -396.778776) (xy 340.734339 -396.834362) (xy 340.712552 -396.860014) (xy 340.706761 -396.867163)
			(xy 340.700244 -396.884351) (xy 340.699852 -396.893542) (xy 340.699852 -397.38681) (xy 340.700268 -397.395996)
			(xy 340.706779 -397.41318) (xy 340.712552 -397.420338) (xy 340.734302 -397.446021) (xy 340.772253 -397.501603)
			(xy 340.800676 -397.556296) (xy 341.928924 -397.556296) (xy 341.936999 -397.489359) (xy 341.953033 -397.42387)
			(xy 341.976796 -397.360774) (xy 342.007946 -397.300978) (xy 342.046033 -397.245343) (xy 342.067896 -397.219678)
			(xy 342.073684 -397.212527) (xy 342.080204 -397.195341) (xy 342.080596 -397.18615) (xy 342.080596 -397.028924)
			(xy 342.081035 -397.018804) (xy 342.088775 -397.000101) (xy 342.103084 -396.985786) (xy 342.121784 -396.978039)
			(xy 342.131904 -396.977616) (xy 342.848184 -396.977616) (xy 342.858307 -396.978029) (xy 342.877014 -396.985775)
			(xy 342.891329 -397.000093) (xy 342.899072 -397.0188) (xy 342.899492 -397.028924) (xy 342.899492 -397.18615)
			(xy 342.899928 -397.195334) (xy 342.906424 -397.212519) (xy 342.912192 -397.219678) (xy 342.934066 -397.245335)
			(xy 342.972155 -397.300971) (xy 343.003306 -397.360768) (xy 343.02707 -397.423866) (xy 343.043105 -397.489356)
			(xy 343.05118 -397.556295) (xy 343.051179 -397.62372) (xy 343.043102 -397.690659) (xy 343.027065 -397.756149)
			(xy 343.0033 -397.819246) (xy 343.000914 -397.823825) (xy 344.12905 -397.823825) (xy 344.129054 -397.756517)
			(xy 344.137101 -397.689692) (xy 344.153078 -397.624308) (xy 344.176755 -397.561302) (xy 344.207793 -397.501577)
			(xy 344.245746 -397.44599) (xy 344.267536 -397.420338) (xy 344.273346 -397.413202) (xy 344.279852 -397.396004)
			(xy 344.280236 -397.38681) (xy 344.280236 -396.893542) (xy 344.279797 -396.884358) (xy 344.273303 -396.867174)
			(xy 344.267536 -396.860014) (xy 344.245738 -396.83437) (xy 344.20779 -396.778782) (xy 344.176757 -396.719058)
			(xy 344.153085 -396.656052) (xy 344.137113 -396.590669) (xy 344.12907 -396.523845) (xy 344.129071 -396.45654)
			(xy 344.137116 -396.389716) (xy 344.15309 -396.324334) (xy 344.176764 -396.261329) (xy 344.207798 -396.201605)
			(xy 344.245748 -396.146018) (xy 344.267536 -396.120366) (xy 344.273334 -396.113222) (xy 344.279847 -396.09603)
			(xy 344.280236 -396.086838) (xy 344.280236 -395.92885) (xy 344.280705 -395.918682) (xy 344.288473 -395.899889)
			(xy 344.302845 -395.885502) (xy 344.32163 -395.877715) (xy 344.331798 -395.877288) (xy 345.048078 -395.877288)
			(xy 345.058254 -395.877683) (xy 345.077058 -395.88547) (xy 345.091445 -395.899866) (xy 345.099222 -395.918673)
			(xy 345.09964 -395.92885) (xy 345.09964 -396.086838) (xy 345.100045 -396.096025) (xy 345.106564 -396.113209)
			(xy 345.11234 -396.120366) (xy 345.134118 -396.146026) (xy 345.172069 -396.201611) (xy 345.203104 -396.261333)
			(xy 345.226778 -396.324337) (xy 345.242752 -396.389718) (xy 345.250798 -396.45654) (xy 345.250798 -396.523845)
			(xy 345.242755 -396.590667) (xy 345.226782 -396.656049) (xy 345.20311 -396.719053) (xy 345.172077 -396.778776)
			(xy 345.134128 -396.834362) (xy 345.11234 -396.860014) (xy 345.106548 -396.867162) (xy 345.100032 -396.884351)
			(xy 345.09964 -396.893542) (xy 345.09964 -397.38681) (xy 345.100059 -397.395996) (xy 345.106568 -397.41318)
			(xy 345.11234 -397.420338) (xy 345.134091 -397.446021) (xy 345.172042 -397.501602) (xy 345.200497 -397.556355)
			(xy 346.32922 -397.556355) (xy 346.337264 -397.489532) (xy 346.353237 -397.42415) (xy 346.37691 -397.361146)
			(xy 346.407945 -397.301423) (xy 346.445896 -397.245838) (xy 346.467684 -397.220186) (xy 346.473467 -397.213031)
			(xy 346.47999 -397.195848) (xy 346.480384 -397.186658) (xy 346.480384 -397.028924) (xy 346.480841 -397.018773)
			(xy 346.488625 -397.000025) (xy 346.503011 -396.985701) (xy 346.521794 -396.977997) (xy 346.531946 -396.977616)
			(xy 347.248226 -396.977616) (xy 347.258351 -396.978104) (xy 347.277069 -396.985836) (xy 347.291423 -397.000121)
			(xy 347.299246 -397.018801) (xy 347.299788 -397.028924) (xy 347.299788 -397.186658) (xy 347.300221 -397.195843)
			(xy 347.306719 -397.213027) (xy 347.312488 -397.220186) (xy 347.334285 -397.24583) (xy 347.372232 -397.301419)
			(xy 347.403263 -397.361143) (xy 347.426934 -397.424149) (xy 347.442905 -397.489532) (xy 347.450948 -397.556355)
			(xy 347.450947 -397.62366) (xy 347.442903 -397.690483) (xy 347.426929 -397.755865) (xy 347.403257 -397.81887)
			(xy 347.400682 -397.823826) (xy 374.92908 -397.823826) (xy 374.929084 -397.756517) (xy 374.937132 -397.689691)
			(xy 374.95311 -397.624306) (xy 374.976789 -397.5613) (xy 375.007829 -397.501576) (xy 375.045785 -397.445989)
			(xy 375.067576 -397.420338) (xy 375.073379 -397.413197) (xy 375.07989 -397.396003) (xy 375.080276 -397.38681)
			(xy 375.080276 -396.893542) (xy 375.079851 -396.884356) (xy 375.073348 -396.867171) (xy 375.067576 -396.860014)
			(xy 375.045777 -396.83437) (xy 375.007826 -396.778784) (xy 374.976792 -396.719059) (xy 374.953118 -396.656053)
			(xy 374.937144 -396.59067) (xy 374.9291 -396.523846) (xy 374.929101 -396.456539) (xy 374.937147 -396.389715)
			(xy 374.953122 -396.324332) (xy 374.976798 -396.261327) (xy 375.007834 -396.201604) (xy 375.045787 -396.146018)
			(xy 375.067576 -396.120366) (xy 375.073367 -396.113216) (xy 375.079886 -396.096029) (xy 375.080276 -396.086838)
			(xy 375.080276 -395.92885) (xy 375.080706 -395.918677) (xy 375.088481 -395.899876) (xy 375.102866 -395.885488)
			(xy 375.121665 -395.877708) (xy 375.131838 -395.877288) (xy 375.848118 -395.877288) (xy 375.858297 -395.87765)
			(xy 375.877102 -395.885451) (xy 375.891487 -395.899856) (xy 375.899263 -395.91867) (xy 375.89968 -395.92885)
			(xy 375.89968 -396.086838) (xy 375.900076 -396.096027) (xy 375.9066 -396.113211) (xy 375.91238 -396.120366)
			(xy 375.934157 -396.146026) (xy 375.972105 -396.201612) (xy 376.003138 -396.261335) (xy 376.02681 -396.324338)
			(xy 376.042784 -396.389719) (xy 376.050828 -396.456541) (xy 376.050829 -396.523844) (xy 376.042786 -396.590666)
			(xy 376.026815 -396.656047) (xy 376.003144 -396.719051) (xy 375.972113 -396.778775) (xy 375.934167 -396.834362)
			(xy 375.91238 -396.860014) (xy 375.906593 -396.867166) (xy 375.900073 -396.884351) (xy 375.89968 -396.893542)
			(xy 375.89968 -397.38681) (xy 375.90009 -397.395997) (xy 375.906604 -397.413181) (xy 375.91238 -397.420338)
			(xy 375.93413 -397.446021) (xy 375.972078 -397.501604) (xy 376.0005 -397.556296) (xy 377.128745 -397.556296)
			(xy 377.136821 -397.489358) (xy 377.152856 -397.423869) (xy 377.17662 -397.360772) (xy 377.207771 -397.300977)
			(xy 377.24586 -397.245343) (xy 377.267724 -397.219678) (xy 377.273515 -397.212529) (xy 377.280032 -397.195341)
			(xy 377.280424 -397.18615) (xy 377.280424 -397.028924) (xy 377.280836 -397.0188) (xy 377.288581 -397.000092)
			(xy 377.302899 -396.985776) (xy 377.321608 -396.978034) (xy 377.331732 -396.977616) (xy 378.048012 -396.977616)
			(xy 378.058137 -396.978006) (xy 378.076844 -396.985761) (xy 378.091159 -397.000086) (xy 378.098901 -397.018798)
			(xy 378.09932 -397.028924) (xy 378.09932 -397.18615) (xy 378.09975 -397.195335) (xy 378.10625 -397.21252)
			(xy 378.11202 -397.219678) (xy 378.133893 -397.245335) (xy 378.17198 -397.300972) (xy 378.203129 -397.360769)
			(xy 378.226892 -397.423867) (xy 378.242926 -397.489357) (xy 378.251001 -397.556295) (xy 378.251 -397.62372)
			(xy 378.242924 -397.690658) (xy 378.226888 -397.756147) (xy 378.203123 -397.819245) (xy 378.200706 -397.823885)
			(xy 379.328873 -397.823885) (xy 379.328877 -397.756458) (xy 379.336956 -397.689518) (xy 379.352995 -397.624027)
			(xy 379.376762 -397.560929) (xy 379.407915 -397.501131) (xy 379.446007 -397.445496) (xy 379.467872 -397.41983)
			(xy 379.47369 -397.4127) (xy 379.48019 -397.395498) (xy 379.480572 -397.386302) (xy 379.480572 -396.89405)
			(xy 379.480144 -396.884865) (xy 379.473643 -396.86768) (xy 379.467872 -396.860522) (xy 379.445999 -396.834864)
			(xy 379.407913 -396.779228) (xy 379.376764 -396.719431) (xy 379.353002 -396.656333) (xy 379.336968 -396.590843)
			(xy 379.328893 -396.523904) (xy 379.328894 -396.456481) (xy 379.33697 -396.389542) (xy 379.353006 -396.324053)
			(xy 379.37677 -396.260956) (xy 379.40792 -396.201159) (xy 379.446008 -396.145524) (xy 379.467872 -396.119858)
			(xy 379.473678 -396.11272) (xy 379.480185 -396.095524) (xy 379.480572 -396.08633) (xy 379.480572 -395.92885)
			(xy 379.481069 -395.918723) (xy 379.488786 -395.899996) (xy 379.50307 -395.885637) (xy 379.521755 -395.877822)
			(xy 379.53188 -395.877288) (xy 380.24816 -395.877288) (xy 380.25831 -395.877754) (xy 380.277059 -395.885534)
			(xy 380.291384 -395.899917) (xy 380.299087 -395.918698) (xy 380.299468 -395.92885) (xy 380.299468 -396.08633)
			(xy 380.299871 -396.095518) (xy 380.30639 -396.112702) (xy 380.312168 -396.119858) (xy 380.334023 -396.145531)
			(xy 380.372114 -396.201163) (xy 380.403267 -396.260958) (xy 380.427033 -396.324054) (xy 380.443071 -396.389543)
			(xy 380.451148 -396.456481) (xy 380.451149 -396.523904) (xy 380.443073 -396.590842) (xy 380.427038 -396.656331)
			(xy 380.403273 -396.719428) (xy 380.372122 -396.779224) (xy 380.334032 -396.834857) (xy 380.312168 -396.860522)
			(xy 380.306375 -396.86767) (xy 380.299859 -396.884858) (xy 380.299468 -396.89405) (xy 380.299468 -397.386302)
			(xy 380.299884 -397.395488) (xy 380.306394 -397.412672) (xy 380.312168 -397.41983) (xy 380.333996 -397.445525)
			(xy 380.372088 -397.501155) (xy 380.40085 -397.556356) (xy 381.529065 -397.556356) (xy 381.537108 -397.489534)
			(xy 381.553079 -397.424153) (xy 381.576749 -397.361149) (xy 381.60778 -397.301425) (xy 381.645726 -397.245838)
			(xy 381.667512 -397.220186) (xy 381.673298 -397.213034) (xy 381.679819 -397.195849) (xy 381.680212 -397.186658)
			(xy 381.680212 -397.028924) (xy 381.680641 -397.01877) (xy 381.688431 -397.000016) (xy 381.702826 -396.985691)
			(xy 381.721618 -396.977993) (xy 381.731774 -396.977616) (xy 382.448054 -396.977616) (xy 382.458175 -396.978164)
			(xy 382.47689 -396.985872) (xy 382.491247 -397.000139) (xy 382.499072 -397.018806) (xy 382.499616 -397.028924)
			(xy 382.499616 -397.186658) (xy 382.500043 -397.195844) (xy 382.506544 -397.213028) (xy 382.512316 -397.220186)
			(xy 382.534115 -397.245829) (xy 382.572066 -397.301416) (xy 382.603102 -397.36114) (xy 382.626776 -397.424146)
			(xy 382.642749 -397.48953) (xy 382.650793 -397.556354) (xy 382.650793 -397.623661) (xy 382.642747 -397.690485)
			(xy 382.626771 -397.755868) (xy 382.603096 -397.818873) (xy 382.600522 -397.823826) (xy 383.729168 -397.823826)
			(xy 383.729172 -397.756517) (xy 383.73722 -397.689692) (xy 383.753198 -397.624307) (xy 383.776876 -397.561301)
			(xy 383.807914 -397.501576) (xy 383.845869 -397.44599) (xy 383.86766 -397.420338) (xy 383.873473 -397.413205)
			(xy 383.879976 -397.396005) (xy 383.88036 -397.38681) (xy 383.88036 -396.893542) (xy 383.879916 -396.884359)
			(xy 383.873425 -396.867175) (xy 383.86766 -396.860014) (xy 383.845862 -396.83437) (xy 383.807912 -396.778783)
			(xy 383.776878 -396.719058) (xy 383.753205 -396.656053) (xy 383.737232 -396.590669) (xy 383.729188 -396.523846)
			(xy 383.729189 -396.456539) (xy 383.737235 -396.389716) (xy 383.753209 -396.324333) (xy 383.776884 -396.261328)
			(xy 383.80792 -396.201604) (xy 383.845871 -396.146018) (xy 383.86766 -396.120366) (xy 383.873461 -396.113224)
			(xy 383.879971 -396.096031) (xy 383.88036 -396.086838) (xy 383.88036 -395.92885) (xy 383.880805 -395.918679)
			(xy 383.888578 -395.899881) (xy 383.902958 -395.885494) (xy 383.921751 -395.877711) (xy 383.931922 -395.877288)
			(xy 384.648202 -395.877288) (xy 384.65838 -395.877663) (xy 384.677184 -395.885458) (xy 384.691571 -395.899859)
			(xy 384.699347 -395.918672) (xy 384.699764 -395.92885) (xy 384.699764 -396.086838) (xy 384.700164 -396.096026)
			(xy 384.706686 -396.11321) (xy 384.712464 -396.120366) (xy 384.734242 -396.146026) (xy 384.772191 -396.201612)
			(xy 384.803224 -396.261334) (xy 384.826898 -396.324337) (xy 384.842871 -396.389719) (xy 384.850916 -396.45654)
			(xy 384.850917 -396.523845) (xy 384.842874 -396.590666) (xy 384.826902 -396.656048) (xy 384.803231 -396.719052)
			(xy 384.772199 -396.778776) (xy 384.734251 -396.834362) (xy 384.712464 -396.860014) (xy 384.706674 -396.867164)
			(xy 384.700156 -396.884351) (xy 384.699764 -396.893542) (xy 384.699764 -397.38681) (xy 384.700177 -397.395997)
			(xy 384.70669 -397.413181) (xy 384.712464 -397.420338) (xy 384.734214 -397.446021) (xy 384.772164 -397.501603)
			(xy 384.800587 -397.556296) (xy 385.928833 -397.556296) (xy 385.936908 -397.489358) (xy 385.952943 -397.42387)
			(xy 385.976706 -397.360773) (xy 386.007856 -397.300977) (xy 386.045944 -397.245343) (xy 386.067808 -397.219678)
			(xy 386.073597 -397.212528) (xy 386.080116 -397.195341) (xy 386.080508 -397.18615) (xy 386.080508 -397.028924)
			(xy 386.080936 -397.018802) (xy 386.088677 -397.000097) (xy 386.102991 -396.985782) (xy 386.121694 -396.978037)
			(xy 386.131816 -396.977616) (xy 386.848096 -396.977616) (xy 386.85822 -396.97802) (xy 386.876927 -396.985769)
			(xy 386.891242 -397.00009) (xy 386.898984 -397.0188) (xy 386.899404 -397.028924) (xy 386.899404 -397.18615)
			(xy 386.899837 -397.195335) (xy 386.906335 -397.212519) (xy 386.912104 -397.219678) (xy 386.933978 -397.245335)
			(xy 386.972066 -397.300971) (xy 387.003216 -397.360768) (xy 387.026979 -397.423866) (xy 387.043014 -397.489356)
			(xy 387.051089 -397.556295) (xy 387.051088 -397.62372) (xy 387.043011 -397.690659) (xy 387.026975 -397.756148)
			(xy 387.00321 -397.819245) (xy 387.000823 -397.823826) (xy 388.128959 -397.823826) (xy 388.128963 -397.756517)
			(xy 388.137011 -397.689692) (xy 388.152988 -397.624308) (xy 388.176665 -397.561301) (xy 388.207704 -397.501577)
			(xy 388.245658 -397.44599) (xy 388.267448 -397.420338) (xy 388.273259 -397.413204) (xy 388.279764 -397.396005)
			(xy 388.280148 -397.38681) (xy 388.280148 -396.893542) (xy 388.279707 -396.884358) (xy 388.273213 -396.867174)
			(xy 388.267448 -396.860014) (xy 388.24565 -396.83437) (xy 388.207701 -396.778783) (xy 388.176668 -396.719058)
			(xy 388.152995 -396.656052) (xy 388.137022 -396.590669) (xy 388.128979 -396.523845) (xy 388.12898 -396.456539)
			(xy 388.137025 -396.389716) (xy 388.152999 -396.324333) (xy 388.176674 -396.261328) (xy 388.207709 -396.201604)
			(xy 388.245659 -396.146018) (xy 388.267448 -396.120366) (xy 388.273247 -396.113223) (xy 388.279759 -396.096031)
			(xy 388.280148 -396.086838) (xy 388.280148 -395.92885) (xy 388.280605 -395.91868) (xy 388.288375 -395.899885)
			(xy 388.302751 -395.885498) (xy 388.321541 -395.877713) (xy 388.33171 -395.877288) (xy 389.04799 -395.877288)
			(xy 389.058167 -395.877673) (xy 389.076971 -395.885464) (xy 389.091358 -395.899862) (xy 389.099135 -395.918672)
			(xy 389.099552 -395.92885) (xy 389.099552 -396.086838) (xy 389.099955 -396.096026) (xy 389.106475 -396.113209)
			(xy 389.112252 -396.120366) (xy 389.13403 -396.146026) (xy 389.17198 -396.201611) (xy 389.203014 -396.261334)
			(xy 389.226688 -396.324337) (xy 389.242662 -396.389718) (xy 389.250707 -396.45654) (xy 389.250707 -396.523845)
			(xy 389.242664 -396.590667) (xy 389.226692 -396.656048) (xy 389.20302 -396.719053) (xy 389.171987 -396.778776)
			(xy 389.134039 -396.834362) (xy 389.112252 -396.860014) (xy 389.106461 -396.867163) (xy 389.099944 -396.884351)
			(xy 389.099552 -396.893542) (xy 389.099552 -397.38681) (xy 389.099968 -397.395996) (xy 389.106479 -397.41318)
			(xy 389.112252 -397.420338) (xy 389.134002 -397.446021) (xy 389.171953 -397.501603) (xy 389.200407 -397.556356)
			(xy 390.329153 -397.556356) (xy 390.337195 -397.489535) (xy 390.353166 -397.424153) (xy 390.376836 -397.36115)
			(xy 390.407865 -397.301426) (xy 390.44581 -397.245839) (xy 390.467596 -397.220186) (xy 390.473381 -397.213032)
			(xy 390.479903 -397.195848) (xy 390.480296 -397.186658) (xy 390.480296 -397.028924) (xy 390.480741 -397.018772)
			(xy 390.488528 -397.000021) (xy 390.502918 -396.985697) (xy 390.521704 -396.977995) (xy 390.531858 -396.977616)
			(xy 391.248138 -396.977616) (xy 391.258264 -396.978095) (xy 391.276982 -396.985831) (xy 391.291336 -397.000119)
			(xy 391.299158 -397.0188) (xy 391.2997 -397.028924) (xy 391.2997 -397.186658) (xy 391.30013 -397.195843)
			(xy 391.30663 -397.213028) (xy 391.3124 -397.220186) (xy 391.334196 -397.245831) (xy 391.372142 -397.301419)
			(xy 391.403173 -397.361144) (xy 391.426844 -397.424149) (xy 391.442815 -397.489532) (xy 391.450857 -397.556355)
			(xy 391.450856 -397.62366) (xy 391.442812 -397.690483) (xy 391.426839 -397.755865) (xy 391.403167 -397.81887)
			(xy 391.372135 -397.878594) (xy 391.334187 -397.934181) (xy 391.3124 -397.959834) (xy 391.306606 -397.966981)
			(xy 391.30009 -397.98417) (xy 391.2997 -397.993362) (xy 391.2997 -398.486884) (xy 391.300118 -398.49607)
			(xy 391.306626 -398.513255) (xy 391.3124 -398.520412) (xy 391.334222 -398.546036) (xy 391.372167 -398.601627)
			(xy 391.403197 -398.661355) (xy 391.426866 -398.724363) (xy 391.442835 -398.789748) (xy 391.450876 -398.856574)
			(xy 391.450872 -398.923881) (xy 391.442825 -398.990705) (xy 391.42685 -399.056089) (xy 391.403175 -399.119095)
			(xy 391.372139 -399.178819) (xy 391.334189 -399.234407) (xy 391.3124 -399.26006) (xy 391.306595 -399.2672)
			(xy 391.300086 -399.284394) (xy 391.2997 -399.293588) (xy 391.2997 -399.451576) (xy 391.299259 -399.461729)
			(xy 391.291471 -399.480481) (xy 391.27708 -399.494805) (xy 391.258292 -399.502505) (xy 391.248138 -399.502884)
			(xy 390.531858 -399.502884) (xy 390.521732 -399.502409) (xy 390.503014 -399.494671) (xy 390.48866 -399.480382)
			(xy 390.480838 -399.4617) (xy 390.480296 -399.451576) (xy 390.480296 -399.293588) (xy 390.479892 -399.2844)
			(xy 390.473374 -399.267216) (xy 390.467596 -399.26006) (xy 390.445845 -399.234378) (xy 390.407898 -399.178795)
			(xy 390.376865 -399.119075) (xy 390.353192 -399.056075) (xy 390.337218 -398.990696) (xy 390.329172 -398.923878)
			(xy 390.329169 -398.856576) (xy 390.337209 -398.789757) (xy 390.353176 -398.724377) (xy 390.376843 -398.661374)
			(xy 390.40787 -398.601652) (xy 390.445812 -398.546065) (xy 390.467596 -398.520412) (xy 390.473412 -398.51328)
			(xy 390.479915 -398.49608) (xy 390.480296 -398.486884) (xy 390.480296 -397.993362) (xy 390.479905 -397.984173)
			(xy 390.473378 -397.966988) (xy 390.467596 -397.959834) (xy 390.445819 -397.934173) (xy 390.407873 -397.878587)
			(xy 390.376842 -397.818864) (xy 390.35317 -397.755861) (xy 390.337198 -397.69048) (xy 390.329154 -397.623659)
			(xy 390.329153 -397.556356) (xy 389.200407 -397.556356) (xy 389.202988 -397.561322) (xy 389.226664 -397.624322)
			(xy 389.24264 -397.689701) (xy 389.250687 -397.75652) (xy 389.25069 -397.823823) (xy 389.24265 -397.890643)
			(xy 389.226681 -397.956023) (xy 389.203012 -398.019026) (xy 389.171982 -398.078748) (xy 389.134038 -398.134334)
			(xy 389.112252 -398.159986) (xy 389.10643 -398.167113) (xy 389.099932 -398.184318) (xy 389.099552 -398.193514)
			(xy 389.099552 -398.351502) (xy 389.099138 -398.361675) (xy 389.09135 -398.380472) (xy 389.076962 -398.394857)
			(xy 389.058163 -398.40264) (xy 389.04799 -398.403064) (xy 388.33171 -398.403064) (xy 388.321539 -398.402628)
			(xy 388.302745 -398.394847) (xy 388.28836 -398.380465) (xy 388.280574 -398.361673) (xy 388.280148 -398.351502)
			(xy 388.280148 -398.193514) (xy 388.27972 -398.184329) (xy 388.273218 -398.167145) (xy 388.267448 -398.159986)
			(xy 388.245622 -398.134365) (xy 388.207674 -398.078774) (xy 388.176642 -398.019046) (xy 388.152971 -397.956038)
			(xy 388.137 -397.890652) (xy 388.128959 -397.823826) (xy 387.000823 -397.823826) (xy 386.972058 -397.879042)
			(xy 386.933968 -397.934677) (xy 386.912104 -397.960342) (xy 386.906308 -397.967487) (xy 386.899793 -397.984678)
			(xy 386.899404 -397.99387) (xy 386.899404 -398.486376) (xy 386.899825 -398.495562) (xy 386.906331 -398.512747)
			(xy 386.912104 -398.519904) (xy 386.934003 -398.54554) (xy 386.972091 -398.601179) (xy 387.003239 -398.660979)
			(xy 387.027001 -398.72408) (xy 387.043034 -398.789572) (xy 387.051107 -398.856514) (xy 387.051104 -398.92394)
			(xy 387.043025 -398.990881) (xy 387.026985 -399.056372) (xy 387.003217 -399.11947) (xy 386.972063 -399.179268)
			(xy 386.93397 -399.234903) (xy 386.912104 -399.260568) (xy 386.906297 -399.267706) (xy 386.899788 -399.284902)
			(xy 386.899404 -399.294096) (xy 386.899404 -399.451576) (xy 386.898965 -399.461696) (xy 386.891225 -399.480399)
			(xy 386.876916 -399.494714) (xy 386.858216 -399.502461) (xy 386.848096 -399.502884) (xy 386.131816 -399.502884)
			(xy 386.121693 -399.502471) (xy 386.102986 -399.494725) (xy 386.088671 -399.480407) (xy 386.080928 -399.4617)
			(xy 386.080508 -399.451576) (xy 386.080508 -399.294096) (xy 386.080098 -399.284909) (xy 386.073584 -399.267725)
			(xy 386.067808 -399.260568) (xy 386.045979 -399.234874) (xy 386.007889 -399.179244) (xy 385.976736 -399.119451)
			(xy 385.95297 -399.056358) (xy 385.936931 -398.990873) (xy 385.928852 -398.923938) (xy 385.928849 -398.856517)
			(xy 385.936922 -398.789581) (xy 385.952954 -398.724093) (xy 385.976714 -398.660998) (xy 386.007861 -398.601203)
			(xy 386.045946 -398.545569) (xy 386.067808 -398.519904) (xy 386.073586 -398.512746) (xy 386.080112 -398.495565)
			(xy 386.080508 -398.486376) (xy 386.080508 -397.99387) (xy 386.080111 -397.984681) (xy 386.073588 -397.967497)
			(xy 386.067808 -397.960342) (xy 386.045954 -397.934669) (xy 386.007864 -397.879036) (xy 385.976712 -397.819241)
			(xy 385.952947 -397.756145) (xy 385.936911 -397.690657) (xy 385.928834 -397.623719) (xy 385.928833 -397.556296)
			(xy 384.800587 -397.556296) (xy 384.803199 -397.561322) (xy 384.826873 -397.624323) (xy 384.842849 -397.689701)
			(xy 384.850896 -397.75652) (xy 384.850899 -397.823822) (xy 384.842859 -397.890642) (xy 384.82689 -397.956022)
			(xy 384.803222 -398.019025) (xy 384.772193 -398.078748) (xy 384.734249 -398.134334) (xy 384.712464 -398.159986)
			(xy 384.706644 -398.167114) (xy 384.700144 -398.184318) (xy 384.699764 -398.193514) (xy 384.699764 -398.351502)
			(xy 384.699268 -398.36166) (xy 384.691494 -398.380428) (xy 384.677128 -398.394794) (xy 384.65836 -398.402568)
			(xy 384.648202 -398.403064) (xy 383.931922 -398.403064) (xy 383.921752 -398.402618) (xy 383.902958 -398.394841)
			(xy 383.888573 -398.380462) (xy 383.880787 -398.361672) (xy 383.88036 -398.351502) (xy 383.88036 -398.193514)
			(xy 383.87993 -398.184329) (xy 383.873429 -398.167145) (xy 383.86766 -398.159986) (xy 383.845834 -398.134365)
			(xy 383.807885 -398.078775) (xy 383.776852 -398.019047) (xy 383.753181 -397.956038) (xy 383.73721 -397.890652)
			(xy 383.729168 -397.823826) (xy 382.600522 -397.823826) (xy 382.572059 -397.878597) (xy 382.534106 -397.934182)
			(xy 382.512316 -397.959834) (xy 382.506524 -397.966983) (xy 382.500006 -397.98417) (xy 382.499616 -397.993362)
			(xy 382.499616 -398.486884) (xy 382.50003 -398.496071) (xy 382.506541 -398.513255) (xy 382.512316 -398.520412)
			(xy 382.53414 -398.546034) (xy 382.572091 -398.601624) (xy 382.603125 -398.661351) (xy 382.626798 -398.72436)
			(xy 382.64277 -398.789746) (xy 382.650812 -398.856573) (xy 382.650808 -398.923881) (xy 382.64276 -398.990707)
			(xy 382.626782 -399.056092) (xy 382.603103 -399.119098) (xy 382.572063 -399.178822) (xy 382.534107 -399.234408)
			(xy 382.512316 -399.26006) (xy 382.506513 -399.267201) (xy 382.500002 -399.284395) (xy 382.499616 -399.293588)
			(xy 382.499616 -399.451576) (xy 382.499159 -399.461727) (xy 382.491375 -399.480475) (xy 382.476989 -399.494799)
			(xy 382.458206 -399.502503) (xy 382.448054 -399.502884) (xy 381.731774 -399.502884) (xy 381.721649 -399.502396)
			(xy 381.702931 -399.494664) (xy 381.688577 -399.480379) (xy 381.680754 -399.461699) (xy 381.680212 -399.451576)
			(xy 381.680212 -399.293588) (xy 381.679805 -399.284401) (xy 381.673289 -399.267216) (xy 381.667512 -399.26006)
			(xy 381.64576 -399.234378) (xy 381.607812 -399.178796) (xy 381.576779 -399.119076) (xy 381.553105 -399.056075)
			(xy 381.537131 -398.990697) (xy 381.529084 -398.923878) (xy 381.529081 -398.856576) (xy 381.537121 -398.789757)
			(xy 381.553089 -398.724377) (xy 381.576757 -398.661374) (xy 381.607784 -398.601651) (xy 381.645727 -398.546064)
			(xy 381.667512 -398.520412) (xy 381.67333 -398.513282) (xy 381.679831 -398.49608) (xy 381.680212 -398.486884)
			(xy 381.680212 -397.993362) (xy 381.679818 -397.984173) (xy 381.673293 -397.966989) (xy 381.667512 -397.959834)
			(xy 381.645735 -397.934173) (xy 381.607788 -397.878588) (xy 381.576755 -397.818865) (xy 381.553083 -397.755862)
			(xy 381.53711 -397.690481) (xy 381.529066 -397.623659) (xy 381.529065 -397.556356) (xy 380.40085 -397.556356)
			(xy 380.403242 -397.560947) (xy 380.42701 -397.62404) (xy 380.443049 -397.689525) (xy 380.451128 -397.756461)
			(xy 380.451131 -397.823882) (xy 380.443059 -397.890818) (xy 380.427026 -397.956306) (xy 380.403265 -398.019401)
			(xy 380.372117 -398.079196) (xy 380.334031 -398.134829) (xy 380.312168 -398.160494) (xy 380.306387 -398.16765)
			(xy 380.299864 -398.184832) (xy 380.299468 -398.194022) (xy 380.299468 -398.351502) (xy 380.298975 -398.361628)
			(xy 380.291248 -398.380347) (xy 380.276964 -398.394703) (xy 380.258283 -398.402524) (xy 380.24816 -398.403064)
			(xy 379.53188 -398.403064) (xy 379.52172 -398.402694) (xy 379.50296 -398.394885) (xy 379.488636 -398.380472)
			(xy 379.480944 -398.361664) (xy 379.480572 -398.351502) (xy 379.480572 -398.194022) (xy 379.480158 -398.184835)
			(xy 379.473648 -398.16765) (xy 379.467872 -398.160494) (xy 379.445972 -398.134859) (xy 379.407886 -398.07922)
			(xy 379.376738 -398.019419) (xy 379.352978 -397.956318) (xy 379.336946 -397.890826) (xy 379.328873 -397.823885)
			(xy 378.200706 -397.823885) (xy 378.171972 -397.879041) (xy 378.133884 -397.934676) (xy 378.11202 -397.960342)
			(xy 378.106225 -397.967489) (xy 378.099709 -397.984678) (xy 378.09932 -397.99387) (xy 378.09932 -398.486376)
			(xy 378.099737 -398.495563) (xy 378.106245 -398.512747) (xy 378.11202 -398.519904) (xy 378.133919 -398.54554)
			(xy 378.172005 -398.60118) (xy 378.203153 -398.66098) (xy 378.226914 -398.724081) (xy 378.242947 -398.789573)
			(xy 378.251019 -398.856514) (xy 378.251016 -398.92394) (xy 378.242937 -398.99088) (xy 378.226898 -399.056371)
			(xy 378.203131 -399.11947) (xy 378.171977 -399.179267) (xy 378.133885 -399.234902) (xy 378.11202 -399.260568)
			(xy 378.106214 -399.267707) (xy 378.099704 -399.284902) (xy 378.09932 -399.294096) (xy 378.09932 -399.451576)
			(xy 378.098865 -399.461694) (xy 378.091128 -399.480394) (xy 378.076824 -399.494708) (xy 378.05813 -399.502458)
			(xy 378.048012 -399.502884) (xy 377.331732 -399.502884) (xy 377.32161 -399.502458) (xy 377.302903 -399.494717)
			(xy 377.288587 -399.480403) (xy 377.280844 -399.461698) (xy 377.280424 -399.451576) (xy 377.280424 -399.294096)
			(xy 377.280011 -399.284909) (xy 377.273499 -399.267725) (xy 377.267724 -399.260568) (xy 377.245895 -399.234874)
			(xy 377.207803 -399.179244) (xy 377.17665 -399.119452) (xy 377.152882 -399.056359) (xy 377.136844 -398.990873)
			(xy 377.128765 -398.923938) (xy 377.128761 -398.856516) (xy 377.136834 -398.78958) (xy 377.152866 -398.724093)
			(xy 377.176627 -398.660997) (xy 377.207775 -398.601202) (xy 377.245861 -398.545569) (xy 377.267724 -398.519904)
			(xy 377.273504 -398.512747) (xy 377.280028 -398.495565) (xy 377.280424 -398.486376) (xy 377.280424 -397.99387)
			(xy 377.280023 -397.984682) (xy 377.273502 -397.967498) (xy 377.267724 -397.960342) (xy 377.245869 -397.934669)
			(xy 377.207778 -397.879036) (xy 377.176626 -397.819241) (xy 377.15286 -397.756145) (xy 377.136823 -397.690657)
			(xy 377.128746 -397.623719) (xy 377.128745 -397.556296) (xy 376.0005 -397.556296) (xy 376.003112 -397.561323)
			(xy 376.026786 -397.624324) (xy 376.042761 -397.689702) (xy 376.050808 -397.756521) (xy 376.050811 -397.823822)
			(xy 376.042771 -397.890642) (xy 376.026803 -397.956022) (xy 376.003135 -398.019025) (xy 375.972108 -398.078747)
			(xy 375.934165 -398.134333) (xy 375.91238 -398.159986) (xy 375.906562 -398.167116) (xy 375.900061 -398.184318)
			(xy 375.89968 -398.193514) (xy 375.89968 -398.351502) (xy 375.899169 -398.361658) (xy 375.891397 -398.380423)
			(xy 375.877037 -398.394788) (xy 375.858274 -398.402565) (xy 375.848118 -398.403064) (xy 375.131838 -398.403064)
			(xy 375.121669 -398.402605) (xy 375.102876 -398.394833) (xy 375.08849 -398.380458) (xy 375.080703 -398.361671)
			(xy 375.080276 -398.351502) (xy 375.080276 -398.193514) (xy 375.079865 -398.184327) (xy 375.073352 -398.167142)
			(xy 375.067576 -398.159986) (xy 375.04575 -398.134365) (xy 375.007799 -398.078775) (xy 374.976766 -398.019048)
			(xy 374.953093 -397.956039) (xy 374.937122 -397.890652) (xy 374.92908 -397.823826) (xy 347.400682 -397.823826)
			(xy 347.372224 -397.878594) (xy 347.334276 -397.934182) (xy 347.312488 -397.959834) (xy 347.306693 -397.96698)
			(xy 347.300178 -397.98417) (xy 347.299788 -397.993362) (xy 347.299788 -398.486884) (xy 347.300209 -398.49607)
			(xy 347.306715 -398.513254) (xy 347.312488 -398.520412) (xy 347.33431 -398.546035) (xy 347.372256 -398.601627)
			(xy 347.403286 -398.661354) (xy 347.426956 -398.724363) (xy 347.442926 -398.789748) (xy 347.450967 -398.856573)
			(xy 347.450963 -398.923881) (xy 347.442916 -398.990705) (xy 347.42694 -399.056089) (xy 347.403264 -399.119095)
			(xy 347.372228 -399.17882) (xy 347.334277 -399.234407) (xy 347.312488 -399.26006) (xy 347.306682 -399.267199)
			(xy 347.300173 -399.284394) (xy 347.299788 -399.293588) (xy 347.299788 -399.451576) (xy 347.299359 -399.46173)
			(xy 347.291569 -399.480484) (xy 347.277174 -399.494809) (xy 347.258382 -399.502507) (xy 347.248226 -399.502884)
			(xy 346.531946 -399.502884) (xy 346.521825 -399.502336) (xy 346.50311 -399.494628) (xy 346.488753 -399.480361)
			(xy 346.480928 -399.461694) (xy 346.480384 -399.451576) (xy 346.480384 -399.293588) (xy 346.479983 -399.2844)
			(xy 346.473463 -399.267215) (xy 346.467684 -399.26006) (xy 346.44593 -399.234379) (xy 346.407977 -399.178798)
			(xy 346.37694 -399.119079) (xy 346.353263 -399.056078) (xy 346.337287 -398.990699) (xy 346.329239 -398.923879)
			(xy 346.329236 -398.856576) (xy 346.337277 -398.789755) (xy 346.353247 -398.724374) (xy 346.376918 -398.661371)
			(xy 346.40795 -398.601648) (xy 346.445897 -398.546064) (xy 346.467684 -398.520412) (xy 346.473499 -398.513279)
			(xy 346.480003 -398.496079) (xy 346.480384 -398.486884) (xy 346.480384 -397.993362) (xy 346.479996 -397.984172)
			(xy 346.473467 -397.966988) (xy 346.467684 -397.959834) (xy 346.445905 -397.934174) (xy 346.407953 -397.87859)
			(xy 346.376917 -397.818868) (xy 346.353241 -397.755864) (xy 346.337266 -397.690483) (xy 346.329221 -397.62366)
			(xy 346.32922 -397.556355) (xy 345.200497 -397.556355) (xy 345.203078 -397.561321) (xy 345.226754 -397.624322)
			(xy 345.24273 -397.689701) (xy 345.250778 -397.75652) (xy 345.250781 -397.823823) (xy 345.242741 -397.890643)
			(xy 345.226771 -397.956023) (xy 345.203102 -398.019026) (xy 345.172072 -398.078749) (xy 345.134126 -398.134334)
			(xy 345.11234 -398.159986) (xy 345.106517 -398.167112) (xy 345.10002 -398.184318) (xy 345.09964 -398.193514)
			(xy 345.09964 -398.351502) (xy 345.099237 -398.361676) (xy 345.091447 -398.380475) (xy 345.077055 -398.394861)
			(xy 345.058253 -398.402642) (xy 345.048078 -398.403064) (xy 344.331798 -398.403064) (xy 344.32164 -398.402568)
			(xy 344.302872 -398.394794) (xy 344.288506 -398.380428) (xy 344.280732 -398.36166) (xy 344.280236 -398.351502)
			(xy 344.280236 -398.193514) (xy 344.279811 -398.184329) (xy 344.273307 -398.167144) (xy 344.267536 -398.159986)
			(xy 344.245711 -398.134365) (xy 344.207763 -398.078774) (xy 344.176732 -398.019046) (xy 344.153061 -397.956037)
			(xy 344.137091 -397.890651) (xy 344.12905 -397.823825) (xy 343.000914 -397.823825) (xy 342.972147 -397.879042)
			(xy 342.934057 -397.934677) (xy 342.912192 -397.960342) (xy 342.906394 -397.967486) (xy 342.899881 -397.984678)
			(xy 342.899492 -397.99387) (xy 342.899492 -398.486376) (xy 342.899916 -398.495562) (xy 342.90642 -398.512746)
			(xy 342.912192 -398.519904) (xy 342.934092 -398.54554) (xy 342.97218 -398.601178) (xy 343.003329 -398.660979)
			(xy 343.027092 -398.724079) (xy 343.043125 -398.789572) (xy 343.051198 -398.856514) (xy 343.051195 -398.92394)
			(xy 343.043115 -398.990881) (xy 343.027076 -399.056372) (xy 343.003307 -399.119471) (xy 342.972152 -399.179268)
			(xy 342.934058 -399.234903) (xy 342.912192 -399.260568) (xy 342.906383 -399.267704) (xy 342.899876 -399.284902)
			(xy 342.899492 -399.294096) (xy 342.899492 -399.451576) (xy 342.899064 -399.461698) (xy 342.891323 -399.480403)
			(xy 342.877009 -399.494718) (xy 342.858306 -399.502463) (xy 342.848184 -399.502884) (xy 342.131904 -399.502884)
			(xy 342.12178 -399.50248) (xy 342.103073 -399.494731) (xy 342.088758 -399.48041) (xy 342.081016 -399.4617)
			(xy 342.080596 -399.451576) (xy 342.080596 -399.294096) (xy 342.080189 -399.284909) (xy 342.073673 -399.267724)
			(xy 342.067896 -399.260568) (xy 342.046068 -399.234874) (xy 342.007978 -399.179243) (xy 341.976826 -399.119451)
			(xy 341.95306 -399.056358) (xy 341.937022 -398.990872) (xy 341.928943 -398.923937) (xy 341.92894 -398.856517)
			(xy 341.937012 -398.789581) (xy 341.953044 -398.724094) (xy 341.976804 -398.660999) (xy 342.00795 -398.601203)
			(xy 342.046034 -398.545569) (xy 342.067896 -398.519904) (xy 342.073673 -398.512745) (xy 342.080199 -398.495565)
			(xy 342.080596 -398.486376) (xy 342.080596 -397.99387) (xy 342.080201 -397.984681) (xy 342.073677 -397.967497)
			(xy 342.067896 -397.960342) (xy 342.046042 -397.934669) (xy 342.007953 -397.879035) (xy 341.976802 -397.81924)
			(xy 341.953038 -397.756144) (xy 341.937002 -397.690656) (xy 341.928925 -397.623719) (xy 341.928924 -397.556296)
			(xy 340.800676 -397.556296) (xy 340.803288 -397.561322) (xy 340.826964 -397.624322) (xy 340.84294 -397.689701)
			(xy 340.850987 -397.75652) (xy 340.85099 -397.823823) (xy 340.84295 -397.890643) (xy 340.826981 -397.956023)
			(xy 340.803312 -398.019026) (xy 340.772282 -398.078748) (xy 340.734338 -398.134334) (xy 340.712552 -398.159986)
			(xy 340.70673 -398.167113) (xy 340.700232 -398.184318) (xy 340.699852 -398.193514) (xy 340.699852 -398.351502)
			(xy 340.699438 -398.361675) (xy 340.69165 -398.380472) (xy 340.677262 -398.394857) (xy 340.658463 -398.40264)
			(xy 340.64829 -398.403064) (xy 339.93201 -398.403064) (xy 339.921839 -398.402628) (xy 339.903045 -398.394847)
			(xy 339.88866 -398.380465) (xy 339.880874 -398.361673) (xy 339.880448 -398.351502) (xy 339.880448 -398.193514)
			(xy 339.88002 -398.184329) (xy 339.873518 -398.167145) (xy 339.867748 -398.159986) (xy 339.845922 -398.134365)
			(xy 339.807974 -398.078774) (xy 339.776942 -398.019046) (xy 339.753271 -397.956038) (xy 339.7373 -397.890652)
			(xy 339.729259 -397.823826) (xy 338.600595 -397.823826) (xy 338.572138 -397.878594) (xy 338.534191 -397.934181)
			(xy 338.512404 -397.959834) (xy 338.506611 -397.966982) (xy 338.500094 -397.98417) (xy 338.499704 -397.993362)
			(xy 338.499704 -398.486884) (xy 338.500121 -398.49607) (xy 338.50663 -398.513255) (xy 338.512404 -398.520412)
			(xy 338.534226 -398.546036) (xy 338.572171 -398.601627) (xy 338.6032 -398.661355) (xy 338.626869 -398.724363)
			(xy 338.642838 -398.789748) (xy 338.650879 -398.856574) (xy 338.650875 -398.923881) (xy 338.642828 -398.990705)
			(xy 338.626853 -399.056089) (xy 338.603178 -399.119094) (xy 338.572143 -399.178819) (xy 338.534193 -399.234407)
			(xy 338.512404 -399.26006) (xy 338.5066 -399.2672) (xy 338.50009 -399.284394) (xy 338.499704 -399.293588)
			(xy 338.499704 -399.451576) (xy 338.499259 -399.461728) (xy 338.491472 -399.480479) (xy 338.477082 -399.494803)
			(xy 338.458296 -399.502505) (xy 338.448142 -399.502884) (xy 337.731862 -399.502884) (xy 337.721736 -399.502405)
			(xy 337.703018 -399.494669) (xy 337.688664 -399.480381) (xy 337.680842 -399.4617) (xy 337.6803 -399.451576)
			(xy 337.6803 -399.293588) (xy 337.679895 -399.2844) (xy 337.673378 -399.267216) (xy 337.6676 -399.26006)
			(xy 337.645849 -399.234378) (xy 337.607901 -399.178795) (xy 337.576869 -399.119075) (xy 337.553196 -399.056075)
			(xy 337.537221 -398.990697) (xy 337.529175 -398.923878) (xy 337.529172 -398.856576) (xy 337.537212 -398.789757)
			(xy 337.55318 -398.724377) (xy 337.576847 -398.661374) (xy 337.607874 -398.601651) (xy 337.645816 -398.546065)
			(xy 337.6676 -398.520412) (xy 337.673416 -398.513281) (xy 337.679919 -398.49608) (xy 337.6803 -398.486884)
			(xy 337.6803 -397.993362) (xy 337.679908 -397.984173) (xy 337.673382 -397.966989) (xy 337.6676 -397.959834)
			(xy 337.645823 -397.934173) (xy 337.607877 -397.878587) (xy 337.576845 -397.818864) (xy 337.553174 -397.755861)
			(xy 337.537201 -397.69048) (xy 337.529157 -397.623659) (xy 337.529156 -397.556356) (xy 336.40094 -397.556356)
			(xy 336.403332 -397.560946) (xy 336.4271 -397.624039) (xy 336.443139 -397.689525) (xy 336.451219 -397.756461)
			(xy 336.451222 -397.823882) (xy 336.44315 -397.890819) (xy 336.427117 -397.956306) (xy 336.403355 -398.019402)
			(xy 336.372206 -398.079196) (xy 336.334119 -398.13483) (xy 336.312256 -398.160494) (xy 336.306474 -398.167649)
			(xy 336.299952 -398.184832) (xy 336.299556 -398.194022) (xy 336.299556 -398.351502) (xy 336.299075 -398.361629)
			(xy 336.291346 -398.380351) (xy 336.277058 -398.394708) (xy 336.258373 -398.402526) (xy 336.248248 -398.403064)
			(xy 335.531968 -398.403064) (xy 335.521807 -398.402704) (xy 335.503047 -398.394891) (xy 335.488724 -398.380475)
			(xy 335.481032 -398.361665) (xy 335.48066 -398.351502) (xy 335.48066 -398.194022) (xy 335.480226 -398.184838)
			(xy 335.473727 -398.167654) (xy 335.46796 -398.160494) (xy 335.44606 -398.134859) (xy 335.407975 -398.079219)
			(xy 335.376828 -398.019418) (xy 335.353068 -397.956318) (xy 335.337036 -397.890825) (xy 335.328964 -397.823884)
			(xy 334.200796 -397.823884) (xy 334.172062 -397.879042) (xy 334.133972 -397.934677) (xy 334.112108 -397.960342)
			(xy 334.106312 -397.967488) (xy 334.099797 -397.984678) (xy 334.099408 -397.99387) (xy 334.099408 -398.486376)
			(xy 334.099828 -398.495562) (xy 334.106335 -398.512747) (xy 334.112108 -398.519904) (xy 334.134007 -398.54554)
			(xy 334.172094 -398.601179) (xy 334.203243 -398.660979) (xy 334.227005 -398.72408) (xy 334.243037 -398.789573)
			(xy 334.25111 -398.856514) (xy 334.251107 -398.92394) (xy 334.243028 -398.990881) (xy 334.226989 -399.056372)
			(xy 334.203221 -399.11947) (xy 334.172066 -399.179267) (xy 334.133974 -399.234903) (xy 334.112108 -399.260568)
			(xy 334.106301 -399.267706) (xy 334.099792 -399.284902) (xy 334.099408 -399.294096) (xy 334.099408 -399.451576)
			(xy 334.098965 -399.461696) (xy 334.091226 -399.480398) (xy 334.076918 -399.494712) (xy 334.05822 -399.50246)
			(xy 334.0481 -399.502884) (xy 333.33182 -399.502884) (xy 333.321697 -399.502467) (xy 333.302991 -399.494723)
			(xy 333.288675 -399.480406) (xy 333.280932 -399.461699) (xy 333.280512 -399.451576) (xy 333.280512 -399.294096)
			(xy 333.280101 -399.284909) (xy 333.273587 -399.267725) (xy 333.267812 -399.260568) (xy 333.245983 -399.234874)
			(xy 333.207892 -399.179244) (xy 333.176739 -399.119452) (xy 333.152973 -399.056358) (xy 333.136934 -398.990873)
			(xy 333.128855 -398.923938) (xy 333.128852 -398.856516) (xy 333.136925 -398.78958) (xy 333.152957 -398.724093)
			(xy 333.176717 -398.660998) (xy 333.207865 -398.601203) (xy 333.24595 -398.545569) (xy 333.267812 -398.519904)
			(xy 333.273591 -398.512746) (xy 333.280116 -398.495565) (xy 333.280512 -398.486376) (xy 333.280512 -397.99387)
			(xy 333.280114 -397.984682) (xy 333.273592 -397.967497) (xy 333.267812 -397.960342) (xy 333.245957 -397.934669)
			(xy 333.207868 -397.879036) (xy 333.176716 -397.819241) (xy 333.152951 -397.756145) (xy 333.136914 -397.690657)
			(xy 333.128837 -397.623719) (xy 333.128836 -397.556296) (xy 332.00059 -397.556296) (xy 332.003202 -397.561323)
			(xy 332.026877 -397.624323) (xy 332.042852 -397.689701) (xy 332.050899 -397.75652) (xy 332.050902 -397.823822)
			(xy 332.042862 -397.890642) (xy 332.026893 -397.956022) (xy 332.003225 -398.019025) (xy 331.972197 -398.078748)
			(xy 331.934253 -398.134334) (xy 331.912468 -398.159986) (xy 331.906648 -398.167115) (xy 331.900148 -398.184318)
			(xy 331.899768 -398.193514) (xy 331.899768 -398.351502) (xy 331.899268 -398.361659) (xy 331.891494 -398.380427)
			(xy 331.877131 -398.394792) (xy 331.858363 -398.402568) (xy 331.848206 -398.403064) (xy 331.131926 -398.403064)
			(xy 331.121756 -398.402615) (xy 331.102963 -398.394839) (xy 331.088577 -398.380461) (xy 331.080791 -398.361671)
			(xy 331.080364 -398.351502) (xy 331.080364 -398.193514) (xy 331.079933 -398.184329) (xy 331.073432 -398.167146)
			(xy 331.067664 -398.159986) (xy 331.045838 -398.134365) (xy 331.007889 -398.078775) (xy 330.976856 -398.019047)
			(xy 330.953184 -397.956038) (xy 330.937213 -397.890652) (xy 330.929171 -397.823826) (xy 326.525636 -397.823826)
			(xy 326.525636 -401.723737) (xy 330.929183 -401.723737) (xy 330.929184 -401.65643) (xy 330.937231 -401.589605)
			(xy 330.953207 -401.524221) (xy 330.976884 -401.461216) (xy 331.007921 -401.401492) (xy 331.045874 -401.345906)
			(xy 331.067664 -401.320254) (xy 331.07347 -401.313116) (xy 331.079977 -401.29592) (xy 331.080364 -401.286726)
			(xy 331.080364 -400.793458) (xy 331.07996 -400.78427) (xy 331.073441 -400.767087) (xy 331.067664 -400.75993)
			(xy 331.045882 -400.734273) (xy 331.007931 -400.678688) (xy 330.976896 -400.618965) (xy 330.953222 -400.555961)
			(xy 330.937248 -400.490579) (xy 330.929203 -400.423757) (xy 330.929202 -400.356452) (xy 330.937246 -400.289629)
			(xy 330.953219 -400.224247) (xy 330.976892 -400.161243) (xy 331.007926 -400.10152) (xy 331.045876 -400.045934)
			(xy 331.067664 -400.020282) (xy 331.073459 -400.013136) (xy 331.079973 -399.995946) (xy 331.080364 -399.986754)
			(xy 331.080364 -399.828766) (xy 331.080806 -399.818603) (xy 331.088597 -399.799828) (xy 331.102978 -399.785463)
			(xy 331.121762 -399.777694) (xy 331.131926 -399.777204) (xy 331.848206 -399.777204) (xy 331.85836 -399.777728)
			(xy 331.877123 -399.785498) (xy 331.891486 -399.799854) (xy 331.899267 -399.818612) (xy 331.899768 -399.828766)
			(xy 331.899768 -399.986754) (xy 331.900208 -399.995938) (xy 331.906702 -400.013122) (xy 331.912468 -400.020282)
			(xy 331.934262 -400.045929) (xy 331.97221 -400.101517) (xy 332.003242 -400.161241) (xy 332.026915 -400.224246)
			(xy 332.042887 -400.289629) (xy 332.05093 -400.356452) (xy 332.05093 -400.423757) (xy 332.042885 -400.49058)
			(xy 332.026912 -400.555963) (xy 332.003239 -400.618967) (xy 331.972205 -400.678691) (xy 331.934256 -400.734278)
			(xy 331.912468 -400.75993) (xy 331.906672 -400.767076) (xy 331.900158 -400.784266) (xy 331.899768 -400.793458)
			(xy 331.899768 -401.286726) (xy 331.900173 -401.295914) (xy 331.906691 -401.313098) (xy 331.912468 -401.320254)
			(xy 331.934234 -401.345924) (xy 331.972183 -401.401508) (xy 332.003216 -401.461229) (xy 332.02689 -401.524231)
			(xy 332.042864 -401.589611) (xy 332.05091 -401.656432) (xy 332.050912 -401.723735) (xy 332.04287 -401.790556)
			(xy 332.0269 -401.855937) (xy 332.00323 -401.91894) (xy 331.9722 -401.978663) (xy 331.934254 -402.03425)
			(xy 331.912468 -402.059902) (xy 331.906684 -402.067056) (xy 331.900163 -402.08424) (xy 331.899768 -402.09343)
			(xy 331.899768 -402.251418) (xy 331.899282 -402.261576) (xy 331.891502 -402.280345) (xy 331.877135 -402.294709)
			(xy 331.858364 -402.302484) (xy 331.848206 -402.30298) (xy 331.131926 -402.30298) (xy 331.121758 -402.302515)
			(xy 331.102968 -402.294742) (xy 331.088583 -402.280369) (xy 331.080794 -402.261585) (xy 331.080364 -402.251418)
			(xy 331.080364 -402.09343) (xy 331.079925 -402.084246) (xy 331.07343 -402.067062) (xy 331.067664 -402.059902)
			(xy 331.045854 -402.034268) (xy 331.007904 -401.97868) (xy 330.97687 -401.918954) (xy 330.953197 -401.855947)
			(xy 330.937225 -401.790562) (xy 330.929183 -401.723737) (xy 326.525636 -401.723737) (xy 326.525636 -402.823878)
			(xy 333.128796 -402.823878) (xy 333.128801 -402.75645) (xy 333.136882 -402.689508) (xy 333.152922 -402.624016)
			(xy 333.176693 -402.560918) (xy 333.20785 -402.50112) (xy 333.245945 -402.445485) (xy 333.267812 -402.41982)
			(xy 333.273626 -402.412687) (xy 333.28013 -402.395487) (xy 333.280512 -402.386292) (xy 333.280512 -401.89404)
			(xy 333.28008 -401.884855) (xy 333.273581 -401.867671) (xy 333.267812 -401.860512) (xy 333.245928 -401.834863)
			(xy 333.207839 -401.779227) (xy 333.176689 -401.719428) (xy 333.152925 -401.656329) (xy 333.136891 -401.590838)
			(xy 333.128816 -401.523898) (xy 333.128818 -401.456472) (xy 333.136896 -401.389532) (xy 333.152934 -401.324042)
			(xy 333.176701 -401.260944) (xy 333.207855 -401.201148) (xy 333.245946 -401.145513) (xy 333.267812 -401.119848)
			(xy 333.273615 -401.112707) (xy 333.280125 -401.095513) (xy 333.280512 -401.08632) (xy 333.280512 -400.92884)
			(xy 333.280949 -400.918719) (xy 333.288686 -400.900014) (xy 333.302997 -400.885698) (xy 333.321699 -400.877953)
			(xy 333.33182 -400.877532) (xy 334.0481 -400.877532) (xy 334.058226 -400.877917) (xy 334.076936 -400.885671)
			(xy 334.091252 -400.899997) (xy 334.098991 -400.918713) (xy 334.099408 -400.92884) (xy 334.099408 -401.08632)
			(xy 334.099807 -401.095508) (xy 334.106328 -401.112693) (xy 334.112108 -401.119848) (xy 334.133952 -401.14553)
			(xy 334.172041 -401.201162) (xy 334.203192 -401.260956) (xy 334.226957 -401.324051) (xy 334.242994 -401.389538)
			(xy 334.251071 -401.456474) (xy 334.251073 -401.523896) (xy 334.242999 -401.590833) (xy 334.226966 -401.656321)
			(xy 334.203204 -401.719417) (xy 334.200923 -401.723796) (xy 335.328975 -401.723796) (xy 335.328977 -401.656371)
			(xy 335.337055 -401.589432) (xy 335.353091 -401.523942) (xy 335.376856 -401.460845) (xy 335.408007 -401.401048)
			(xy 335.446096 -401.345412) (xy 335.46796 -401.319746) (xy 335.473769 -401.31261) (xy 335.480275 -401.295412)
			(xy 335.48066 -401.286218) (xy 335.48066 -400.793966) (xy 335.480253 -400.784779) (xy 335.473735 -400.767595)
			(xy 335.46796 -400.760438) (xy 335.446103 -400.734767) (xy 335.408017 -400.679133) (xy 335.376868 -400.619337)
			(xy 335.353106 -400.556241) (xy 335.337071 -400.490753) (xy 335.328995 -400.423816) (xy 335.328995 -400.356393)
			(xy 335.337069 -400.289456) (xy 335.353103 -400.223968) (xy 335.376865 -400.160872) (xy 335.408012 -400.101075)
			(xy 335.446098 -400.04544) (xy 335.46796 -400.019774) (xy 335.473757 -400.01263) (xy 335.48027 -399.995438)
			(xy 335.48066 -399.986246) (xy 335.48066 -399.828766) (xy 335.481099 -399.818635) (xy 335.488842 -399.799909)
			(xy 335.503143 -399.785553) (xy 335.521839 -399.777739) (xy 335.531968 -399.777204) (xy 336.248248 -399.777204)
			(xy 336.258406 -399.777583) (xy 336.27716 -399.785395) (xy 336.291482 -399.799804) (xy 336.299179 -399.818606)
			(xy 336.299556 -399.828766) (xy 336.299556 -399.986246) (xy 336.300002 -399.995429) (xy 336.306492 -400.012613)
			(xy 336.312256 -400.019774) (xy 336.334127 -400.045434) (xy 336.372219 -400.101068) (xy 336.403372 -400.160864)
			(xy 336.427138 -400.223962) (xy 336.443174 -400.289452) (xy 336.45125 -400.356392) (xy 336.451249 -400.423817)
			(xy 336.443172 -400.490756) (xy 336.427135 -400.556246) (xy 336.403368 -400.619344) (xy 336.372214 -400.67914)
			(xy 336.334122 -400.734774) (xy 336.312256 -400.760438) (xy 336.306455 -400.76758) (xy 336.299944 -400.784773)
			(xy 336.299556 -400.793966) (xy 336.299556 -401.286218) (xy 336.299967 -401.295405) (xy 336.306481 -401.312589)
			(xy 336.312256 -401.319746) (xy 336.3341 -401.345428) (xy 336.372192 -401.401059) (xy 336.403346 -401.460853)
			(xy 336.427114 -401.523948) (xy 336.443152 -401.589435) (xy 336.45123 -401.656372) (xy 336.451232 -401.723795)
			(xy 336.443158 -401.790732) (xy 336.427123 -401.856221) (xy 336.40336 -401.919317) (xy 336.372209 -401.979112)
			(xy 336.33412 -402.034746) (xy 336.312256 -402.06041) (xy 336.306467 -402.06756) (xy 336.299949 -402.084747)
			(xy 336.299556 -402.093938) (xy 336.299556 -402.251418) (xy 336.299088 -402.261546) (xy 336.291354 -402.280269)
			(xy 336.277062 -402.294625) (xy 336.258374 -402.302443) (xy 336.248248 -402.30298) (xy 335.531968 -402.30298)
			(xy 335.521809 -402.302604) (xy 335.503052 -402.294794) (xy 335.488729 -402.280384) (xy 335.481034 -402.261579)
			(xy 335.48066 -402.251418) (xy 335.48066 -402.093938) (xy 335.480218 -402.084754) (xy 335.473725 -402.06757)
			(xy 335.46796 -402.06041) (xy 335.446076 -402.034762) (xy 335.40799 -401.979124) (xy 335.376843 -401.919325)
			(xy 335.353082 -401.856226) (xy 335.337049 -401.790735) (xy 335.328975 -401.723796) (xy 334.200923 -401.723796)
			(xy 334.172056 -401.779212) (xy 334.13397 -401.834847) (xy 334.112108 -401.860512) (xy 334.106325 -401.867667)
			(xy 334.099802 -401.88485) (xy 334.099408 -401.89404) (xy 334.099408 -402.386292) (xy 334.09982 -402.395479)
			(xy 334.106332 -402.412663) (xy 334.112108 -402.41982) (xy 334.133925 -402.445524) (xy 334.172014 -402.501153)
			(xy 334.203166 -402.560944) (xy 334.226933 -402.624036) (xy 334.242972 -402.68952) (xy 334.251051 -402.756454)
			(xy 334.251055 -402.823818) (xy 337.529116 -402.823818) (xy 337.52912 -402.75651) (xy 337.537169 -402.689685)
			(xy 337.553145 -402.6243) (xy 337.576822 -402.561294) (xy 337.607859 -402.501569) (xy 337.645811 -402.445981)
			(xy 337.6676 -402.420328) (xy 337.67341 -402.413192) (xy 337.679917 -402.395994) (xy 337.6803 -402.3868)
			(xy 337.6803 -401.893532) (xy 337.679874 -401.884346) (xy 337.673371 -401.867162) (xy 337.6676 -401.860004)
			(xy 337.645794 -401.834367) (xy 337.607848 -401.778778) (xy 337.576818 -401.719052) (xy 337.553148 -401.656045)
			(xy 337.537178 -401.590662) (xy 337.529136 -401.523838) (xy 337.529137 -401.456532) (xy 337.537183 -401.389709)
			(xy 337.553157 -401.324326) (xy 337.57683 -401.261321) (xy 337.607864 -401.201596) (xy 337.645812 -401.146009)
			(xy 337.6676 -401.120356) (xy 337.673398 -401.113212) (xy 337.679912 -401.09602) (xy 337.6803 -401.086828)
			(xy 337.6803 -400.92884) (xy 337.680755 -400.918688) (xy 337.688537 -400.899937) (xy 337.702924 -400.885612)
			(xy 337.721709 -400.877911) (xy 337.731862 -400.877532) (xy 338.448142 -400.877532) (xy 338.45827 -400.877992)
			(xy 338.476991 -400.885732) (xy 338.491346 -400.900026) (xy 338.499165 -400.918714) (xy 338.499704 -400.92884)
			(xy 338.499704 -401.086828) (xy 338.5001 -401.096017) (xy 338.506623 -401.113201) (xy 338.512404 -401.120356)
			(xy 338.534171 -401.146025) (xy 338.572117 -401.20161) (xy 338.603149 -401.261332) (xy 338.626821 -401.324334)
			(xy 338.642794 -401.389714) (xy 338.650839 -401.456534) (xy 338.650841 -401.523836) (xy 338.6428 -401.590657)
			(xy 338.62683 -401.656037) (xy 338.603161 -401.719041) (xy 338.600721 -401.723737) (xy 339.72927 -401.723737)
			(xy 339.729272 -401.65643) (xy 339.737319 -401.589606) (xy 339.753294 -401.524222) (xy 339.77697 -401.461217)
			(xy 339.808006 -401.401492) (xy 339.845959 -401.345906) (xy 339.867748 -401.320254) (xy 339.873553 -401.313115)
			(xy 339.880061 -401.295919) (xy 339.880448 -401.286726) (xy 339.880448 -400.793458) (xy 339.880047 -400.78427)
			(xy 339.873526 -400.767086) (xy 339.867748 -400.75993) (xy 339.845966 -400.734273) (xy 339.808017 -400.678687)
			(xy 339.776983 -400.618965) (xy 339.753309 -400.555961) (xy 339.737335 -400.490579) (xy 339.729291 -400.423757)
			(xy 339.72929 -400.356452) (xy 339.737334 -400.28963) (xy 339.753306 -400.224248) (xy 339.776979 -400.161244)
			(xy 339.808012 -400.10152) (xy 339.845961 -400.045934) (xy 339.867748 -400.020282) (xy 339.873541 -400.013134)
			(xy 339.880056 -399.995946) (xy 339.880448 -399.986754) (xy 339.880448 -399.828766) (xy 339.880906 -399.818605)
			(xy 339.888693 -399.799833) (xy 339.90307 -399.785469) (xy 339.921848 -399.777697) (xy 339.93201 -399.777204)
			(xy 340.64829 -399.777204) (xy 340.658443 -399.777741) (xy 340.677205 -399.785506) (xy 340.69157 -399.799858)
			(xy 340.699351 -399.818613) (xy 340.699852 -399.828766) (xy 340.699852 -399.986754) (xy 340.700295 -399.995937)
			(xy 340.706787 -400.013121) (xy 340.712552 -400.020282) (xy 340.734346 -400.045929) (xy 340.772295 -400.101516)
			(xy 340.803329 -400.16124) (xy 340.827002 -400.224245) (xy 340.842975 -400.289628) (xy 340.851018 -400.356452)
			(xy 340.851018 -400.423757) (xy 340.842973 -400.490581) (xy 340.826999 -400.555963) (xy 340.803325 -400.618968)
			(xy 340.772291 -400.678692) (xy 340.734341 -400.734278) (xy 340.712552 -400.75993) (xy 340.706754 -400.767074)
			(xy 340.700242 -400.784266) (xy 340.699852 -400.793458) (xy 340.699852 -401.286726) (xy 340.70026 -401.295913)
			(xy 340.706777 -401.313097) (xy 340.712552 -401.320254) (xy 340.734318 -401.345924) (xy 340.772268 -401.401508)
			(xy 340.803303 -401.461229) (xy 340.826977 -401.524231) (xy 340.842952 -401.589611) (xy 340.850998 -401.656432)
			(xy 340.851 -401.723735) (xy 340.842958 -401.790556) (xy 340.826987 -401.855937) (xy 340.803316 -401.918941)
			(xy 340.772285 -401.978664) (xy 340.734338 -402.03425) (xy 340.712552 -402.059902) (xy 340.706766 -402.067055)
			(xy 340.700246 -402.08424) (xy 340.699852 -402.09343) (xy 340.699852 -402.251418) (xy 340.699381 -402.261578)
			(xy 340.691599 -402.28035) (xy 340.677226 -402.294715) (xy 340.65845 -402.302487) (xy 340.64829 -402.30298)
			(xy 339.93201 -402.30298) (xy 339.921855 -402.302459) (xy 339.90309 -402.294691) (xy 339.888725 -402.280334)
			(xy 339.880947 -402.261573) (xy 339.880448 -402.251418) (xy 339.880448 -402.09343) (xy 339.880013 -402.084246)
			(xy 339.873515 -402.067062) (xy 339.867748 -402.059902) (xy 339.845938 -402.034268) (xy 339.807989 -401.978679)
			(xy 339.776957 -401.918953) (xy 339.753285 -401.855946) (xy 339.737313 -401.790562) (xy 339.72927 -401.723737)
			(xy 338.600721 -401.723737) (xy 338.572133 -401.778764) (xy 338.534189 -401.834351) (xy 338.512404 -401.860004)
			(xy 338.506624 -401.867161) (xy 338.500099 -401.884342) (xy 338.499704 -401.893532) (xy 338.499704 -402.3868)
			(xy 338.500113 -402.395987) (xy 338.506628 -402.413172) (xy 338.512404 -402.420328) (xy 338.534143 -402.44602)
			(xy 338.572091 -402.501601) (xy 338.603124 -402.56132) (xy 338.626797 -402.624319) (xy 338.642772 -402.689696)
			(xy 338.65082 -402.756514) (xy 338.650824 -402.823814) (xy 338.650816 -402.823878) (xy 341.928884 -402.823878)
			(xy 341.928889 -402.75645) (xy 341.936969 -402.689509) (xy 341.95301 -402.624017) (xy 341.976779 -402.560918)
			(xy 342.007935 -402.501121) (xy 342.046029 -402.445485) (xy 342.067896 -402.41982) (xy 342.073709 -402.412686)
			(xy 342.080214 -402.395487) (xy 342.080596 -402.386292) (xy 342.080596 -401.89404) (xy 342.080168 -401.884855)
			(xy 342.073667 -401.86767) (xy 342.067896 -401.860512) (xy 342.046013 -401.834863) (xy 342.007925 -401.779226)
			(xy 341.976775 -401.719428) (xy 341.953012 -401.656329) (xy 341.936978 -401.590838) (xy 341.928904 -401.523898)
			(xy 341.928906 -401.456472) (xy 341.936984 -401.389533) (xy 341.953021 -401.324043) (xy 341.976787 -401.260945)
			(xy 342.00794 -401.201148) (xy 342.046031 -401.145513) (xy 342.067896 -401.119848) (xy 342.073697 -401.112706)
			(xy 342.080209 -401.095513) (xy 342.080596 -401.08632) (xy 342.080596 -400.92884) (xy 342.081049 -400.918721)
			(xy 342.088783 -400.900019) (xy 342.103088 -400.885703) (xy 342.121785 -400.877956) (xy 342.131904 -400.877532)
			(xy 342.848184 -400.877532) (xy 342.858309 -400.87793) (xy 342.877019 -400.885679) (xy 342.891335 -400.900001)
			(xy 342.899075 -400.918714) (xy 342.899492 -400.92884) (xy 342.899492 -401.08632) (xy 342.899894 -401.095508)
			(xy 342.906413 -401.112692) (xy 342.912192 -401.119848) (xy 342.934037 -401.145529) (xy 342.972126 -401.201161)
			(xy 343.003278 -401.260955) (xy 343.027044 -401.32405) (xy 343.043081 -401.389537) (xy 343.051159 -401.456474)
			(xy 343.051161 -401.523896) (xy 343.043087 -401.590833) (xy 343.027053 -401.656321) (xy 343.003291 -401.719417)
			(xy 343.001041 -401.723737) (xy 344.129061 -401.723737) (xy 344.129063 -401.65643) (xy 344.13711 -401.589606)
			(xy 344.153085 -401.524223) (xy 344.17676 -401.461217) (xy 344.207796 -401.401493) (xy 344.245747 -401.345906)
			(xy 344.267536 -401.320254) (xy 344.273339 -401.313114) (xy 344.279849 -401.295919) (xy 344.280236 -401.286726)
			(xy 344.280236 -400.793458) (xy 344.279838 -400.78427) (xy 344.273315 -400.767086) (xy 344.267536 -400.75993)
			(xy 344.245754 -400.734273) (xy 344.207805 -400.678687) (xy 344.176772 -400.618964) (xy 344.153099 -400.55596)
			(xy 344.137126 -400.490579) (xy 344.129081 -400.423757) (xy 344.129081 -400.356452) (xy 344.137124 -400.28963)
			(xy 344.153096 -400.224248) (xy 344.176768 -400.161244) (xy 344.207801 -400.101521) (xy 344.245749 -400.045934)
			(xy 344.267536 -400.020282) (xy 344.273327 -400.013133) (xy 344.279844 -399.995945) (xy 344.280236 -399.986754)
			(xy 344.280236 -399.828766) (xy 344.280705 -399.818606) (xy 344.288491 -399.799837) (xy 344.302864 -399.785473)
			(xy 344.321638 -399.777699) (xy 344.331798 -399.777204) (xy 345.048078 -399.777204) (xy 345.05823 -399.77775)
			(xy 345.076992 -399.785511) (xy 345.091357 -399.799861) (xy 345.099139 -399.818614) (xy 345.09964 -399.828766)
			(xy 345.09964 -399.986754) (xy 345.100086 -399.995937) (xy 345.106576 -400.013121) (xy 345.11234 -400.020282)
			(xy 345.134134 -400.045929) (xy 345.172084 -400.101516) (xy 345.203118 -400.16124) (xy 345.226792 -400.224245)
			(xy 345.242765 -400.289628) (xy 345.250809 -400.356452) (xy 345.250808 -400.423757) (xy 345.242763 -400.490581)
			(xy 345.226789 -400.555964) (xy 345.203115 -400.618968) (xy 345.172079 -400.678692) (xy 345.134129 -400.734278)
			(xy 345.11234 -400.75993) (xy 345.106541 -400.767073) (xy 345.100029 -400.784265) (xy 345.09964 -400.793458)
			(xy 345.09964 -401.286726) (xy 345.100051 -401.295913) (xy 345.106566 -401.313096) (xy 345.11234 -401.320254)
			(xy 345.134107 -401.345924) (xy 345.172057 -401.401507) (xy 345.203093 -401.461228) (xy 345.226768 -401.52423)
			(xy 345.242743 -401.589611) (xy 345.250789 -401.656432) (xy 345.250791 -401.723735) (xy 345.242749 -401.790557)
			(xy 345.226778 -401.855938) (xy 345.203106 -401.918942) (xy 345.172074 -401.978664) (xy 345.134127 -402.03425)
			(xy 345.11234 -402.059902) (xy 345.106553 -402.067053) (xy 345.100034 -402.084239) (xy 345.09964 -402.09343)
			(xy 345.09964 -402.251418) (xy 345.09925 -402.261593) (xy 345.091455 -402.280393) (xy 345.077059 -402.294778)
			(xy 345.058254 -402.302558) (xy 345.048078 -402.30298) (xy 344.331798 -402.30298) (xy 344.321642 -402.302469)
			(xy 344.302877 -402.294697) (xy 344.288512 -402.280337) (xy 344.280735 -402.261574) (xy 344.280236 -402.251418)
			(xy 344.280236 -402.09343) (xy 344.279803 -402.084245) (xy 344.273304 -402.067061) (xy 344.267536 -402.059902)
			(xy 344.245727 -402.034268) (xy 344.207779 -401.978679) (xy 344.176746 -401.918953) (xy 344.153075 -401.855946)
			(xy 344.137104 -401.790561) (xy 344.129061 -401.723737) (xy 343.001041 -401.723737) (xy 342.972142 -401.779213)
			(xy 342.934055 -401.834847) (xy 342.912192 -401.860512) (xy 342.906407 -401.867665) (xy 342.899886 -401.88485)
			(xy 342.899492 -401.89404) (xy 342.899492 -402.386292) (xy 342.899908 -402.395479) (xy 342.906418 -402.412663)
			(xy 342.912192 -402.41982) (xy 342.934009 -402.445524) (xy 342.9721 -402.501153) (xy 343.003253 -402.560944)
			(xy 343.02702 -402.624035) (xy 343.043059 -402.68952) (xy 343.051139 -402.756454) (xy 343.051143 -402.823819)
			(xy 346.329179 -402.823819) (xy 346.329184 -402.756509) (xy 346.337233 -402.689682) (xy 346.353213 -402.624297)
			(xy 346.376893 -402.56129) (xy 346.407934 -402.501566) (xy 346.445892 -402.445979) (xy 346.467684 -402.420328)
			(xy 346.473492 -402.413191) (xy 346.48 -402.395994) (xy 346.480384 -402.3868) (xy 346.480384 -401.893532)
			(xy 346.479962 -401.884346) (xy 346.473457 -401.867161) (xy 346.467684 -401.860004) (xy 346.445875 -401.834369)
			(xy 346.407924 -401.778781) (xy 346.376889 -401.719055) (xy 346.353216 -401.656049) (xy 346.337243 -401.590664)
			(xy 346.3292 -401.523839) (xy 346.329201 -401.456531) (xy 346.337248 -401.389707) (xy 346.353225 -401.324323)
			(xy 346.376902 -401.261317) (xy 346.40794 -401.201593) (xy 346.445894 -401.146008) (xy 346.467684 -401.120356)
			(xy 346.47348 -401.11321) (xy 346.479995 -401.09602) (xy 346.480384 -401.086828) (xy 346.480384 -400.92884)
			(xy 346.480854 -400.91869) (xy 346.488634 -400.899942) (xy 346.503015 -400.885618) (xy 346.521795 -400.877914)
			(xy 346.531946 -400.877532) (xy 347.248226 -400.877532) (xy 347.258353 -400.878005) (xy 347.277074 -400.88574)
			(xy 347.291429 -400.90003) (xy 347.299249 -400.918715) (xy 347.299788 -400.92884) (xy 347.299788 -401.086828)
			(xy 347.300187 -401.096016) (xy 347.306709 -401.1132) (xy 347.312488 -401.120356) (xy 347.334255 -401.146025)
			(xy 347.372203 -401.201609) (xy 347.403236 -401.261331) (xy 347.426908 -401.324333) (xy 347.442882 -401.389713)
			(xy 347.450927 -401.456533) (xy 347.450929 -401.523836) (xy 347.442887 -401.590657) (xy 347.426917 -401.656038)
			(xy 347.403248 -401.719042) (xy 347.400809 -401.723737) (xy 374.929092 -401.723737) (xy 374.929094 -401.65643)
			(xy 374.937141 -401.589605) (xy 374.953117 -401.524221) (xy 374.976794 -401.461216) (xy 375.007832 -401.401492)
			(xy 375.045786 -401.345906) (xy 375.067576 -401.320254) (xy 375.073372 -401.313108) (xy 375.079888 -401.295918)
			(xy 375.080276 -401.286726) (xy 375.080276 -400.793458) (xy 375.079891 -400.784268) (xy 375.07336 -400.767084)
			(xy 375.067576 -400.75993) (xy 375.045793 -400.734273) (xy 375.007842 -400.678688) (xy 374.976806 -400.618966)
			(xy 374.953131 -400.555962) (xy 374.937157 -400.49058) (xy 374.929112 -400.423757) (xy 374.929111 -400.356452)
			(xy 374.937155 -400.289629) (xy 374.953129 -400.224247) (xy 374.976802 -400.161242) (xy 375.007837 -400.101519)
			(xy 375.045788 -400.045934) (xy 375.067576 -400.020282) (xy 375.07336 -400.013128) (xy 375.079883 -399.995944)
			(xy 375.080276 -399.986754) (xy 375.080276 -399.828766) (xy 375.080637 -399.818587) (xy 375.08844 -399.799785)
			(xy 375.102845 -399.7854) (xy 375.121659 -399.777623) (xy 375.131838 -399.777204) (xy 375.848118 -399.777204)
			(xy 375.858273 -399.777718) (xy 375.877036 -399.785492) (xy 375.891399 -399.799851) (xy 375.899179 -399.818611)
			(xy 375.89968 -399.828766) (xy 375.89968 -399.986754) (xy 375.900117 -399.995938) (xy 375.906612 -400.013123)
			(xy 375.91238 -400.020282) (xy 375.934173 -400.045929) (xy 375.972121 -400.101517) (xy 376.003152 -400.161241)
			(xy 376.026824 -400.224247) (xy 376.042796 -400.289629) (xy 376.050839 -400.356452) (xy 376.050839 -400.423757)
			(xy 376.042794 -400.49058) (xy 376.026821 -400.555962) (xy 376.003149 -400.618967) (xy 375.972116 -400.678691)
			(xy 375.934168 -400.734278) (xy 375.91238 -400.75993) (xy 375.906586 -400.767077) (xy 375.90007 -400.784266)
			(xy 375.89968 -400.793458) (xy 375.89968 -401.286726) (xy 375.900082 -401.295914) (xy 375.906602 -401.313098)
			(xy 375.91238 -401.320254) (xy 375.934146 -401.345924) (xy 375.972094 -401.401508) (xy 376.003127 -401.46123)
			(xy 376.0268 -401.524232) (xy 376.042774 -401.589612) (xy 376.05082 -401.656432) (xy 376.050822 -401.723735)
			(xy 376.04278 -401.790556) (xy 376.02681 -401.855937) (xy 376.003141 -401.91894) (xy 375.972111 -401.978663)
			(xy 375.934166 -402.03425) (xy 375.91238 -402.059902) (xy 375.906598 -402.067057) (xy 375.900075 -402.08424)
			(xy 375.89968 -402.09343) (xy 375.89968 -402.251418) (xy 375.899182 -402.261575) (xy 375.891405 -402.280341)
			(xy 375.877041 -402.294705) (xy 375.858275 -402.302482) (xy 375.848118 -402.30298) (xy 375.131838 -402.30298)
			(xy 375.121671 -402.302505) (xy 375.102881 -402.294736) (xy 375.088495 -402.280366) (xy 375.080706 -402.261584)
			(xy 375.080276 -402.251418) (xy 375.080276 -402.09343) (xy 375.079857 -402.084244) (xy 375.07335 -402.067059)
			(xy 375.067576 -402.059902) (xy 375.045766 -402.034268) (xy 375.007815 -401.97868) (xy 374.976781 -401.918954)
			(xy 374.953108 -401.855947) (xy 374.937135 -401.790562) (xy 374.929092 -401.723737) (xy 347.400809 -401.723737)
			(xy 347.372218 -401.778765) (xy 347.334274 -401.834352) (xy 347.312488 -401.860004) (xy 347.306706 -401.867159)
			(xy 347.300183 -401.884342) (xy 347.299788 -401.893532) (xy 347.299788 -402.3868) (xy 347.300201 -402.395987)
			(xy 347.306713 -402.413171) (xy 347.312488 -402.420328) (xy 347.334227 -402.44602) (xy 347.372176 -402.501601)
			(xy 347.40321 -402.561319) (xy 347.426884 -402.624319) (xy 347.442859 -402.689696) (xy 347.450907 -402.756514)
			(xy 347.450911 -402.823814) (xy 347.442872 -402.890633) (xy 347.426905 -402.956012) (xy 347.403239 -403.019015)
			(xy 347.372213 -403.078737) (xy 347.334272 -403.134323) (xy 347.312488 -403.159976) (xy 347.306675 -403.16711)
			(xy 347.300171 -403.184309) (xy 347.299788 -403.193504) (xy 347.299788 -403.351492) (xy 347.299372 -403.361647)
			(xy 347.291576 -403.380402) (xy 347.277178 -403.394726) (xy 347.258383 -403.402424) (xy 347.248226 -403.4028)
			(xy 346.531946 -403.4028) (xy 346.521827 -403.402237) (xy 346.503115 -403.394532) (xy 346.488758 -403.380269)
			(xy 346.48093 -403.361607) (xy 346.480384 -403.351492) (xy 346.480384 -403.193504) (xy 346.479975 -403.184317)
			(xy 346.473461 -403.167132) (xy 346.467684 -403.159976) (xy 346.445847 -403.134364) (xy 346.407897 -403.078772)
			(xy 346.376863 -403.019044) (xy 346.353191 -402.956034) (xy 346.33722 -402.890646) (xy 346.329179 -402.823819)
			(xy 343.051143 -402.823819) (xy 343.051143 -402.823874) (xy 343.043072 -402.890809) (xy 343.027042 -402.956296)
			(xy 343.003282 -403.019391) (xy 342.972137 -403.079185) (xy 342.934053 -403.134819) (xy 342.912192 -403.160484)
			(xy 342.906376 -403.167616) (xy 342.899873 -403.184817) (xy 342.899492 -403.194012) (xy 342.899492 -403.351492)
			(xy 342.899077 -403.361615) (xy 342.89133 -403.38032) (xy 342.877013 -403.394635) (xy 342.858307 -403.402379)
			(xy 342.848184 -403.4028) (xy 342.131904 -403.4028) (xy 342.121782 -403.402381) (xy 342.103078 -403.394634)
			(xy 342.088764 -403.380318) (xy 342.081019 -403.361614) (xy 342.080596 -403.351492) (xy 342.080596 -403.194012)
			(xy 342.080181 -403.184825) (xy 342.073671 -403.167641) (xy 342.067896 -403.160484) (xy 342.045985 -403.134858)
			(xy 342.007898 -403.079217) (xy 341.97675 -403.019416) (xy 341.952988 -402.956314) (xy 341.936956 -402.89082)
			(xy 341.928884 -402.823878) (xy 338.650816 -402.823878) (xy 338.642785 -402.890633) (xy 338.626819 -402.956012)
			(xy 338.603153 -403.019014) (xy 338.572128 -403.078737) (xy 338.534188 -403.134323) (xy 338.512404 -403.159976)
			(xy 338.506593 -403.167111) (xy 338.500087 -403.184309) (xy 338.499704 -403.193504) (xy 338.499704 -403.351492)
			(xy 338.499272 -403.361645) (xy 338.49148 -403.380397) (xy 338.477086 -403.39472) (xy 338.458297 -403.402421)
			(xy 338.448142 -403.4028) (xy 337.731862 -403.4028) (xy 337.721738 -403.402306) (xy 337.703023 -403.394573)
			(xy 337.68867 -403.38029) (xy 337.680845 -403.361614) (xy 337.6803 -403.351492) (xy 337.6803 -403.193504)
			(xy 337.679888 -403.184317) (xy 337.673375 -403.167133) (xy 337.6676 -403.159976) (xy 337.645766 -403.134362)
			(xy 337.607822 -403.078769) (xy 337.576793 -403.01904) (xy 337.553124 -402.956031) (xy 337.537156 -402.890644)
			(xy 337.529116 -402.823818) (xy 334.251055 -402.823818) (xy 334.251055 -402.823874) (xy 334.242984 -402.890809)
			(xy 334.226954 -402.956295) (xy 334.203196 -403.01939) (xy 334.172051 -403.079185) (xy 334.133969 -403.134819)
			(xy 334.112108 -403.160484) (xy 334.106294 -403.167617) (xy 334.09979 -403.184817) (xy 334.099408 -403.194012)
			(xy 334.099408 -403.351492) (xy 334.098978 -403.361613) (xy 334.091234 -403.380315) (xy 334.076922 -403.394629)
			(xy 334.058221 -403.402376) (xy 334.0481 -403.4028) (xy 333.33182 -403.4028) (xy 333.321699 -403.402368)
			(xy 333.302996 -403.394626) (xy 333.288681 -403.380315) (xy 333.280935 -403.361613) (xy 333.280512 -403.351492)
			(xy 333.280512 -403.194012) (xy 333.280093 -403.184826) (xy 333.273585 -403.167642) (xy 333.267812 -403.160484)
			(xy 333.2459 -403.134858) (xy 333.207812 -403.079218) (xy 333.176663 -403.019417) (xy 333.152901 -402.956315)
			(xy 333.136869 -402.890821) (xy 333.128796 -402.823878) (xy 326.525636 -402.823878) (xy 326.525636 -405.623648)
			(xy 330.929194 -405.623648) (xy 330.929195 -405.556343) (xy 330.93724 -405.489519) (xy 330.953214 -405.424136)
			(xy 330.976889 -405.361131) (xy 331.007924 -405.301408) (xy 331.045875 -405.245822) (xy 331.067664 -405.22017)
			(xy 331.073464 -405.213027) (xy 331.079975 -405.195835) (xy 331.080364 -405.186642) (xy 331.080364 -404.693374)
			(xy 331.079952 -404.684187) (xy 331.073438 -404.667004) (xy 331.067664 -404.659846) (xy 331.045897 -404.634176)
			(xy 331.007946 -404.578593) (xy 330.976911 -404.518872) (xy 330.953235 -404.45587) (xy 330.93726 -404.390489)
			(xy 330.929214 -404.323668) (xy 330.929212 -404.256365) (xy 330.937254 -404.189543) (xy 330.953226 -404.124162)
			(xy 330.976897 -404.061158) (xy 331.007929 -404.001435) (xy 331.045877 -403.94585) (xy 331.067664 -403.920198)
			(xy 331.073452 -403.913047) (xy 331.07997 -403.895861) (xy 331.080364 -403.88667) (xy 331.080364 -403.728682)
			(xy 331.08075 -403.718506) (xy 331.088546 -403.699706) (xy 331.102943 -403.685321) (xy 331.12175 -403.677541)
			(xy 331.131926 -403.67712) (xy 331.848206 -403.67712) (xy 331.858362 -403.677628) (xy 331.877128 -403.685401)
			(xy 331.891492 -403.699762) (xy 331.899269 -403.718526) (xy 331.899768 -403.728682) (xy 331.899768 -403.88667)
			(xy 331.9002 -403.895855) (xy 331.906699 -403.913039) (xy 331.912468 -403.920198) (xy 331.934277 -403.945832)
			(xy 331.972225 -404.001422) (xy 332.003257 -404.061148) (xy 332.026928 -404.124154) (xy 332.042899 -404.189539)
			(xy 332.050942 -404.256363) (xy 332.05094 -404.32367) (xy 332.042893 -404.390494) (xy 332.026918 -404.455877)
			(xy 332.003243 -404.518883) (xy 331.972208 -404.578607) (xy 331.934257 -404.634194) (xy 331.912468 -404.659846)
			(xy 331.906665 -404.666987) (xy 331.900155 -404.684181) (xy 331.899768 -404.693374) (xy 331.899768 -405.186642)
			(xy 331.900165 -405.19583) (xy 331.906689 -405.213014) (xy 331.912468 -405.22017) (xy 331.93425 -405.245827)
			(xy 331.972198 -405.301413) (xy 332.003231 -405.361136) (xy 332.026904 -405.42414) (xy 332.042877 -405.489521)
			(xy 332.050922 -405.556343) (xy 332.050923 -405.623648) (xy 332.042879 -405.69047) (xy 332.026907 -405.755852)
			(xy 332.003235 -405.818856) (xy 331.972203 -405.878579) (xy 331.934255 -405.934166) (xy 331.912468 -405.959818)
			(xy 331.906677 -405.966967) (xy 331.90016 -405.984155) (xy 331.899768 -405.993346) (xy 331.899768 -406.151334)
			(xy 331.899295 -406.161493) (xy 331.89151 -406.180262) (xy 331.877138 -406.194626) (xy 331.858365 -406.2024)
			(xy 331.848206 -406.202896) (xy 331.131926 -406.202896) (xy 331.121774 -406.202346) (xy 331.103012 -406.194587)
			(xy 331.088647 -406.180238) (xy 331.080865 -406.161485) (xy 331.080364 -406.151334) (xy 331.080364 -405.993346)
			(xy 331.079918 -405.984163) (xy 331.073428 -405.966979) (xy 331.067664 -405.959818) (xy 331.04587 -405.934171)
			(xy 331.007919 -405.878584) (xy 330.976885 -405.81886) (xy 330.953212 -405.755855) (xy 330.937238 -405.690472)
			(xy 330.929194 -405.623648) (xy 326.525636 -405.623648) (xy 326.525636 -406.723789) (xy 333.128808 -406.723789)
			(xy 333.128811 -406.656363) (xy 333.13689 -406.589422) (xy 333.152929 -406.523931) (xy 333.176697 -406.460833)
			(xy 333.207852 -406.401036) (xy 333.245946 -406.345401) (xy 333.267812 -406.319736) (xy 333.27362 -406.312599)
			(xy 333.280127 -406.295402) (xy 333.280512 -406.286208) (xy 333.280512 -405.793956) (xy 333.28012 -405.784767)
			(xy 333.273594 -405.767583) (xy 333.267812 -405.760428) (xy 333.245944 -405.734766) (xy 333.207854 -405.679131)
			(xy 333.176703 -405.619335) (xy 333.152939 -405.556238) (xy 333.136903 -405.490748) (xy 333.128827 -405.423809)
			(xy 333.128828 -405.356385) (xy 333.136904 -405.289446) (xy 333.15294 -405.223957) (xy 333.176706 -405.16086)
			(xy 333.207857 -405.101063) (xy 333.245947 -405.045429) (xy 333.267812 -405.019764) (xy 333.273608 -405.012618)
			(xy 333.280123 -404.995428) (xy 333.280512 -404.986236) (xy 333.280512 -404.828756) (xy 333.280949 -404.818643)
			(xy 333.288704 -404.799961) (xy 333.303015 -404.785668) (xy 333.321706 -404.777937) (xy 333.33182 -404.777448)
			(xy 334.0481 -404.777448) (xy 334.058202 -404.777984) (xy 334.076871 -404.785712) (xy 334.091163 -404.799993)
			(xy 334.098907 -404.818654) (xy 334.099408 -404.828756) (xy 334.099408 -404.986236) (xy 334.099799 -404.995425)
			(xy 334.106326 -405.01261) (xy 334.112108 -405.019764) (xy 334.133968 -405.045433) (xy 334.172056 -405.101067)
			(xy 334.203206 -405.160863) (xy 334.226971 -405.223959) (xy 334.243006 -405.289448) (xy 334.251082 -405.356385)
			(xy 334.251082 -405.423809) (xy 334.243007 -405.490746) (xy 334.226972 -405.556235) (xy 334.203209 -405.619332)
			(xy 334.20093 -405.623707) (xy 335.328987 -405.623707) (xy 335.328987 -405.556284) (xy 335.337063 -405.489346)
			(xy 335.353098 -405.423857) (xy 335.376861 -405.36076) (xy 335.40801 -405.300963) (xy 335.446097 -405.245328)
			(xy 335.46796 -405.219662) (xy 335.473763 -405.212521) (xy 335.480272 -405.195327) (xy 335.48066 -405.186134)
			(xy 335.48066 -404.693882) (xy 335.480245 -404.684696) (xy 335.473733 -404.667512) (xy 335.46796 -404.660354)
			(xy 335.446119 -404.63467) (xy 335.408032 -404.579037) (xy 335.376883 -404.519243) (xy 335.353119 -404.456149)
			(xy 335.337083 -404.390663) (xy 335.329006 -404.323727) (xy 335.329004 -404.256306) (xy 335.337078 -404.18937)
			(xy 335.353109 -404.123883) (xy 335.376869 -404.060787) (xy 335.408015 -404.000991) (xy 335.446099 -403.945356)
			(xy 335.46796 -403.91969) (xy 335.473751 -403.912541) (xy 335.480267 -403.895353) (xy 335.48066 -403.886162)
			(xy 335.48066 -403.728682) (xy 335.481112 -403.718552) (xy 335.48885 -403.699826) (xy 335.503147 -403.68547)
			(xy 335.52184 -403.677655) (xy 335.531968 -403.67712) (xy 336.248248 -403.67712) (xy 336.258408 -403.677483)
			(xy 336.277165 -403.685298) (xy 336.291487 -403.699713) (xy 336.299182 -403.71852) (xy 336.299556 -403.728682)
			(xy 336.299556 -403.886162) (xy 336.299995 -403.895346) (xy 336.30649 -403.91253) (xy 336.312256 -403.91969)
			(xy 336.334143 -403.945337) (xy 336.372234 -404.000973) (xy 336.403386 -404.060771) (xy 336.427151 -404.123871)
			(xy 336.443186 -404.189362) (xy 336.451261 -404.256303) (xy 336.451259 -404.32373) (xy 336.443181 -404.39067)
			(xy 336.427141 -404.456161) (xy 336.403373 -404.519259) (xy 336.372217 -404.579056) (xy 336.334123 -404.634689)
			(xy 336.312256 -404.660354) (xy 336.306449 -404.667491) (xy 336.299941 -404.684688) (xy 336.299556 -404.693882)
			(xy 336.299556 -405.186134) (xy 336.29996 -405.195322) (xy 336.306479 -405.212505) (xy 336.312256 -405.219662)
			(xy 336.334116 -405.245331) (xy 336.372207 -405.300964) (xy 336.403361 -405.360759) (xy 336.427127 -405.423856)
			(xy 336.443164 -405.489345) (xy 336.451242 -405.556283) (xy 336.451242 -405.623708) (xy 336.443166 -405.690646)
			(xy 336.42713 -405.756135) (xy 336.403365 -405.819232) (xy 336.372212 -405.879028) (xy 336.334121 -405.934662)
			(xy 336.312256 -405.960326) (xy 336.30646 -405.967472) (xy 336.299946 -405.984662) (xy 336.299556 -405.993854)
			(xy 336.299556 -406.151334) (xy 336.299101 -406.161463) (xy 336.291362 -406.180186) (xy 336.277066 -406.194541)
			(xy 336.258375 -406.202359) (xy 336.248248 -406.202896) (xy 335.531968 -406.202896) (xy 335.521811 -406.202505)
			(xy 335.503057 -406.194698) (xy 335.488735 -406.180292) (xy 335.481037 -406.161493) (xy 335.48066 -406.151334)
			(xy 335.48066 -405.993854) (xy 335.48021 -405.984671) (xy 335.473722 -405.967487) (xy 335.46796 -405.960326)
			(xy 335.446092 -405.934665) (xy 335.408006 -405.879029) (xy 335.376857 -405.819232) (xy 335.353095 -405.756134)
			(xy 335.337062 -405.690645) (xy 335.328987 -405.623707) (xy 334.20093 -405.623707) (xy 334.172059 -405.679128)
			(xy 334.133971 -405.734763) (xy 334.112108 -405.760428) (xy 334.106318 -405.767578) (xy 334.099799 -405.784765)
			(xy 334.099408 -405.793956) (xy 334.099408 -406.286208) (xy 334.099813 -406.295396) (xy 334.10633 -406.31258)
			(xy 334.112108 -406.319736) (xy 334.13394 -406.345427) (xy 334.172029 -406.401058) (xy 334.203181 -406.460851)
			(xy 334.226947 -406.523944) (xy 334.242984 -406.58943) (xy 334.251062 -406.656365) (xy 334.251065 -406.723729)
			(xy 337.529127 -406.723729) (xy 337.52913 -406.656423) (xy 337.537177 -406.589598) (xy 337.553152 -406.524215)
			(xy 337.576827 -406.461209) (xy 337.607861 -406.401484) (xy 337.645812 -406.345897) (xy 337.6676 -406.320244)
			(xy 337.673403 -406.313103) (xy 337.679914 -406.295909) (xy 337.6803 -406.286716) (xy 337.6803 -405.793448)
			(xy 337.679867 -405.784263) (xy 337.673369 -405.767079) (xy 337.6676 -405.75992) (xy 337.64581 -405.734271)
			(xy 337.607863 -405.678683) (xy 337.576832 -405.618958) (xy 337.553162 -405.555954) (xy 337.53719 -405.490572)
			(xy 337.529147 -405.423749) (xy 337.529147 -405.356445) (xy 337.537191 -405.289622) (xy 337.553163 -405.224241)
			(xy 337.576835 -405.161236) (xy 337.607866 -405.101512) (xy 337.645813 -405.045925) (xy 337.6676 -405.020272)
			(xy 337.673391 -405.013123) (xy 337.679909 -404.995935) (xy 337.6803 -404.986744) (xy 337.6803 -404.828756)
			(xy 337.680686 -404.818599) (xy 337.688496 -404.799846) (xy 337.702903 -404.785524) (xy 337.721703 -404.777826)
			(xy 337.731862 -404.777448) (xy 338.448142 -404.777448) (xy 338.458272 -404.777892) (xy 338.476996 -404.785635)
			(xy 338.491351 -404.799934) (xy 338.499167 -404.818628) (xy 338.499704 -404.828756) (xy 338.499704 -404.986744)
			(xy 338.500092 -404.995934) (xy 338.506621 -405.013118) (xy 338.512404 -405.020272) (xy 338.534186 -405.045928)
			(xy 338.572133 -405.101515) (xy 338.603164 -405.161238) (xy 338.626835 -405.224242) (xy 338.642807 -405.289624)
			(xy 338.650851 -405.356445) (xy 338.650851 -405.423749) (xy 338.642808 -405.490571) (xy 338.626837 -405.555952)
			(xy 338.603166 -405.618956) (xy 338.600728 -405.623648) (xy 339.729282 -405.623648) (xy 339.729282 -405.556343)
			(xy 339.737327 -405.489519) (xy 339.753301 -405.424137) (xy 339.776975 -405.361132) (xy 339.808009 -405.301408)
			(xy 339.845959 -405.245822) (xy 339.867748 -405.22017) (xy 339.873546 -405.213026) (xy 339.880058 -405.195834)
			(xy 339.880448 -405.186642) (xy 339.880448 -404.693374) (xy 339.88004 -404.684187) (xy 339.873523 -404.667003)
			(xy 339.867748 -404.659846) (xy 339.845982 -404.634176) (xy 339.808032 -404.578592) (xy 339.776997 -404.518871)
			(xy 339.753323 -404.455869) (xy 339.737348 -404.390489) (xy 339.729302 -404.323668) (xy 339.7293 -404.256365)
			(xy 339.737342 -404.189544) (xy 339.753313 -404.124163) (xy 339.776984 -404.061159) (xy 339.808015 -404.001436)
			(xy 339.845962 -403.94585) (xy 339.867748 -403.920198) (xy 339.873534 -403.913045) (xy 339.880054 -403.89586)
			(xy 339.880448 -403.88667) (xy 339.880448 -403.728682) (xy 339.880919 -403.718522) (xy 339.888701 -403.69975)
			(xy 339.903074 -403.685385) (xy 339.92185 -403.677613) (xy 339.93201 -403.67712) (xy 340.64829 -403.67712)
			(xy 340.658445 -403.677641) (xy 340.67721 -403.685409) (xy 340.691575 -403.699766) (xy 340.699353 -403.718527)
			(xy 340.699852 -403.728682) (xy 340.699852 -403.88667) (xy 340.700287 -403.895854) (xy 340.706785 -403.913038)
			(xy 340.712552 -403.920198) (xy 340.734362 -403.945832) (xy 340.772311 -404.001421) (xy 340.803343 -404.061147)
			(xy 340.827015 -404.124154) (xy 340.842987 -404.189538) (xy 340.85103 -404.256363) (xy 340.851028 -404.32367)
			(xy 340.842981 -404.390494) (xy 340.827006 -404.455878) (xy 340.80333 -404.518883) (xy 340.772294 -404.578608)
			(xy 340.734341 -404.634194) (xy 340.712552 -404.659846) (xy 340.706747 -404.666985) (xy 340.700239 -404.684181)
			(xy 340.699852 -404.693374) (xy 340.699852 -405.186642) (xy 340.700253 -405.19583) (xy 340.706774 -405.213014)
			(xy 340.712552 -405.22017) (xy 340.734334 -405.245827) (xy 340.772283 -405.301413) (xy 340.803317 -405.361135)
			(xy 340.826991 -405.424139) (xy 340.842965 -405.489521) (xy 340.851009 -405.556343) (xy 340.85101 -405.623648)
			(xy 340.842966 -405.69047) (xy 340.826994 -405.755852) (xy 340.803321 -405.818856) (xy 340.772288 -405.87858)
			(xy 340.734339 -405.934166) (xy 340.712552 -405.959818) (xy 340.706759 -405.966966) (xy 340.700244 -405.984154)
			(xy 340.699852 -405.993346) (xy 340.699852 -406.151334) (xy 340.699394 -406.161495) (xy 340.691607 -406.180267)
			(xy 340.67723 -406.194631) (xy 340.658452 -406.202403) (xy 340.64829 -406.202896) (xy 339.93201 -406.202896)
			(xy 339.921857 -406.202359) (xy 339.903095 -406.194594) (xy 339.88873 -406.180242) (xy 339.880949 -406.161487)
			(xy 339.880448 -406.151334) (xy 339.880448 -405.993346) (xy 339.880005 -405.984163) (xy 339.873513 -405.966979)
			(xy 339.867748 -405.959818) (xy 339.845954 -405.934171) (xy 339.808005 -405.878584) (xy 339.776971 -405.81886)
			(xy 339.753298 -405.755855) (xy 339.737325 -405.690472) (xy 339.729282 -405.623648) (xy 338.600728 -405.623648)
			(xy 338.572136 -405.67868) (xy 338.53419 -405.734267) (xy 338.512404 -405.75992) (xy 338.506617 -405.767072)
			(xy 338.500096 -405.784257) (xy 338.499704 -405.793448) (xy 338.499704 -406.286716) (xy 338.500106 -406.295904)
			(xy 338.506625 -406.313088) (xy 338.512404 -406.320244) (xy 338.534159 -406.345923) (xy 338.572106 -406.401506)
			(xy 338.603138 -406.461227) (xy 338.626811 -406.524228) (xy 338.642785 -406.589606) (xy 338.650831 -406.656425)
			(xy 338.650834 -406.723727) (xy 338.650827 -406.723789) (xy 341.928896 -406.723789) (xy 341.928898 -406.656363)
			(xy 341.936977 -406.589423) (xy 341.953016 -406.523932) (xy 341.976784 -406.460834) (xy 342.007938 -406.401036)
			(xy 342.04603 -406.345401) (xy 342.067896 -406.319736) (xy 342.073702 -406.312597) (xy 342.080211 -406.295402)
			(xy 342.080596 -406.286208) (xy 342.080596 -405.793956) (xy 342.080208 -405.784766) (xy 342.073679 -405.767582)
			(xy 342.067896 -405.760428) (xy 342.046028 -405.734766) (xy 342.00794 -405.679131) (xy 341.97679 -405.619334)
			(xy 341.953026 -405.556237) (xy 341.936991 -405.490748) (xy 341.928915 -405.423809) (xy 341.928916 -405.356385)
			(xy 341.936992 -405.289447) (xy 341.953028 -405.223957) (xy 341.976792 -405.16086) (xy 342.007943 -405.101064)
			(xy 342.046032 -405.045429) (xy 342.067896 -405.019764) (xy 342.07369 -405.012617) (xy 342.080206 -404.995428)
			(xy 342.080596 -404.986236) (xy 342.080596 -404.828756) (xy 342.081049 -404.818645) (xy 342.0888 -404.799967)
			(xy 342.103107 -404.785673) (xy 342.121793 -404.77794) (xy 342.131904 -404.777448) (xy 342.848184 -404.777448)
			(xy 342.858285 -404.777997) (xy 342.876953 -404.78572) (xy 342.891247 -404.799996) (xy 342.898991 -404.818655)
			(xy 342.899492 -404.828756) (xy 342.899492 -404.986236) (xy 342.899886 -404.995425) (xy 342.906411 -405.012609)
			(xy 342.912192 -405.019764) (xy 342.934052 -405.045432) (xy 342.972142 -405.101066) (xy 343.003293 -405.160862)
			(xy 343.027058 -405.223958) (xy 343.043094 -405.289447) (xy 343.05117 -405.356385) (xy 343.05117 -405.423809)
			(xy 343.043095 -405.490747) (xy 343.02706 -405.556236) (xy 343.003295 -405.619333) (xy 343.001047 -405.623648)
			(xy 344.129073 -405.623648) (xy 344.129073 -405.556343) (xy 344.137118 -405.48952) (xy 344.153091 -405.424137)
			(xy 344.176765 -405.361132) (xy 344.207799 -405.301409) (xy 344.245748 -405.245822) (xy 344.267536 -405.22017)
			(xy 344.273332 -405.213025) (xy 344.279846 -405.195834) (xy 344.280236 -405.186642) (xy 344.280236 -404.693374)
			(xy 344.27983 -404.684187) (xy 344.273313 -404.667003) (xy 344.267536 -404.659846) (xy 344.24577 -404.634176)
			(xy 344.207821 -404.578592) (xy 344.176787 -404.518871) (xy 344.153113 -404.455869) (xy 344.137139 -404.390489)
			(xy 344.129093 -404.323668) (xy 344.129091 -404.256365) (xy 344.137133 -404.189544) (xy 344.153103 -404.124163)
			(xy 344.176773 -404.061159) (xy 344.207804 -404.001437) (xy 344.24575 -403.94585) (xy 344.267536 -403.920198)
			(xy 344.273321 -403.913044) (xy 344.279842 -403.89586) (xy 344.280236 -403.88667) (xy 344.280236 -403.728682)
			(xy 344.280718 -403.718523) (xy 344.288498 -403.699754) (xy 344.302867 -403.685389) (xy 344.321639 -403.677615)
			(xy 344.331798 -403.67712) (xy 345.048078 -403.67712) (xy 345.058246 -403.677582) (xy 345.077037 -403.685356)
			(xy 345.091422 -403.69973) (xy 345.09921 -403.718514) (xy 345.09964 -403.728682) (xy 345.09964 -403.88667)
			(xy 345.100078 -403.895854) (xy 345.106574 -403.913038) (xy 345.11234 -403.920198) (xy 345.13415 -403.945832)
			(xy 345.1721 -404.00142) (xy 345.203133 -404.061146) (xy 345.226806 -404.124153) (xy 345.242778 -404.189538)
			(xy 345.250821 -404.256363) (xy 345.250819 -404.32367) (xy 345.242772 -404.390495) (xy 345.226796 -404.455878)
			(xy 345.20312 -404.518884) (xy 345.172083 -404.578608) (xy 345.13413 -404.634194) (xy 345.11234 -404.659846)
			(xy 345.106534 -404.666984) (xy 345.100027 -404.68418) (xy 345.09964 -404.693374) (xy 345.09964 -405.186642)
			(xy 345.100043 -405.19583) (xy 345.106563 -405.213013) (xy 345.11234 -405.22017) (xy 345.134122 -405.245827)
			(xy 345.172073 -405.301412) (xy 345.203107 -405.361135) (xy 345.226781 -405.424139) (xy 345.242755 -405.489521)
			(xy 345.2508 -405.556343) (xy 345.250801 -405.623648) (xy 345.242757 -405.69047) (xy 345.226784 -405.755853)
			(xy 345.203111 -405.818857) (xy 345.172077 -405.87858) (xy 345.134128 -405.934166) (xy 345.11234 -405.959818)
			(xy 345.106546 -405.966965) (xy 345.100031 -405.984154) (xy 345.09964 -405.993346) (xy 345.09964 -406.151334)
			(xy 345.099194 -406.161497) (xy 345.091404 -406.180271) (xy 345.077024 -406.194636) (xy 345.058241 -406.202405)
			(xy 345.048078 -406.202896) (xy 344.331798 -406.202896) (xy 344.321644 -406.202369) (xy 344.302882 -406.1946)
			(xy 344.288518 -406.180245) (xy 344.280737 -406.161487) (xy 344.280236 -406.151334) (xy 344.280236 -405.993346)
			(xy 344.279795 -405.984162) (xy 344.273302 -405.966978) (xy 344.267536 -405.959818) (xy 344.245742 -405.934171)
			(xy 344.207794 -405.878584) (xy 344.176761 -405.818859) (xy 344.153089 -405.755854) (xy 344.137116 -405.690471)
			(xy 344.129073 -405.623648) (xy 343.001047 -405.623648) (xy 342.972145 -405.679129) (xy 342.934056 -405.734763)
			(xy 342.912192 -405.760428) (xy 342.9064 -405.767576) (xy 342.899883 -405.784765) (xy 342.899492 -405.793956)
			(xy 342.899492 -406.286208) (xy 342.8999 -406.295395) (xy 342.906416 -406.312579) (xy 342.912192 -406.319736)
			(xy 342.934025 -406.345427) (xy 342.972115 -406.401058) (xy 343.003268 -406.46085) (xy 343.027034 -406.523944)
			(xy 343.043072 -406.58943) (xy 343.05115 -406.656365) (xy 343.051153 -406.72373) (xy 346.329191 -406.72373)
			(xy 346.329194 -406.656422) (xy 346.337242 -406.589596) (xy 346.35322 -406.524212) (xy 346.376898 -406.461206)
			(xy 346.407937 -406.401482) (xy 346.445893 -406.345896) (xy 346.467684 -406.320244) (xy 346.473485 -406.313102)
			(xy 346.479998 -406.295909) (xy 346.480384 -406.286716) (xy 346.480384 -405.793448) (xy 346.479955 -405.784263)
			(xy 346.473455 -405.767078) (xy 346.467684 -405.75992) (xy 346.445891 -405.734272) (xy 346.407939 -405.678686)
			(xy 346.376904 -405.618962) (xy 346.353229 -405.555957) (xy 346.337255 -405.490574) (xy 346.329211 -405.42375)
			(xy 346.329211 -405.356444) (xy 346.337256 -405.28962) (xy 346.353231 -405.224237) (xy 346.376906 -405.161232)
			(xy 346.407942 -405.101509) (xy 346.445895 -405.045924) (xy 346.467684 -405.020272) (xy 346.473473 -405.013121)
			(xy 346.479993 -404.995935) (xy 346.480384 -404.986744) (xy 346.480384 -404.828756) (xy 346.480785 -404.818601)
			(xy 346.488592 -404.799851) (xy 346.502995 -404.78553) (xy 346.521789 -404.777829) (xy 346.531946 -404.777448)
			(xy 347.248226 -404.777448) (xy 347.258355 -404.777905) (xy 347.277079 -404.785643) (xy 347.291434 -404.799938)
			(xy 347.299251 -404.818629) (xy 347.299788 -404.828756) (xy 347.299788 -404.986744) (xy 347.30018 -404.995933)
			(xy 347.306706 -405.013117) (xy 347.312488 -405.020272) (xy 347.334271 -405.045928) (xy 347.372218 -405.101514)
			(xy 347.40325 -405.161238) (xy 347.426922 -405.224242) (xy 347.442894 -405.289623) (xy 347.450938 -405.356445)
			(xy 347.450939 -405.423749) (xy 347.442895 -405.490571) (xy 347.426924 -405.555953) (xy 347.403253 -405.618957)
			(xy 347.372221 -405.678681) (xy 347.334275 -405.734268) (xy 347.312488 -405.75992) (xy 347.306699 -405.767071)
			(xy 347.30018 -405.784257) (xy 347.299788 -405.793448) (xy 347.299788 -406.286716) (xy 347.300193 -406.295904)
			(xy 347.30671 -406.313088) (xy 347.312488 -406.320244) (xy 347.334244 -406.345922) (xy 347.372192 -406.401506)
			(xy 347.403225 -406.461226) (xy 347.426898 -406.524227) (xy 347.442873 -406.589606) (xy 347.450919 -406.656425)
			(xy 347.450922 -406.723727) (xy 347.442881 -406.790547) (xy 347.426912 -406.855927) (xy 347.403244 -406.91893)
			(xy 347.372216 -406.978653) (xy 347.334273 -407.03424) (xy 347.312488 -407.059892) (xy 347.306711 -407.067051)
			(xy 347.300185 -407.084231) (xy 347.299788 -407.09342) (xy 347.299788 -407.251408) (xy 347.299385 -407.261564)
			(xy 347.291584 -407.280319) (xy 347.277182 -407.294642) (xy 347.258384 -407.30234) (xy 347.248226 -407.302716)
			(xy 346.531946 -407.302716) (xy 346.521817 -407.302234) (xy 346.503088 -407.294514) (xy 346.488729 -407.280225)
			(xy 346.480916 -407.261535) (xy 346.480384 -407.251408) (xy 346.480384 -407.09342) (xy 346.479968 -407.084233)
			(xy 346.473459 -407.067049) (xy 346.467684 -407.059892) (xy 346.445864 -407.034266) (xy 346.407913 -406.978677)
			(xy 346.376878 -406.91895) (xy 346.353205 -406.855942) (xy 346.337233 -406.790556) (xy 346.329191 -406.72373)
			(xy 343.051153 -406.72373) (xy 343.051153 -406.723787) (xy 343.04308 -406.790723) (xy 343.027048 -406.85621)
			(xy 343.003287 -406.919306) (xy 342.97214 -406.979101) (xy 342.934054 -407.034735) (xy 342.912192 -407.0604)
			(xy 342.906412 -407.067557) (xy 342.899888 -407.084738) (xy 342.899492 -407.093928) (xy 342.899492 -407.251408)
			(xy 342.89909 -407.261532) (xy 342.891338 -407.280237) (xy 342.877017 -407.294551) (xy 342.858308 -407.302295)
			(xy 342.848184 -407.302716) (xy 342.131904 -407.302716) (xy 342.121798 -407.302212) (xy 342.103122 -407.294479)
			(xy 342.088828 -407.280188) (xy 342.08109 -407.261514) (xy 342.080596 -407.251408) (xy 342.080596 -407.093928)
			(xy 342.080173 -407.084742) (xy 342.073668 -407.067558) (xy 342.067896 -407.0604) (xy 342.046001 -407.034761)
			(xy 342.007913 -406.979122) (xy 341.976764 -406.919322) (xy 341.953002 -406.856222) (xy 341.936969 -406.79073)
			(xy 341.928896 -406.723789) (xy 338.650827 -406.723789) (xy 338.642793 -406.790546) (xy 338.626825 -406.855926)
			(xy 338.603158 -406.918929) (xy 338.572131 -406.978652) (xy 338.534188 -407.034239) (xy 338.512404 -407.059892)
			(xy 338.506629 -407.067052) (xy 338.500101 -407.084231) (xy 338.499704 -407.09342) (xy 338.499704 -407.251408)
			(xy 338.499285 -407.261562) (xy 338.491487 -407.280314) (xy 338.47709 -407.294637) (xy 338.458298 -407.302337)
			(xy 338.448142 -407.302716) (xy 337.731862 -407.302716) (xy 337.721727 -407.302303) (xy 337.702997 -407.294555)
			(xy 337.688641 -407.280246) (xy 337.68083 -407.261541) (xy 337.6803 -407.251408) (xy 337.6803 -407.09342)
			(xy 337.67988 -407.084234) (xy 337.673373 -407.067049) (xy 337.6676 -407.059892) (xy 337.645782 -407.034265)
			(xy 337.607837 -406.978674) (xy 337.576807 -406.918947) (xy 337.553138 -406.855939) (xy 337.537168 -406.790554)
			(xy 337.529127 -406.723729) (xy 334.251065 -406.723729) (xy 334.251065 -406.723786) (xy 334.242993 -406.790722)
			(xy 334.226961 -406.85621) (xy 334.203201 -406.919305) (xy 334.172054 -406.9791) (xy 334.13397 -407.034735)
			(xy 334.112108 -407.0604) (xy 334.10633 -407.067558) (xy 334.099804 -407.084739) (xy 334.099408 -407.093928)
			(xy 334.099408 -407.251408) (xy 334.098921 -407.261516) (xy 334.091183 -407.280193) (xy 334.076886 -407.294487)
			(xy 334.058208 -407.302223) (xy 334.0481 -407.302716) (xy 333.33182 -407.302716) (xy 333.321701 -407.302268)
			(xy 333.303001 -407.29453) (xy 333.288686 -407.280223) (xy 333.280937 -407.261527) (xy 333.280512 -407.251408)
			(xy 333.280512 -407.093928) (xy 333.280086 -407.084743) (xy 333.273583 -407.067558) (xy 333.267812 -407.0604)
			(xy 333.245916 -407.034761) (xy 333.207828 -406.979123) (xy 333.176678 -406.919323) (xy 333.152915 -406.856223)
			(xy 333.136881 -406.790731) (xy 333.128808 -406.723789) (xy 326.525636 -406.723789) (xy 326.525636 -409.523827)
			(xy 330.929173 -409.523827) (xy 330.929176 -409.456519) (xy 330.937224 -409.389693) (xy 330.953202 -409.324309)
			(xy 330.976879 -409.261303) (xy 331.007918 -409.201578) (xy 331.045873 -409.145992) (xy 331.067664 -409.12034)
			(xy 331.073476 -409.113206) (xy 331.07998 -409.096007) (xy 331.080364 -409.086812) (xy 331.080364 -408.593544)
			(xy 331.079919 -408.584361) (xy 331.073428 -408.567177) (xy 331.067664 -408.560016) (xy 331.045868 -408.534371)
			(xy 331.007918 -408.478784) (xy 330.976883 -408.419059) (xy 330.95321 -408.356054) (xy 330.937237 -408.290671)
			(xy 330.929193 -408.223847) (xy 330.929194 -408.156541) (xy 330.937239 -408.089717) (xy 330.953213 -408.024334)
			(xy 330.976888 -407.96133) (xy 331.007924 -407.901606) (xy 331.045875 -407.84602) (xy 331.067664 -407.820368)
			(xy 331.073464 -407.813226) (xy 331.079975 -407.796033) (xy 331.080364 -407.78684) (xy 331.080364 -407.628852)
			(xy 331.080782 -407.618699) (xy 331.088586 -407.599953) (xy 331.102983 -407.585633) (xy 331.121771 -407.577928)
			(xy 331.131926 -407.577544) (xy 331.848206 -407.577544) (xy 331.858334 -407.578022) (xy 331.877056 -407.585752)
			(xy 331.891412 -407.600041) (xy 331.89923 -407.618727) (xy 331.899768 -407.628852) (xy 331.899768 -407.78684)
			(xy 331.900166 -407.796028) (xy 331.906689 -407.813212) (xy 331.912468 -407.820368) (xy 331.934248 -407.846027)
			(xy 331.972196 -407.901612) (xy 332.00323 -407.961335) (xy 332.026903 -408.024339) (xy 332.042876 -408.08972)
			(xy 332.050921 -408.156542) (xy 332.050921 -408.223846) (xy 332.042878 -408.290668) (xy 332.026906 -408.35605)
			(xy 332.003235 -408.419054) (xy 331.972203 -408.478777) (xy 331.934255 -408.534364) (xy 331.912468 -408.560016)
			(xy 331.906678 -408.567166) (xy 331.90016 -408.584353) (xy 331.899768 -408.593544) (xy 331.899768 -409.086812)
			(xy 331.900179 -409.095999) (xy 331.906693 -409.113183) (xy 331.912468 -409.12034) (xy 331.93422 -409.146022)
			(xy 331.972169 -409.201604) (xy 332.003204 -409.261323) (xy 332.026878 -409.324324) (xy 332.042853 -409.389703)
			(xy 332.0509 -409.456522) (xy 332.050904 -409.523824) (xy 332.042863 -409.590644) (xy 332.026894 -409.656024)
			(xy 332.003226 -409.719027) (xy 331.972197 -409.77875) (xy 331.934253 -409.834336) (xy 331.912468 -409.859988)
			(xy 331.906647 -409.867116) (xy 331.900148 -409.88432) (xy 331.899768 -409.893516) (xy 331.899768 -410.051504)
			(xy 331.899381 -410.061662) (xy 331.891578 -410.080421) (xy 331.87717 -410.094745) (xy 331.858367 -410.102439)
			(xy 331.848206 -410.102812) (xy 331.131926 -410.102812) (xy 331.121807 -410.102254) (xy 331.103097 -410.094544)
			(xy 331.088741 -410.08028) (xy 331.080912 -410.061619) (xy 331.080364 -410.051504) (xy 331.080364 -409.893516)
			(xy 331.079932 -409.884331) (xy 331.073432 -409.867148) (xy 331.067664 -409.859988) (xy 331.04584 -409.834365)
			(xy 331.007891 -409.778775) (xy 330.976857 -409.719048) (xy 330.953186 -409.656039) (xy 330.937214 -409.590653)
			(xy 330.929173 -409.523827) (xy 326.525636 -409.523827) (xy 326.525636 -410.623701) (xy 333.128819 -410.623701)
			(xy 333.12882 -410.556275) (xy 333.136898 -410.489336) (xy 333.152936 -410.423846) (xy 333.176702 -410.360748)
			(xy 333.207855 -410.300952) (xy 333.245947 -410.245317) (xy 333.267812 -410.219652) (xy 333.273613 -410.21251)
			(xy 333.280125 -410.195317) (xy 333.280512 -410.186124) (xy 333.280512 -409.693872) (xy 333.280113 -409.684684)
			(xy 333.273591 -409.6675) (xy 333.267812 -409.660344) (xy 333.245959 -409.634669) (xy 333.20787 -409.579036)
			(xy 333.176718 -409.519242) (xy 333.152952 -409.456146) (xy 333.136916 -409.390658) (xy 333.128839 -409.32372)
			(xy 333.128837 -409.256298) (xy 333.136912 -409.18936) (xy 333.152947 -409.123871) (xy 333.17671 -409.060775)
			(xy 333.20786 -409.000979) (xy 333.245948 -408.945345) (xy 333.267812 -408.91968) (xy 333.273601 -408.912529)
			(xy 333.28012 -408.895343) (xy 333.280512 -408.886152) (xy 333.280512 -408.728672) (xy 333.280962 -408.71856)
			(xy 333.288711 -408.699879) (xy 333.303019 -408.685585) (xy 333.321708 -408.677853) (xy 333.33182 -408.677364)
			(xy 334.0481 -408.677364) (xy 334.058204 -408.677884) (xy 334.076876 -408.685615) (xy 334.091169 -408.699901)
			(xy 334.09891 -408.718568) (xy 334.099408 -408.728672) (xy 334.099408 -408.886152) (xy 334.099839 -408.895337)
			(xy 334.106338 -408.912522) (xy 334.112108 -408.91968) (xy 334.133983 -408.945336) (xy 334.172071 -409.000972)
			(xy 334.203221 -409.060769) (xy 334.226984 -409.123867) (xy 334.243019 -409.189358) (xy 334.251093 -409.256297)
			(xy 334.251092 -409.323721) (xy 334.243015 -409.39066) (xy 334.226979 -409.45615) (xy 334.203214 -409.519247)
			(xy 334.200797 -409.523886) (xy 335.328966 -409.523886) (xy 335.328969 -409.45646) (xy 335.337048 -409.38952)
			(xy 335.353086 -409.32403) (xy 335.376852 -409.260931) (xy 335.408005 -409.201134) (xy 335.446095 -409.145498)
			(xy 335.46796 -409.119832) (xy 335.473775 -409.1127) (xy 335.480277 -409.095499) (xy 335.48066 -409.086304)
			(xy 335.48066 -408.594052) (xy 335.480211 -408.584869) (xy 335.473723 -408.567685) (xy 335.46796 -408.560524)
			(xy 335.44609 -408.534865) (xy 335.408004 -408.479228) (xy 335.376856 -408.419431) (xy 335.353094 -408.356333)
			(xy 335.33706 -408.290844) (xy 335.328985 -408.223906) (xy 335.328986 -408.156482) (xy 335.337062 -408.089544)
			(xy 335.353097 -408.024055) (xy 335.376861 -407.960958) (xy 335.40801 -407.901161) (xy 335.446097 -407.845526)
			(xy 335.46796 -407.81986) (xy 335.473763 -407.81272) (xy 335.480272 -407.795525) (xy 335.48066 -407.786332)
			(xy 335.48066 -407.628852) (xy 335.481145 -407.618745) (xy 335.488891 -407.600074) (xy 335.503187 -407.585782)
			(xy 335.521861 -407.578042) (xy 335.531968 -407.577544) (xy 336.248248 -407.577544) (xy 336.258353 -407.578045)
			(xy 336.277021 -407.585788) (xy 336.291312 -407.600079) (xy 336.299055 -407.618747) (xy 336.299556 -407.628852)
			(xy 336.299556 -407.786332) (xy 336.299961 -407.79552) (xy 336.306479 -407.812703) (xy 336.312256 -407.81986)
			(xy 336.334114 -407.845531) (xy 336.372205 -407.901164) (xy 336.403359 -407.960959) (xy 336.427126 -408.024055)
			(xy 336.443163 -408.089544) (xy 336.45124 -408.156482) (xy 336.451241 -408.223906) (xy 336.443165 -408.290844)
			(xy 336.427129 -408.356334) (xy 336.403364 -408.41943) (xy 336.372212 -408.479226) (xy 336.334121 -408.53486)
			(xy 336.312256 -408.560524) (xy 336.306461 -408.56767) (xy 336.299947 -408.58486) (xy 336.299556 -408.594052)
			(xy 336.299556 -409.086304) (xy 336.299974 -409.09549) (xy 336.306483 -409.112674) (xy 336.312256 -409.119832)
			(xy 336.334086 -409.145526) (xy 336.372179 -409.201155) (xy 336.403334 -409.260947) (xy 336.427102 -409.32404)
			(xy 336.443141 -409.389526) (xy 336.45122 -409.456462) (xy 336.451224 -409.523884) (xy 336.443151 -409.59082)
			(xy 336.427118 -409.656308) (xy 336.403356 -409.719404) (xy 336.372207 -409.779198) (xy 336.334119 -409.834832)
			(xy 336.312256 -409.860496) (xy 336.306473 -409.867651) (xy 336.299951 -409.884834) (xy 336.299556 -409.894024)
			(xy 336.299556 -410.051504) (xy 336.299019 -410.061606) (xy 336.291291 -410.080274) (xy 336.277011 -410.094566)
			(xy 336.25835 -410.102311) (xy 336.248248 -410.102812) (xy 335.531968 -410.102812) (xy 335.521859 -410.102341)
			(xy 335.503182 -410.094595) (xy 335.488889 -410.080294) (xy 335.481153 -410.061614) (xy 335.48066 -410.051504)
			(xy 335.48066 -409.894024) (xy 335.480225 -409.88484) (xy 335.473727 -409.867656) (xy 335.46796 -409.860496)
			(xy 335.446062 -409.834859) (xy 335.407977 -409.77922) (xy 335.37683 -409.719419) (xy 335.35307 -409.656319)
			(xy 335.337038 -409.590827) (xy 335.328966 -409.523886) (xy 334.200797 -409.523886) (xy 334.172062 -409.579044)
			(xy 334.133972 -409.634679) (xy 334.112108 -409.660344) (xy 334.106311 -409.667489) (xy 334.099796 -409.68468)
			(xy 334.099408 -409.693872) (xy 334.099408 -410.186124) (xy 334.099805 -410.195313) (xy 334.106328 -410.212497)
			(xy 334.112108 -410.219652) (xy 334.133956 -410.24533) (xy 334.172045 -410.300963) (xy 334.203196 -410.360758)
			(xy 334.22696 -410.423853) (xy 334.242997 -410.48934) (xy 334.251074 -410.556277) (xy 334.251075 -410.623641)
			(xy 337.529138 -410.623641) (xy 337.52914 -410.556335) (xy 337.537185 -410.489512) (xy 337.553158 -410.42413)
			(xy 337.576831 -410.361125) (xy 337.607864 -410.3014) (xy 337.645813 -410.245813) (xy 337.6676 -410.22016)
			(xy 337.673396 -410.213014) (xy 337.679911 -410.195824) (xy 337.6803 -410.186632) (xy 337.6803 -409.693364)
			(xy 337.679907 -409.684175) (xy 337.673382 -409.666991) (xy 337.6676 -409.659836) (xy 337.645825 -409.634174)
			(xy 337.607879 -409.578588) (xy 337.576847 -409.518865) (xy 337.553175 -409.455862) (xy 337.537203 -409.390482)
			(xy 337.529158 -409.323661) (xy 337.529157 -409.256357) (xy 337.537199 -409.189536) (xy 337.55317 -409.124155)
			(xy 337.57684 -409.061151) (xy 337.607869 -409.001428) (xy 337.645814 -408.945841) (xy 337.6676 -408.920188)
			(xy 337.673384 -408.913034) (xy 337.679906 -408.89585) (xy 337.6803 -408.88666) (xy 337.6803 -408.728672)
			(xy 337.680699 -408.718516) (xy 337.688503 -408.699763) (xy 337.702907 -408.685441) (xy 337.721704 -408.677742)
			(xy 337.731862 -408.677364) (xy 338.448142 -408.677364) (xy 338.458274 -408.677793) (xy 338.477001 -408.685539)
			(xy 338.491357 -408.699843) (xy 338.49917 -408.718542) (xy 338.499704 -408.728672) (xy 338.499704 -408.88666)
			(xy 338.500132 -408.895845) (xy 338.506633 -408.91303) (xy 338.512404 -408.920188) (xy 338.534202 -408.945831)
			(xy 338.572148 -409.00142) (xy 338.603178 -409.061145) (xy 338.626848 -409.124151) (xy 338.642819 -409.189534)
			(xy 338.650862 -409.256356) (xy 338.650861 -409.323662) (xy 338.642816 -409.390484) (xy 338.626843 -409.455867)
			(xy 338.603171 -409.518871) (xy 338.600596 -409.523827) (xy 339.729261 -409.523827) (xy 339.729264 -409.456519)
			(xy 339.737312 -409.389694) (xy 339.753289 -409.324309) (xy 339.776966 -409.261303) (xy 339.808004 -409.201579)
			(xy 339.845958 -409.145992) (xy 339.867748 -409.12034) (xy 339.873559 -409.113205) (xy 339.880064 -409.096006)
			(xy 339.880448 -409.086812) (xy 339.880448 -408.593544) (xy 339.880006 -408.58436) (xy 339.873513 -408.567176)
			(xy 339.867748 -408.560016) (xy 339.845952 -408.534371) (xy 339.808003 -408.478783) (xy 339.776969 -408.419059)
			(xy 339.753297 -408.356054) (xy 339.737324 -408.29067) (xy 339.72928 -408.223847) (xy 339.729281 -408.156541)
			(xy 339.737326 -408.089718) (xy 339.7533 -408.024335) (xy 339.776974 -407.96133) (xy 339.808009 -407.901606)
			(xy 339.845959 -407.84602) (xy 339.867748 -407.820368) (xy 339.873547 -407.813224) (xy 339.880059 -407.796032)
			(xy 339.880448 -407.78684) (xy 339.880448 -407.628852) (xy 339.880881 -407.618701) (xy 339.888683 -407.599958)
			(xy 339.903075 -407.585638) (xy 339.921857 -407.577931) (xy 339.93201 -407.577544) (xy 340.64829 -407.577544)
			(xy 340.658417 -407.578035) (xy 340.677138 -407.58576) (xy 340.691495 -407.600045) (xy 340.699314 -407.618728)
			(xy 340.699852 -407.628852) (xy 340.699852 -407.78684) (xy 340.700254 -407.796028) (xy 340.706775 -407.813211)
			(xy 340.712552 -407.820368) (xy 340.734332 -407.846027) (xy 340.772282 -407.901612) (xy 340.803316 -407.961335)
			(xy 340.826989 -408.024338) (xy 340.842963 -408.08972) (xy 340.851008 -408.156542) (xy 340.851009 -408.223846)
			(xy 340.842965 -408.290668) (xy 340.826993 -408.35605) (xy 340.803321 -408.419054) (xy 340.772288 -408.478778)
			(xy 340.734339 -408.534364) (xy 340.712552 -408.560016) (xy 340.70676 -408.567164) (xy 340.700244 -408.584353)
			(xy 340.699852 -408.593544) (xy 340.699852 -409.086812) (xy 340.700267 -409.095998) (xy 340.706779 -409.113182)
			(xy 340.712552 -409.12034) (xy 340.734304 -409.146021) (xy 340.772255 -409.201603) (xy 340.80329 -409.261323)
			(xy 340.826965 -409.324323) (xy 340.842941 -409.389702) (xy 340.850988 -409.456522) (xy 340.850992 -409.523824)
			(xy 340.842951 -409.590644) (xy 340.826981 -409.656025) (xy 340.803312 -409.719028) (xy 340.772283 -409.77875)
			(xy 340.734338 -409.834336) (xy 340.712552 -409.859988) (xy 340.70673 -409.867115) (xy 340.700232 -409.88432)
			(xy 340.699852 -409.893516) (xy 340.699852 -410.051504) (xy 340.699383 -410.061652) (xy 340.691595 -410.080394)
			(xy 340.677214 -410.094716) (xy 340.65844 -410.102424) (xy 340.64829 -410.102812) (xy 339.93201 -410.102812)
			(xy 339.92189 -410.102267) (xy 339.903179 -410.094552) (xy 339.888824 -410.080284) (xy 339.880996 -410.061621)
			(xy 339.880448 -410.051504) (xy 339.880448 -409.893516) (xy 339.88002 -409.884331) (xy 339.873517 -409.867147)
			(xy 339.867748 -409.859988) (xy 339.845924 -409.834365) (xy 339.807976 -409.778775) (xy 339.776944 -409.719047)
			(xy 339.753273 -409.656039) (xy 339.737302 -409.590653) (xy 339.729261 -409.523827) (xy 338.600596 -409.523827)
			(xy 338.572139 -409.578596) (xy 338.534191 -409.634183) (xy 338.512404 -409.659836) (xy 338.50661 -409.666983)
			(xy 338.500094 -409.684172) (xy 338.499704 -409.693364) (xy 338.499704 -410.186632) (xy 338.500098 -410.195821)
			(xy 338.506623 -410.213005) (xy 338.512404 -410.22016) (xy 338.534175 -410.245826) (xy 338.572121 -410.301411)
			(xy 338.603153 -410.361133) (xy 338.626825 -410.424136) (xy 338.642797 -410.489516) (xy 338.650842 -410.556336)
			(xy 338.650844 -410.623639) (xy 338.650837 -410.6237) (xy 341.928907 -410.6237) (xy 341.928908 -410.556276)
			(xy 341.936986 -410.489336) (xy 341.953023 -410.423846) (xy 341.976789 -410.360749) (xy 342.007941 -410.300952)
			(xy 342.046031 -410.245317) (xy 342.067896 -410.219652) (xy 342.073695 -410.212508) (xy 342.080208 -410.195317)
			(xy 342.080596 -410.186124) (xy 342.080596 -409.693872) (xy 342.0802 -409.684683) (xy 342.073677 -409.667499)
			(xy 342.067896 -409.660344) (xy 342.046044 -409.634669) (xy 342.007955 -409.579036) (xy 341.976804 -409.519241)
			(xy 341.953039 -409.456145) (xy 341.937003 -409.390657) (xy 341.928927 -409.32372) (xy 341.928925 -409.256298)
			(xy 341.937 -409.18936) (xy 341.953034 -409.123872) (xy 341.976797 -409.060776) (xy 342.007946 -409.00098)
			(xy 342.046033 -408.945345) (xy 342.067896 -408.91968) (xy 342.073683 -408.912528) (xy 342.080204 -408.895343)
			(xy 342.080596 -408.886152) (xy 342.080596 -408.728672) (xy 342.081062 -408.718562) (xy 342.088808 -408.699884)
			(xy 342.103111 -408.68559) (xy 342.121794 -408.677856) (xy 342.131904 -408.677364) (xy 342.848184 -408.677364)
			(xy 342.858287 -408.677897) (xy 342.876958 -408.685623) (xy 342.891252 -408.699905) (xy 342.898994 -408.718569)
			(xy 342.899492 -408.728672) (xy 342.899492 -408.886152) (xy 342.899927 -408.895337) (xy 342.906424 -408.912521)
			(xy 342.912192 -408.91968) (xy 342.934068 -408.945335) (xy 342.972157 -409.000971) (xy 343.003308 -409.060769)
			(xy 343.027071 -409.123867) (xy 343.043106 -409.189357) (xy 343.051181 -409.256297) (xy 343.05118 -409.323721)
			(xy 343.043103 -409.390661) (xy 343.027066 -409.45615) (xy 343.0033 -409.519248) (xy 343.000914 -409.523827)
			(xy 344.129052 -409.523827) (xy 344.129055 -409.456519) (xy 344.137102 -409.389694) (xy 344.153079 -409.32431)
			(xy 344.176756 -409.261304) (xy 344.207793 -409.201579) (xy 344.245746 -409.145992) (xy 344.267536 -409.12034)
			(xy 344.273345 -409.113204) (xy 344.279851 -409.096006) (xy 344.280236 -409.086812) (xy 344.280236 -408.593544)
			(xy 344.279796 -408.58436) (xy 344.273302 -408.567176) (xy 344.267536 -408.560016) (xy 344.24574 -408.53437)
			(xy 344.207792 -408.478783) (xy 344.176759 -408.419058) (xy 344.153087 -408.356053) (xy 344.137115 -408.29067)
			(xy 344.129071 -408.223847) (xy 344.129072 -408.156541) (xy 344.137117 -408.089718) (xy 344.153091 -408.024335)
			(xy 344.176764 -407.961331) (xy 344.207798 -407.901607) (xy 344.245748 -407.84602) (xy 344.267536 -407.820368)
			(xy 344.273333 -407.813223) (xy 344.279847 -407.796032) (xy 344.280236 -407.78684) (xy 344.280236 -407.628852)
			(xy 344.280583 -407.61869) (xy 344.288401 -407.59993) (xy 344.302821 -407.585607) (xy 344.321634 -407.577916)
			(xy 344.331798 -407.577544) (xy 345.048078 -407.577544) (xy 345.058204 -407.578045) (xy 345.076925 -407.585766)
			(xy 345.09113 -407.599896) (xy 358.331016 -407.599896) (xy 358.33502 -407.394708) (xy 358.347027 -407.189832)
			(xy 358.367018 -406.985581) (xy 358.394963 -406.782266) (xy 358.430819 -406.580195) (xy 358.474533 -406.379677)
			(xy 358.526036 -406.181018) (xy 358.585251 -405.984519) (xy 358.652087 -405.79048) (xy 358.726443 -405.599197)
			(xy 358.808206 -405.41096) (xy 358.897251 -405.226057) (xy 358.993442 -405.044769) (xy 359.096633 -404.867372)
			(xy 359.206667 -404.694135) (xy 359.323376 -404.525324) (xy 359.446582 -404.361195) (xy 359.576099 -404.201998)
			(xy 359.711728 -404.047976) (xy 359.853263 -403.899362) (xy 360.000488 -403.756384) (xy 360.15318 -403.619259)
			(xy 360.311106 -403.488195) (xy 360.474025 -403.363393) (xy 360.64169 -403.245043) (xy 360.813844 -403.133324)
			(xy 360.990226 -403.028407) (xy 361.170567 -402.930452) (xy 361.354593 -402.839608) (xy 361.542023 -402.756012)
			(xy 361.732572 -402.679793) (xy 361.925949 -402.611067) (xy 362.121861 -402.549938) (xy 362.320008 -402.496499)
			(xy 362.52009 -402.450832) (xy 362.721801 -402.413005) (xy 362.924834 -402.383078) (xy 363.128881 -402.361095)
			(xy 363.33363 -402.34709) (xy 363.538769 -402.341084) (xy 363.743986 -402.343086) (xy 363.948969 -402.353094)
			(xy 364.153406 -402.371091) (xy 364.356984 -402.397051) (xy 364.559395 -402.430934) (xy 364.760329 -402.472689)
			(xy 364.959482 -402.522252) (xy 365.156549 -402.579547) (xy 365.351231 -402.644487) (xy 365.543231 -402.716973)
			(xy 365.732256 -402.796896) (xy 365.789712 -402.823878) (xy 377.128705 -402.823878) (xy 377.12871 -402.75645)
			(xy 377.136791 -402.689508) (xy 377.152832 -402.624016) (xy 377.176603 -402.560917) (xy 377.20776 -402.50112)
			(xy 377.245856 -402.445485) (xy 377.267724 -402.41982) (xy 377.27354 -402.412689) (xy 377.280042 -402.395487)
			(xy 377.280424 -402.386292) (xy 377.280424 -401.89404) (xy 377.279989 -401.884856) (xy 377.273492 -401.867671)
			(xy 377.267724 -401.860512) (xy 377.24584 -401.834863) (xy 377.20775 -401.779227) (xy 377.176599 -401.719429)
			(xy 377.152835 -401.65633) (xy 377.1368 -401.590838) (xy 377.128725 -401.523898) (xy 377.128727 -401.456472)
			(xy 377.136805 -401.389532) (xy 377.152843 -401.324042) (xy 377.176611 -401.260944) (xy 377.207765 -401.201147)
			(xy 377.245858 -401.145513) (xy 377.267724 -401.119848) (xy 377.273528 -401.112708) (xy 377.280037 -401.095513)
			(xy 377.280424 -401.08632) (xy 377.280424 -400.92884) (xy 377.280849 -400.918717) (xy 377.288589 -400.90001)
			(xy 377.302903 -400.885693) (xy 377.321609 -400.877951) (xy 377.331732 -400.877532) (xy 378.048012 -400.877532)
			(xy 378.058139 -400.877907) (xy 378.076849 -400.885665) (xy 378.091164 -400.899994) (xy 378.098904 -400.918712)
			(xy 378.09932 -400.92884) (xy 378.09932 -401.08632) (xy 378.099716 -401.095509) (xy 378.106239 -401.112693)
			(xy 378.11202 -401.119848) (xy 378.133864 -401.14553) (xy 378.171952 -401.201162) (xy 378.203102 -401.260957)
			(xy 378.226866 -401.324051) (xy 378.242903 -401.389538) (xy 378.25098 -401.456474) (xy 378.250982 -401.523896)
			(xy 378.242908 -401.590832) (xy 378.226875 -401.65632) (xy 378.203114 -401.719416) (xy 378.200833 -401.723796)
			(xy 379.328885 -401.723796) (xy 379.328887 -401.656371) (xy 379.336964 -401.589432) (xy 379.353001 -401.523942)
			(xy 379.376766 -401.460844) (xy 379.407918 -401.401047) (xy 379.446008 -401.345412) (xy 379.467872 -401.319746)
			(xy 379.473683 -401.312611) (xy 379.480187 -401.295412) (xy 379.480572 -401.286218) (xy 379.480572 -400.793966)
			(xy 379.480184 -400.784776) (xy 379.473656 -400.767592) (xy 379.467872 -400.760438) (xy 379.446015 -400.734767)
			(xy 379.407928 -400.679133) (xy 379.376778 -400.619337) (xy 379.353015 -400.556241) (xy 379.33698 -400.490753)
			(xy 379.328904 -400.423816) (xy 379.328904 -400.356393) (xy 379.336979 -400.289456) (xy 379.353013 -400.223967)
			(xy 379.376775 -400.160871) (xy 379.407923 -400.101075) (xy 379.446009 -400.04544) (xy 379.467872 -400.019774)
			(xy 379.473671 -400.012631) (xy 379.480182 -399.995438) (xy 379.480572 -399.986246) (xy 379.480572 -399.828766)
			(xy 379.481 -399.818633) (xy 379.488744 -399.799905) (xy 379.503049 -399.785549) (xy 379.521749 -399.777737)
			(xy 379.53188 -399.777204) (xy 380.24816 -399.777204) (xy 380.258312 -399.777655) (xy 380.277064 -399.785438)
			(xy 380.291389 -399.799826) (xy 380.29909 -399.818612) (xy 380.299468 -399.828766) (xy 380.299468 -399.986246)
			(xy 380.299911 -399.99543) (xy 380.306403 -400.012614) (xy 380.312168 -400.019774) (xy 380.334039 -400.045434)
			(xy 380.37213 -400.101068) (xy 380.403282 -400.160865) (xy 380.427047 -400.223963) (xy 380.443083 -400.289453)
			(xy 380.451159 -400.356392) (xy 380.451158 -400.423817) (xy 380.443082 -400.490756) (xy 380.427044 -400.556246)
			(xy 380.403278 -400.619343) (xy 380.372125 -400.679139) (xy 380.334033 -400.734773) (xy 380.312168 -400.760438)
			(xy 380.306369 -400.767581) (xy 380.299856 -400.784773) (xy 380.299468 -400.793966) (xy 380.299468 -401.286218)
			(xy 380.299877 -401.295405) (xy 380.306392 -401.312589) (xy 380.312168 -401.319746) (xy 380.334011 -401.345429)
			(xy 380.372103 -401.40106) (xy 380.403256 -401.460853) (xy 380.427023 -401.523948) (xy 380.443061 -401.589435)
			(xy 380.451139 -401.656372) (xy 380.451141 -401.723795) (xy 380.443067 -401.790732) (xy 380.427033 -401.85622)
			(xy 380.40327 -401.919316) (xy 380.37212 -401.979112) (xy 380.334032 -402.034745) (xy 380.312168 -402.06041)
			(xy 380.306381 -402.067562) (xy 380.299861 -402.084747) (xy 380.299468 -402.093938) (xy 380.299468 -402.251418)
			(xy 380.298989 -402.261545) (xy 380.291256 -402.280265) (xy 380.276968 -402.29462) (xy 380.258284 -402.30244)
			(xy 380.24816 -402.30298) (xy 379.53188 -402.30298) (xy 379.521722 -402.302595) (xy 379.502965 -402.294789)
			(xy 379.488642 -402.280381) (xy 379.480946 -402.261578) (xy 379.480572 -402.251418) (xy 379.480572 -402.093938)
			(xy 379.48015 -402.084752) (xy 379.473645 -402.067567) (xy 379.467872 -402.06041) (xy 379.445987 -402.034762)
			(xy 379.407901 -401.979124) (xy 379.376753 -401.919326) (xy 379.352991 -401.856227) (xy 379.336958 -401.790736)
			(xy 379.328885 -401.723796) (xy 378.200833 -401.723796) (xy 378.171967 -401.779212) (xy 378.133882 -401.834846)
			(xy 378.11202 -401.860512) (xy 378.106238 -401.867668) (xy 378.099714 -401.88485) (xy 378.09932 -401.89404)
			(xy 378.09932 -402.386292) (xy 378.099729 -402.395479) (xy 378.106243 -402.412664) (xy 378.11202 -402.41982)
			(xy 378.133836 -402.445524) (xy 378.171925 -402.501154) (xy 378.203077 -402.560945) (xy 378.226843 -402.624037)
			(xy 378.242881 -402.689521) (xy 378.25096 -402.756454) (xy 378.250965 -402.823818) (xy 381.529025 -402.823818)
			(xy 381.529029 -402.75651) (xy 381.537078 -402.689684) (xy 381.553055 -402.6243) (xy 381.576732 -402.561293)
			(xy 381.607769 -402.501568) (xy 381.645722 -402.445981) (xy 381.667512 -402.420328) (xy 381.673323 -402.413193)
			(xy 381.679829 -402.395995) (xy 381.680212 -402.3868) (xy 381.680212 -401.893532) (xy 381.679784 -401.884347)
			(xy 381.673282 -401.867162) (xy 381.667512 -401.860004) (xy 381.645705 -401.834368) (xy 381.607759 -401.778778)
			(xy 381.576728 -401.719052) (xy 381.553058 -401.656046) (xy 381.537087 -401.590662) (xy 381.529045 -401.523838)
			(xy 381.529046 -401.456532) (xy 381.537092 -401.389708) (xy 381.553066 -401.324325) (xy 381.57674 -401.26132)
			(xy 381.607774 -401.201596) (xy 381.645724 -401.146009) (xy 381.667512 -401.120356) (xy 381.673311 -401.113213)
			(xy 381.679824 -401.096021) (xy 381.680212 -401.086828) (xy 381.680212 -400.92884) (xy 381.680655 -400.918687)
			(xy 381.688439 -400.899933) (xy 381.70283 -400.885608) (xy 381.721619 -400.877909) (xy 381.731774 -400.877532)
			(xy 382.448054 -400.877532) (xy 382.458177 -400.878064) (xy 382.476895 -400.885775) (xy 382.491253 -400.900048)
			(xy 382.499075 -400.91872) (xy 382.499616 -400.92884) (xy 382.499616 -401.086828) (xy 382.500009 -401.096017)
			(xy 382.506534 -401.113201) (xy 382.512316 -401.120356) (xy 382.534085 -401.146024) (xy 382.572038 -401.201607)
			(xy 382.603074 -401.261328) (xy 382.62675 -401.32433) (xy 382.642726 -401.389711) (xy 382.650772 -401.456533)
			(xy 382.650774 -401.523837) (xy 382.642731 -401.590659) (xy 382.626759 -401.656041) (xy 382.603087 -401.719045)
			(xy 382.600649 -401.723737) (xy 383.729179 -401.723737) (xy 383.729181 -401.65643) (xy 383.737228 -401.589605)
			(xy 383.753204 -401.524222) (xy 383.77688 -401.461216) (xy 383.807917 -401.401492) (xy 383.84587 -401.345906)
			(xy 383.86766 -401.320254) (xy 383.873466 -401.313116) (xy 383.879973 -401.29592) (xy 383.88036 -401.286726)
			(xy 383.88036 -400.793458) (xy 383.879957 -400.78427) (xy 383.873437 -400.767087) (xy 383.86766 -400.75993)
			(xy 383.845878 -400.734273) (xy 383.807927 -400.678688) (xy 383.776893 -400.618965) (xy 383.753219 -400.555961)
			(xy 383.737245 -400.490579) (xy 383.7292 -400.423757) (xy 383.729199 -400.356452) (xy 383.737243 -400.28963)
			(xy 383.753216 -400.224247) (xy 383.776889 -400.161243) (xy 383.807923 -400.10152) (xy 383.845872 -400.045934)
			(xy 383.86766 -400.020282) (xy 383.873454 -400.013135) (xy 383.879969 -399.995946) (xy 383.88036 -399.986754)
			(xy 383.88036 -399.828766) (xy 383.880806 -399.818603) (xy 383.888596 -399.799829) (xy 383.902976 -399.785464)
			(xy 383.921759 -399.777695) (xy 383.931922 -399.777204) (xy 384.648202 -399.777204) (xy 384.658356 -399.777731)
			(xy 384.677118 -399.7855) (xy 384.691482 -399.799855) (xy 384.699263 -399.818613) (xy 384.699764 -399.828766)
			(xy 384.699764 -399.986754) (xy 384.700205 -399.995938) (xy 384.706698 -400.013122) (xy 384.712464 -400.020282)
			(xy 384.734258 -400.045929) (xy 384.772206 -400.101516) (xy 384.803239 -400.161241) (xy 384.826911 -400.224246)
			(xy 384.842884 -400.289629) (xy 384.850927 -400.356452) (xy 384.850927 -400.423757) (xy 384.842882 -400.49058)
			(xy 384.826909 -400.555963) (xy 384.803235 -400.618968) (xy 384.772201 -400.678691) (xy 384.734252 -400.734278)
			(xy 384.712464 -400.75993) (xy 384.706668 -400.767075) (xy 384.700154 -400.784266) (xy 384.699764 -400.793458)
			(xy 384.699764 -401.286726) (xy 384.70017 -401.295913) (xy 384.706687 -401.313097) (xy 384.712464 -401.320254)
			(xy 384.73423 -401.345924) (xy 384.772179 -401.401508) (xy 384.803213 -401.461229) (xy 384.826887 -401.524231)
			(xy 384.842861 -401.589611) (xy 384.850907 -401.656432) (xy 384.850909 -401.723735) (xy 384.842867 -401.790556)
			(xy 384.826897 -401.855937) (xy 384.803227 -401.918941) (xy 384.772196 -401.978663) (xy 384.73425 -402.03425)
			(xy 384.712464 -402.059902) (xy 384.706679 -402.067056) (xy 384.700158 -402.08424) (xy 384.699764 -402.09343)
			(xy 384.699764 -402.251418) (xy 384.699282 -402.261577) (xy 384.691502 -402.280346) (xy 384.677133 -402.294711)
			(xy 384.658361 -402.302485) (xy 384.648202 -402.30298) (xy 383.931922 -402.30298) (xy 383.921754 -402.302518)
			(xy 383.902963 -402.294744) (xy 383.888578 -402.28037) (xy 383.88079 -402.261586) (xy 383.88036 -402.251418)
			(xy 383.88036 -402.09343) (xy 383.879922 -402.084246) (xy 383.873426 -402.067062) (xy 383.86766 -402.059902)
			(xy 383.84585 -402.034268) (xy 383.8079 -401.97868) (xy 383.776867 -401.918954) (xy 383.753194 -401.855947)
			(xy 383.737222 -401.790562) (xy 383.729179 -401.723737) (xy 382.600649 -401.723737) (xy 382.572053 -401.778767)
			(xy 382.534104 -401.834352) (xy 382.512316 -401.860004) (xy 382.506537 -401.867162) (xy 382.500011 -401.884343)
			(xy 382.499616 -401.893532) (xy 382.499616 -402.3868) (xy 382.500023 -402.395988) (xy 382.506538 -402.413172)
			(xy 382.512316 -402.420328) (xy 382.534058 -402.446018) (xy 382.572011 -402.501598) (xy 382.603049 -402.561316)
			(xy 382.626726 -402.624316) (xy 382.642704 -402.689694) (xy 382.650753 -402.756513) (xy 382.650757 -402.823815)
			(xy 382.650749 -402.823878) (xy 385.928793 -402.823878) (xy 385.928798 -402.75645) (xy 385.936878 -402.689508)
			(xy 385.952919 -402.624017) (xy 385.976689 -402.560918) (xy 386.007846 -402.50112) (xy 386.045941 -402.445485)
			(xy 386.067808 -402.41982) (xy 386.073622 -402.412687) (xy 386.080126 -402.395487) (xy 386.080508 -402.386292)
			(xy 386.080508 -401.89404) (xy 386.080077 -401.884855) (xy 386.073578 -401.867671) (xy 386.067808 -401.860512)
			(xy 386.045924 -401.834863) (xy 386.007835 -401.779226) (xy 385.976685 -401.719428) (xy 385.952922 -401.656329)
			(xy 385.936887 -401.590838) (xy 385.928813 -401.523898) (xy 385.928815 -401.456472) (xy 385.936893 -401.389533)
			(xy 385.952931 -401.324042) (xy 385.976697 -401.260944) (xy 386.007851 -401.201148) (xy 386.045943 -401.145513)
			(xy 386.067808 -401.119848) (xy 386.07361 -401.112707) (xy 386.080121 -401.095513) (xy 386.080508 -401.08632)
			(xy 386.080508 -400.92884) (xy 386.080949 -400.918719) (xy 386.088686 -400.900015) (xy 386.102995 -400.885699)
			(xy 386.121695 -400.877954) (xy 386.131816 -400.877532) (xy 386.848096 -400.877532) (xy 386.858222 -400.87792)
			(xy 386.876932 -400.885673) (xy 386.891247 -400.899998) (xy 386.898987 -400.918714) (xy 386.899404 -400.92884)
			(xy 386.899404 -401.08632) (xy 386.899804 -401.095508) (xy 386.906325 -401.112692) (xy 386.912104 -401.119848)
			(xy 386.933948 -401.14553) (xy 386.972037 -401.201162) (xy 387.003189 -401.260956) (xy 387.026954 -401.324051)
			(xy 387.04299 -401.389538) (xy 387.051068 -401.456474) (xy 387.05107 -401.523896) (xy 387.042996 -401.590833)
			(xy 387.026963 -401.656321) (xy 387.003201 -401.719417) (xy 387.000951 -401.723737) (xy 388.12897 -401.723737)
			(xy 388.128972 -401.65643) (xy 388.137019 -401.589606) (xy 388.152994 -401.524222) (xy 388.17667 -401.461217)
			(xy 388.207706 -401.401492) (xy 388.245659 -401.345906) (xy 388.267448 -401.320254) (xy 388.273253 -401.313115)
			(xy 388.279761 -401.295919) (xy 388.280148 -401.286726) (xy 388.280148 -400.793458) (xy 388.279747 -400.78427)
			(xy 388.273226 -400.767086) (xy 388.267448 -400.75993) (xy 388.245666 -400.734273) (xy 388.207717 -400.678687)
			(xy 388.176683 -400.618965) (xy 388.153009 -400.555961) (xy 388.137035 -400.490579) (xy 388.128991 -400.423757)
			(xy 388.12899 -400.356452) (xy 388.137034 -400.28963) (xy 388.153006 -400.224248) (xy 388.176679 -400.161244)
			(xy 388.207712 -400.10152) (xy 388.245661 -400.045934) (xy 388.267448 -400.020282) (xy 388.273241 -400.013134)
			(xy 388.279756 -399.995946) (xy 388.280148 -399.986754) (xy 388.280148 -399.828766) (xy 388.280606 -399.818605)
			(xy 388.288393 -399.799833) (xy 388.30277 -399.785469) (xy 388.321548 -399.777697) (xy 388.33171 -399.777204)
			(xy 389.04799 -399.777204) (xy 389.058143 -399.777741) (xy 389.076905 -399.785506) (xy 389.09127 -399.799858)
			(xy 389.099051 -399.818613) (xy 389.099552 -399.828766) (xy 389.099552 -399.986754) (xy 389.099995 -399.995937)
			(xy 389.106487 -400.013121) (xy 389.112252 -400.020282) (xy 389.134046 -400.045929) (xy 389.171995 -400.101516)
			(xy 389.203029 -400.16124) (xy 389.226702 -400.224245) (xy 389.242675 -400.289628) (xy 389.250718 -400.356452)
			(xy 389.250718 -400.423757) (xy 389.242673 -400.490581) (xy 389.226699 -400.555963) (xy 389.203025 -400.618968)
			(xy 389.171991 -400.678692) (xy 389.134041 -400.734278) (xy 389.112252 -400.75993) (xy 389.106454 -400.767074)
			(xy 389.099942 -400.784266) (xy 389.099552 -400.793458) (xy 389.099552 -401.286726) (xy 389.09996 -401.295913)
			(xy 389.106477 -401.313097) (xy 389.112252 -401.320254) (xy 389.134018 -401.345924) (xy 389.171968 -401.401508)
			(xy 389.203003 -401.461229) (xy 389.226677 -401.524231) (xy 389.242652 -401.589611) (xy 389.250698 -401.656432)
			(xy 389.2507 -401.723735) (xy 389.242658 -401.790556) (xy 389.226687 -401.855937) (xy 389.203016 -401.918941)
			(xy 389.171985 -401.978664) (xy 389.134038 -402.03425) (xy 389.112252 -402.059902) (xy 389.106466 -402.067055)
			(xy 389.099946 -402.08424) (xy 389.099552 -402.09343) (xy 389.099552 -402.251418) (xy 389.099081 -402.261578)
			(xy 389.091299 -402.28035) (xy 389.076926 -402.294715) (xy 389.05815 -402.302487) (xy 389.04799 -402.30298)
			(xy 388.33171 -402.30298) (xy 388.321555 -402.302459) (xy 388.30279 -402.294691) (xy 388.288425 -402.280334)
			(xy 388.280647 -402.261573) (xy 388.280148 -402.251418) (xy 388.280148 -402.09343) (xy 388.279713 -402.084246)
			(xy 388.273215 -402.067062) (xy 388.267448 -402.059902) (xy 388.245638 -402.034268) (xy 388.207689 -401.978679)
			(xy 388.176657 -401.918953) (xy 388.152985 -401.855946) (xy 388.137013 -401.790562) (xy 388.12897 -401.723737)
			(xy 387.000951 -401.723737) (xy 386.972053 -401.779212) (xy 386.933967 -401.834847) (xy 386.912104 -401.860512)
			(xy 386.90632 -401.867666) (xy 386.899798 -401.88485) (xy 386.899404 -401.89404) (xy 386.899404 -402.386292)
			(xy 386.899817 -402.395479) (xy 386.906329 -402.412663) (xy 386.912104 -402.41982) (xy 386.933921 -402.445524)
			(xy 386.972011 -402.501153) (xy 387.003163 -402.560944) (xy 387.02693 -402.624036) (xy 387.042968 -402.68952)
			(xy 387.051048 -402.756454) (xy 387.051052 -402.823818) (xy 390.329113 -402.823818) (xy 390.329117 -402.75651)
			(xy 390.337166 -402.689685) (xy 390.353142 -402.6243) (xy 390.376819 -402.561294) (xy 390.407855 -402.501569)
			(xy 390.445807 -402.445981) (xy 390.467596 -402.420328) (xy 390.473405 -402.413192) (xy 390.479912 -402.395994)
			(xy 390.480296 -402.3868) (xy 390.480296 -401.893532) (xy 390.479871 -401.884346) (xy 390.473368 -401.867162)
			(xy 390.467596 -401.860004) (xy 390.44579 -401.834367) (xy 390.407845 -401.778778) (xy 390.376815 -401.719052)
			(xy 390.353145 -401.656045) (xy 390.337174 -401.590661) (xy 390.329133 -401.523838) (xy 390.329134 -401.456532)
			(xy 390.33718 -401.389709) (xy 390.353154 -401.324326) (xy 390.376827 -401.261321) (xy 390.40786 -401.201596)
			(xy 390.445808 -401.146009) (xy 390.467596 -401.120356) (xy 390.473393 -401.113211) (xy 390.479908 -401.09602)
			(xy 390.480296 -401.086828) (xy 390.480296 -400.92884) (xy 390.480754 -400.918689) (xy 390.488536 -400.899938)
			(xy 390.502922 -400.885614) (xy 390.521705 -400.877912) (xy 390.531858 -400.877532) (xy 391.248138 -400.877532)
			(xy 391.258266 -400.877995) (xy 391.276987 -400.885734) (xy 391.291341 -400.900027) (xy 391.299161 -400.918714)
			(xy 391.2997 -400.92884) (xy 391.2997 -401.086828) (xy 391.300096 -401.096017) (xy 391.30662 -401.113201)
			(xy 391.3124 -401.120356) (xy 391.334167 -401.146025) (xy 391.372114 -401.20161) (xy 391.403146 -401.261331)
			(xy 391.426818 -401.324334) (xy 391.442791 -401.389713) (xy 391.450836 -401.456534) (xy 391.450838 -401.523836)
			(xy 391.442797 -401.590657) (xy 391.426827 -401.656038) (xy 391.403158 -401.719041) (xy 391.372129 -401.778764)
			(xy 391.334185 -401.834351) (xy 391.3124 -401.860004) (xy 391.306619 -401.86716) (xy 391.300095 -401.884342)
			(xy 391.2997 -401.893532) (xy 391.2997 -402.3868) (xy 391.30011 -402.395987) (xy 391.306624 -402.413171)
			(xy 391.3124 -402.420328) (xy 391.334139 -402.446019) (xy 391.372087 -402.501601) (xy 391.40312 -402.56132)
			(xy 391.426794 -402.624319) (xy 391.442769 -402.689696) (xy 391.450817 -402.756514) (xy 391.450821 -402.823814)
			(xy 391.442782 -402.890633) (xy 391.426815 -402.956012) (xy 391.40315 -403.019014) (xy 391.372124 -403.078737)
			(xy 391.334184 -403.134323) (xy 391.3124 -403.159976) (xy 391.306589 -403.167111) (xy 391.300083 -403.184309)
			(xy 391.2997 -403.193504) (xy 391.2997 -403.351492) (xy 391.299272 -403.361646) (xy 391.291479 -403.380398)
			(xy 391.277084 -403.394721) (xy 391.258294 -403.402421) (xy 391.248138 -403.4028) (xy 390.531858 -403.4028)
			(xy 390.521734 -403.402309) (xy 390.503019 -403.394575) (xy 390.488666 -403.380291) (xy 390.480841 -403.361614)
			(xy 390.480296 -403.351492) (xy 390.480296 -403.193504) (xy 390.479885 -403.184317) (xy 390.473372 -403.167133)
			(xy 390.467596 -403.159976) (xy 390.445763 -403.134362) (xy 390.407818 -403.078769) (xy 390.376789 -403.01904)
			(xy 390.353121 -402.95603) (xy 390.337153 -402.890644) (xy 390.329113 -402.823818) (xy 387.051052 -402.823818)
			(xy 387.051052 -402.823874) (xy 387.042981 -402.890809) (xy 387.026951 -402.956295) (xy 387.003193 -403.01939)
			(xy 386.972048 -403.079185) (xy 386.933965 -403.134819) (xy 386.912104 -403.160484) (xy 386.90629 -403.167617)
			(xy 386.899785 -403.184817) (xy 386.899404 -403.194012) (xy 386.899404 -403.351492) (xy 386.898978 -403.361613)
			(xy 386.891233 -403.380316) (xy 386.87692 -403.394631) (xy 386.858217 -403.402377) (xy 386.848096 -403.4028)
			(xy 386.131816 -403.4028) (xy 386.121695 -403.402371) (xy 386.102991 -403.394628) (xy 386.088676 -403.380315)
			(xy 386.080931 -403.361613) (xy 386.080508 -403.351492) (xy 386.080508 -403.194012) (xy 386.08009 -403.184826)
			(xy 386.073582 -403.167641) (xy 386.067808 -403.160484) (xy 386.045897 -403.134858) (xy 386.007809 -403.079218)
			(xy 385.97666 -403.019416) (xy 385.952898 -402.956314) (xy 385.936865 -402.89082) (xy 385.928793 -402.823878)
			(xy 382.650749 -402.823878) (xy 382.642717 -402.890635) (xy 382.626748 -402.956015) (xy 382.603078 -403.019018)
			(xy 382.572048 -403.07874) (xy 382.534102 -403.134324) (xy 382.512316 -403.159976) (xy 382.506507 -403.167112)
			(xy 382.499999 -403.18431) (xy 382.499616 -403.193504) (xy 382.499616 -403.351492) (xy 382.499172 -403.361644)
			(xy 382.491382 -403.380393) (xy 382.476993 -403.394716) (xy 382.458207 -403.402419) (xy 382.448054 -403.4028)
			(xy 381.731774 -403.4028) (xy 381.721651 -403.402296) (xy 381.702936 -403.394567) (xy 381.688582 -403.380287)
			(xy 381.680757 -403.361613) (xy 381.680212 -403.351492) (xy 381.680212 -403.193504) (xy 381.679797 -403.184317)
			(xy 381.673286 -403.167133) (xy 381.667512 -403.159976) (xy 381.645678 -403.134362) (xy 381.607732 -403.07877)
			(xy 381.576703 -403.019041) (xy 381.553034 -402.956031) (xy 381.537065 -402.890644) (xy 381.529025 -402.823818)
			(xy 378.250965 -402.823818) (xy 378.250965 -402.823874) (xy 378.242894 -402.890808) (xy 378.226864 -402.956294)
			(xy 378.203106 -403.019389) (xy 378.171962 -403.079184) (xy 378.13388 -403.134818) (xy 378.11202 -403.160484)
			(xy 378.106208 -403.167618) (xy 378.099702 -403.184817) (xy 378.09932 -403.194012) (xy 378.09932 -403.351492)
			(xy 378.098809 -403.361598) (xy 378.091078 -403.380272) (xy 378.076789 -403.394566) (xy 378.058118 -403.402305)
			(xy 378.048012 -403.4028) (xy 377.331732 -403.4028) (xy 377.321612 -403.402358) (xy 377.302909 -403.39462)
			(xy 377.288593 -403.380312) (xy 377.280847 -403.361612) (xy 377.280424 -403.351492) (xy 377.280424 -403.194012)
			(xy 377.280002 -403.184826) (xy 377.273496 -403.167642) (xy 377.267724 -403.160484) (xy 377.245812 -403.134858)
			(xy 377.207723 -403.079218) (xy 377.176573 -403.019417) (xy 377.152811 -402.956315) (xy 377.136778 -402.890821)
			(xy 377.128705 -402.823878) (xy 365.789712 -402.823878) (xy 365.918019 -402.884132) (xy 366.100237 -402.97855)
			(xy 366.278633 -403.080005) (xy 366.452934 -403.188344) (xy 366.622876 -403.3034) (xy 366.788199 -403.425)
			(xy 366.948652 -403.552957) (xy 367.103991 -403.687076) (xy 367.253978 -403.827155) (xy 367.398386 -403.972979)
			(xy 367.536994 -404.124325) (xy 367.669592 -404.280965) (xy 367.795978 -404.442659) (xy 367.915958 -404.609161)
			(xy 368.029351 -404.780217) (xy 368.135984 -404.955567) (xy 368.235694 -405.134944) (xy 368.32833 -405.318074)
			(xy 368.41375 -405.50468) (xy 368.462689 -405.623649) (xy 374.929103 -405.623649) (xy 374.929104 -405.556342)
			(xy 374.937149 -405.489519) (xy 374.953124 -405.424136) (xy 374.976799 -405.361131) (xy 375.007835 -405.301407)
			(xy 375.045787 -405.245822) (xy 375.067576 -405.22017) (xy 375.073365 -405.213019) (xy 375.079885 -405.195833)
			(xy 375.080276 -405.186642) (xy 375.080276 -404.693374) (xy 375.079884 -404.684185) (xy 375.073358 -404.667)
			(xy 375.067576 -404.659846) (xy 375.045809 -404.634177) (xy 375.007857 -404.578593) (xy 374.976821 -404.518873)
			(xy 374.953145 -404.45587) (xy 374.937169 -404.39049) (xy 374.929123 -404.323669) (xy 374.929121 -404.256365)
			(xy 374.937164 -404.189543) (xy 374.953135 -404.124161) (xy 374.976807 -404.061158) (xy 375.00784 -404.001435)
			(xy 375.045789 -403.94585) (xy 375.067576 -403.920198) (xy 375.073353 -403.913039) (xy 375.07988 -403.895859)
			(xy 375.080276 -403.88667) (xy 375.080276 -403.728682) (xy 375.08065 -403.718505) (xy 375.088448 -403.699702)
			(xy 375.102849 -403.685317) (xy 375.12166 -403.677539) (xy 375.131838 -403.67712) (xy 375.848118 -403.67712)
			(xy 375.858275 -403.677618) (xy 375.877041 -403.685395) (xy 375.891405 -403.699759) (xy 375.899182 -403.718525)
			(xy 375.89968 -403.728682) (xy 375.89968 -403.88667) (xy 375.900109 -403.895855) (xy 375.90661 -403.913039)
			(xy 375.91238 -403.920198) (xy 375.934189 -403.945833) (xy 375.972136 -404.001422) (xy 376.003167 -404.061148)
			(xy 376.026838 -404.124155) (xy 376.042809 -404.189539) (xy 376.050851 -404.256363) (xy 376.050849 -404.32367)
			(xy 376.042803 -404.390494) (xy 376.026828 -404.455877) (xy 376.003154 -404.518882) (xy 375.972119 -404.578606)
			(xy 375.934169 -404.634194) (xy 375.91238 -404.659846) (xy 375.906579 -404.666988) (xy 375.900068 -404.684181)
			(xy 375.89968 -404.693374) (xy 375.89968 -405.186642) (xy 375.900074 -405.195831) (xy 375.9066 -405.213015)
			(xy 375.91238 -405.22017) (xy 375.934161 -405.245827) (xy 375.972109 -405.301413) (xy 376.003142 -405.361136)
			(xy 376.026814 -405.42414) (xy 376.042787 -405.489522) (xy 376.050831 -405.556343) (xy 376.050832 -405.623648)
			(xy 376.042788 -405.690469) (xy 376.026817 -405.755851) (xy 376.003145 -405.818855) (xy 375.972114 -405.878579)
			(xy 375.934167 -405.934166) (xy 375.91238 -405.959818) (xy 375.906591 -405.966968) (xy 375.900072 -405.984155)
			(xy 375.89968 -405.993346) (xy 375.89968 -406.151334) (xy 375.899195 -406.161492) (xy 375.891413 -406.180258)
			(xy 375.877045 -406.194622) (xy 375.858276 -406.202398) (xy 375.848118 -406.202896) (xy 375.131838 -406.202896)
			(xy 375.121673 -406.202406) (xy 375.102886 -406.19464) (xy 375.088501 -406.180275) (xy 375.080708 -406.161498)
			(xy 375.080276 -406.151334) (xy 375.080276 -405.993346) (xy 375.079849 -405.984161) (xy 375.073347 -405.966976)
			(xy 375.067576 -405.959818) (xy 375.045781 -405.934171) (xy 375.00783 -405.878585) (xy 374.976795 -405.818861)
			(xy 374.953121 -405.755856) (xy 374.937148 -405.690472) (xy 374.929103 -405.623649) (xy 368.462689 -405.623649)
			(xy 368.491824 -405.694476) (xy 368.562434 -405.887174) (xy 368.625471 -406.08248) (xy 368.680841 -406.280096)
			(xy 368.728458 -406.479723) (xy 368.76825 -406.681055) (xy 368.774976 -406.723789) (xy 377.128717 -406.723789)
			(xy 377.12872 -406.656363) (xy 377.136799 -406.589422) (xy 377.152839 -406.523931) (xy 377.176607 -406.460832)
			(xy 377.207763 -406.401035) (xy 377.245857 -406.345401) (xy 377.267724 -406.319736) (xy 377.273533 -406.3126)
			(xy 377.280039 -406.295402) (xy 377.280424 -406.286208) (xy 377.280424 -405.793956) (xy 377.28003 -405.784767)
			(xy 377.273504 -405.767583) (xy 377.267724 -405.760428) (xy 377.245855 -405.734766) (xy 377.207765 -405.679132)
			(xy 377.176613 -405.619335) (xy 377.152848 -405.556238) (xy 377.136812 -405.490748) (xy 377.128736 -405.423809)
			(xy 377.128737 -405.356385) (xy 377.136813 -405.289446) (xy 377.15285 -405.223956) (xy 377.176616 -405.160859)
			(xy 377.207768 -405.101063) (xy 377.245859 -405.045429) (xy 377.267724 -405.019764) (xy 377.273521 -405.012619)
			(xy 377.280035 -404.995428) (xy 377.280424 -404.986236) (xy 377.280424 -404.828756) (xy 377.28085 -404.818641)
			(xy 377.288606 -404.799958) (xy 377.302922 -404.785664) (xy 377.321617 -404.777935) (xy 377.331732 -404.777448)
			(xy 378.048012 -404.777448) (xy 378.058115 -404.777974) (xy 378.076783 -404.785706) (xy 378.091076 -404.79999)
			(xy 378.098819 -404.818653) (xy 378.09932 -404.828756) (xy 378.09932 -404.986236) (xy 378.099709 -404.995426)
			(xy 378.106237 -405.01261) (xy 378.11202 -405.019764) (xy 378.133879 -405.045433) (xy 378.171967 -405.101067)
			(xy 378.203117 -405.160863) (xy 378.22688 -405.22396) (xy 378.242915 -405.289448) (xy 378.250991 -405.356386)
			(xy 378.250992 -405.423808) (xy 378.242916 -405.490746) (xy 378.226882 -405.556235) (xy 378.203119 -405.619331)
			(xy 378.200839 -405.623707) (xy 379.328896 -405.623707) (xy 379.328896 -405.556284) (xy 379.336972 -405.489346)
			(xy 379.353008 -405.423856) (xy 379.376771 -405.360759) (xy 379.407921 -405.300963) (xy 379.446009 -405.245328)
			(xy 379.467872 -405.219662) (xy 379.473676 -405.212522) (xy 379.480184 -405.195327) (xy 379.480572 -405.186134)
			(xy 379.480572 -404.693882) (xy 379.480177 -404.684693) (xy 379.473653 -404.667509) (xy 379.467872 -404.660354)
			(xy 379.446031 -404.63467) (xy 379.407943 -404.579038) (xy 379.376793 -404.519244) (xy 379.353029 -404.45615)
			(xy 379.336993 -404.390663) (xy 379.328915 -404.323727) (xy 379.328913 -404.256306) (xy 379.336987 -404.18937)
			(xy 379.353019 -404.123882) (xy 379.376779 -404.060786) (xy 379.407926 -404.00099) (xy 379.44601 -403.945356)
			(xy 379.467872 -403.91969) (xy 379.473664 -403.912542) (xy 379.480179 -403.895353) (xy 379.480572 -403.886162)
			(xy 379.480572 -403.728682) (xy 379.481013 -403.71855) (xy 379.488752 -403.699822) (xy 379.503053 -403.685466)
			(xy 379.52175 -403.677653) (xy 379.53188 -403.67712) (xy 380.24816 -403.67712) (xy 380.258314 -403.677555)
			(xy 380.277069 -403.685341) (xy 380.291395 -403.699734) (xy 380.299092 -403.718526) (xy 380.299468 -403.728682)
			(xy 380.299468 -403.886162) (xy 380.299904 -403.895346) (xy 380.306401 -403.91253) (xy 380.312168 -403.91969)
			(xy 380.334055 -403.945337) (xy 380.372145 -404.000973) (xy 380.403296 -404.060772) (xy 380.427061 -404.123871)
			(xy 380.443096 -404.189363) (xy 380.45117 -404.256303) (xy 380.451168 -404.32373) (xy 380.44309 -404.39067)
			(xy 380.427051 -404.456161) (xy 380.403283 -404.519259) (xy 380.372128 -404.579055) (xy 380.334034 -404.634689)
			(xy 380.312168 -404.660354) (xy 380.306362 -404.667492) (xy 380.299854 -404.684688) (xy 380.299468 -404.693882)
			(xy 380.299468 -405.186134) (xy 380.299869 -405.195322) (xy 380.30639 -405.212506) (xy 380.312168 -405.219662)
			(xy 380.334027 -405.245332) (xy 380.372118 -405.300965) (xy 380.403271 -405.36076) (xy 380.427037 -405.423856)
			(xy 380.443074 -405.489345) (xy 380.451151 -405.556284) (xy 380.451151 -405.623707) (xy 380.443075 -405.690646)
			(xy 380.42704 -405.756135) (xy 380.403275 -405.819232) (xy 380.372123 -405.879028) (xy 380.334033 -405.934661)
			(xy 380.312168 -405.960326) (xy 380.306374 -405.967473) (xy 380.299858 -405.984662) (xy 380.299468 -405.993854)
			(xy 380.299468 -406.151334) (xy 380.299002 -406.161462) (xy 380.291264 -406.180182) (xy 380.276972 -406.194537)
			(xy 380.258286 -406.202357) (xy 380.24816 -406.202896) (xy 379.53188 -406.202896) (xy 379.521724 -406.202495)
			(xy 379.50297 -406.194692) (xy 379.488648 -406.180289) (xy 379.480949 -406.161492) (xy 379.480572 -406.151334)
			(xy 379.480572 -405.993854) (xy 379.480142 -405.984669) (xy 379.473643 -405.967484) (xy 379.467872 -405.960326)
			(xy 379.446003 -405.934665) (xy 379.407916 -405.879029) (xy 379.376768 -405.819232) (xy 379.353005 -405.756135)
			(xy 379.336971 -405.690646) (xy 379.328896 -405.623707) (xy 378.200839 -405.623707) (xy 378.17197 -405.679128)
			(xy 378.133883 -405.734762) (xy 378.11202 -405.760428) (xy 378.106231 -405.767579) (xy 378.099711 -405.784765)
			(xy 378.09932 -405.793956) (xy 378.09932 -406.286208) (xy 378.099722 -406.295396) (xy 378.106241 -406.312581)
			(xy 378.11202 -406.319736) (xy 378.133852 -406.345428) (xy 378.17194 -406.401059) (xy 378.203091 -406.460852)
			(xy 378.226856 -406.523945) (xy 378.242893 -406.589431) (xy 378.250971 -406.656366) (xy 378.250974 -406.723729)
			(xy 381.529036 -406.723729) (xy 381.529039 -406.656422) (xy 381.537086 -406.589598) (xy 381.553062 -406.524214)
			(xy 381.576737 -406.461209) (xy 381.607772 -406.401484) (xy 381.645723 -406.345897) (xy 381.667512 -406.320244)
			(xy 381.673316 -406.313104) (xy 381.679826 -406.29591) (xy 381.680212 -406.286716) (xy 381.680212 -405.793448)
			(xy 381.679776 -405.784264) (xy 381.67328 -405.767079) (xy 381.667512 -405.75992) (xy 381.645721 -405.734271)
			(xy 381.607774 -405.678683) (xy 381.576743 -405.618959) (xy 381.553071 -405.555954) (xy 381.537099 -405.490572)
			(xy 381.529056 -405.423749) (xy 381.529056 -405.356445) (xy 381.5371 -405.289622) (xy 381.553073 -405.22424)
			(xy 381.576745 -405.161235) (xy 381.607777 -405.101512) (xy 381.645725 -405.045924) (xy 381.667512 -405.020272)
			(xy 381.673304 -405.013124) (xy 381.679821 -404.995936) (xy 381.680212 -404.986744) (xy 381.680212 -404.828756)
			(xy 381.680586 -404.818598) (xy 381.688398 -404.799842) (xy 381.702809 -404.78552) (xy 381.721613 -404.777824)
			(xy 381.731774 -404.777448) (xy 382.448054 -404.777448) (xy 382.458179 -404.777965) (xy 382.4769 -404.785679)
			(xy 382.491258 -404.799956) (xy 382.499078 -404.818634) (xy 382.499616 -404.828756) (xy 382.499616 -404.986744)
			(xy 382.500001 -404.995934) (xy 382.506532 -405.013118) (xy 382.512316 -405.020272) (xy 382.534101 -405.045927)
			(xy 382.572053 -405.101512) (xy 382.603089 -405.161235) (xy 382.626764 -405.224239) (xy 382.642738 -405.289621)
			(xy 382.650784 -405.356444) (xy 382.650784 -405.42375) (xy 382.64274 -405.490573) (xy 382.626766 -405.555955)
			(xy 382.603091 -405.61896) (xy 382.600655 -405.623648) (xy 383.729191 -405.623648) (xy 383.729192 -405.556343)
			(xy 383.737237 -405.489519) (xy 383.753211 -405.424136) (xy 383.776885 -405.361132) (xy 383.807921 -405.301408)
			(xy 383.845871 -405.245822) (xy 383.86766 -405.22017) (xy 383.873459 -405.213027) (xy 383.879971 -405.195835)
			(xy 383.88036 -405.186642) (xy 383.88036 -404.693374) (xy 383.879949 -404.684187) (xy 383.873434 -404.667004)
			(xy 383.86766 -404.659846) (xy 383.845893 -404.634176) (xy 383.807943 -404.578593) (xy 383.776907 -404.518872)
			(xy 383.753232 -404.45587) (xy 383.737257 -404.390489) (xy 383.729211 -404.323668) (xy 383.729209 -404.256365)
			(xy 383.737251 -404.189543) (xy 383.753222 -404.124162) (xy 383.776894 -404.061158) (xy 383.807926 -404.001436)
			(xy 383.845873 -403.94585) (xy 383.86766 -403.920198) (xy 383.873447 -403.913047) (xy 383.879966 -403.895861)
			(xy 383.88036 -403.88667) (xy 383.88036 -403.728682) (xy 383.88075 -403.718507) (xy 383.888545 -403.699707)
			(xy 383.902941 -403.685322) (xy 383.921746 -403.677542) (xy 383.931922 -403.67712) (xy 384.648202 -403.67712)
			(xy 384.658358 -403.677631) (xy 384.677123 -403.685403) (xy 384.691488 -403.699763) (xy 384.699265 -403.718526)
			(xy 384.699764 -403.728682) (xy 384.699764 -403.88667) (xy 384.700197 -403.895855) (xy 384.706696 -403.913039)
			(xy 384.712464 -403.920198) (xy 384.734273 -403.945832) (xy 384.772221 -404.001421) (xy 384.803254 -404.061147)
			(xy 384.826925 -404.124154) (xy 384.842896 -404.189539) (xy 384.850939 -404.256363) (xy 384.850937 -404.32367)
			(xy 384.84289 -404.390494) (xy 384.826915 -404.455877) (xy 384.80324 -404.518883) (xy 384.772204 -404.578607)
			(xy 384.734253 -404.634194) (xy 384.712464 -404.659846) (xy 384.706661 -404.666986) (xy 384.700151 -404.684181)
			(xy 384.699764 -404.693374) (xy 384.699764 -405.186642) (xy 384.700162 -405.19583) (xy 384.706685 -405.213014)
			(xy 384.712464 -405.22017) (xy 384.734246 -405.245827) (xy 384.772195 -405.301413) (xy 384.803228 -405.361136)
			(xy 384.826901 -405.42414) (xy 384.842874 -405.489521) (xy 384.850919 -405.556343) (xy 384.850919 -405.623648)
			(xy 384.842876 -405.69047) (xy 384.826904 -405.755852) (xy 384.803232 -405.818856) (xy 384.772199 -405.878579)
			(xy 384.734251 -405.934166) (xy 384.712464 -405.959818) (xy 384.706673 -405.966967) (xy 384.700156 -405.984155)
			(xy 384.699764 -405.993346) (xy 384.699764 -406.151334) (xy 384.699295 -406.161494) (xy 384.691509 -406.180263)
			(xy 384.677136 -406.194627) (xy 384.658362 -406.202401) (xy 384.648202 -406.202896) (xy 383.931922 -406.202896)
			(xy 383.92177 -406.20235) (xy 383.903008 -406.194589) (xy 383.888643 -406.180239) (xy 383.880861 -406.161486)
			(xy 383.88036 -406.151334) (xy 383.88036 -405.993346) (xy 383.879914 -405.984163) (xy 383.873424 -405.966979)
			(xy 383.86766 -405.959818) (xy 383.845866 -405.934171) (xy 383.807916 -405.878584) (xy 383.776882 -405.81886)
			(xy 383.753208 -405.755855) (xy 383.737235 -405.690472) (xy 383.729191 -405.623648) (xy 382.600655 -405.623648)
			(xy 382.572056 -405.678683) (xy 382.534105 -405.734268) (xy 382.512316 -405.75992) (xy 382.50653 -405.767073)
			(xy 382.500009 -405.784257) (xy 382.499616 -405.793448) (xy 382.499616 -406.286716) (xy 382.500015 -406.295904)
			(xy 382.506536 -406.313089) (xy 382.512316 -406.320244) (xy 382.534074 -406.345921) (xy 382.572026 -406.401503)
			(xy 382.603063 -406.461223) (xy 382.62674 -406.524224) (xy 382.642717 -406.589604) (xy 382.650764 -406.656424)
			(xy 382.650767 -406.723728) (xy 382.65076 -406.723789) (xy 385.928805 -406.723789) (xy 385.928807 -406.656363)
			(xy 385.936887 -406.589422) (xy 385.952926 -406.523931) (xy 385.976694 -406.460833) (xy 386.007849 -406.401036)
			(xy 386.045942 -406.345401) (xy 386.067808 -406.319736) (xy 386.073615 -406.312598) (xy 386.080123 -406.295402)
			(xy 386.080508 -406.286208) (xy 386.080508 -405.793956) (xy 386.080117 -405.784767) (xy 386.07359 -405.767583)
			(xy 386.067808 -405.760428) (xy 386.04594 -405.734766) (xy 386.007851 -405.679131) (xy 385.9767 -405.619335)
			(xy 385.952935 -405.556237) (xy 385.9369 -405.490748) (xy 385.928824 -405.423809) (xy 385.928825 -405.356385)
			(xy 385.936901 -405.289446) (xy 385.952937 -405.223957) (xy 385.976702 -405.16086) (xy 386.007854 -405.101064)
			(xy 386.045944 -405.045429) (xy 386.067808 -405.019764) (xy 386.073603 -405.012618) (xy 386.080118 -404.995428)
			(xy 386.080508 -404.986236) (xy 386.080508 -404.828756) (xy 386.080949 -404.818643) (xy 386.088703 -404.799963)
			(xy 386.103013 -404.785669) (xy 386.121703 -404.777938) (xy 386.131816 -404.777448) (xy 386.848096 -404.777448)
			(xy 386.858198 -404.777987) (xy 386.876866 -404.785714) (xy 386.891159 -404.799993) (xy 386.898903 -404.818654)
			(xy 386.899404 -404.828756) (xy 386.899404 -404.986236) (xy 386.899796 -404.995425) (xy 386.906322 -405.012609)
			(xy 386.912104 -405.019764) (xy 386.933964 -405.045433) (xy 386.972052 -405.101067) (xy 387.003203 -405.160862)
			(xy 387.026967 -405.223959) (xy 387.043003 -405.289448) (xy 387.051079 -405.356385) (xy 387.051079 -405.423809)
			(xy 387.043004 -405.490747) (xy 387.026969 -405.556235) (xy 387.003206 -405.619332) (xy 387.000958 -405.623648)
			(xy 388.128982 -405.623648) (xy 388.128982 -405.556343) (xy 388.137027 -405.489519) (xy 388.153001 -405.424137)
			(xy 388.176675 -405.361132) (xy 388.207709 -405.301408) (xy 388.245659 -405.245822) (xy 388.267448 -405.22017)
			(xy 388.273246 -405.213026) (xy 388.279758 -405.195834) (xy 388.280148 -405.186642) (xy 388.280148 -404.693374)
			(xy 388.27974 -404.684187) (xy 388.273223 -404.667003) (xy 388.267448 -404.659846) (xy 388.245682 -404.634176)
			(xy 388.207732 -404.578592) (xy 388.176697 -404.518871) (xy 388.153023 -404.455869) (xy 388.137048 -404.390489)
			(xy 388.129002 -404.323668) (xy 388.129 -404.256365) (xy 388.137042 -404.189544) (xy 388.153013 -404.124163)
			(xy 388.176684 -404.061159) (xy 388.207715 -404.001436) (xy 388.245662 -403.94585) (xy 388.267448 -403.920198)
			(xy 388.273234 -403.913045) (xy 388.279754 -403.89586) (xy 388.280148 -403.88667) (xy 388.280148 -403.728682)
			(xy 388.280619 -403.718522) (xy 388.288401 -403.69975) (xy 388.302774 -403.685385) (xy 388.32155 -403.677613)
			(xy 388.33171 -403.67712) (xy 389.04799 -403.67712) (xy 389.058145 -403.677641) (xy 389.07691 -403.685409)
			(xy 389.091275 -403.699766) (xy 389.099053 -403.718527) (xy 389.099552 -403.728682) (xy 389.099552 -403.88667)
			(xy 389.099987 -403.895854) (xy 389.106485 -403.913038) (xy 389.112252 -403.920198) (xy 389.134062 -403.945832)
			(xy 389.172011 -404.001421) (xy 389.203043 -404.061147) (xy 389.226715 -404.124154) (xy 389.242687 -404.189538)
			(xy 389.25073 -404.256363) (xy 389.250728 -404.32367) (xy 389.242681 -404.390494) (xy 389.226706 -404.455878)
			(xy 389.20303 -404.518883) (xy 389.171994 -404.578608) (xy 389.134041 -404.634194) (xy 389.112252 -404.659846)
			(xy 389.106447 -404.666985) (xy 389.099939 -404.684181) (xy 389.099552 -404.693374) (xy 389.099552 -405.186642)
			(xy 389.099953 -405.19583) (xy 389.106474 -405.213014) (xy 389.112252 -405.22017) (xy 389.134034 -405.245827)
			(xy 389.171983 -405.301413) (xy 389.203017 -405.361135) (xy 389.226691 -405.424139) (xy 389.242665 -405.489521)
			(xy 389.250709 -405.556343) (xy 389.25071 -405.623648) (xy 389.242666 -405.69047) (xy 389.226694 -405.755852)
			(xy 389.203021 -405.818856) (xy 389.171988 -405.87858) (xy 389.134039 -405.934166) (xy 389.112252 -405.959818)
			(xy 389.106459 -405.966966) (xy 389.099944 -405.984154) (xy 389.099552 -405.993346) (xy 389.099552 -406.151334)
			(xy 389.099094 -406.161495) (xy 389.091307 -406.180267) (xy 389.07693 -406.194631) (xy 389.058152 -406.202403)
			(xy 389.04799 -406.202896) (xy 388.33171 -406.202896) (xy 388.321557 -406.202359) (xy 388.302795 -406.194594)
			(xy 388.28843 -406.180242) (xy 388.280649 -406.161487) (xy 388.280148 -406.151334) (xy 388.280148 -405.993346)
			(xy 388.279705 -405.984163) (xy 388.273213 -405.966979) (xy 388.267448 -405.959818) (xy 388.245654 -405.934171)
			(xy 388.207705 -405.878584) (xy 388.176671 -405.81886) (xy 388.152998 -405.755855) (xy 388.137025 -405.690472)
			(xy 388.128982 -405.623648) (xy 387.000958 -405.623648) (xy 386.972056 -405.679128) (xy 386.933968 -405.734763)
			(xy 386.912104 -405.760428) (xy 386.906314 -405.767578) (xy 386.899795 -405.784765) (xy 386.899404 -405.793956)
			(xy 386.899404 -406.286208) (xy 386.89981 -406.295396) (xy 386.906326 -406.31258) (xy 386.912104 -406.319736)
			(xy 386.933936 -406.345427) (xy 386.972026 -406.401058) (xy 387.003178 -406.460851) (xy 387.026943 -406.523944)
			(xy 387.042981 -406.58943) (xy 387.051059 -406.656365) (xy 387.051062 -406.723729) (xy 390.329124 -406.723729)
			(xy 390.329127 -406.656423) (xy 390.337174 -406.589599) (xy 390.353149 -406.524215) (xy 390.376823 -406.461209)
			(xy 390.407858 -406.401485) (xy 390.445808 -406.345897) (xy 390.467596 -406.320244) (xy 390.473398 -406.313103)
			(xy 390.47991 -406.295909) (xy 390.480296 -406.286716) (xy 390.480296 -405.793448) (xy 390.479864 -405.784263)
			(xy 390.473366 -405.767078) (xy 390.467596 -405.75992) (xy 390.445806 -405.73427) (xy 390.40786 -405.678683)
			(xy 390.376829 -405.618958) (xy 390.353158 -405.555954) (xy 390.337187 -405.490571) (xy 390.329144 -405.423749)
			(xy 390.329144 -405.356445) (xy 390.337188 -405.289623) (xy 390.35316 -405.224241) (xy 390.376832 -405.161236)
			(xy 390.407863 -405.101512) (xy 390.445809 -405.045925) (xy 390.467596 -405.020272) (xy 390.473386 -405.013122)
			(xy 390.479905 -404.995935) (xy 390.480296 -404.986744) (xy 390.480296 -404.828756) (xy 390.480686 -404.8186)
			(xy 390.488495 -404.799847) (xy 390.502901 -404.785525) (xy 390.521699 -404.777826) (xy 390.531858 -404.777448)
			(xy 391.248138 -404.777448) (xy 391.258268 -404.777896) (xy 391.276992 -404.785637) (xy 391.291347 -404.799935)
			(xy 391.299163 -404.818628) (xy 391.2997 -404.828756) (xy 391.2997 -404.986744) (xy 391.300089 -404.995933)
			(xy 391.306617 -405.013118) (xy 391.3124 -405.020272) (xy 391.334183 -405.045928) (xy 391.372129 -405.101515)
			(xy 391.40316 -405.161238) (xy 391.426832 -405.224242) (xy 391.442804 -405.289623) (xy 391.450848 -405.356445)
			(xy 391.450848 -405.423749) (xy 391.442805 -405.490571) (xy 391.426833 -405.555952) (xy 391.403163 -405.618956)
			(xy 391.372132 -405.67868) (xy 391.334186 -405.734267) (xy 391.3124 -405.75992) (xy 391.306612 -405.767072)
			(xy 391.300092 -405.784257) (xy 391.2997 -405.793448) (xy 391.2997 -406.286716) (xy 391.300103 -406.295904)
			(xy 391.306622 -406.313088) (xy 391.3124 -406.320244) (xy 391.334155 -406.345923) (xy 391.372102 -406.401506)
			(xy 391.403135 -406.461226) (xy 391.426808 -406.524227) (xy 391.442782 -406.589606) (xy 391.450828 -406.656425)
			(xy 391.450831 -406.723727) (xy 391.44279 -406.790547) (xy 391.426822 -406.855927) (xy 391.403154 -406.91893)
			(xy 391.372127 -406.978653) (xy 391.334185 -407.034239) (xy 391.3124 -407.059892) (xy 391.306624 -407.067052)
			(xy 391.300097 -407.084231) (xy 391.2997 -407.09342) (xy 391.2997 -407.251408) (xy 391.299285 -407.261563)
			(xy 391.291487 -407.280315) (xy 391.277088 -407.294638) (xy 391.258295 -407.302338) (xy 391.248138 -407.302716)
			(xy 390.531858 -407.302716) (xy 390.521723 -407.302307) (xy 390.502993 -407.294557) (xy 390.488636 -407.280247)
			(xy 390.480826 -407.261541) (xy 390.480296 -407.251408) (xy 390.480296 -407.09342) (xy 390.479877 -407.084234)
			(xy 390.47337 -407.067049) (xy 390.467596 -407.059892) (xy 390.445778 -407.034265) (xy 390.407833 -406.978674)
			(xy 390.376804 -406.918947) (xy 390.353135 -406.855939) (xy 390.337165 -406.790554) (xy 390.329124 -406.723729)
			(xy 387.051062 -406.723729) (xy 387.051062 -406.723787) (xy 387.04299 -406.790723) (xy 387.026958 -406.85621)
			(xy 387.003197 -406.919305) (xy 386.972051 -406.979101) (xy 386.933966 -407.034735) (xy 386.912104 -407.0604)
			(xy 386.906325 -407.067558) (xy 386.8998 -407.084739) (xy 386.899404 -407.093928) (xy 386.899404 -407.251408)
			(xy 386.898921 -407.261517) (xy 386.891182 -407.280194) (xy 386.876884 -407.294489) (xy 386.858205 -407.302224)
			(xy 386.848096 -407.302716) (xy 386.131816 -407.302716) (xy 386.121697 -407.302271) (xy 386.102996 -407.294531)
			(xy 386.088682 -407.280224) (xy 386.080933 -407.261527) (xy 386.080508 -407.251408) (xy 386.080508 -407.093928)
			(xy 386.080083 -407.084742) (xy 386.073579 -407.067558) (xy 386.067808 -407.0604) (xy 386.045912 -407.034761)
			(xy 386.007824 -406.979123) (xy 385.976674 -406.919323) (xy 385.952912 -406.856223) (xy 385.936878 -406.79073)
			(xy 385.928805 -406.723789) (xy 382.65076 -406.723789) (xy 382.642725 -406.790549) (xy 382.626754 -406.85593)
			(xy 382.603083 -406.918933) (xy 382.572051 -406.978655) (xy 382.534103 -407.03424) (xy 382.512316 -407.059892)
			(xy 382.506542 -407.067053) (xy 382.500013 -407.084231) (xy 382.499616 -407.09342) (xy 382.499616 -407.251408)
			(xy 382.499185 -407.261561) (xy 382.49139 -407.28031) (xy 382.476996 -407.294632) (xy 382.458209 -407.302335)
			(xy 382.448054 -407.302716) (xy 381.731774 -407.302716) (xy 381.72164 -407.302294) (xy 381.70291 -407.294549)
			(xy 381.688553 -407.280243) (xy 381.680743 -407.26154) (xy 381.680212 -407.251408) (xy 381.680212 -407.09342)
			(xy 381.679789 -407.084234) (xy 381.673284 -407.06705) (xy 381.667512 -407.059892) (xy 381.645694 -407.034265)
			(xy 381.607748 -406.978675) (xy 381.576717 -406.918947) (xy 381.553047 -406.855939) (xy 381.537077 -406.790554)
			(xy 381.529036 -406.723729) (xy 378.250974 -406.723729) (xy 378.250974 -406.723786) (xy 378.242902 -406.790722)
			(xy 378.226871 -406.856209) (xy 378.203111 -406.919305) (xy 378.171965 -406.9791) (xy 378.133881 -407.034734)
			(xy 378.11202 -407.0604) (xy 378.106243 -407.067559) (xy 378.099716 -407.084739) (xy 378.09932 -407.093928)
			(xy 378.09932 -407.251408) (xy 378.098822 -407.261515) (xy 378.091085 -407.280189) (xy 378.076793 -407.294483)
			(xy 378.058119 -407.302221) (xy 378.048012 -407.302716) (xy 377.331732 -407.302716) (xy 377.321614 -407.302258)
			(xy 377.302914 -407.294524) (xy 377.288599 -407.28022) (xy 377.280849 -407.261526) (xy 377.280424 -407.251408)
			(xy 377.280424 -407.093928) (xy 377.279995 -407.084743) (xy 377.273494 -407.067559) (xy 377.267724 -407.0604)
			(xy 377.245828 -407.034761) (xy 377.207738 -406.979123) (xy 377.176588 -406.919324) (xy 377.152824 -406.856223)
			(xy 377.13679 -406.790731) (xy 377.128717 -406.723789) (xy 368.774976 -406.723789) (xy 368.800157 -406.883787)
			(xy 368.82413 -407.087609) (xy 368.840132 -407.292212) (xy 368.848139 -407.497282) (xy 368.84864 -407.599896)
			(xy 368.848139 -407.70251) (xy 368.840132 -407.90758) (xy 368.82413 -408.112183) (xy 368.800157 -408.316005)
			(xy 368.76825 -408.518737) (xy 368.728458 -408.720069) (xy 368.680841 -408.919696) (xy 368.625471 -409.117312)
			(xy 368.562434 -409.312618) (xy 368.491824 -409.505316) (xy 368.484209 -409.523827) (xy 374.929082 -409.523827)
			(xy 374.929085 -409.456519) (xy 374.937133 -409.389693) (xy 374.953111 -409.324308) (xy 374.97679 -409.261302)
			(xy 375.007829 -409.201578) (xy 375.045785 -409.145991) (xy 375.067576 -409.12034) (xy 375.073378 -409.113198)
			(xy 375.07989 -409.096005) (xy 375.080276 -409.086812) (xy 375.080276 -408.593544) (xy 375.07985 -408.584358)
			(xy 375.073348 -408.567174) (xy 375.067576 -408.560016) (xy 375.045779 -408.534371) (xy 375.007828 -408.478784)
			(xy 374.976793 -408.41906) (xy 374.953119 -408.356055) (xy 374.937146 -408.290671) (xy 374.929102 -408.223847)
			(xy 374.929103 -408.156541) (xy 374.937148 -408.089717) (xy 374.953123 -408.024334) (xy 374.976798 -407.961329)
			(xy 375.007835 -407.901605) (xy 375.045787 -407.84602) (xy 375.067576 -407.820368) (xy 375.073366 -407.813218)
			(xy 375.079885 -407.796031) (xy 375.080276 -407.78684) (xy 375.080276 -407.628852) (xy 375.080682 -407.618698)
			(xy 375.088489 -407.599949) (xy 375.10289 -407.585628) (xy 375.121682 -407.577926) (xy 375.131838 -407.577544)
			(xy 375.848118 -407.577544) (xy 375.858246 -407.578012) (xy 375.876969 -407.585746) (xy 375.891325 -407.600038)
			(xy 375.899143 -407.618726) (xy 375.89968 -407.628852) (xy 375.89968 -407.78684) (xy 375.900075 -407.796029)
			(xy 375.9066 -407.813213) (xy 375.91238 -407.820368) (xy 375.934159 -407.846027) (xy 375.972107 -407.901613)
			(xy 376.00314 -407.961336) (xy 376.026812 -408.024339) (xy 376.042785 -408.08972) (xy 376.05083 -408.156542)
			(xy 376.05083 -408.223846) (xy 376.042787 -408.290668) (xy 376.026816 -408.356049) (xy 376.003145 -408.419053)
			(xy 375.972113 -408.478777) (xy 375.934167 -408.534364) (xy 375.91238 -408.560016) (xy 375.906592 -408.567167)
			(xy 375.900073 -408.584353) (xy 375.89968 -408.593544) (xy 375.89968 -409.086812) (xy 375.900089 -409.095999)
			(xy 375.906604 -409.113183) (xy 375.91238 -409.12034) (xy 375.934131 -409.146022) (xy 375.97208 -409.201604)
			(xy 376.003114 -409.261324) (xy 376.026788 -409.324325) (xy 376.042763 -409.389703) (xy 376.050809 -409.456522)
			(xy 376.050813 -409.523824) (xy 376.042772 -409.590644) (xy 376.026804 -409.656024) (xy 376.003136 -409.719026)
			(xy 375.972108 -409.778749) (xy 375.934165 -409.834335) (xy 375.91238 -409.859988) (xy 375.906561 -409.867117)
			(xy 375.90006 -409.88432) (xy 375.89968 -409.893516) (xy 375.89968 -410.051504) (xy 375.899281 -410.061661)
			(xy 375.891481 -410.080417) (xy 375.877077 -410.094741) (xy 375.858277 -410.102437) (xy 375.848118 -410.102812)
			(xy 375.131838 -410.102812) (xy 375.12172 -410.102244) (xy 375.10301 -410.094538) (xy 375.088654 -410.080277)
			(xy 375.080824 -410.061618) (xy 375.080276 -410.051504) (xy 375.080276 -409.893516) (xy 375.079864 -409.884329)
			(xy 375.073352 -409.867144) (xy 375.067576 -409.859988) (xy 375.045751 -409.834366) (xy 375.007801 -409.778776)
			(xy 374.976768 -409.719048) (xy 374.953095 -409.65604) (xy 374.937124 -409.590654) (xy 374.929082 -409.523827)
			(xy 368.484209 -409.523827) (xy 368.41375 -409.695112) (xy 368.32833 -409.881718) (xy 368.235694 -410.064848)
			(xy 368.135984 -410.244225) (xy 368.029351 -410.419575) (xy 367.915958 -410.590631) (xy 367.892128 -410.623701)
			(xy 377.128728 -410.623701) (xy 377.128729 -410.556275) (xy 377.136807 -410.489335) (xy 377.152845 -410.423845)
			(xy 377.176612 -410.360748) (xy 377.207766 -410.300951) (xy 377.245858 -410.245317) (xy 377.267724 -410.219652)
			(xy 377.273526 -410.212511) (xy 377.280037 -410.195317) (xy 377.280424 -410.186124) (xy 377.280424 -409.693872)
			(xy 377.280022 -409.684684) (xy 377.273502 -409.6675) (xy 377.267724 -409.660344) (xy 377.245871 -409.634669)
			(xy 377.20778 -409.579037) (xy 377.176628 -409.519242) (xy 377.152862 -409.456146) (xy 377.136825 -409.390658)
			(xy 377.128748 -409.323721) (xy 377.128747 -409.256297) (xy 377.136822 -409.18936) (xy 377.152857 -409.123871)
			(xy 377.17662 -409.060774) (xy 377.207771 -409.000979) (xy 377.24586 -408.945345) (xy 377.267724 -408.91968)
			(xy 377.273514 -408.912531) (xy 377.280032 -408.895343) (xy 377.280424 -408.886152) (xy 377.280424 -408.728672)
			(xy 377.280794 -408.718545) (xy 377.288555 -408.699836) (xy 377.302886 -408.685522) (xy 377.321604 -408.677782)
			(xy 377.331732 -408.677364) (xy 378.048012 -408.677364) (xy 378.058117 -408.677875) (xy 378.076789 -408.685609)
			(xy 378.091082 -408.699898) (xy 378.098822 -408.718567) (xy 378.09932 -408.728672) (xy 378.09932 -408.886152)
			(xy 378.099749 -408.895337) (xy 378.106249 -408.912522) (xy 378.11202 -408.91968) (xy 378.133895 -408.945336)
			(xy 378.171982 -409.000972) (xy 378.203131 -409.06077) (xy 378.226894 -409.123868) (xy 378.242928 -409.189358)
			(xy 378.251002 -409.256297) (xy 378.251001 -409.323721) (xy 378.242925 -409.39066) (xy 378.226888 -409.456149)
			(xy 378.203124 -409.519247) (xy 378.200707 -409.523886) (xy 379.328875 -409.523886) (xy 379.328878 -409.45646)
			(xy 379.336957 -409.38952) (xy 379.352995 -409.324029) (xy 379.376762 -409.260931) (xy 379.407916 -409.201133)
			(xy 379.446007 -409.145498) (xy 379.467872 -409.119832) (xy 379.473689 -409.112701) (xy 379.480189 -409.095499)
			(xy 379.480572 -409.086304) (xy 379.480572 -408.594052) (xy 379.480143 -408.584867) (xy 379.473643 -408.567682)
			(xy 379.467872 -408.560524) (xy 379.446001 -408.534865) (xy 379.407915 -408.479229) (xy 379.376766 -408.419431)
			(xy 379.353003 -408.356334) (xy 379.336969 -408.290844) (xy 379.328894 -408.223906) (xy 379.328895 -408.156482)
			(xy 379.336971 -408.089544) (xy 379.353007 -408.024055) (xy 379.376771 -407.960958) (xy 379.407921 -407.901161)
			(xy 379.446009 -407.845526) (xy 379.467872 -407.81986) (xy 379.473677 -407.812721) (xy 379.480185 -407.795525)
			(xy 379.480572 -407.786332) (xy 379.480572 -407.628852) (xy 379.481045 -407.618744) (xy 379.488793 -407.60007)
			(xy 379.503093 -407.585778) (xy 379.521771 -407.57804) (xy 379.53188 -407.577544) (xy 380.24816 -407.577544)
			(xy 380.258259 -407.578117) (xy 380.276926 -407.585831) (xy 380.29122 -407.6001) (xy 380.298966 -407.618754)
			(xy 380.299468 -407.628852) (xy 380.299468 -407.786332) (xy 380.29987 -407.79552) (xy 380.30639 -407.812704)
			(xy 380.312168 -407.81986) (xy 380.334025 -407.845531) (xy 380.372116 -407.901164) (xy 380.403269 -407.960959)
			(xy 380.427035 -408.024055) (xy 380.443072 -408.089544) (xy 380.451149 -408.156482) (xy 380.45115 -408.223906)
			(xy 380.443074 -408.290844) (xy 380.427039 -408.356333) (xy 380.403274 -408.41943) (xy 380.372122 -408.479226)
			(xy 380.334033 -408.534859) (xy 380.312168 -408.560524) (xy 380.306375 -408.567671) (xy 380.299859 -408.58486)
			(xy 380.299468 -408.594052) (xy 380.299468 -409.086304) (xy 380.299883 -409.09549) (xy 380.306394 -409.112675)
			(xy 380.312168 -409.119832) (xy 380.333998 -409.145526) (xy 380.37209 -409.201156) (xy 380.403244 -409.260947)
			(xy 380.427011 -409.324041) (xy 380.44305 -409.389527) (xy 380.451129 -409.456462) (xy 380.451133 -409.523884)
			(xy 380.44306 -409.59082) (xy 380.427027 -409.656308) (xy 380.403266 -409.719403) (xy 380.372117 -409.779198)
			(xy 380.334031 -409.834831) (xy 380.312168 -409.860496) (xy 380.306386 -409.867652) (xy 380.299864 -409.884834)
			(xy 380.299468 -409.894024) (xy 380.299468 -410.051504) (xy 380.299086 -410.061631) (xy 380.291331 -410.08034)
			(xy 380.277003 -410.094656) (xy 380.258287 -410.102395) (xy 380.24816 -410.102812) (xy 379.53188 -410.102812)
			(xy 379.521771 -410.102332) (xy 379.503095 -410.09459) (xy 379.488801 -410.080292) (xy 379.481065 -410.061613)
			(xy 379.480572 -410.051504) (xy 379.480572 -409.894024) (xy 379.480157 -409.884837) (xy 379.473647 -409.867652)
			(xy 379.467872 -409.860496) (xy 379.445974 -409.834859) (xy 379.407888 -409.77922) (xy 379.37674 -409.71942)
			(xy 379.352979 -409.656319) (xy 379.336947 -409.590827) (xy 379.328875 -409.523886) (xy 378.200707 -409.523886)
			(xy 378.171973 -409.579043) (xy 378.133884 -409.634678) (xy 378.11202 -409.660344) (xy 378.106225 -409.66749)
			(xy 378.099709 -409.68468) (xy 378.09932 -409.693872) (xy 378.09932 -410.186124) (xy 378.099714 -410.195313)
			(xy 378.106239 -410.212497) (xy 378.11202 -410.219652) (xy 378.133868 -410.245331) (xy 378.171955 -410.300964)
			(xy 378.203106 -410.360758) (xy 378.22687 -410.423853) (xy 378.242906 -410.48934) (xy 378.250983 -410.556277)
			(xy 378.250984 -410.623641) (xy 381.529047 -410.623641) (xy 381.529049 -410.556335) (xy 381.537094 -410.489512)
			(xy 381.553068 -410.424129) (xy 381.576742 -410.361124) (xy 381.607775 -410.3014) (xy 381.645724 -410.245812)
			(xy 381.667512 -410.22016) (xy 381.673309 -410.213015) (xy 381.679823 -410.195824) (xy 381.680212 -410.186632)
			(xy 381.680212 -409.693364) (xy 381.679817 -409.684175) (xy 381.673292 -409.666991) (xy 381.667512 -409.659836)
			(xy 381.645737 -409.634174) (xy 381.607789 -409.578588) (xy 381.576757 -409.518866) (xy 381.553085 -409.455863)
			(xy 381.537112 -409.390482) (xy 381.529067 -409.323661) (xy 381.529066 -409.256357) (xy 381.537109 -409.189536)
			(xy 381.553079 -409.124155) (xy 381.57675 -409.061151) (xy 381.60778 -409.001427) (xy 381.645726 -408.94584)
			(xy 381.667512 -408.920188) (xy 381.673298 -408.913035) (xy 381.679818 -408.89585) (xy 381.680212 -408.88666)
			(xy 381.680212 -408.728672) (xy 381.680599 -408.718515) (xy 381.688406 -408.699759) (xy 381.702813 -408.685436)
			(xy 381.721614 -408.67774) (xy 381.731774 -408.677364) (xy 382.448054 -408.677364) (xy 382.458181 -408.677865)
			(xy 382.476905 -408.685582) (xy 382.491264 -408.699865) (xy 382.499081 -408.718548) (xy 382.499616 -408.728672)
			(xy 382.499616 -408.88666) (xy 382.500042 -408.895846) (xy 382.506544 -408.91303) (xy 382.512316 -408.920188)
			(xy 382.534117 -408.94583) (xy 382.572068 -409.001417) (xy 382.603103 -409.061141) (xy 382.626778 -409.124147)
			(xy 382.642751 -409.189531) (xy 382.650795 -409.256356) (xy 382.650794 -409.323662) (xy 382.642748 -409.390487)
			(xy 382.626772 -409.45587) (xy 382.603096 -409.518875) (xy 382.600523 -409.523827) (xy 383.72917 -409.523827)
			(xy 383.729173 -409.456519) (xy 383.737221 -409.389693) (xy 383.753198 -409.324309) (xy 383.776876 -409.261303)
			(xy 383.807915 -409.201578) (xy 383.845869 -409.145992) (xy 383.86766 -409.12034) (xy 383.873472 -409.113206)
			(xy 383.879976 -409.096007) (xy 383.88036 -409.086812) (xy 383.88036 -408.593544) (xy 383.879915 -408.584361)
			(xy 383.873424 -408.567177) (xy 383.86766 -408.560016) (xy 383.845864 -408.53437) (xy 383.807914 -408.478784)
			(xy 383.77688 -408.419059) (xy 383.753207 -408.356054) (xy 383.737234 -408.290671) (xy 383.72919 -408.223847)
			(xy 383.729191 -408.156541) (xy 383.737236 -408.089717) (xy 383.75321 -408.024335) (xy 383.776885 -407.96133)
			(xy 383.80792 -407.901606) (xy 383.845871 -407.84602) (xy 383.86766 -407.820368) (xy 383.87346 -407.813226)
			(xy 383.879971 -407.796033) (xy 383.88036 -407.78684) (xy 383.88036 -407.628852) (xy 383.880782 -407.6187)
			(xy 383.888586 -407.599954) (xy 383.902981 -407.585634) (xy 383.921768 -407.577929) (xy 383.931922 -407.577544)
			(xy 384.648202 -407.577544) (xy 384.658329 -407.578025) (xy 384.677051 -407.585754) (xy 384.691408 -407.600042)
			(xy 384.699226 -407.618727) (xy 384.699764 -407.628852) (xy 384.699764 -407.78684) (xy 384.700163 -407.796028)
			(xy 384.706685 -407.813212) (xy 384.712464 -407.820368) (xy 384.734244 -407.846027) (xy 384.772193 -407.901612)
			(xy 384.803226 -407.961335) (xy 384.826899 -408.024339) (xy 384.842873 -408.08972) (xy 384.850918 -408.156542)
			(xy 384.850918 -408.223846) (xy 384.842875 -408.290668) (xy 384.826903 -408.35605) (xy 384.803231 -408.419054)
			(xy 384.772199 -408.478778) (xy 384.734251 -408.534364) (xy 384.712464 -408.560016) (xy 384.706674 -408.567165)
			(xy 384.700156 -408.584353) (xy 384.699764 -408.593544) (xy 384.699764 -409.086812) (xy 384.700176 -409.095999)
			(xy 384.706689 -409.113183) (xy 384.712464 -409.12034) (xy 384.734216 -409.146021) (xy 384.772166 -409.201604)
			(xy 384.8032 -409.261323) (xy 384.826875 -409.324324) (xy 384.84285 -409.389703) (xy 384.850897 -409.456522)
			(xy 384.850901 -409.523824) (xy 384.84286 -409.590644) (xy 384.826891 -409.656024) (xy 384.803222 -409.719027)
			(xy 384.772194 -409.77875) (xy 384.734249 -409.834336) (xy 384.712464 -409.859988) (xy 384.706643 -409.867116)
			(xy 384.700144 -409.88432) (xy 384.699764 -409.893516) (xy 384.699764 -410.051504) (xy 384.699381 -410.061663)
			(xy 384.691577 -410.080422) (xy 384.677168 -410.094747) (xy 384.658363 -410.10244) (xy 384.648202 -410.102812)
			(xy 383.931922 -410.102812) (xy 383.921803 -410.102257) (xy 383.903092 -410.094546) (xy 383.888737 -410.080281)
			(xy 383.880908 -410.06162) (xy 383.88036 -410.051504) (xy 383.88036 -409.893516) (xy 383.879929 -409.884331)
			(xy 383.873428 -409.867147) (xy 383.86766 -409.859988) (xy 383.845836 -409.834365) (xy 383.807887 -409.778775)
			(xy 383.776854 -409.719048) (xy 383.753182 -409.656039) (xy 383.737211 -409.590653) (xy 383.72917 -409.523827)
			(xy 382.600523 -409.523827) (xy 382.572059 -409.578599) (xy 382.534106 -409.634184) (xy 382.512316 -409.659836)
			(xy 382.506523 -409.666984) (xy 382.500006 -409.684172) (xy 382.499616 -409.693364) (xy 382.499616 -410.186632)
			(xy 382.500007 -410.195821) (xy 382.506534 -410.213006) (xy 382.512316 -410.22016) (xy 382.534089 -410.245824)
			(xy 382.572042 -410.301408) (xy 382.603078 -410.36113) (xy 382.626754 -410.424133) (xy 382.642729 -410.489514)
			(xy 382.650775 -410.556336) (xy 382.650777 -410.62364) (xy 382.65077 -410.623701) (xy 385.928816 -410.623701)
			(xy 385.928817 -410.556275) (xy 385.936895 -410.489336) (xy 385.952932 -410.423846) (xy 385.976699 -410.360748)
			(xy 386.007852 -410.300952) (xy 386.045943 -410.245317) (xy 386.067808 -410.219652) (xy 386.073608 -410.21251)
			(xy 386.080121 -410.195317) (xy 386.080508 -410.186124) (xy 386.080508 -409.693872) (xy 386.08011 -409.684684)
			(xy 386.073588 -409.667499) (xy 386.067808 -409.660344) (xy 386.045956 -409.634669) (xy 386.007866 -409.579036)
			(xy 385.976714 -409.519241) (xy 385.952949 -409.456146) (xy 385.936913 -409.390658) (xy 385.928836 -409.32372)
			(xy 385.928834 -409.256298) (xy 385.936909 -409.18936) (xy 385.952944 -409.123871) (xy 385.976707 -409.060775)
			(xy 386.007857 -409.000979) (xy 386.045944 -408.945345) (xy 386.067808 -408.91968) (xy 386.073596 -408.912529)
			(xy 386.080116 -408.895343) (xy 386.080508 -408.886152) (xy 386.080508 -408.728672) (xy 386.080962 -408.71856)
			(xy 386.088711 -408.69988) (xy 386.103017 -408.685586) (xy 386.121704 -408.677854) (xy 386.131816 -408.677364)
			(xy 386.848096 -408.677364) (xy 386.8582 -408.677888) (xy 386.876871 -408.685617) (xy 386.891165 -408.699902)
			(xy 386.898906 -408.718568) (xy 386.899404 -408.728672) (xy 386.899404 -408.886152) (xy 386.899836 -408.895337)
			(xy 386.906334 -408.912522) (xy 386.912104 -408.91968) (xy 386.93398 -408.945336) (xy 386.972068 -409.000972)
			(xy 387.003218 -409.060769) (xy 387.026981 -409.123867) (xy 387.043016 -409.189357) (xy 387.05109 -409.256297)
			(xy 387.051089 -409.323721) (xy 387.043012 -409.39066) (xy 387.026976 -409.45615) (xy 387.00321 -409.519247)
			(xy 387.000824 -409.523827) (xy 388.128961 -409.523827) (xy 388.128964 -409.456519) (xy 388.137012 -409.389694)
			(xy 388.152989 -409.324309) (xy 388.176666 -409.261303) (xy 388.207704 -409.201579) (xy 388.245658 -409.145992)
			(xy 388.267448 -409.12034) (xy 388.273259 -409.113205) (xy 388.279764 -409.096006) (xy 388.280148 -409.086812)
			(xy 388.280148 -408.593544) (xy 388.279706 -408.58436) (xy 388.273213 -408.567176) (xy 388.267448 -408.560016)
			(xy 388.245652 -408.534371) (xy 388.207703 -408.478783) (xy 388.176669 -408.419059) (xy 388.152997 -408.356054)
			(xy 388.137024 -408.29067) (xy 388.12898 -408.223847) (xy 388.128981 -408.156541) (xy 388.137026 -408.089718)
			(xy 388.153 -408.024335) (xy 388.176674 -407.96133) (xy 388.207709 -407.901606) (xy 388.245659 -407.84602)
			(xy 388.267448 -407.820368) (xy 388.273247 -407.813224) (xy 388.279759 -407.796032) (xy 388.280148 -407.78684)
			(xy 388.280148 -407.628852) (xy 388.280581 -407.618701) (xy 388.288383 -407.599958) (xy 388.302775 -407.585638)
			(xy 388.321557 -407.577931) (xy 388.33171 -407.577544) (xy 389.04799 -407.577544) (xy 389.058117 -407.578035)
			(xy 389.076838 -407.58576) (xy 389.091195 -407.600045) (xy 389.099014 -407.618728) (xy 389.099552 -407.628852)
			(xy 389.099552 -407.78684) (xy 389.099954 -407.796028) (xy 389.106475 -407.813211) (xy 389.112252 -407.820368)
			(xy 389.134032 -407.846027) (xy 389.171982 -407.901612) (xy 389.203016 -407.961335) (xy 389.226689 -408.024338)
			(xy 389.242663 -408.08972) (xy 389.250708 -408.156542) (xy 389.250709 -408.223846) (xy 389.242665 -408.290668)
			(xy 389.226693 -408.35605) (xy 389.203021 -408.419054) (xy 389.171988 -408.478778) (xy 389.134039 -408.534364)
			(xy 389.112252 -408.560016) (xy 389.10646 -408.567164) (xy 389.099944 -408.584353) (xy 389.099552 -408.593544)
			(xy 389.099552 -409.086812) (xy 389.099967 -409.095998) (xy 389.106479 -409.113182) (xy 389.112252 -409.12034)
			(xy 389.134004 -409.146021) (xy 389.171955 -409.201603) (xy 389.20299 -409.261323) (xy 389.226665 -409.324323)
			(xy 389.242641 -409.389702) (xy 389.250688 -409.456522) (xy 389.250692 -409.523824) (xy 389.242651 -409.590644)
			(xy 389.226681 -409.656025) (xy 389.203012 -409.719028) (xy 389.171983 -409.77875) (xy 389.134038 -409.834336)
			(xy 389.112252 -409.859988) (xy 389.10643 -409.867115) (xy 389.099932 -409.88432) (xy 389.099552 -409.893516)
			(xy 389.099552 -410.051504) (xy 389.099083 -410.061652) (xy 389.091295 -410.080394) (xy 389.076914 -410.094716)
			(xy 389.05814 -410.102424) (xy 389.04799 -410.102812) (xy 388.33171 -410.102812) (xy 388.32159 -410.102267)
			(xy 388.302879 -410.094552) (xy 388.288524 -410.080284) (xy 388.280696 -410.061621) (xy 388.280148 -410.051504)
			(xy 388.280148 -409.893516) (xy 388.27972 -409.884331) (xy 388.273217 -409.867147) (xy 388.267448 -409.859988)
			(xy 388.245624 -409.834365) (xy 388.207676 -409.778775) (xy 388.176644 -409.719047) (xy 388.152973 -409.656039)
			(xy 388.137002 -409.590653) (xy 388.128961 -409.523827) (xy 387.000824 -409.523827) (xy 386.972058 -409.579044)
			(xy 386.933969 -409.634679) (xy 386.912104 -409.660344) (xy 386.906307 -409.667489) (xy 386.899792 -409.68468)
			(xy 386.899404 -409.693872) (xy 386.899404 -410.186124) (xy 386.899801 -410.195313) (xy 386.906324 -410.212497)
			(xy 386.912104 -410.219652) (xy 386.933952 -410.24533) (xy 386.972041 -410.300963) (xy 387.003192 -410.360757)
			(xy 387.026957 -410.423853) (xy 387.042994 -410.48934) (xy 387.051071 -410.556277) (xy 387.051072 -410.623641)
			(xy 390.329135 -410.623641) (xy 390.329137 -410.556335) (xy 390.337182 -410.489512) (xy 390.353155 -410.42413)
			(xy 390.376828 -410.361125) (xy 390.407861 -410.3014) (xy 390.445809 -410.245813) (xy 390.467596 -410.22016)
			(xy 390.473392 -410.213014) (xy 390.479907 -410.195824) (xy 390.480296 -410.186632) (xy 390.480296 -409.693364)
			(xy 390.479904 -409.684175) (xy 390.473378 -409.666991) (xy 390.467596 -409.659836) (xy 390.445821 -409.634174)
			(xy 390.407875 -409.578588) (xy 390.376844 -409.518865) (xy 390.353172 -409.455862) (xy 390.3372 -409.390481)
			(xy 390.329155 -409.323661) (xy 390.329154 -409.256357) (xy 390.337196 -409.189536) (xy 390.353167 -409.124155)
			(xy 390.376836 -409.061151) (xy 390.407866 -409.001428) (xy 390.44581 -408.945841) (xy 390.467596 -408.920188)
			(xy 390.47338 -408.913034) (xy 390.479902 -408.89585) (xy 390.480296 -408.88666) (xy 390.480296 -408.728672)
			(xy 390.480699 -408.718517) (xy 390.488503 -408.699764) (xy 390.502905 -408.685442) (xy 390.5217 -408.677743)
			(xy 390.531858 -408.677364) (xy 391.248138 -408.677364) (xy 391.25827 -408.677796) (xy 391.276997 -408.685541)
			(xy 391.291352 -408.699844) (xy 391.299166 -408.718542) (xy 391.2997 -408.728672) (xy 391.2997 -408.88666)
			(xy 391.300129 -408.895845) (xy 391.30663 -408.91303) (xy 391.3124 -408.920188) (xy 391.334198 -408.945831)
			(xy 391.372144 -409.00142) (xy 391.403175 -409.061145) (xy 391.426845 -409.12415) (xy 391.442816 -409.189533)
			(xy 391.450859 -409.256356) (xy 391.450858 -409.323662) (xy 391.442813 -409.390484) (xy 391.42684 -409.455867)
			(xy 391.403167 -409.518872) (xy 391.372135 -409.578596) (xy 391.334187 -409.634183) (xy 391.3124 -409.659836)
			(xy 391.306606 -409.666983) (xy 391.30009 -409.684172) (xy 391.2997 -409.693364) (xy 391.2997 -410.186632)
			(xy 391.300095 -410.195821) (xy 391.306619 -410.213005) (xy 391.3124 -410.22016) (xy 391.334171 -410.245826)
			(xy 391.372118 -410.301411) (xy 391.403149 -410.361133) (xy 391.426821 -410.424136) (xy 391.442794 -410.489516)
			(xy 391.450839 -410.556336) (xy 391.450841 -410.623639) (xy 391.442799 -410.69046) (xy 391.426828 -410.755841)
			(xy 391.403159 -410.818845) (xy 391.37213 -410.878568) (xy 391.334186 -410.934155) (xy 391.3124 -410.959808)
			(xy 391.306618 -410.966963) (xy 391.300094 -410.984146) (xy 391.2997 -410.993336) (xy 391.2997 -411.151324)
			(xy 391.299298 -411.16148) (xy 391.291495 -411.180233) (xy 391.277092 -411.194555) (xy 391.258296 -411.202254)
			(xy 391.248138 -411.202632) (xy 390.531858 -411.202632) (xy 390.521725 -411.202207) (xy 390.502998 -411.19446)
			(xy 390.488642 -411.180155) (xy 390.480829 -411.161455) (xy 390.480296 -411.151324) (xy 390.480296 -410.993336)
			(xy 390.479869 -410.984151) (xy 390.473367 -410.966966) (xy 390.467596 -410.959808) (xy 390.445794 -410.934168)
			(xy 390.407848 -410.878579) (xy 390.376818 -410.818853) (xy 390.353148 -410.755847) (xy 390.337178 -410.690464)
			(xy 390.329135 -410.623641) (xy 387.051072 -410.623641) (xy 387.051072 -410.623699) (xy 387.042998 -410.690636)
			(xy 387.026964 -410.756124) (xy 387.003202 -410.819221) (xy 386.972053 -410.879016) (xy 386.933967 -410.934651)
			(xy 386.912104 -410.960316) (xy 386.906319 -410.967469) (xy 386.899797 -410.984654) (xy 386.899404 -410.993844)
			(xy 386.899404 -411.151324) (xy 386.898935 -411.161434) (xy 386.89119 -411.180112) (xy 386.876888 -411.194406)
			(xy 386.858206 -411.20214) (xy 386.848096 -411.202632) (xy 386.131816 -411.202632) (xy 386.121712 -411.202103)
			(xy 386.10304 -411.194376) (xy 386.088746 -411.180093) (xy 386.081005 -411.161427) (xy 386.080508 -411.151324)
			(xy 386.080508 -410.993844) (xy 386.080075 -410.984659) (xy 386.073577 -410.967475) (xy 386.067808 -410.960316)
			(xy 386.045928 -410.934664) (xy 386.007839 -410.879028) (xy 385.976689 -410.81923) (xy 385.952925 -410.756131)
			(xy 385.936891 -410.69064) (xy 385.928816 -410.623701) (xy 382.65077 -410.623701) (xy 382.642733 -410.690463)
			(xy 382.626761 -410.755844) (xy 382.603088 -410.818848) (xy 382.572054 -410.878571) (xy 382.534104 -410.934156)
			(xy 382.512316 -410.959808) (xy 382.506535 -410.966965) (xy 382.500011 -410.984146) (xy 382.499616 -410.993336)
			(xy 382.499616 -411.151324) (xy 382.499198 -411.161478) (xy 382.491398 -411.180228) (xy 382.477 -411.19455)
			(xy 382.45821 -411.202251) (xy 382.448054 -411.202632) (xy 381.731774 -411.202632) (xy 381.721642 -411.202194)
			(xy 381.702915 -411.194453) (xy 381.688559 -411.180151) (xy 381.680745 -411.161454) (xy 381.680212 -411.151324)
			(xy 381.680212 -410.993336) (xy 381.679782 -410.984151) (xy 381.673282 -410.966967) (xy 381.667512 -410.959808)
			(xy 381.645709 -410.934168) (xy 381.607763 -410.87858) (xy 381.576732 -410.818854) (xy 381.553061 -410.755848)
			(xy 381.53709 -410.690464) (xy 381.529047 -410.623641) (xy 378.250984 -410.623641) (xy 378.250984 -410.623699)
			(xy 378.24291 -410.690636) (xy 378.226877 -410.756124) (xy 378.203116 -410.81922) (xy 378.171968 -410.879016)
			(xy 378.133882 -410.93465) (xy 378.11202 -410.960316) (xy 378.106236 -410.967471) (xy 378.099713 -410.984654)
			(xy 378.09932 -410.993844) (xy 378.09932 -411.151324) (xy 378.098835 -411.161432) (xy 378.091093 -411.180107)
			(xy 378.076797 -411.1944) (xy 378.05812 -411.202138) (xy 378.048012 -411.202632) (xy 377.331732 -411.202632)
			(xy 377.321615 -411.202159) (xy 377.302919 -411.194427) (xy 377.288604 -411.180128) (xy 377.280852 -411.16144)
			(xy 377.280424 -411.151324) (xy 377.280424 -410.993844) (xy 377.279987 -410.98466) (xy 377.273491 -410.967475)
			(xy 377.267724 -410.960316) (xy 377.245843 -410.934664) (xy 377.207754 -410.879028) (xy 377.176602 -410.81923)
			(xy 377.152838 -410.756132) (xy 377.136803 -410.690641) (xy 377.128728 -410.623701) (xy 367.892128 -410.623701)
			(xy 367.795978 -410.757133) (xy 367.669592 -410.918827) (xy 367.536994 -411.075467) (xy 367.398386 -411.226813)
			(xy 367.253978 -411.372637) (xy 367.103991 -411.512716) (xy 366.948652 -411.646835) (xy 366.788199 -411.774792)
			(xy 366.622876 -411.896392) (xy 366.452934 -412.011448) (xy 366.278633 -412.119787) (xy 366.100237 -412.221242)
			(xy 365.918019 -412.31566) (xy 365.732256 -412.402896) (xy 365.543231 -412.482819) (xy 365.351231 -412.555305)
			(xy 365.156549 -412.620245) (xy 364.959482 -412.67754) (xy 364.760329 -412.727103) (xy 364.559395 -412.768858)
			(xy 364.356984 -412.802741) (xy 364.153406 -412.828701) (xy 363.948969 -412.846698) (xy 363.743986 -412.856706)
			(xy 363.538769 -412.858708) (xy 363.33363 -412.852702) (xy 363.128881 -412.838697) (xy 362.924834 -412.816714)
			(xy 362.721801 -412.786787) (xy 362.52009 -412.74896) (xy 362.320008 -412.703293) (xy 362.121861 -412.649854)
			(xy 361.925949 -412.588725) (xy 361.732572 -412.519999) (xy 361.542023 -412.44378) (xy 361.354593 -412.360184)
			(xy 361.170567 -412.26934) (xy 360.990226 -412.171385) (xy 360.813844 -412.066468) (xy 360.64169 -411.954749)
			(xy 360.474025 -411.836399) (xy 360.311106 -411.711597) (xy 360.15318 -411.580533) (xy 360.000488 -411.443408)
			(xy 359.853263 -411.30043) (xy 359.711728 -411.151816) (xy 359.576099 -410.997794) (xy 359.446582 -410.838597)
			(xy 359.323376 -410.674468) (xy 359.206667 -410.505657) (xy 359.096633 -410.33242) (xy 358.993442 -410.155023)
			(xy 358.897251 -409.973735) (xy 358.808206 -409.788832) (xy 358.726443 -409.600595) (xy 358.652087 -409.409312)
			(xy 358.585251 -409.215273) (xy 358.526036 -409.018774) (xy 358.474533 -408.820115) (xy 358.430819 -408.619597)
			(xy 358.394963 -408.417526) (xy 358.367018 -408.214211) (xy 358.347027 -408.00996) (xy 358.33502 -407.805084)
			(xy 358.331016 -407.599896) (xy 345.09113 -407.599896) (xy 345.091283 -407.600048) (xy 345.099102 -407.618729)
			(xy 345.09964 -407.628852) (xy 345.09964 -407.78684) (xy 345.100044 -407.796028) (xy 345.106563 -407.813211)
			(xy 345.11234 -407.820368) (xy 345.13412 -407.846026) (xy 345.172071 -407.901611) (xy 345.203106 -407.961334)
			(xy 345.22678 -408.024338) (xy 345.242754 -408.089719) (xy 345.250799 -408.156542) (xy 345.2508 -408.223846)
			(xy 345.242756 -408.290669) (xy 345.226783 -408.356051) (xy 345.20311 -408.419055) (xy 345.172077 -408.478778)
			(xy 345.134128 -408.534364) (xy 345.11234 -408.560016) (xy 345.106547 -408.567163) (xy 345.100032 -408.584352)
			(xy 345.09964 -408.593544) (xy 345.09964 -409.086812) (xy 345.100058 -409.095998) (xy 345.106568 -409.113182)
			(xy 345.11234 -409.12034) (xy 345.134093 -409.146021) (xy 345.172044 -409.201603) (xy 345.20308 -409.261322)
			(xy 345.226756 -409.324323) (xy 345.242732 -409.389702) (xy 345.250779 -409.456522) (xy 345.250783 -409.523824)
			(xy 345.242742 -409.590645) (xy 345.226772 -409.656025) (xy 345.203102 -409.719028) (xy 345.172072 -409.778751)
			(xy 345.134126 -409.834336) (xy 345.11234 -409.859988) (xy 345.106516 -409.867114) (xy 345.100019 -409.884319)
			(xy 345.09964 -409.893516) (xy 345.09964 -410.051504) (xy 345.099182 -410.061653) (xy 345.091393 -410.080398)
			(xy 345.077008 -410.09472) (xy 345.058229 -410.102427) (xy 345.048078 -410.102812) (xy 344.331798 -410.102812)
			(xy 344.321678 -410.102277) (xy 344.302966 -410.094558) (xy 344.288612 -410.080287) (xy 344.280784 -410.061621)
			(xy 344.280236 -410.051504) (xy 344.280236 -409.893516) (xy 344.27981 -409.884331) (xy 344.273307 -409.867146)
			(xy 344.267536 -409.859988) (xy 344.245713 -409.834365) (xy 344.207765 -409.778774) (xy 344.176734 -409.719047)
			(xy 344.153063 -409.656038) (xy 344.137093 -409.590653) (xy 344.129052 -409.523827) (xy 343.000914 -409.523827)
			(xy 342.972148 -409.579044) (xy 342.934057 -409.634679) (xy 342.912192 -409.660344) (xy 342.906393 -409.667488)
			(xy 342.89988 -409.684679) (xy 342.899492 -409.693872) (xy 342.899492 -410.186124) (xy 342.899892 -410.195312)
			(xy 342.906413 -410.212496) (xy 342.912192 -410.219652) (xy 342.934041 -410.24533) (xy 342.97213 -410.300963)
			(xy 343.003282 -410.360757) (xy 343.027048 -410.423852) (xy 343.043084 -410.48934) (xy 343.051162 -410.556277)
			(xy 343.051163 -410.623642) (xy 346.329202 -410.623642) (xy 346.329204 -410.556334) (xy 346.33725 -410.48951)
			(xy 346.353226 -410.424126) (xy 346.376903 -410.361121) (xy 346.40794 -410.301397) (xy 346.445894 -410.245812)
			(xy 346.467684 -410.22016) (xy 346.473478 -410.213013) (xy 346.479995 -410.195824) (xy 346.480384 -410.186632)
			(xy 346.480384 -409.693364) (xy 346.479995 -409.684175) (xy 346.473467 -409.66699) (xy 346.467684 -409.659836)
			(xy 346.445907 -409.634175) (xy 346.407955 -409.578591) (xy 346.376918 -409.518869) (xy 346.353243 -409.455865)
			(xy 346.337268 -409.390484) (xy 346.329222 -409.323661) (xy 346.329221 -409.256357) (xy 346.337265 -409.189534)
			(xy 346.353238 -409.124152) (xy 346.376911 -409.061148) (xy 346.407945 -409.001425) (xy 346.445896 -408.94584)
			(xy 346.467684 -408.920188) (xy 346.473466 -408.913033) (xy 346.47999 -408.89585) (xy 346.480384 -408.88666)
			(xy 346.480384 -408.728672) (xy 346.480798 -408.718518) (xy 346.4886 -408.699768) (xy 346.502999 -408.685446)
			(xy 346.52179 -408.677745) (xy 346.531946 -408.677364) (xy 347.248226 -408.677364) (xy 347.258357 -408.677806)
			(xy 347.277084 -408.685547) (xy 347.29144 -408.699847) (xy 347.299254 -408.718543) (xy 347.299788 -408.728672)
			(xy 347.299788 -408.88666) (xy 347.30022 -408.895845) (xy 347.306719 -408.913029) (xy 347.312488 -408.920188)
			(xy 347.334287 -408.945831) (xy 347.372233 -409.001419) (xy 347.403265 -409.061144) (xy 347.426936 -409.12415)
			(xy 347.442907 -409.189533) (xy 347.45095 -409.256356) (xy 347.450949 -409.323662) (xy 347.442904 -409.390485)
			(xy 347.42693 -409.455867) (xy 347.403257 -409.518872) (xy 347.372224 -409.578596) (xy 347.334276 -409.634184)
			(xy 347.312488 -409.659836) (xy 347.306692 -409.666982) (xy 347.300177 -409.684172) (xy 347.299788 -409.693364)
			(xy 347.299788 -410.186632) (xy 347.300185 -410.195821) (xy 347.306708 -410.213005) (xy 347.312488 -410.22016)
			(xy 347.334259 -410.245825) (xy 347.372207 -410.301411) (xy 347.403239 -410.361133) (xy 347.426912 -410.424135)
			(xy 347.442885 -410.489516) (xy 347.45093 -410.556336) (xy 347.450931 -410.62364) (xy 347.442889 -410.690461)
			(xy 347.426919 -410.755842) (xy 347.403249 -410.818845) (xy 347.372219 -410.878569) (xy 347.334274 -410.934156)
			(xy 347.312488 -410.959808) (xy 347.306704 -410.966962) (xy 347.300182 -410.984146) (xy 347.299788 -410.993336)
			(xy 347.299788 -411.151324) (xy 347.299398 -411.161481) (xy 347.291592 -411.180236) (xy 347.277186 -411.194559)
			(xy 347.258386 -411.202256) (xy 347.248226 -411.202632) (xy 346.531946 -411.202632) (xy 346.521819 -411.202135)
			(xy 346.503093 -411.194417) (xy 346.488735 -411.180133) (xy 346.480919 -411.161449) (xy 346.480384 -411.151324)
			(xy 346.480384 -410.993336) (xy 346.47996 -410.98415) (xy 346.473456 -410.966965) (xy 346.467684 -410.959808)
			(xy 346.445879 -410.934169) (xy 346.407928 -410.878582) (xy 346.376893 -410.818857) (xy 346.353219 -410.755851)
			(xy 346.337246 -410.690466) (xy 346.329202 -410.623642) (xy 343.051163 -410.623642) (xy 343.051163 -410.623699)
			(xy 343.043089 -410.690637) (xy 343.027055 -410.756125) (xy 343.003292 -410.819221) (xy 342.972143 -410.879017)
			(xy 342.934055 -410.934651) (xy 342.912192 -410.960316) (xy 342.906405 -410.967468) (xy 342.899885 -410.984653)
			(xy 342.899492 -410.993844) (xy 342.899492 -411.151324) (xy 342.899034 -411.161435) (xy 342.891287 -411.180116)
			(xy 342.876982 -411.19441) (xy 342.858296 -411.202142) (xy 342.848184 -411.202632) (xy 342.131904 -411.202632)
			(xy 342.121799 -411.202112) (xy 342.103128 -411.194382) (xy 342.088834 -411.180096) (xy 342.081093 -411.161428)
			(xy 342.080596 -411.151324) (xy 342.080596 -410.993844) (xy 342.080166 -410.984659) (xy 342.073666 -410.967474)
			(xy 342.067896 -410.960316) (xy 342.046016 -410.934664) (xy 342.007928 -410.879027) (xy 341.976779 -410.819229)
			(xy 341.953016 -410.756131) (xy 341.936981 -410.69064) (xy 341.928907 -410.6237) (xy 338.650837 -410.6237)
			(xy 338.642802 -410.69046) (xy 338.626832 -410.755841) (xy 338.603163 -410.818845) (xy 338.572134 -410.878568)
			(xy 338.534189 -410.934155) (xy 338.512404 -410.959808) (xy 338.506622 -410.966964) (xy 338.500098 -410.984146)
			(xy 338.499704 -410.993336) (xy 338.499704 -411.151324) (xy 338.499298 -411.161479) (xy 338.491495 -411.180231)
			(xy 338.477094 -411.194554) (xy 338.458299 -411.202253) (xy 338.448142 -411.202632) (xy 337.731862 -411.202632)
			(xy 337.721729 -411.202204) (xy 337.703002 -411.194458) (xy 337.688646 -411.180154) (xy 337.680833 -411.161455)
			(xy 337.6803 -411.151324) (xy 337.6803 -410.993336) (xy 337.679873 -410.984151) (xy 337.673371 -410.966966)
			(xy 337.6676 -410.959808) (xy 337.645798 -410.934168) (xy 337.607852 -410.878579) (xy 337.576822 -410.818853)
			(xy 337.553151 -410.755847) (xy 337.537181 -410.690464) (xy 337.529138 -410.623641) (xy 334.251075 -410.623641)
			(xy 334.251075 -410.623699) (xy 334.243001 -410.690636) (xy 334.226967 -410.756124) (xy 334.203205 -410.81922)
			(xy 334.172057 -410.879016) (xy 334.133971 -410.934651) (xy 334.112108 -410.960316) (xy 334.106323 -410.96747)
			(xy 334.099801 -410.984654) (xy 334.099408 -410.993844) (xy 334.099408 -411.151324) (xy 334.098935 -411.161433)
			(xy 334.091191 -411.180111) (xy 334.07689 -411.194404) (xy 334.05821 -411.20214) (xy 334.0481 -411.202632)
			(xy 333.33182 -411.202632) (xy 333.321716 -411.202099) (xy 333.303045 -411.194374) (xy 333.28875 -411.180092)
			(xy 333.281009 -411.161427) (xy 333.280512 -411.151324) (xy 333.280512 -410.993844) (xy 333.280078 -410.984659)
			(xy 333.273581 -410.967475) (xy 333.267812 -410.960316) (xy 333.245932 -410.934664) (xy 333.207843 -410.879028)
			(xy 333.176692 -410.81923) (xy 333.152928 -410.756131) (xy 333.136894 -410.69064) (xy 333.128819 -410.623701)
			(xy 326.525636 -410.623701) (xy 326.525636 -417.018724) (xy 326.526762 -417.028228) (xy 326.535073 -417.045453)
			(xy 326.549085 -417.05847) (xy 326.566875 -417.065491) (xy 326.576436 -417.065968) (xy 401.023328 -417.065968)
			(xy 401.032909 -417.065579) (xy 401.050747 -417.058582) (xy 401.06478 -417.045534) (xy 401.073054 -417.028252)
			(xy 401.074128 -417.018724) (xy 401.074128 -394.27912) (xy 414.451292 -394.27912) (xy 414.525968 -394.353542)
			(xy 414.525968 -397.823826) (xy 418.92899 -397.823826) (xy 418.928993 -397.756517) (xy 418.937042 -397.689691)
			(xy 418.95302 -397.624306) (xy 418.9767 -397.5613) (xy 419.00774 -397.501575) (xy 419.045697 -397.44599)
			(xy 419.067488 -397.420338) (xy 419.073292 -397.413198) (xy 419.079803 -397.396004) (xy 419.080188 -397.38681)
			(xy 419.080188 -396.893542) (xy 419.07976 -396.884357) (xy 419.073259 -396.867172) (xy 419.067488 -396.860014)
			(xy 419.045689 -396.834371) (xy 419.007737 -396.778784) (xy 418.976702 -396.71906) (xy 418.953027 -396.656054)
			(xy 418.937054 -396.59067) (xy 418.92901 -396.523846) (xy 418.92901 -396.456539) (xy 418.937056 -396.389715)
			(xy 418.953032 -396.324332) (xy 418.976708 -396.261327) (xy 419.007745 -396.201603) (xy 419.045698 -396.146018)
			(xy 419.067488 -396.120366) (xy 419.07328 -396.113218) (xy 419.079798 -396.09603) (xy 419.080188 -396.086838)
			(xy 419.080188 -395.92885) (xy 419.080606 -395.918675) (xy 419.088384 -395.899872) (xy 419.102772 -395.885484)
			(xy 419.121575 -395.877706) (xy 419.13175 -395.877288) (xy 419.84803 -395.877288) (xy 419.85821 -395.87764)
			(xy 419.877015 -395.885445) (xy 419.8914 -395.899852) (xy 419.899175 -395.91867) (xy 419.899592 -395.92885)
			(xy 419.899592 -396.086838) (xy 419.899986 -396.096027) (xy 419.906511 -396.113211) (xy 419.912292 -396.120366)
			(xy 419.934069 -396.146027) (xy 419.972016 -396.201613) (xy 420.003048 -396.261335) (xy 420.02672 -396.324339)
			(xy 420.042693 -396.389719) (xy 420.050737 -396.456541) (xy 420.050738 -396.523844) (xy 420.042695 -396.590666)
			(xy 420.026725 -396.656047) (xy 420.003054 -396.719051) (xy 419.972024 -396.778774) (xy 419.934078 -396.834361)
			(xy 419.912292 -396.860014) (xy 419.906506 -396.867167) (xy 419.899985 -396.884351) (xy 419.899592 -396.893542)
			(xy 419.899592 -397.38681) (xy 419.899999 -397.395998) (xy 419.906515 -397.413182) (xy 419.912292 -397.420338)
			(xy 419.934041 -397.446021) (xy 419.971989 -397.501604) (xy 420.00041 -397.556296) (xy 421.128654 -397.556296)
			(xy 421.13673 -397.489357) (xy 421.152765 -397.423869) (xy 421.17653 -397.360772) (xy 421.207681 -397.300976)
			(xy 421.245771 -397.245343) (xy 421.267636 -397.219678) (xy 421.273429 -397.21253) (xy 421.279945 -397.195342)
			(xy 421.280336 -397.18615) (xy 421.280336 -397.028924) (xy 421.280736 -397.018799) (xy 421.288483 -397.000089)
			(xy 421.302805 -396.985772) (xy 421.321518 -396.978032) (xy 421.331644 -396.977616) (xy 422.047924 -396.977616)
			(xy 422.058036 -396.978066) (xy 422.076718 -396.985814) (xy 422.091013 -397.000122) (xy 422.098744 -397.018811)
			(xy 422.099232 -397.028924) (xy 422.099232 -397.18615) (xy 422.099681 -397.195333) (xy 422.106169 -397.212517)
			(xy 422.111932 -397.219678) (xy 422.133805 -397.245336) (xy 422.171891 -397.300972) (xy 422.203039 -397.36077)
			(xy 422.226802 -397.423867) (xy 422.242835 -397.489357) (xy 422.25091 -397.556296) (xy 422.250909 -397.623719)
			(xy 422.242833 -397.690658) (xy 422.226797 -397.756147) (xy 422.203033 -397.819244) (xy 422.200615 -397.823885)
			(xy 423.328782 -397.823885) (xy 423.328786 -397.756458) (xy 423.336865 -397.689518) (xy 423.352904 -397.624027)
			(xy 423.376672 -397.560928) (xy 423.407826 -397.501131) (xy 423.445918 -397.445496) (xy 423.467784 -397.41983)
			(xy 423.473591 -397.412692) (xy 423.4801 -397.395496) (xy 423.480484 -397.386302) (xy 423.480484 -396.89405)
			(xy 423.480054 -396.884865) (xy 423.473554 -396.86768) (xy 423.467784 -396.860522) (xy 423.445911 -396.834865)
			(xy 423.407823 -396.779229) (xy 423.376674 -396.719431) (xy 423.352911 -396.656333) (xy 423.336877 -396.590843)
			(xy 423.328802 -396.523905) (xy 423.328803 -396.45648) (xy 423.33688 -396.389542) (xy 423.352916 -396.324052)
			(xy 423.37668 -396.260955) (xy 423.407831 -396.201159) (xy 423.44592 -396.145524) (xy 423.467784 -396.119858)
			(xy 423.473579 -396.112712) (xy 423.480095 -396.095522) (xy 423.480484 -396.08633) (xy 423.480484 -395.92885)
			(xy 423.480969 -395.918721) (xy 423.488688 -395.899993) (xy 423.502976 -395.885633) (xy 423.521666 -395.87782)
			(xy 423.531792 -395.877288) (xy 424.248072 -395.877288) (xy 424.258223 -395.877744) (xy 424.276972 -395.885528)
			(xy 424.291296 -395.899914) (xy 424.298999 -395.918697) (xy 424.29938 -395.92885) (xy 424.29938 -396.08633)
			(xy 424.29978 -396.095518) (xy 424.306301 -396.112702) (xy 424.31208 -396.119858) (xy 424.333935 -396.145531)
			(xy 424.372025 -396.201164) (xy 424.403177 -396.260959) (xy 424.426943 -396.324055) (xy 424.44298 -396.389543)
			(xy 424.451057 -396.456481) (xy 424.451058 -396.523904) (xy 424.442983 -396.590842) (xy 424.426948 -396.656331)
			(xy 424.403184 -396.719427) (xy 424.372033 -396.779223) (xy 424.333944 -396.834857) (xy 424.31208 -396.860522)
			(xy 424.306289 -396.867671) (xy 424.299772 -396.884859) (xy 424.29938 -396.89405) (xy 424.29938 -397.386302)
			(xy 424.299793 -397.395489) (xy 424.306305 -397.412673) (xy 424.31208 -397.41983) (xy 424.333907 -397.445526)
			(xy 424.371998 -397.501155) (xy 424.40076 -397.556356) (xy 425.528974 -397.556356) (xy 425.537017 -397.489534)
			(xy 425.552988 -397.424152) (xy 425.576659 -397.361148) (xy 425.607691 -397.301425) (xy 425.645637 -397.245838)
			(xy 425.667424 -397.220186) (xy 425.673212 -397.213035) (xy 425.679731 -397.195849) (xy 425.680124 -397.186658)
			(xy 425.680124 -397.028924) (xy 425.680542 -397.018768) (xy 425.688334 -397.000012) (xy 425.702732 -396.985687)
			(xy 425.721528 -396.97799) (xy 425.731686 -396.977616) (xy 426.447966 -396.977616) (xy 426.458088 -396.978154)
			(xy 426.476803 -396.985866) (xy 426.49116 -397.000137) (xy 426.498984 -397.018806) (xy 426.499528 -397.028924)
			(xy 426.499528 -397.186658) (xy 426.499952 -397.195844) (xy 426.506456 -397.213029) (xy 426.512228 -397.220186)
			(xy 426.534026 -397.24583) (xy 426.571977 -397.301417) (xy 426.603012 -397.361141) (xy 426.626685 -397.424147)
			(xy 426.642659 -397.48953) (xy 426.650703 -397.556354) (xy 426.650702 -397.623661) (xy 426.642656 -397.690485)
			(xy 426.626681 -397.755868) (xy 426.603006 -397.818873) (xy 426.600432 -397.823826) (xy 427.729077 -397.823826)
			(xy 427.729081 -397.756517) (xy 427.737129 -397.689691) (xy 427.753107 -397.624307) (xy 427.776786 -397.5613)
			(xy 427.807825 -397.501576) (xy 427.845781 -397.44599) (xy 427.867572 -397.420338) (xy 427.873386 -397.413206)
			(xy 427.879888 -397.396005) (xy 427.880272 -397.38681) (xy 427.880272 -396.893542) (xy 427.879848 -396.884356)
			(xy 427.873344 -396.867171) (xy 427.867572 -396.860014) (xy 427.845774 -396.83437) (xy 427.807823 -396.778783)
			(xy 427.776788 -396.719059) (xy 427.753115 -396.656053) (xy 427.737141 -396.59067) (xy 427.729097 -396.523846)
			(xy 427.729098 -396.456539) (xy 427.737144 -396.389715) (xy 427.753119 -396.324332) (xy 427.776794 -396.261327)
			(xy 427.807831 -396.201604) (xy 427.845783 -396.146018) (xy 427.867572 -396.120366) (xy 427.873374 -396.113225)
			(xy 427.879883 -396.096031) (xy 427.880272 -396.086838) (xy 427.880272 -395.92885) (xy 427.880706 -395.918677)
			(xy 427.88848 -395.899877) (xy 427.902864 -395.885489) (xy 427.921662 -395.877709) (xy 427.931834 -395.877288)
			(xy 428.648114 -395.877288) (xy 428.658293 -395.877654) (xy 428.677097 -395.885453) (xy 428.691483 -395.899857)
			(xy 428.699259 -395.918671) (xy 428.699676 -395.92885) (xy 428.699676 -396.086838) (xy 428.700073 -396.096026)
			(xy 428.706596 -396.11321) (xy 428.712376 -396.120366) (xy 428.734154 -396.146026) (xy 428.772102 -396.201612)
			(xy 428.803135 -396.261335) (xy 428.826807 -396.324338) (xy 428.84278 -396.389719) (xy 428.850825 -396.45654)
			(xy 428.850826 -396.523844) (xy 428.842783 -396.590666) (xy 428.826812 -396.656048) (xy 428.803141 -396.719052)
			(xy 428.772109 -396.778775) (xy 428.734163 -396.834362) (xy 428.712376 -396.860014) (xy 428.706588 -396.867165)
			(xy 428.700069 -396.884351) (xy 428.699676 -396.893542) (xy 428.699676 -397.38681) (xy 428.700087 -397.395997)
			(xy 428.7066 -397.413181) (xy 428.712376 -397.420338) (xy 428.734126 -397.446021) (xy 428.772075 -397.501604)
			(xy 428.800497 -397.556296) (xy 429.928742 -397.556296) (xy 429.936817 -397.489358) (xy 429.952852 -397.423869)
			(xy 429.976616 -397.360773) (xy 430.007767 -397.300977) (xy 430.045856 -397.245343) (xy 430.06772 -397.219678)
			(xy 430.073511 -397.212529) (xy 430.080028 -397.195341) (xy 430.08042 -397.18615) (xy 430.08042 -397.028924)
			(xy 430.080836 -397.018801) (xy 430.08858 -397.000094) (xy 430.102897 -396.985778) (xy 430.121605 -396.978035)
			(xy 430.131728 -396.977616) (xy 430.848008 -396.977616) (xy 430.858133 -396.97801) (xy 430.87684 -396.985764)
			(xy 430.891154 -397.000087) (xy 430.898896 -397.018799) (xy 430.899316 -397.028924) (xy 430.899316 -397.18615)
			(xy 430.899746 -397.195335) (xy 430.906246 -397.21252) (xy 430.912016 -397.219678) (xy 430.933889 -397.245335)
			(xy 430.971977 -397.300971) (xy 431.003126 -397.360769) (xy 431.026889 -397.423867) (xy 431.042923 -397.489357)
			(xy 431.050998 -397.556295) (xy 431.050997 -397.62372) (xy 431.04292 -397.690658) (xy 431.026884 -397.756148)
			(xy 431.00312 -397.819245) (xy 431.000734 -397.823826) (xy 432.128868 -397.823826) (xy 432.128872 -397.756517)
			(xy 432.13692 -397.689692) (xy 432.152898 -397.624307) (xy 432.176576 -397.561301) (xy 432.207614 -397.501576)
			(xy 432.245569 -397.44599) (xy 432.26736 -397.420338) (xy 432.273173 -397.413205) (xy 432.279676 -397.396005)
			(xy 432.28006 -397.38681) (xy 432.28006 -396.893542) (xy 432.279616 -396.884359) (xy 432.273125 -396.867175)
			(xy 432.26736 -396.860014) (xy 432.245562 -396.83437) (xy 432.207612 -396.778783) (xy 432.176578 -396.719058)
			(xy 432.152905 -396.656053) (xy 432.136932 -396.590669) (xy 432.128888 -396.523846) (xy 432.128889 -396.456539)
			(xy 432.136935 -396.389716) (xy 432.152909 -396.324333) (xy 432.176584 -396.261328) (xy 432.20762 -396.201604)
			(xy 432.245571 -396.146018) (xy 432.26736 -396.120366) (xy 432.273161 -396.113224) (xy 432.279671 -396.096031)
			(xy 432.28006 -396.086838) (xy 432.28006 -395.92885) (xy 432.280505 -395.918679) (xy 432.288278 -395.899881)
			(xy 432.302658 -395.885494) (xy 432.321451 -395.877711) (xy 432.331622 -395.877288) (xy 433.047902 -395.877288)
			(xy 433.05808 -395.877663) (xy 433.076884 -395.885458) (xy 433.091271 -395.899859) (xy 433.099047 -395.918672)
			(xy 433.099464 -395.92885) (xy 433.099464 -396.086838) (xy 433.099864 -396.096026) (xy 433.106386 -396.11321)
			(xy 433.112164 -396.120366) (xy 433.133942 -396.146026) (xy 433.171891 -396.201612) (xy 433.202924 -396.261334)
			(xy 433.226598 -396.324337) (xy 433.242571 -396.389719) (xy 433.250616 -396.45654) (xy 433.250617 -396.523845)
			(xy 433.242574 -396.590666) (xy 433.226602 -396.656048) (xy 433.202931 -396.719052) (xy 433.171899 -396.778776)
			(xy 433.133951 -396.834362) (xy 433.112164 -396.860014) (xy 433.106374 -396.867164) (xy 433.099856 -396.884351)
			(xy 433.099464 -396.893542) (xy 433.099464 -397.38681) (xy 433.099877 -397.395997) (xy 433.10639 -397.413181)
			(xy 433.112164 -397.420338) (xy 433.133914 -397.446021) (xy 433.171864 -397.501603) (xy 433.200318 -397.556356)
			(xy 434.329062 -397.556356) (xy 434.337105 -397.489534) (xy 434.353075 -397.424153) (xy 434.376746 -397.361149)
			(xy 434.407776 -397.301426) (xy 434.445722 -397.245839) (xy 434.467508 -397.220186) (xy 434.473294 -397.213033)
			(xy 434.479815 -397.195849) (xy 434.480208 -397.186658) (xy 434.480208 -397.028924) (xy 434.480641 -397.01877)
			(xy 434.48843 -397.000017) (xy 434.502824 -396.985692) (xy 434.521614 -396.977993) (xy 434.53177 -396.977616)
			(xy 435.24805 -396.977616) (xy 435.258171 -396.978167) (xy 435.276886 -396.985874) (xy 435.291243 -397.00014)
			(xy 435.299068 -397.018807) (xy 435.299612 -397.028924) (xy 435.299612 -397.186658) (xy 435.30004 -397.195843)
			(xy 435.306541 -397.213028) (xy 435.312312 -397.220186) (xy 435.334111 -397.245829) (xy 435.372063 -397.301416)
			(xy 435.403098 -397.36114) (xy 435.426773 -397.424146) (xy 435.442746 -397.48953) (xy 435.45079 -397.556354)
			(xy 435.45079 -397.623661) (xy 435.442744 -397.690485) (xy 435.426768 -397.755868) (xy 435.403092 -397.818873)
			(xy 435.372055 -397.878597) (xy 435.334102 -397.934182) (xy 435.312312 -397.959834) (xy 435.30652 -397.966982)
			(xy 435.300002 -397.98417) (xy 435.299612 -397.993362) (xy 435.299612 -398.100042) (xy 459.541382 -398.100042)
			(xy 459.545364 -397.972056) (xy 459.557296 -397.844565) (xy 459.57713 -397.718062) (xy 459.604791 -397.593037)
			(xy 459.640171 -397.469974) (xy 459.683133 -397.349348) (xy 459.733511 -397.231627) (xy 459.791111 -397.117265)
			(xy 459.855709 -397.006706) (xy 459.927056 -396.900376) (xy 460.004875 -396.798688) (xy 460.088865 -396.702034)
			(xy 460.178702 -396.610789) (xy 460.274038 -396.525306) (xy 460.374503 -396.445915) (xy 460.479711 -396.372923)
			(xy 460.589252 -396.306614) (xy 460.702704 -396.247243) (xy 460.819628 -396.195039) (xy 460.939571 -396.150206)
			(xy 461.062069 -396.112917) (xy 461.186649 -396.083315) (xy 461.312827 -396.061516) (xy 461.440117 -396.047603)
			(xy 461.568026 -396.041631) (xy 461.696059 -396.043622) (xy 461.82372 -396.05357) (xy 461.950516 -396.071434)
			(xy 462.075955 -396.097147) (xy 462.199554 -396.130609) (xy 462.320833 -396.17169) (xy 462.439324 -396.220232)
			(xy 462.554568 -396.276046) (xy 462.666118 -396.338917) (xy 462.773545 -396.408601) (xy 462.876431 -396.484829)
			(xy 462.974379 -396.567306) (xy 463.06701 -396.655713) (xy 463.153966 -396.749708) (xy 463.23491 -396.848927)
			(xy 463.309529 -396.952986) (xy 463.377534 -397.061483) (xy 463.438662 -397.173998) (xy 463.492677 -397.290096)
			(xy 463.53937 -397.409327) (xy 463.57856 -397.531231) (xy 463.610096 -397.655335) (xy 463.633855 -397.781159)
			(xy 463.649745 -397.908218) (xy 463.657706 -398.036018) (xy 463.658204 -398.100042) (xy 463.657706 -398.164066)
			(xy 463.649745 -398.291866) (xy 463.633855 -398.418925) (xy 463.610096 -398.544749) (xy 463.57856 -398.668853)
			(xy 463.53937 -398.790757) (xy 463.492677 -398.909988) (xy 463.438662 -399.026086) (xy 463.377534 -399.138601)
			(xy 463.309529 -399.247098) (xy 463.23491 -399.351157) (xy 463.153966 -399.450376) (xy 463.06701 -399.544371)
			(xy 462.974379 -399.632778) (xy 462.876431 -399.715255) (xy 462.773545 -399.791483) (xy 462.666118 -399.861167)
			(xy 462.554568 -399.924038) (xy 462.439324 -399.979852) (xy 462.320833 -400.028394) (xy 462.199554 -400.069475)
			(xy 462.075955 -400.102937) (xy 461.950516 -400.12865) (xy 461.82372 -400.146514) (xy 461.696059 -400.156462)
			(xy 461.568026 -400.158453) (xy 461.440117 -400.152481) (xy 461.312827 -400.138568) (xy 461.186649 -400.116769)
			(xy 461.062069 -400.087167) (xy 460.939571 -400.049878) (xy 460.819628 -400.005045) (xy 460.702704 -399.952841)
			(xy 460.589252 -399.89347) (xy 460.479711 -399.827161) (xy 460.374503 -399.754169) (xy 460.274038 -399.674778)
			(xy 460.178702 -399.589295) (xy 460.088865 -399.49805) (xy 460.004875 -399.401396) (xy 459.927056 -399.299708)
			(xy 459.855709 -399.193378) (xy 459.791111 -399.082819) (xy 459.733511 -398.968457) (xy 459.683133 -398.850736)
			(xy 459.640171 -398.73011) (xy 459.604791 -398.607047) (xy 459.57713 -398.482022) (xy 459.557296 -398.355519)
			(xy 459.545364 -398.228028) (xy 459.541382 -398.100042) (xy 435.299612 -398.100042) (xy 435.299612 -398.486884)
			(xy 435.300027 -398.496071) (xy 435.306537 -398.513255) (xy 435.312312 -398.520412) (xy 435.334137 -398.546034)
			(xy 435.372087 -398.601624) (xy 435.403122 -398.661351) (xy 435.426795 -398.72436) (xy 435.442767 -398.789746)
			(xy 435.450809 -398.856573) (xy 435.450805 -398.923881) (xy 435.442757 -398.990707) (xy 435.426779 -399.056092)
			(xy 435.4031 -399.119098) (xy 435.37206 -399.178823) (xy 435.334103 -399.234408) (xy 435.312312 -399.26006)
			(xy 435.306509 -399.267201) (xy 435.299998 -399.284395) (xy 435.299612 -399.293588) (xy 435.299612 -399.451576)
			(xy 435.299159 -399.461727) (xy 435.291374 -399.480477) (xy 435.276987 -399.494801) (xy 435.258203 -399.502503)
			(xy 435.24805 -399.502884) (xy 434.53177 -399.502884) (xy 434.521644 -399.502399) (xy 434.502927 -399.494666)
			(xy 434.488573 -399.480379) (xy 434.48075 -399.461699) (xy 434.480208 -399.451576) (xy 434.480208 -399.293588)
			(xy 434.479802 -399.2844) (xy 434.473285 -399.267216) (xy 434.467508 -399.26006) (xy 434.445757 -399.234378)
			(xy 434.407809 -399.178795) (xy 434.376776 -399.119076) (xy 434.353102 -399.056075) (xy 434.337128 -398.990697)
			(xy 434.329081 -398.923878) (xy 434.329078 -398.856576) (xy 434.337118 -398.789757) (xy 434.353086 -398.724377)
			(xy 434.376753 -398.661374) (xy 434.407781 -398.601651) (xy 434.445723 -398.546064) (xy 434.467508 -398.520412)
			(xy 434.473325 -398.513282) (xy 434.479827 -398.49608) (xy 434.480208 -398.486884) (xy 434.480208 -397.993362)
			(xy 434.479814 -397.984173) (xy 434.473289 -397.966989) (xy 434.467508 -397.959834) (xy 434.445731 -397.934173)
			(xy 434.407784 -397.878587) (xy 434.376752 -397.818865) (xy 434.35308 -397.755861) (xy 434.337107 -397.690481)
			(xy 434.329063 -397.623659) (xy 434.329062 -397.556356) (xy 433.200318 -397.556356) (xy 433.202899 -397.561322)
			(xy 433.226573 -397.624323) (xy 433.242549 -397.689701) (xy 433.250596 -397.75652) (xy 433.250599 -397.823822)
			(xy 433.242559 -397.890642) (xy 433.22659 -397.956022) (xy 433.202922 -398.019025) (xy 433.171893 -398.078748)
			(xy 433.133949 -398.134334) (xy 433.112164 -398.159986) (xy 433.106344 -398.167114) (xy 433.099844 -398.184318)
			(xy 433.099464 -398.193514) (xy 433.099464 -398.351502) (xy 433.098968 -398.36166) (xy 433.091194 -398.380428)
			(xy 433.076828 -398.394794) (xy 433.05806 -398.402568) (xy 433.047902 -398.403064) (xy 432.331622 -398.403064)
			(xy 432.321452 -398.402618) (xy 432.302658 -398.394841) (xy 432.288273 -398.380462) (xy 432.280487 -398.361672)
			(xy 432.28006 -398.351502) (xy 432.28006 -398.193514) (xy 432.27963 -398.184329) (xy 432.273129 -398.167145)
			(xy 432.26736 -398.159986) (xy 432.245534 -398.134365) (xy 432.207585 -398.078775) (xy 432.176552 -398.019047)
			(xy 432.152881 -397.956038) (xy 432.13691 -397.890652) (xy 432.128868 -397.823826) (xy 431.000734 -397.823826)
			(xy 430.971969 -397.879041) (xy 430.93388 -397.934676) (xy 430.912016 -397.960342) (xy 430.906221 -397.967488)
			(xy 430.899705 -397.984678) (xy 430.899316 -397.99387) (xy 430.899316 -398.486376) (xy 430.899734 -398.495562)
			(xy 430.906242 -398.512747) (xy 430.912016 -398.519904) (xy 430.933915 -398.54554) (xy 430.972001 -398.601179)
			(xy 431.00315 -398.66098) (xy 431.026911 -398.72408) (xy 431.042944 -398.789573) (xy 431.051016 -398.856514)
			(xy 431.051013 -398.92394) (xy 431.042934 -398.990881) (xy 431.026895 -399.056371) (xy 431.003128 -399.11947)
			(xy 430.971974 -399.179267) (xy 430.933882 -399.234902) (xy 430.912016 -399.260568) (xy 430.90621 -399.267707)
			(xy 430.8997 -399.284902) (xy 430.899316 -399.294096) (xy 430.899316 -399.451576) (xy 430.898865 -399.461695)
			(xy 430.891128 -399.480395) (xy 430.876822 -399.49471) (xy 430.858127 -399.502459) (xy 430.848008 -399.502884)
			(xy 430.131728 -399.502884) (xy 430.121605 -399.502461) (xy 430.102899 -399.494719) (xy 430.088583 -399.480404)
			(xy 430.08084 -399.461699) (xy 430.08042 -399.451576) (xy 430.08042 -399.294096) (xy 430.080008 -399.284909)
			(xy 430.073495 -399.267725) (xy 430.06772 -399.260568) (xy 430.045891 -399.234874) (xy 430.0078 -399.179244)
			(xy 429.976646 -399.119452) (xy 429.952879 -399.056359) (xy 429.936841 -398.990873) (xy 429.928761 -398.923938)
			(xy 429.928758 -398.856516) (xy 429.936831 -398.78958) (xy 429.952863 -398.724093) (xy 429.976624 -398.660997)
			(xy 430.007772 -398.601202) (xy 430.045857 -398.545569) (xy 430.06772 -398.519904) (xy 430.0735 -398.512747)
			(xy 430.080024 -398.495565) (xy 430.08042 -398.486376) (xy 430.08042 -397.99387) (xy 430.08002 -397.984682)
			(xy 430.073499 -397.967498) (xy 430.06772 -397.960342) (xy 430.045865 -397.934669) (xy 430.007775 -397.879036)
			(xy 429.976623 -397.819241) (xy 429.952857 -397.756145) (xy 429.93682 -397.690657) (xy 429.928743 -397.623719)
			(xy 429.928742 -397.556296) (xy 428.800497 -397.556296) (xy 428.803109 -397.561323) (xy 428.826783 -397.624323)
			(xy 428.842758 -397.689702) (xy 428.850805 -397.756521) (xy 428.850808 -397.823822) (xy 428.842768 -397.890642)
			(xy 428.8268 -397.956022) (xy 428.803132 -398.019025) (xy 428.772104 -398.078747) (xy 428.734161 -398.134333)
			(xy 428.712376 -398.159986) (xy 428.706558 -398.167116) (xy 428.700057 -398.184318) (xy 428.699676 -398.193514)
			(xy 428.699676 -398.351502) (xy 428.699169 -398.361658) (xy 428.691396 -398.380425) (xy 428.677035 -398.394789)
			(xy 428.65827 -398.402566) (xy 428.648114 -398.403064) (xy 427.931834 -398.403064) (xy 427.921665 -398.402608)
			(xy 427.902871 -398.394835) (xy 427.888485 -398.380459) (xy 427.880699 -398.361671) (xy 427.880272 -398.351502)
			(xy 427.880272 -398.193514) (xy 427.879861 -398.184327) (xy 427.873349 -398.167142) (xy 427.867572 -398.159986)
			(xy 427.845746 -398.134365) (xy 427.807796 -398.078775) (xy 427.776762 -398.019047) (xy 427.75309 -397.956039)
			(xy 427.737119 -397.890652) (xy 427.729077 -397.823826) (xy 426.600432 -397.823826) (xy 426.571969 -397.878596)
			(xy 426.534017 -397.934182) (xy 426.512228 -397.959834) (xy 426.506426 -397.966975) (xy 426.499917 -397.984169)
			(xy 426.499528 -397.993362) (xy 426.499528 -398.486884) (xy 426.499939 -398.496071) (xy 426.506451 -398.513256)
			(xy 426.512228 -398.520412) (xy 426.534052 -398.546034) (xy 426.572002 -398.601624) (xy 426.603036 -398.661352)
			(xy 426.626708 -398.72436) (xy 426.64268 -398.789746) (xy 426.650721 -398.856573) (xy 426.650718 -398.923881)
			(xy 426.64267 -398.990707) (xy 426.626692 -399.056092) (xy 426.603014 -399.119098) (xy 426.571974 -399.178822)
			(xy 426.534019 -399.234408) (xy 426.512228 -399.26006) (xy 426.506415 -399.267193) (xy 426.499912 -399.284393)
			(xy 426.499528 -399.293588) (xy 426.499528 -399.451576) (xy 426.499059 -399.461725) (xy 426.491277 -399.480472)
			(xy 426.476895 -399.494795) (xy 426.458117 -399.502501) (xy 426.447966 -399.502884) (xy 425.731686 -399.502884)
			(xy 425.721561 -399.502385) (xy 425.702845 -399.494657) (xy 425.68849 -399.480375) (xy 425.680667 -399.461698)
			(xy 425.680124 -399.451576) (xy 425.680124 -399.293588) (xy 425.679714 -399.284401) (xy 425.6732 -399.267217)
			(xy 425.667424 -399.26006) (xy 425.645672 -399.234378) (xy 425.607723 -399.178796) (xy 425.576689 -399.119076)
			(xy 425.553015 -399.056076) (xy 425.53704 -398.990697) (xy 425.528994 -398.923878) (xy 425.52899 -398.856576)
			(xy 425.537031 -398.789756) (xy 425.552999 -398.724376) (xy 425.576667 -398.661373) (xy 425.607696 -398.601651)
			(xy 425.645639 -398.546065) (xy 425.667424 -398.520412) (xy 425.673243 -398.513283) (xy 425.679744 -398.49608)
			(xy 425.680124 -398.486884) (xy 425.680124 -397.993362) (xy 425.679727 -397.984174) (xy 425.673204 -397.96699)
			(xy 425.667424 -397.959834) (xy 425.645646 -397.934174) (xy 425.607698 -397.878588) (xy 425.576665 -397.818865)
			(xy 425.552993 -397.755862) (xy 425.53702 -397.690481) (xy 425.528975 -397.62366) (xy 425.528974 -397.556356)
			(xy 424.40076 -397.556356) (xy 424.403152 -397.560947) (xy 424.426919 -397.62404) (xy 424.442958 -397.689526)
			(xy 424.451037 -397.756461) (xy 424.451041 -397.823882) (xy 424.442968 -397.890818) (xy 424.426936 -397.956305)
			(xy 424.403175 -398.019401) (xy 424.372028 -398.079196) (xy 424.333942 -398.134829) (xy 424.31208 -398.160494)
			(xy 424.306301 -398.167652) (xy 424.299777 -398.184833) (xy 424.29938 -398.194022) (xy 424.29938 -398.351502)
			(xy 424.298876 -398.361626) (xy 424.291151 -398.380344) (xy 424.27687 -398.394699) (xy 424.258194 -398.402522)
			(xy 424.248072 -398.403064) (xy 423.531792 -398.403064) (xy 423.521633 -398.402684) (xy 423.502873 -398.394879)
			(xy 423.488549 -398.380469) (xy 423.480856 -398.361663) (xy 423.480484 -398.351502) (xy 423.480484 -398.194022)
			(xy 423.480067 -398.184835) (xy 423.473558 -398.167651) (xy 423.467784 -398.160494) (xy 423.445883 -398.134859)
			(xy 423.407797 -398.07922) (xy 423.376649 -398.019419) (xy 423.352887 -397.956319) (xy 423.336855 -397.890826)
			(xy 423.328782 -397.823885) (xy 422.200615 -397.823885) (xy 422.171883 -397.879041) (xy 422.133795 -397.934676)
			(xy 422.111932 -397.960342) (xy 422.106127 -397.967481) (xy 422.099619 -397.984676) (xy 422.099232 -397.99387)
			(xy 422.099232 -398.486376) (xy 422.099669 -398.49556) (xy 422.106166 -398.512744) (xy 422.111932 -398.519904)
			(xy 422.13383 -398.545541) (xy 422.171916 -398.60118) (xy 422.203063 -398.66098) (xy 422.226824 -398.724081)
			(xy 422.242856 -398.789573) (xy 422.250928 -398.856514) (xy 422.250925 -398.92394) (xy 422.242846 -398.99088)
			(xy 422.226808 -399.056371) (xy 422.203041 -399.119469) (xy 422.171888 -399.179266) (xy 422.133797 -399.234902)
			(xy 422.111932 -399.260568) (xy 422.106116 -399.267699) (xy 422.099615 -399.284901) (xy 422.099232 -399.294096)
			(xy 422.099232 -399.451576) (xy 422.098696 -399.461679) (xy 422.090972 -399.480351) (xy 422.076691 -399.494645)
			(xy 422.058027 -399.502387) (xy 422.047924 -399.502884) (xy 421.331644 -399.502884) (xy 421.321522 -399.502447)
			(xy 421.302817 -399.494711) (xy 421.2885 -399.4804) (xy 421.280756 -399.461697) (xy 421.280336 -399.451576)
			(xy 421.280336 -399.294096) (xy 421.27992 -399.28491) (xy 421.27341 -399.267726) (xy 421.267636 -399.260568)
			(xy 421.245806 -399.234874) (xy 421.207714 -399.179245) (xy 421.17656 -399.119453) (xy 421.152792 -399.056359)
			(xy 421.136753 -398.990873) (xy 421.128674 -398.923938) (xy 421.12867 -398.856516) (xy 421.136743 -398.78958)
			(xy 421.152776 -398.724092) (xy 421.176538 -398.660997) (xy 421.207686 -398.601202) (xy 421.245773 -398.545569)
			(xy 421.267636 -398.519904) (xy 421.273418 -398.512749) (xy 421.27994 -398.495566) (xy 421.280336 -398.486376)
			(xy 421.280336 -397.99387) (xy 421.279932 -397.984682) (xy 421.273413 -397.967498) (xy 421.267636 -397.960342)
			(xy 421.245781 -397.934669) (xy 421.207689 -397.879037) (xy 421.176536 -397.819242) (xy 421.15277 -397.756146)
			(xy 421.136732 -397.690657) (xy 421.128655 -397.623719) (xy 421.128654 -397.556296) (xy 420.00041 -397.556296)
			(xy 420.003023 -397.561324) (xy 420.026696 -397.624324) (xy 420.042671 -397.689702) (xy 420.050718 -397.756521)
			(xy 420.050721 -397.823822) (xy 420.042681 -397.890642) (xy 420.026713 -397.956021) (xy 420.003046 -398.019024)
			(xy 419.972019 -398.078747) (xy 419.934077 -398.134334) (xy 419.912292 -398.159986) (xy 419.906475 -398.167117)
			(xy 419.899973 -398.184318) (xy 419.899592 -398.193514) (xy 419.899592 -398.351502) (xy 419.899069 -398.361656)
			(xy 419.891299 -398.38042) (xy 419.876943 -398.394784) (xy 419.858184 -398.402563) (xy 419.84803 -398.403064)
			(xy 419.13175 -398.403064) (xy 419.121582 -398.402595) (xy 419.102789 -398.394827) (xy 419.088402 -398.380455)
			(xy 419.080615 -398.36167) (xy 419.080188 -398.351502) (xy 419.080188 -398.193514) (xy 419.079774 -398.184327)
			(xy 419.073263 -398.167143) (xy 419.067488 -398.159986) (xy 419.045661 -398.134365) (xy 419.007711 -398.078775)
			(xy 418.976676 -398.019048) (xy 418.953004 -397.956039) (xy 418.937032 -397.890653) (xy 418.92899 -397.823826)
			(xy 414.525968 -397.823826) (xy 414.525968 -401.723737) (xy 418.929001 -401.723737) (xy 418.929003 -401.65643)
			(xy 418.93705 -401.589605) (xy 418.953027 -401.524221) (xy 418.976704 -401.461215) (xy 419.007743 -401.401491)
			(xy 419.045697 -401.345906) (xy 419.067488 -401.320254) (xy 419.073285 -401.313109) (xy 419.0798 -401.295918)
			(xy 419.080188 -401.286726) (xy 419.080188 -400.793458) (xy 419.079801 -400.784268) (xy 419.073272 -400.767084)
			(xy 419.067488 -400.75993) (xy 419.045705 -400.734274) (xy 419.007752 -400.678689) (xy 418.976716 -400.618966)
			(xy 418.953041 -400.555962) (xy 418.937066 -400.49058) (xy 418.929021 -400.423757) (xy 418.92902 -400.356452)
			(xy 418.937065 -400.289629) (xy 418.953038 -400.224246) (xy 418.976713 -400.161242) (xy 419.007748 -400.101519)
			(xy 419.045699 -400.045933) (xy 419.067488 -400.020282) (xy 419.073273 -400.013129) (xy 419.079795 -399.995944)
			(xy 419.080188 -399.986754) (xy 419.080188 -399.828766) (xy 419.080537 -399.818586) (xy 419.088343 -399.799781)
			(xy 419.102752 -399.785395) (xy 419.121569 -399.777621) (xy 419.13175 -399.777204) (xy 419.84803 -399.777204)
			(xy 419.858186 -399.777708) (xy 419.876949 -399.785486) (xy 419.891312 -399.799848) (xy 419.899091 -399.818611)
			(xy 419.899592 -399.828766) (xy 419.899592 -399.986754) (xy 419.900026 -399.995939) (xy 419.906523 -400.013123)
			(xy 419.912292 -400.020282) (xy 419.934085 -400.04593) (xy 419.972031 -400.101518) (xy 420.003063 -400.161242)
			(xy 420.026734 -400.224247) (xy 420.042705 -400.289629) (xy 420.050749 -400.356452) (xy 420.050748 -400.423757)
			(xy 420.042704 -400.490579) (xy 420.026731 -400.555962) (xy 420.003059 -400.618966) (xy 419.972027 -400.67869)
			(xy 419.934079 -400.734277) (xy 419.912292 -400.75993) (xy 419.906499 -400.767078) (xy 419.899983 -400.784266)
			(xy 419.899592 -400.793458) (xy 419.899592 -401.286726) (xy 419.899991 -401.295914) (xy 419.906513 -401.313099)
			(xy 419.912292 -401.320254) (xy 419.934057 -401.345924) (xy 419.972005 -401.401509) (xy 420.003037 -401.46123)
			(xy 420.02671 -401.524232) (xy 420.042683 -401.589612) (xy 420.050729 -401.656432) (xy 420.050731 -401.723735)
			(xy 420.042689 -401.790555) (xy 420.02672 -401.855936) (xy 420.003051 -401.918939) (xy 419.972022 -401.978663)
			(xy 419.934077 -402.034249) (xy 419.912292 -402.059902) (xy 419.906511 -402.067058) (xy 419.899987 -402.08424)
			(xy 419.899592 -402.09343) (xy 419.899592 -402.251418) (xy 419.899082 -402.261573) (xy 419.891308 -402.280337)
			(xy 419.876947 -402.294701) (xy 419.858185 -402.30248) (xy 419.84803 -402.30298) (xy 419.13175 -402.30298)
			(xy 419.121584 -402.302496) (xy 419.102794 -402.29473) (xy 419.088408 -402.280363) (xy 419.080618 -402.261584)
			(xy 419.080188 -402.251418) (xy 419.080188 -402.09343) (xy 419.079766 -402.084244) (xy 419.073261 -402.067059)
			(xy 419.067488 -402.059902) (xy 419.045677 -402.034268) (xy 419.007726 -401.97868) (xy 418.976691 -401.918955)
			(xy 418.953017 -401.855948) (xy 418.937044 -401.790563) (xy 418.929001 -401.723737) (xy 414.525968 -401.723737)
			(xy 414.525968 -402.823878) (xy 421.128614 -402.823878) (xy 421.128619 -402.75645) (xy 421.1367 -402.689508)
			(xy 421.152742 -402.624016) (xy 421.176513 -402.560916) (xy 421.207671 -402.501119) (xy 421.245768 -402.445485)
			(xy 421.267636 -402.41982) (xy 421.273454 -402.41269) (xy 421.279955 -402.395488) (xy 421.280336 -402.386292)
			(xy 421.280336 -401.89404) (xy 421.279898 -401.884856) (xy 421.273403 -401.867672) (xy 421.267636 -401.860512)
			(xy 421.245751 -401.834864) (xy 421.207661 -401.779227) (xy 421.176509 -401.719429) (xy 421.152744 -401.65633)
			(xy 421.136709 -401.590839) (xy 421.128634 -401.523898) (xy 421.128636 -401.456472) (xy 421.136714 -401.389532)
			(xy 421.152753 -401.324041) (xy 421.176521 -401.260943) (xy 421.207676 -401.201147) (xy 421.24577 -401.145513)
			(xy 421.267636 -401.119848) (xy 421.273442 -401.112709) (xy 421.27995 -401.095514) (xy 421.280336 -401.08632)
			(xy 421.280336 -400.92884) (xy 421.28075 -400.918716) (xy 421.288491 -400.900006) (xy 421.302809 -400.885689)
			(xy 421.32152 -400.877949) (xy 421.331644 -400.877532) (xy 422.047924 -400.877532) (xy 422.058052 -400.877897)
			(xy 422.076762 -400.885659) (xy 422.091077 -400.899991) (xy 422.098816 -400.918711) (xy 422.099232 -400.92884)
			(xy 422.099232 -401.08632) (xy 422.099648 -401.095506) (xy 422.106159 -401.11269) (xy 422.111932 -401.119848)
			(xy 422.133775 -401.14553) (xy 422.171862 -401.201163) (xy 422.203012 -401.260957) (xy 422.226776 -401.324052)
			(xy 422.242812 -401.389538) (xy 422.250889 -401.456474) (xy 422.250891 -401.523896) (xy 422.242817 -401.590832)
			(xy 422.226785 -401.65632) (xy 422.203024 -401.719415) (xy 422.200742 -401.723796) (xy 423.328794 -401.723796)
			(xy 423.328796 -401.656371) (xy 423.336873 -401.589431) (xy 423.352911 -401.523941) (xy 423.376677 -401.460844)
			(xy 423.407829 -401.401047) (xy 423.445919 -401.345412) (xy 423.467784 -401.319746) (xy 423.473584 -401.312603)
			(xy 423.480097 -401.295411) (xy 423.480484 -401.286218) (xy 423.480484 -400.793966) (xy 423.480094 -400.784777)
			(xy 423.473566 -400.767592) (xy 423.467784 -400.760438) (xy 423.445926 -400.734768) (xy 423.407839 -400.679133)
			(xy 423.376689 -400.619338) (xy 423.352925 -400.556242) (xy 423.336889 -400.490753) (xy 423.328813 -400.423816)
			(xy 423.328813 -400.356393) (xy 423.336888 -400.289455) (xy 423.352922 -400.223967) (xy 423.376685 -400.16087)
			(xy 423.407834 -400.101074) (xy 423.445921 -400.045439) (xy 423.467784 -400.019774) (xy 423.473572 -400.012623)
			(xy 423.480092 -399.995437) (xy 423.480484 -399.986246) (xy 423.480484 -399.828766) (xy 423.4809 -399.818632)
			(xy 423.488647 -399.799901) (xy 423.502955 -399.785545) (xy 423.521659 -399.777735) (xy 423.531792 -399.777204)
			(xy 424.248072 -399.777204) (xy 424.258225 -399.777644) (xy 424.276977 -399.785431) (xy 424.291302 -399.799823)
			(xy 424.299002 -399.818611) (xy 424.29938 -399.828766) (xy 424.29938 -399.986246) (xy 424.299821 -399.99543)
			(xy 424.306314 -400.012614) (xy 424.31208 -400.019774) (xy 424.333951 -400.045434) (xy 424.37204 -400.101069)
			(xy 424.403192 -400.160866) (xy 424.426957 -400.223963) (xy 424.442992 -400.289453) (xy 424.451068 -400.356392)
			(xy 424.451068 -400.423817) (xy 424.442991 -400.490756) (xy 424.426954 -400.556245) (xy 424.403188 -400.619343)
			(xy 424.372036 -400.679139) (xy 424.333945 -400.734773) (xy 424.31208 -400.760438) (xy 424.306282 -400.767582)
			(xy 424.299769 -400.784774) (xy 424.29938 -400.793966) (xy 424.29938 -401.286218) (xy 424.299786 -401.295406)
			(xy 424.306303 -401.31259) (xy 424.31208 -401.319746) (xy 424.333923 -401.345429) (xy 424.372014 -401.40106)
			(xy 424.403167 -401.460854) (xy 424.426933 -401.523949) (xy 424.44297 -401.589436) (xy 424.451048 -401.656372)
			(xy 424.45105 -401.723795) (xy 424.442976 -401.790732) (xy 424.426943 -401.85622) (xy 424.40318 -401.919316)
			(xy 424.372031 -401.979111) (xy 424.333943 -402.034745) (xy 424.31208 -402.06041) (xy 424.306294 -402.067563)
			(xy 424.299774 -402.084748) (xy 424.29938 -402.093938) (xy 424.29938 -402.251418) (xy 424.298889 -402.261543)
			(xy 424.291159 -402.280261) (xy 424.276874 -402.294616) (xy 424.258195 -402.302438) (xy 424.248072 -402.30298)
			(xy 423.531792 -402.30298) (xy 423.521635 -402.302584) (xy 423.502879 -402.294782) (xy 423.488555 -402.280378)
			(xy 423.480859 -402.261577) (xy 423.480484 -402.251418) (xy 423.480484 -402.093938) (xy 423.480059 -402.084752)
			(xy 423.473556 -402.067568) (xy 423.467784 -402.06041) (xy 423.445899 -402.034762) (xy 423.407812 -401.979125)
			(xy 423.376663 -401.919326) (xy 423.352901 -401.856227) (xy 423.336867 -401.790736) (xy 423.328794 -401.723796)
			(xy 422.200742 -401.723796) (xy 422.171878 -401.779211) (xy 422.133794 -401.834846) (xy 422.111932 -401.860512)
			(xy 422.10614 -401.86766) (xy 422.099624 -401.884849) (xy 422.099232 -401.89404) (xy 422.099232 -402.386292)
			(xy 422.099661 -402.395477) (xy 422.106163 -402.412661) (xy 422.111932 -402.41982) (xy 422.133748 -402.445525)
			(xy 422.171836 -402.501154) (xy 422.202987 -402.560945) (xy 422.226752 -402.624037) (xy 422.24279 -402.689521)
			(xy 422.250869 -402.756454) (xy 422.250874 -402.823818) (xy 425.528934 -402.823818) (xy 425.528938 -402.75651)
			(xy 425.536987 -402.689684) (xy 425.552965 -402.624299) (xy 425.576642 -402.561293) (xy 425.60768 -402.501568)
			(xy 425.645634 -402.44598) (xy 425.667424 -402.420328) (xy 425.673236 -402.413194) (xy 425.679741 -402.395995)
			(xy 425.680124 -402.3868) (xy 425.680124 -401.893532) (xy 425.679693 -401.884347) (xy 425.673193 -401.867163)
			(xy 425.667424 -401.860004) (xy 425.645617 -401.834368) (xy 425.60767 -401.778779) (xy 425.576638 -401.719053)
			(xy 425.552967 -401.656046) (xy 425.536996 -401.590662) (xy 425.528954 -401.523838) (xy 425.528956 -401.456532)
			(xy 425.537001 -401.389708) (xy 425.552976 -401.324325) (xy 425.57665 -401.26132) (xy 425.607685 -401.201595)
			(xy 425.645635 -401.146008) (xy 425.667424 -401.120356) (xy 425.673225 -401.113214) (xy 425.679736 -401.096021)
			(xy 425.680124 -401.086828) (xy 425.680124 -400.92884) (xy 425.680555 -400.918686) (xy 425.688342 -400.899929)
			(xy 425.702736 -400.885604) (xy 425.72153 -400.877907) (xy 425.731686 -400.877532) (xy 426.447966 -400.877532)
			(xy 426.45809 -400.878054) (xy 426.476808 -400.88577) (xy 426.491165 -400.900045) (xy 426.498987 -400.918719)
			(xy 426.499528 -400.92884) (xy 426.499528 -401.086828) (xy 426.499918 -401.096017) (xy 426.506445 -401.113202)
			(xy 426.512228 -401.120356) (xy 426.533997 -401.146024) (xy 426.571949 -401.201607) (xy 426.602985 -401.261328)
			(xy 426.62666 -401.324331) (xy 426.642635 -401.389712) (xy 426.650681 -401.456533) (xy 426.650683 -401.523837)
			(xy 426.642641 -401.590659) (xy 426.626669 -401.65604) (xy 426.602997 -401.719044) (xy 426.600558 -401.723737)
			(xy 427.729089 -401.723737) (xy 427.729091 -401.65643) (xy 427.737138 -401.589605) (xy 427.753114 -401.524221)
			(xy 427.776791 -401.461216) (xy 427.807828 -401.401492) (xy 427.845782 -401.345906) (xy 427.867572 -401.320254)
			(xy 427.873379 -401.313117) (xy 427.879886 -401.29592) (xy 427.880272 -401.286726) (xy 427.880272 -400.793458)
			(xy 427.879888 -400.784268) (xy 427.873357 -400.767084) (xy 427.867572 -400.75993) (xy 427.845789 -400.734273)
			(xy 427.807838 -400.678688) (xy 427.776803 -400.618966) (xy 427.753128 -400.555962) (xy 427.737154 -400.49058)
			(xy 427.729109 -400.423757) (xy 427.729108 -400.356452) (xy 427.737152 -400.289629) (xy 427.753126 -400.224247)
			(xy 427.776799 -400.161243) (xy 427.807833 -400.101519) (xy 427.845784 -400.045934) (xy 427.867572 -400.020282)
			(xy 427.873367 -400.013136) (xy 427.879881 -399.995946) (xy 427.880272 -399.986754) (xy 427.880272 -399.828766)
			(xy 427.880706 -399.818602) (xy 427.888498 -399.799825) (xy 427.902883 -399.78546) (xy 427.921669 -399.777693)
			(xy 427.931834 -399.777204) (xy 428.648114 -399.777204) (xy 428.658268 -399.777721) (xy 428.677031 -399.785494)
			(xy 428.691395 -399.799852) (xy 428.699175 -399.818612) (xy 428.699676 -399.828766) (xy 428.699676 -399.986754)
			(xy 428.700114 -399.995938) (xy 428.706609 -400.013122) (xy 428.712376 -400.020282) (xy 428.734169 -400.045929)
			(xy 428.772117 -400.101517) (xy 428.803149 -400.161241) (xy 428.826821 -400.224246) (xy 428.842793 -400.289629)
			(xy 428.850836 -400.356452) (xy 428.850836 -400.423757) (xy 428.842791 -400.49058) (xy 428.826818 -400.555962)
			(xy 428.803145 -400.618967) (xy 428.772112 -400.678691) (xy 428.734164 -400.734278) (xy 428.712376 -400.75993)
			(xy 428.706581 -400.767076) (xy 428.700066 -400.784266) (xy 428.699676 -400.793458) (xy 428.699676 -401.286726)
			(xy 428.700079 -401.295914) (xy 428.706598 -401.313098) (xy 428.712376 -401.320254) (xy 428.734142 -401.345924)
			(xy 428.77209 -401.401508) (xy 428.803124 -401.46123) (xy 428.826797 -401.524232) (xy 428.842771 -401.589612)
			(xy 428.850817 -401.656432) (xy 428.850819 -401.723735) (xy 428.842777 -401.790556) (xy 428.826807 -401.855937)
			(xy 428.803137 -401.91894) (xy 428.772107 -401.978663) (xy 428.734162 -402.03425) (xy 428.712376 -402.059902)
			(xy 428.706593 -402.067057) (xy 428.700071 -402.08424) (xy 428.699676 -402.09343) (xy 428.699676 -402.251418)
			(xy 428.699182 -402.261575) (xy 428.691404 -402.280342) (xy 428.677039 -402.294706) (xy 428.658271 -402.302483)
			(xy 428.648114 -402.30298) (xy 427.931834 -402.30298) (xy 427.921667 -402.302509) (xy 427.902876 -402.294738)
			(xy 427.888491 -402.280367) (xy 427.880702 -402.261585) (xy 427.880272 -402.251418) (xy 427.880272 -402.09343)
			(xy 427.879854 -402.084244) (xy 427.873347 -402.067059) (xy 427.867572 -402.059902) (xy 427.845762 -402.034268)
			(xy 427.807811 -401.97868) (xy 427.776777 -401.918954) (xy 427.753104 -401.855947) (xy 427.737132 -401.790562)
			(xy 427.729089 -401.723737) (xy 426.600558 -401.723737) (xy 426.571964 -401.778767) (xy 426.534015 -401.834352)
			(xy 426.512228 -401.860004) (xy 426.506438 -401.867154) (xy 426.499922 -401.884341) (xy 426.499528 -401.893532)
			(xy 426.499528 -402.3868) (xy 426.499932 -402.395988) (xy 426.506449 -402.413173) (xy 426.512228 -402.420328)
			(xy 426.53397 -402.446019) (xy 426.571922 -402.501599) (xy 426.602959 -402.561317) (xy 426.626636 -402.624316)
			(xy 426.642613 -402.689694) (xy 426.650662 -402.756513) (xy 426.650666 -402.823815) (xy 426.650658 -402.823878)
			(xy 429.928702 -402.823878) (xy 429.928707 -402.75645) (xy 429.936788 -402.689508) (xy 429.952829 -402.624016)
			(xy 429.976599 -402.560917) (xy 430.007757 -402.50112) (xy 430.045852 -402.445485) (xy 430.06772 -402.41982)
			(xy 430.073535 -402.412688) (xy 430.080038 -402.395487) (xy 430.08042 -402.386292) (xy 430.08042 -401.89404)
			(xy 430.079986 -401.884855) (xy 430.073488 -401.867671) (xy 430.06772 -401.860512) (xy 430.045836 -401.834863)
			(xy 430.007746 -401.779227) (xy 429.976595 -401.719429) (xy 429.952831 -401.656329) (xy 429.936797 -401.590838)
			(xy 429.928722 -401.523898) (xy 429.928724 -401.456472) (xy 429.936802 -401.389532) (xy 429.95284 -401.324042)
			(xy 429.976608 -401.260944) (xy 430.007762 -401.201147) (xy 430.045854 -401.145513) (xy 430.06772 -401.119848)
			(xy 430.073523 -401.112708) (xy 430.080033 -401.095513) (xy 430.08042 -401.08632) (xy 430.08042 -400.92884)
			(xy 430.080849 -400.918718) (xy 430.088588 -400.900011) (xy 430.102901 -400.885695) (xy 430.121606 -400.877952)
			(xy 430.131728 -400.877532) (xy 430.848008 -400.877532) (xy 430.858135 -400.87791) (xy 430.876845 -400.885667)
			(xy 430.89116 -400.899996) (xy 430.898899 -400.918713) (xy 430.899316 -400.92884) (xy 430.899316 -401.08632)
			(xy 430.899713 -401.095509) (xy 430.906236 -401.112693) (xy 430.912016 -401.119848) (xy 430.93386 -401.14553)
			(xy 430.971948 -401.201162) (xy 431.003099 -401.260956) (xy 431.026863 -401.324051) (xy 431.0429 -401.389538)
			(xy 431.050977 -401.456474) (xy 431.050979 -401.523896) (xy 431.042905 -401.590832) (xy 431.026872 -401.65632)
			(xy 431.003111 -401.719416) (xy 431.00086 -401.723737) (xy 432.128879 -401.723737) (xy 432.128881 -401.65643)
			(xy 432.136928 -401.589605) (xy 432.152904 -401.524222) (xy 432.17658 -401.461216) (xy 432.207617 -401.401492)
			(xy 432.24557 -401.345906) (xy 432.26736 -401.320254) (xy 432.273166 -401.313116) (xy 432.279673 -401.29592)
			(xy 432.28006 -401.286726) (xy 432.28006 -400.793458) (xy 432.279657 -400.78427) (xy 432.273137 -400.767087)
			(xy 432.26736 -400.75993) (xy 432.245578 -400.734273) (xy 432.207627 -400.678688) (xy 432.176593 -400.618965)
			(xy 432.152919 -400.555961) (xy 432.136945 -400.490579) (xy 432.1289 -400.423757) (xy 432.128899 -400.356452)
			(xy 432.136943 -400.28963) (xy 432.152916 -400.224247) (xy 432.176589 -400.161243) (xy 432.207623 -400.10152)
			(xy 432.245572 -400.045934) (xy 432.26736 -400.020282) (xy 432.273154 -400.013135) (xy 432.279669 -399.995946)
			(xy 432.28006 -399.986754) (xy 432.28006 -399.828766) (xy 432.280506 -399.818603) (xy 432.288296 -399.799829)
			(xy 432.302676 -399.785464) (xy 432.321459 -399.777695) (xy 432.331622 -399.777204) (xy 433.047902 -399.777204)
			(xy 433.058056 -399.777731) (xy 433.076818 -399.7855) (xy 433.091182 -399.799855) (xy 433.098963 -399.818613)
			(xy 433.099464 -399.828766) (xy 433.099464 -399.986754) (xy 433.099905 -399.995938) (xy 433.106398 -400.013122)
			(xy 433.112164 -400.020282) (xy 433.133958 -400.045929) (xy 433.171906 -400.101516) (xy 433.202939 -400.161241)
			(xy 433.226611 -400.224246) (xy 433.242584 -400.289629) (xy 433.250627 -400.356452) (xy 433.250627 -400.423757)
			(xy 433.242582 -400.49058) (xy 433.226609 -400.555963) (xy 433.202935 -400.618968) (xy 433.171901 -400.678691)
			(xy 433.133952 -400.734278) (xy 433.112164 -400.75993) (xy 433.106368 -400.767075) (xy 433.099854 -400.784266)
			(xy 433.099464 -400.793458) (xy 433.099464 -401.286726) (xy 433.09987 -401.295913) (xy 433.106387 -401.313097)
			(xy 433.112164 -401.320254) (xy 433.13393 -401.345924) (xy 433.171879 -401.401508) (xy 433.202913 -401.461229)
			(xy 433.226587 -401.524231) (xy 433.242561 -401.589611) (xy 433.250607 -401.656432) (xy 433.250609 -401.723735)
			(xy 433.242567 -401.790556) (xy 433.226597 -401.855937) (xy 433.202927 -401.918941) (xy 433.171896 -401.978663)
			(xy 433.13395 -402.03425) (xy 433.112164 -402.059902) (xy 433.106379 -402.067056) (xy 433.099858 -402.08424)
			(xy 433.099464 -402.09343) (xy 433.099464 -402.251418) (xy 433.098982 -402.261577) (xy 433.091202 -402.280346)
			(xy 433.076833 -402.294711) (xy 433.058061 -402.302485) (xy 433.047902 -402.30298) (xy 432.331622 -402.30298)
			(xy 432.321454 -402.302518) (xy 432.302663 -402.294744) (xy 432.288278 -402.28037) (xy 432.28049 -402.261586)
			(xy 432.28006 -402.251418) (xy 432.28006 -402.09343) (xy 432.279622 -402.084246) (xy 432.273126 -402.067062)
			(xy 432.26736 -402.059902) (xy 432.24555 -402.034268) (xy 432.2076 -401.97868) (xy 432.176567 -401.918954)
			(xy 432.152894 -401.855947) (xy 432.136922 -401.790562) (xy 432.128879 -401.723737) (xy 431.00086 -401.723737)
			(xy 430.971963 -401.779212) (xy 430.933878 -401.834847) (xy 430.912016 -401.860512) (xy 430.906234 -401.867667)
			(xy 430.89971 -401.88485) (xy 430.899316 -401.89404) (xy 430.899316 -402.386292) (xy 430.899726 -402.395479)
			(xy 430.90624 -402.412664) (xy 430.912016 -402.41982) (xy 430.933832 -402.445524) (xy 430.971921 -402.501154)
			(xy 431.003073 -402.560945) (xy 431.026839 -402.624036) (xy 431.042878 -402.68952) (xy 431.050957 -402.756454)
			(xy 431.050962 -402.823818) (xy 434.329022 -402.823818) (xy 434.329026 -402.75651) (xy 434.337075 -402.689684)
			(xy 434.353052 -402.6243) (xy 434.376729 -402.561294) (xy 434.407766 -402.501568) (xy 434.445718 -402.445981)
			(xy 434.467508 -402.420328) (xy 434.473319 -402.413193) (xy 434.479825 -402.395995) (xy 434.480208 -402.3868)
			(xy 434.480208 -401.893532) (xy 434.479781 -401.884347) (xy 434.473279 -401.867162) (xy 434.467508 -401.860004)
			(xy 434.445702 -401.834368) (xy 434.407755 -401.778778) (xy 434.376725 -401.719052) (xy 434.353054 -401.656046)
			(xy 434.337084 -401.590662) (xy 434.329042 -401.523838) (xy 434.329043 -401.456532) (xy 434.337089 -401.389709)
			(xy 434.353063 -401.324326) (xy 434.376737 -401.26132) (xy 434.407771 -401.201596) (xy 434.44572 -401.146009)
			(xy 434.467508 -401.120356) (xy 434.473307 -401.113212) (xy 434.47982 -401.096021) (xy 434.480208 -401.086828)
			(xy 434.480208 -400.92884) (xy 434.480655 -400.918688) (xy 434.488438 -400.899934) (xy 434.502828 -400.885609)
			(xy 434.521616 -400.87791) (xy 434.53177 -400.877532) (xy 435.24805 -400.877532) (xy 435.258173 -400.878067)
			(xy 435.276891 -400.885777) (xy 435.291249 -400.900049) (xy 435.299071 -400.918721) (xy 435.299612 -400.92884)
			(xy 435.299612 -401.086828) (xy 435.300006 -401.096017) (xy 435.306531 -401.113201) (xy 435.312312 -401.120356)
			(xy 435.334082 -401.146024) (xy 435.372034 -401.201607) (xy 435.403071 -401.261328) (xy 435.426747 -401.32433)
			(xy 435.442723 -401.389711) (xy 435.450769 -401.456533) (xy 435.450771 -401.523837) (xy 435.442728 -401.590659)
			(xy 435.426756 -401.656041) (xy 435.403083 -401.719045) (xy 435.37205 -401.778767) (xy 435.3341 -401.834353)
			(xy 435.312312 -401.860004) (xy 435.306533 -401.867161) (xy 435.300007 -401.884343) (xy 435.299612 -401.893532)
			(xy 435.299612 -402.3868) (xy 435.30002 -402.395988) (xy 435.306535 -402.413172) (xy 435.312312 -402.420328)
			(xy 435.334054 -402.446018) (xy 435.372008 -402.501598) (xy 435.403046 -402.561316) (xy 435.426723 -402.624316)
			(xy 435.442701 -402.689694) (xy 435.45075 -402.756513) (xy 435.450754 -402.823815) (xy 435.442714 -402.890635)
			(xy 435.426745 -402.956015) (xy 435.403075 -403.019018) (xy 435.372045 -403.07874) (xy 435.334098 -403.134325)
			(xy 435.312312 -403.159976) (xy 435.306502 -403.167112) (xy 435.299995 -403.184309) (xy 435.299612 -403.193504)
			(xy 435.299612 -403.351492) (xy 435.299172 -403.361644) (xy 435.291381 -403.380394) (xy 435.27699 -403.394717)
			(xy 435.258204 -403.402419) (xy 435.24805 -403.4028) (xy 434.53177 -403.4028) (xy 434.521646 -403.402299)
			(xy 434.502932 -403.394569) (xy 434.488578 -403.380288) (xy 434.480753 -403.361613) (xy 434.480208 -403.351492)
			(xy 434.480208 -403.193504) (xy 434.479794 -403.184317) (xy 434.473283 -403.167133) (xy 434.467508 -403.159976)
			(xy 434.445674 -403.134362) (xy 434.407729 -403.07877) (xy 434.376699 -403.01904) (xy 434.353031 -402.956031)
			(xy 434.337062 -402.890644) (xy 434.329022 -402.823818) (xy 431.050962 -402.823818) (xy 431.050962 -402.823874)
			(xy 431.042891 -402.890808) (xy 431.026861 -402.956295) (xy 431.003103 -403.019389) (xy 430.971958 -403.079184)
			(xy 430.933877 -403.134819) (xy 430.912016 -403.160484) (xy 430.906203 -403.167618) (xy 430.899698 -403.184817)
			(xy 430.899316 -403.194012) (xy 430.899316 -403.351492) (xy 430.898809 -403.361598) (xy 430.891077 -403.380273)
			(xy 430.876787 -403.394568) (xy 430.858114 -403.402306) (xy 430.848008 -403.4028) (xy 430.131728 -403.4028)
			(xy 430.121607 -403.402361) (xy 430.102904 -403.394622) (xy 430.088589 -403.380313) (xy 430.080843 -403.361613)
			(xy 430.08042 -403.351492) (xy 430.08042 -403.194012) (xy 430.079999 -403.184826) (xy 430.073492 -403.167642)
			(xy 430.06772 -403.160484) (xy 430.045808 -403.134858) (xy 430.00772 -403.079218) (xy 429.97657 -403.019417)
			(xy 429.952807 -402.956315) (xy 429.936775 -402.890821) (xy 429.928702 -402.823878) (xy 426.650658 -402.823878)
			(xy 426.642626 -402.890635) (xy 426.626657 -402.956015) (xy 426.602989 -403.019017) (xy 426.571959 -403.078739)
			(xy 426.534014 -403.134324) (xy 426.512228 -403.159976) (xy 426.506408 -403.167104) (xy 426.499909 -403.184308)
			(xy 426.499528 -403.193504) (xy 426.499528 -403.351492) (xy 426.499072 -403.361642) (xy 426.491285 -403.380389)
			(xy 426.476899 -403.394712) (xy 426.458118 -403.402417) (xy 426.447966 -403.4028) (xy 425.731686 -403.4028)
			(xy 425.721563 -403.402286) (xy 425.70285 -403.394561) (xy 425.688495 -403.380284) (xy 425.68067 -403.361612)
			(xy 425.680124 -403.351492) (xy 425.680124 -403.193504) (xy 425.679707 -403.184318) (xy 425.673198 -403.167133)
			(xy 425.667424 -403.159976) (xy 425.64559 -403.134362) (xy 425.607643 -403.07877) (xy 425.576613 -403.019041)
			(xy 425.552943 -402.956032) (xy 425.536974 -402.890645) (xy 425.528934 -402.823818) (xy 422.250874 -402.823818)
			(xy 422.250874 -402.823874) (xy 422.242803 -402.890808) (xy 422.226774 -402.956294) (xy 422.203016 -403.019389)
			(xy 422.171873 -403.079184) (xy 422.133792 -403.134818) (xy 422.111932 -403.160484) (xy 422.106109 -403.16761)
			(xy 422.099612 -403.184816) (xy 422.099232 -403.194012) (xy 422.099232 -403.351492) (xy 422.098709 -403.361596)
			(xy 422.09098 -403.380268) (xy 422.076695 -403.394562) (xy 422.058028 -403.402303) (xy 422.047924 -403.4028)
			(xy 421.331644 -403.4028) (xy 421.321524 -403.402348) (xy 421.302822 -403.394614) (xy 421.288506 -403.380308)
			(xy 421.280759 -403.361611) (xy 421.280336 -403.351492) (xy 421.280336 -403.194012) (xy 421.279912 -403.184826)
			(xy 421.273407 -403.167642) (xy 421.267636 -403.160484) (xy 421.245724 -403.134858) (xy 421.207634 -403.079219)
			(xy 421.176483 -403.019418) (xy 421.15272 -402.956315) (xy 421.136687 -402.890821) (xy 421.128614 -402.823878)
			(xy 414.525968 -402.823878) (xy 414.525968 -405.623649) (xy 418.929012 -405.623649) (xy 418.929013 -405.556342)
			(xy 418.937058 -405.489518) (xy 418.953033 -405.424135) (xy 418.976709 -405.36113) (xy 419.007746 -405.301407)
			(xy 419.045698 -405.245822) (xy 419.067488 -405.22017) (xy 419.073278 -405.21302) (xy 419.079797 -405.195833)
			(xy 419.080188 -405.186642) (xy 419.080188 -404.693374) (xy 419.079793 -404.684185) (xy 419.073269 -404.667001)
			(xy 419.067488 -404.659846) (xy 419.04572 -404.634177) (xy 419.007768 -404.578594) (xy 418.976731 -404.518873)
			(xy 418.953055 -404.455871) (xy 418.937079 -404.39049) (xy 418.929032 -404.323669) (xy 418.92903 -404.256364)
			(xy 418.937073 -404.189542) (xy 418.953045 -404.124161) (xy 418.976717 -404.061157) (xy 419.007751 -404.001435)
			(xy 419.0457 -403.945849) (xy 419.067488 -403.920198) (xy 419.073267 -403.91304) (xy 419.079792 -403.895859)
			(xy 419.080188 -403.88667) (xy 419.080188 -403.728682) (xy 419.08055 -403.718503) (xy 419.088351 -403.699698)
			(xy 419.102756 -403.685313) (xy 419.12157 -403.677537) (xy 419.13175 -403.67712) (xy 419.84803 -403.67712)
			(xy 419.858187 -403.677608) (xy 419.876954 -403.685389) (xy 419.891317 -403.699756) (xy 419.899094 -403.718524)
			(xy 419.899592 -403.728682) (xy 419.899592 -403.88667) (xy 419.900018 -403.895855) (xy 419.906521 -403.91304)
			(xy 419.912292 -403.920198) (xy 419.9341 -403.945833) (xy 419.972047 -404.001422) (xy 420.003077 -404.061149)
			(xy 420.026747 -404.124155) (xy 420.042718 -404.189539) (xy 420.05076 -404.256363) (xy 420.050758 -404.32367)
			(xy 420.042712 -404.390493) (xy 420.026738 -404.455876) (xy 420.003064 -404.518882) (xy 419.97203 -404.578606)
			(xy 419.93408 -404.634193) (xy 419.912292 -404.659846) (xy 419.906492 -404.666989) (xy 419.89998 -404.684181)
			(xy 419.899592 -404.693374) (xy 419.899592 -405.186642) (xy 419.899984 -405.195831) (xy 419.90651 -405.213015)
			(xy 419.912292 -405.22017) (xy 419.934073 -405.245827) (xy 419.97202 -405.301414) (xy 420.003052 -405.361137)
			(xy 420.026723 -405.424141) (xy 420.042696 -405.489522) (xy 420.05074 -405.556343) (xy 420.050741 -405.623647)
			(xy 420.042698 -405.690469) (xy 420.026726 -405.755851) (xy 420.003055 -405.818855) (xy 419.972025 -405.878578)
			(xy 419.934078 -405.934165) (xy 419.912292 -405.959818) (xy 419.906504 -405.96697) (xy 419.899985 -405.984155)
			(xy 419.899592 -405.993346) (xy 419.899592 -406.151334) (xy 419.899095 -406.16149) (xy 419.891315 -406.180254)
			(xy 419.876951 -406.194617) (xy 419.858186 -406.202396) (xy 419.84803 -406.202896) (xy 419.13175 -406.202896)
			(xy 419.121586 -406.202396) (xy 419.102799 -406.194634) (xy 419.088413 -406.180272) (xy 419.08062 -406.161497)
			(xy 419.080188 -406.151334) (xy 419.080188 -405.993346) (xy 419.079759 -405.984161) (xy 419.073259 -405.966976)
			(xy 419.067488 -405.959818) (xy 419.045693 -405.934171) (xy 419.007741 -405.878585) (xy 418.976705 -405.818861)
			(xy 418.953031 -405.755856) (xy 418.937057 -405.690473) (xy 418.929012 -405.623649) (xy 414.525968 -405.623649)
			(xy 414.525968 -406.723789) (xy 421.128626 -406.723789) (xy 421.128629 -406.656363) (xy 421.136708 -406.589421)
			(xy 421.152748 -406.52393) (xy 421.176518 -406.460832) (xy 421.207674 -406.401035) (xy 421.245769 -406.345401)
			(xy 421.267636 -406.319736) (xy 421.273447 -406.312601) (xy 421.279952 -406.295403) (xy 421.280336 -406.286208)
			(xy 421.280336 -405.793956) (xy 421.279939 -405.784768) (xy 421.273415 -405.767584) (xy 421.267636 -405.760428)
			(xy 421.245767 -405.734767) (xy 421.207676 -405.679132) (xy 421.176523 -405.619336) (xy 421.152758 -405.556239)
			(xy 421.136722 -405.490749) (xy 421.128645 -405.423809) (xy 421.128646 -405.356385) (xy 421.136723 -405.289445)
			(xy 421.15276 -405.223956) (xy 421.176526 -405.160859) (xy 421.207679 -405.101062) (xy 421.245771 -405.045429)
			(xy 421.267636 -405.019764) (xy 421.273435 -405.012621) (xy 421.279947 -404.995429) (xy 421.280336 -404.986236)
			(xy 421.280336 -404.828756) (xy 421.28075 -404.81864) (xy 421.288509 -404.799954) (xy 421.302828 -404.785659)
			(xy 421.321527 -404.777933) (xy 421.331644 -404.777448) (xy 422.047924 -404.777448) (xy 422.058028 -404.777964)
			(xy 422.076697 -404.7857) (xy 422.090989 -404.799986) (xy 422.098732 -404.818652) (xy 422.099232 -404.828756)
			(xy 422.099232 -404.986236) (xy 422.09964 -404.995423) (xy 422.106157 -405.012607) (xy 422.111932 -405.019764)
			(xy 422.133791 -405.045433) (xy 422.171878 -405.101068) (xy 422.203027 -405.160864) (xy 422.22679 -405.22396)
			(xy 422.242825 -405.289448) (xy 422.2509 -405.356386) (xy 422.250901 -405.423808) (xy 422.242826 -405.490746)
			(xy 422.226792 -405.556234) (xy 422.203029 -405.619331) (xy 422.20075 -405.623707) (xy 423.328805 -405.623707)
			(xy 423.328805 -405.556284) (xy 423.336882 -405.489345) (xy 423.352917 -405.423856) (xy 423.376681 -405.360759)
			(xy 423.407832 -405.300962) (xy 423.44592 -405.245328) (xy 423.467784 -405.219662) (xy 423.473577 -405.212514)
			(xy 423.480094 -405.195326) (xy 423.480484 -405.186134) (xy 423.480484 -404.693882) (xy 423.480086 -404.684693)
			(xy 423.473564 -404.667509) (xy 423.467784 -404.660354) (xy 423.445942 -404.634671) (xy 423.407854 -404.579038)
			(xy 423.376703 -404.519245) (xy 423.352938 -404.45615) (xy 423.336902 -404.390663) (xy 423.328825 -404.323727)
			(xy 423.328823 -404.256306) (xy 423.336896 -404.189369) (xy 423.352929 -404.123882) (xy 423.37669 -404.060786)
			(xy 423.407837 -404.00099) (xy 423.445922 -403.945355) (xy 423.467784 -403.91969) (xy 423.473565 -403.912534)
			(xy 423.48009 -403.895352) (xy 423.480484 -403.886162) (xy 423.480484 -403.728682) (xy 423.480913 -403.718549)
			(xy 423.488655 -403.699819) (xy 423.502959 -403.685461) (xy 423.521661 -403.677651) (xy 423.531792 -403.67712)
			(xy 424.248072 -403.67712) (xy 424.258227 -403.677545) (xy 424.276983 -403.685335) (xy 424.291308 -403.699731)
			(xy 424.299005 -403.718525) (xy 424.29938 -403.728682) (xy 424.29938 -403.886162) (xy 424.299813 -403.895347)
			(xy 424.306311 -403.912531) (xy 424.31208 -403.91969) (xy 424.333966 -403.945337) (xy 424.372056 -404.000974)
			(xy 424.403207 -404.060772) (xy 424.42697 -404.123872) (xy 424.443005 -404.189363) (xy 424.451079 -404.256304)
			(xy 424.451077 -404.323729) (xy 424.442999 -404.39067) (xy 424.426961 -404.45616) (xy 424.403193 -404.519258)
			(xy 424.372039 -404.579055) (xy 424.333946 -404.634689) (xy 424.31208 -404.660354) (xy 424.306276 -404.667494)
			(xy 424.299766 -404.684688) (xy 424.29938 -404.693882) (xy 424.29938 -405.186134) (xy 424.299778 -405.195322)
			(xy 424.306301 -405.212506) (xy 424.31208 -405.219662) (xy 424.333939 -405.245332) (xy 424.372029 -405.300965)
			(xy 424.403181 -405.360761) (xy 424.426946 -405.423857) (xy 424.442983 -405.489346) (xy 424.45106 -405.556284)
			(xy 424.45106 -405.623707) (xy 424.442985 -405.690646) (xy 424.426949 -405.756134) (xy 424.403185 -405.819231)
			(xy 424.372034 -405.879027) (xy 424.333944 -405.934661) (xy 424.31208 -405.960326) (xy 424.306288 -405.967474)
			(xy 424.299771 -405.984662) (xy 424.29938 -405.993854) (xy 424.29938 -406.151334) (xy 424.298902 -406.16146)
			(xy 424.291167 -406.180179) (xy 424.276878 -406.194533) (xy 424.258196 -406.202355) (xy 424.248072 -406.202896)
			(xy 423.531792 -406.202896) (xy 423.521637 -406.202485) (xy 423.502884 -406.194686) (xy 423.48856 -406.180286)
			(xy 423.480862 -406.161491) (xy 423.480484 -406.151334) (xy 423.480484 -405.993854) (xy 423.480051 -405.984669)
			(xy 423.473553 -405.967484) (xy 423.467784 -405.960326) (xy 423.445915 -405.934665) (xy 423.407827 -405.87903)
			(xy 423.376678 -405.819233) (xy 423.352915 -405.756135) (xy 423.33688 -405.690646) (xy 423.328805 -405.623707)
			(xy 422.20075 -405.623707) (xy 422.171881 -405.679127) (xy 422.133795 -405.734762) (xy 422.111932 -405.760428)
			(xy 422.106133 -405.767571) (xy 422.099622 -405.784763) (xy 422.099232 -405.793956) (xy 422.099232 -406.286208)
			(xy 422.099654 -406.295394) (xy 422.106161 -406.312577) (xy 422.111932 -406.319736) (xy 422.133763 -406.345428)
			(xy 422.171851 -406.401059) (xy 422.203001 -406.460852) (xy 422.226766 -406.523945) (xy 422.242803 -406.589431)
			(xy 422.250881 -406.656366) (xy 422.250883 -406.72373) (xy 425.528945 -406.72373) (xy 425.528948 -406.656422)
			(xy 425.536995 -406.589598) (xy 425.552971 -406.524214) (xy 425.576647 -406.461208) (xy 425.607683 -406.401484)
			(xy 425.645635 -406.345896) (xy 425.667424 -406.320244) (xy 425.67323 -406.313105) (xy 425.679738 -406.29591)
			(xy 425.680124 -406.286716) (xy 425.680124 -405.793448) (xy 425.679685 -405.784264) (xy 425.673191 -405.76708)
			(xy 425.667424 -405.75992) (xy 425.645633 -405.734271) (xy 425.607685 -405.678684) (xy 425.576653 -405.61896)
			(xy 425.552981 -405.555955) (xy 425.537009 -405.490572) (xy 425.528965 -405.42375) (xy 425.528965 -405.356444)
			(xy 425.53701 -405.289622) (xy 425.552983 -405.22424) (xy 425.576655 -405.161235) (xy 425.607688 -405.101511)
			(xy 425.645636 -405.045924) (xy 425.667424 -405.020272) (xy 425.673218 -405.013125) (xy 425.679733 -404.995936)
			(xy 425.680124 -404.986744) (xy 425.680124 -404.828756) (xy 425.680486 -404.818596) (xy 425.688301 -404.799838)
			(xy 425.702716 -404.785515) (xy 425.721523 -404.777822) (xy 425.731686 -404.777448) (xy 426.447966 -404.777448)
			(xy 426.458091 -404.777955) (xy 426.476813 -404.785673) (xy 426.491171 -404.799953) (xy 426.49899 -404.818633)
			(xy 426.499528 -404.828756) (xy 426.499528 -404.986744) (xy 426.499911 -404.995934) (xy 426.506443 -405.013119)
			(xy 426.512228 -405.020272) (xy 426.534013 -405.045927) (xy 426.571964 -405.101512) (xy 426.602999 -405.161235)
			(xy 426.626674 -405.224239) (xy 426.642648 -405.289622) (xy 426.650693 -405.356444) (xy 426.650693 -405.42375)
			(xy 426.642649 -405.490573) (xy 426.626675 -405.555955) (xy 426.603002 -405.618959) (xy 426.600565 -405.623649)
			(xy 427.7291 -405.623649) (xy 427.729101 -405.556342) (xy 427.737146 -405.489519) (xy 427.753121 -405.424136)
			(xy 427.776796 -405.361131) (xy 427.807831 -405.301408) (xy 427.845783 -405.245822) (xy 427.867572 -405.22017)
			(xy 427.873373 -405.213028) (xy 427.879883 -405.195835) (xy 427.880272 -405.186642) (xy 427.880272 -404.693374)
			(xy 427.879881 -404.684185) (xy 427.873355 -404.667) (xy 427.867572 -404.659846) (xy 427.845805 -404.634176)
			(xy 427.807853 -404.578593) (xy 427.776817 -404.518872) (xy 427.753142 -404.45587) (xy 427.737166 -404.39049)
			(xy 427.72912 -404.323668) (xy 427.729118 -404.256365) (xy 427.73716 -404.189543) (xy 427.753132 -404.124162)
			(xy 427.776804 -404.061158) (xy 427.807836 -404.001435) (xy 427.845785 -403.94585) (xy 427.867572 -403.920198)
			(xy 427.873361 -403.913048) (xy 427.879878 -403.895861) (xy 427.880272 -403.88667) (xy 427.880272 -403.728682)
			(xy 427.88065 -403.718505) (xy 427.888447 -403.699703) (xy 427.902847 -403.685318) (xy 427.921657 -403.67754)
			(xy 427.931834 -403.67712) (xy 428.648114 -403.67712) (xy 428.65827 -403.677622) (xy 428.677036 -403.685397)
			(xy 428.6914 -403.69976) (xy 428.699178 -403.718526) (xy 428.699676 -403.728682) (xy 428.699676 -403.88667)
			(xy 428.700106 -403.895855) (xy 428.706607 -403.913039) (xy 428.712376 -403.920198) (xy 428.734185 -403.945833)
			(xy 428.772132 -404.001422) (xy 428.803164 -404.061148) (xy 428.826835 -404.124155) (xy 428.842806 -404.189539)
			(xy 428.850848 -404.256363) (xy 428.850846 -404.32367) (xy 428.8428 -404.390494) (xy 428.826825 -404.455877)
			(xy 428.80315 -404.518882) (xy 428.772115 -404.578607) (xy 428.734165 -404.634194) (xy 428.712376 -404.659846)
			(xy 428.706575 -404.666988) (xy 428.700064 -404.684181) (xy 428.699676 -404.693374) (xy 428.699676 -405.186642)
			(xy 428.700071 -405.195831) (xy 428.706596 -405.213015) (xy 428.712376 -405.22017) (xy 428.734157 -405.245827)
			(xy 428.772106 -405.301413) (xy 428.803138 -405.361136) (xy 428.826811 -405.42414) (xy 428.842784 -405.489522)
			(xy 428.850828 -405.556343) (xy 428.850829 -405.623648) (xy 428.842785 -405.69047) (xy 428.826813 -405.755851)
			(xy 428.803142 -405.818856) (xy 428.77211 -405.878579) (xy 428.734163 -405.934166) (xy 428.712376 -405.959818)
			(xy 428.706587 -405.966968) (xy 428.700068 -405.984155) (xy 428.699676 -405.993346) (xy 428.699676 -406.151334)
			(xy 428.699195 -406.161492) (xy 428.691412 -406.180259) (xy 428.677043 -406.194623) (xy 428.658272 -406.202399)
			(xy 428.648114 -406.202896) (xy 427.931834 -406.202896) (xy 427.921683 -406.202339) (xy 427.902921 -406.194583)
			(xy 427.888556 -406.180236) (xy 427.880774 -406.161485) (xy 427.880272 -406.151334) (xy 427.880272 -405.993346)
			(xy 427.879846 -405.98416) (xy 427.873344 -405.966976) (xy 427.867572 -405.959818) (xy 427.845777 -405.934171)
			(xy 427.807827 -405.878585) (xy 427.776792 -405.818861) (xy 427.753118 -405.755855) (xy 427.737144 -405.690472)
			(xy 427.7291 -405.623649) (xy 426.600565 -405.623649) (xy 426.571967 -405.678683) (xy 426.534016 -405.734268)
			(xy 426.512228 -405.75992) (xy 426.506432 -405.767065) (xy 426.499919 -405.784256) (xy 426.499528 -405.793448)
			(xy 426.499528 -406.286716) (xy 426.499924 -406.295905) (xy 426.506447 -406.313089) (xy 426.512228 -406.320244)
			(xy 426.533985 -406.345922) (xy 426.571937 -406.401504) (xy 426.602974 -406.461223) (xy 426.62665 -406.524225)
			(xy 426.642626 -406.589604) (xy 426.650673 -406.656424) (xy 426.650676 -406.723728) (xy 426.650669 -406.723789)
			(xy 429.928714 -406.723789) (xy 429.928717 -406.656363) (xy 429.936796 -406.589422) (xy 429.952835 -406.523931)
			(xy 429.976604 -406.460832) (xy 430.00776 -406.401036) (xy 430.045853 -406.345401) (xy 430.06772 -406.319736)
			(xy 430.073529 -406.312599) (xy 430.080035 -406.295402) (xy 430.08042 -406.286208) (xy 430.08042 -405.793956)
			(xy 430.080027 -405.784767) (xy 430.073501 -405.767583) (xy 430.06772 -405.760428) (xy 430.045851 -405.734766)
			(xy 430.007761 -405.679132) (xy 429.97661 -405.619335) (xy 429.952845 -405.556238) (xy 429.936809 -405.490748)
			(xy 429.928733 -405.423809) (xy 429.928734 -405.356385) (xy 429.93681 -405.289446) (xy 429.952847 -405.223956)
			(xy 429.976612 -405.160859) (xy 430.007765 -405.101063) (xy 430.045855 -405.045429) (xy 430.06772 -405.019764)
			(xy 430.073517 -405.012619) (xy 430.080031 -404.995428) (xy 430.08042 -404.986236) (xy 430.08042 -404.828756)
			(xy 430.08085 -404.818642) (xy 430.088605 -404.799959) (xy 430.102919 -404.785665) (xy 430.121613 -404.777935)
			(xy 430.131728 -404.777448) (xy 430.848008 -404.777448) (xy 430.858111 -404.777977) (xy 430.876779 -404.785708)
			(xy 430.891072 -404.799991) (xy 430.898815 -404.818654) (xy 430.899316 -404.828756) (xy 430.899316 -404.986236)
			(xy 430.899705 -404.995425) (xy 430.906233 -405.01261) (xy 430.912016 -405.019764) (xy 430.933875 -405.045433)
			(xy 430.971963 -405.101067) (xy 431.003113 -405.160863) (xy 431.026877 -405.223959) (xy 431.042912 -405.289448)
			(xy 431.050988 -405.356385) (xy 431.050989 -405.423809) (xy 431.042913 -405.490746) (xy 431.026879 -405.556235)
			(xy 431.003116 -405.619331) (xy 431.000867 -405.623648) (xy 432.128891 -405.623648) (xy 432.128892 -405.556343)
			(xy 432.136937 -405.489519) (xy 432.152911 -405.424136) (xy 432.176585 -405.361132) (xy 432.207621 -405.301408)
			(xy 432.245571 -405.245822) (xy 432.26736 -405.22017) (xy 432.273159 -405.213027) (xy 432.279671 -405.195835)
			(xy 432.28006 -405.186642) (xy 432.28006 -404.693374) (xy 432.279649 -404.684187) (xy 432.273134 -404.667004)
			(xy 432.26736 -404.659846) (xy 432.245593 -404.634176) (xy 432.207643 -404.578593) (xy 432.176607 -404.518872)
			(xy 432.152932 -404.45587) (xy 432.136957 -404.390489) (xy 432.128911 -404.323668) (xy 432.128909 -404.256365)
			(xy 432.136951 -404.189543) (xy 432.152922 -404.124162) (xy 432.176594 -404.061158) (xy 432.207626 -404.001436)
			(xy 432.245573 -403.94585) (xy 432.26736 -403.920198) (xy 432.273147 -403.913047) (xy 432.279666 -403.895861)
			(xy 432.28006 -403.88667) (xy 432.28006 -403.728682) (xy 432.28045 -403.718507) (xy 432.288245 -403.699707)
			(xy 432.302641 -403.685322) (xy 432.321446 -403.677542) (xy 432.331622 -403.67712) (xy 433.047902 -403.67712)
			(xy 433.058058 -403.677631) (xy 433.076823 -403.685403) (xy 433.091188 -403.699763) (xy 433.098965 -403.718526)
			(xy 433.099464 -403.728682) (xy 433.099464 -403.88667) (xy 433.099897 -403.895855) (xy 433.106396 -403.913039)
			(xy 433.112164 -403.920198) (xy 433.133973 -403.945832) (xy 433.171921 -404.001421) (xy 433.202954 -404.061147)
			(xy 433.226625 -404.124154) (xy 433.242596 -404.189539) (xy 433.250639 -404.256363) (xy 433.250637 -404.32367)
			(xy 433.24259 -404.390494) (xy 433.226615 -404.455877) (xy 433.20294 -404.518883) (xy 433.171904 -404.578607)
			(xy 433.133953 -404.634194) (xy 433.112164 -404.659846) (xy 433.106361 -404.666986) (xy 433.099851 -404.684181)
			(xy 433.099464 -404.693374) (xy 433.099464 -405.186642) (xy 433.099862 -405.19583) (xy 433.106385 -405.213014)
			(xy 433.112164 -405.22017) (xy 433.133946 -405.245827) (xy 433.171895 -405.301413) (xy 433.202928 -405.361136)
			(xy 433.226601 -405.42414) (xy 433.242574 -405.489521) (xy 433.250619 -405.556343) (xy 433.250619 -405.623648)
			(xy 433.242576 -405.69047) (xy 433.226604 -405.755852) (xy 433.202932 -405.818856) (xy 433.171899 -405.878579)
			(xy 433.133951 -405.934166) (xy 433.112164 -405.959818) (xy 433.106373 -405.966967) (xy 433.099856 -405.984155)
			(xy 433.099464 -405.993346) (xy 433.099464 -406.151334) (xy 433.098995 -406.161494) (xy 433.091209 -406.180263)
			(xy 433.076836 -406.194627) (xy 433.058062 -406.202401) (xy 433.047902 -406.202896) (xy 432.331622 -406.202896)
			(xy 432.32147 -406.20235) (xy 432.302708 -406.194589) (xy 432.288343 -406.180239) (xy 432.280561 -406.161486)
			(xy 432.28006 -406.151334) (xy 432.28006 -405.993346) (xy 432.279614 -405.984163) (xy 432.273124 -405.966979)
			(xy 432.26736 -405.959818) (xy 432.245566 -405.934171) (xy 432.207616 -405.878584) (xy 432.176582 -405.81886)
			(xy 432.152908 -405.755855) (xy 432.136935 -405.690472) (xy 432.128891 -405.623648) (xy 431.000867 -405.623648)
			(xy 430.971966 -405.679128) (xy 430.933879 -405.734762) (xy 430.912016 -405.760428) (xy 430.906227 -405.767579)
			(xy 430.899707 -405.784765) (xy 430.899316 -405.793956) (xy 430.899316 -406.286208) (xy 430.899719 -406.295396)
			(xy 430.906237 -406.31258) (xy 430.912016 -406.319736) (xy 430.933848 -406.345427) (xy 430.971937 -406.401059)
			(xy 431.003088 -406.460851) (xy 431.026853 -406.523945) (xy 431.04289 -406.58943) (xy 431.050968 -406.656366)
			(xy 431.050971 -406.723729) (xy 434.329033 -406.723729) (xy 434.329036 -406.656422) (xy 434.337083 -406.589598)
			(xy 434.353058 -406.524215) (xy 434.376733 -406.461209) (xy 434.407769 -406.401484) (xy 434.445719 -406.345897)
			(xy 434.467508 -406.320244) (xy 434.473312 -406.313104) (xy 434.479822 -406.295909) (xy 434.480208 -406.286716)
			(xy 434.480208 -405.793448) (xy 434.479773 -405.784263) (xy 434.473276 -405.767079) (xy 434.467508 -405.75992)
			(xy 434.445717 -405.734271) (xy 434.407771 -405.678683) (xy 434.376739 -405.618959) (xy 434.353068 -405.555954)
			(xy 434.337096 -405.490572) (xy 434.329053 -405.423749) (xy 434.329053 -405.356445) (xy 434.337097 -405.289622)
			(xy 434.35307 -405.22424) (xy 434.376742 -405.161236) (xy 434.407774 -405.101512) (xy 434.445721 -405.045925)
			(xy 434.467508 -405.020272) (xy 434.4733 -405.013124) (xy 434.479817 -404.995935) (xy 434.480208 -404.986744)
			(xy 434.480208 -404.828756) (xy 434.480586 -404.818598) (xy 434.488397 -404.799843) (xy 434.502807 -404.785521)
			(xy 434.52161 -404.777824) (xy 434.53177 -404.777448) (xy 435.24805 -404.777448) (xy 435.258175 -404.777968)
			(xy 435.276896 -404.785681) (xy 435.291254 -404.799957) (xy 435.299074 -404.818634) (xy 435.299612 -404.828756)
			(xy 435.299612 -404.986744) (xy 435.299998 -404.995934) (xy 435.306528 -405.013118) (xy 435.312312 -405.020272)
			(xy 435.334097 -405.045927) (xy 435.372049 -405.101512) (xy 435.403086 -405.161234) (xy 435.426761 -405.224239)
			(xy 435.442735 -405.289621) (xy 435.450781 -405.356444) (xy 435.450781 -405.42375) (xy 435.442736 -405.490573)
			(xy 435.426762 -405.555956) (xy 435.403088 -405.61896) (xy 435.372052 -405.678683) (xy 435.334101 -405.734269)
			(xy 435.312312 -405.75992) (xy 435.306526 -405.767073) (xy 435.300005 -405.784257) (xy 435.299612 -405.793448)
			(xy 435.299612 -406.286716) (xy 435.300012 -406.295904) (xy 435.306532 -406.313089) (xy 435.312312 -406.320244)
			(xy 435.33407 -406.345921) (xy 435.372023 -406.401503) (xy 435.40306 -406.461223) (xy 435.426737 -406.524224)
			(xy 435.442713 -406.589604) (xy 435.450761 -406.656424) (xy 435.450764 -406.723728) (xy 435.442722 -406.790549)
			(xy 435.426751 -406.85593) (xy 435.40308 -406.918933) (xy 435.372048 -406.978656) (xy 435.334099 -407.034241)
			(xy 435.312312 -407.059892) (xy 435.306538 -407.067053) (xy 435.300009 -407.084231) (xy 435.299612 -407.09342)
			(xy 435.299612 -407.251408) (xy 435.299185 -407.261561) (xy 435.291389 -407.280311) (xy 435.276994 -407.294634)
			(xy 435.258205 -407.302335) (xy 435.24805 -407.302716) (xy 434.53177 -407.302716) (xy 434.521636 -407.302297)
			(xy 434.502906 -407.294551) (xy 434.488549 -407.280244) (xy 434.480739 -407.26154) (xy 434.480208 -407.251408)
			(xy 434.480208 -407.09342) (xy 434.479786 -407.084234) (xy 434.47328 -407.06705) (xy 434.467508 -407.059892)
			(xy 434.44569 -407.034265) (xy 434.407744 -406.978674) (xy 434.376714 -406.918947) (xy 434.353044 -406.855939)
			(xy 434.337074 -406.790554) (xy 434.329033 -406.723729) (xy 431.050971 -406.723729) (xy 431.050971 -406.723786)
			(xy 431.042899 -406.790722) (xy 431.026867 -406.856209) (xy 431.003107 -406.919305) (xy 430.971961 -406.9791)
			(xy 430.933877 -407.034735) (xy 430.912016 -407.0604) (xy 430.906239 -407.067559) (xy 430.899712 -407.084739)
			(xy 430.899316 -407.093928) (xy 430.899316 -407.251408) (xy 430.898822 -407.261515) (xy 430.891084 -407.28019)
			(xy 430.87679 -407.294484) (xy 430.858115 -407.302222) (xy 430.848008 -407.302716) (xy 430.131728 -407.302716)
			(xy 430.121609 -407.302262) (xy 430.102909 -407.294526) (xy 430.088595 -407.280221) (xy 430.080845 -407.261526)
			(xy 430.08042 -407.251408) (xy 430.08042 -407.093928) (xy 430.079992 -407.084743) (xy 430.07349 -407.067559)
			(xy 430.06772 -407.0604) (xy 430.045824 -407.034761) (xy 430.007735 -406.979123) (xy 429.976584 -406.919324)
			(xy 429.952821 -406.856223) (xy 429.936787 -406.790731) (xy 429.928714 -406.723789) (xy 426.650669 -406.723789)
			(xy 426.642634 -406.790548) (xy 426.626664 -406.855929) (xy 426.602993 -406.918933) (xy 426.571962 -406.978655)
			(xy 426.534015 -407.03424) (xy 426.512228 -407.059892) (xy 426.506444 -407.067045) (xy 426.499924 -407.08423)
			(xy 426.499528 -407.09342) (xy 426.499528 -407.251408) (xy 426.499085 -407.261559) (xy 426.491292 -407.280306)
			(xy 426.476903 -407.294628) (xy 426.458119 -407.302333) (xy 426.447966 -407.302716) (xy 425.731686 -407.302716)
			(xy 425.721553 -407.302283) (xy 425.702823 -407.294543) (xy 425.688466 -407.28024) (xy 425.680655 -407.261539)
			(xy 425.680124 -407.251408) (xy 425.680124 -407.09342) (xy 425.679699 -407.084235) (xy 425.673195 -407.06705)
			(xy 425.667424 -407.059892) (xy 425.645605 -407.034266) (xy 425.607658 -406.978675) (xy 425.576627 -406.918948)
			(xy 425.552957 -406.85594) (xy 425.536987 -406.790555) (xy 425.528945 -406.72373) (xy 422.250883 -406.72373)
			(xy 422.250883 -406.723786) (xy 422.242811 -406.790722) (xy 422.22678 -406.856209) (xy 422.203021 -406.919304)
			(xy 422.171876 -406.9791) (xy 422.133793 -407.034734) (xy 422.111932 -407.0604) (xy 422.106145 -407.067551)
			(xy 422.099626 -407.084737) (xy 422.099232 -407.093928) (xy 422.099232 -407.251408) (xy 422.098722 -407.261513)
			(xy 422.090988 -407.280185) (xy 422.076699 -407.294479) (xy 422.058029 -407.302219) (xy 422.047924 -407.302716)
			(xy 421.331644 -407.302716) (xy 421.321526 -407.302248) (xy 421.302827 -407.294518) (xy 421.288512 -407.280217)
			(xy 421.280762 -407.261525) (xy 421.280336 -407.251408) (xy 421.280336 -407.093928) (xy 421.279904 -407.084743)
			(xy 421.273405 -407.067559) (xy 421.267636 -407.0604) (xy 421.245739 -407.034761) (xy 421.207649 -406.979124)
			(xy 421.176498 -406.919324) (xy 421.152734 -406.856224) (xy 421.1367 -406.790731) (xy 421.128626 -406.723789)
			(xy 414.525968 -406.723789) (xy 414.525968 -409.523827) (xy 418.928991 -409.523827) (xy 418.928995 -409.456519)
			(xy 418.937043 -409.389693) (xy 418.953021 -409.324308) (xy 418.9767 -409.261302) (xy 419.00774 -409.201577)
			(xy 419.045697 -409.145992) (xy 419.067488 -409.12034) (xy 419.073291 -409.113199) (xy 419.079802 -409.096005)
			(xy 419.080188 -409.086812) (xy 419.080188 -408.593544) (xy 419.079759 -408.584359) (xy 419.073259 -408.567174)
			(xy 419.067488 -408.560016) (xy 419.045691 -408.534371) (xy 419.007739 -408.478785) (xy 418.976704 -408.419061)
			(xy 418.953029 -408.356055) (xy 418.937055 -408.290671) (xy 418.929011 -408.223847) (xy 418.929012 -408.156541)
			(xy 418.937057 -408.089717) (xy 418.953033 -408.024333) (xy 418.976708 -407.961328) (xy 419.007745 -407.901605)
			(xy 419.045698 -407.84602) (xy 419.067488 -407.820368) (xy 419.073279 -407.813219) (xy 419.079797 -407.796031)
			(xy 419.080188 -407.78684) (xy 419.080188 -407.628852) (xy 419.080582 -407.618696) (xy 419.088391 -407.599945)
			(xy 419.102796 -407.585624) (xy 419.121592 -407.577924) (xy 419.13175 -407.577544) (xy 419.84803 -407.577544)
			(xy 419.858159 -407.578002) (xy 419.876882 -407.58574) (xy 419.891237 -407.600035) (xy 419.899055 -407.618725)
			(xy 419.899592 -407.628852) (xy 419.899592 -407.78684) (xy 419.899985 -407.796029) (xy 419.906511 -407.813213)
			(xy 419.912292 -407.820368) (xy 419.934071 -407.846027) (xy 419.972018 -407.901613) (xy 420.00305 -407.961336)
			(xy 420.026722 -408.02434) (xy 420.042694 -408.089721) (xy 420.050739 -408.156542) (xy 420.050739 -408.223846)
			(xy 420.042697 -408.290667) (xy 420.026725 -408.356049) (xy 420.003055 -408.419053) (xy 419.972024 -408.478776)
			(xy 419.934078 -408.534363) (xy 419.912292 -408.560016) (xy 419.906505 -408.567168) (xy 419.899985 -408.584353)
			(xy 419.899592 -408.593544) (xy 419.899592 -409.086812) (xy 419.899998 -409.096) (xy 419.906515 -409.113184)
			(xy 419.912292 -409.12034) (xy 419.934043 -409.146022) (xy 419.971991 -409.201605) (xy 420.003024 -409.261324)
			(xy 420.026698 -409.324325) (xy 420.042672 -409.389703) (xy 420.050719 -409.456522) (xy 420.050722 -409.523824)
			(xy 420.042682 -409.590643) (xy 420.026714 -409.656023) (xy 420.003047 -409.719026) (xy 419.972019 -409.778749)
			(xy 419.934077 -409.834336) (xy 419.912292 -409.859988) (xy 419.906475 -409.867118) (xy 419.899973 -409.88432)
			(xy 419.899592 -409.893516) (xy 419.899592 -410.051504) (xy 419.899181 -410.061659) (xy 419.891383 -410.080413)
			(xy 419.876983 -410.094737) (xy 419.858187 -410.102435) (xy 419.84803 -410.102812) (xy 419.13175 -410.102812)
			(xy 419.121633 -410.102234) (xy 419.102923 -410.094532) (xy 419.088567 -410.080274) (xy 419.080736 -410.061618)
			(xy 419.080188 -410.051504) (xy 419.080188 -409.893516) (xy 419.079773 -409.884329) (xy 419.073263 -409.867145)
			(xy 419.067488 -409.859988) (xy 419.045663 -409.834366) (xy 419.007713 -409.778776) (xy 418.976678 -409.719049)
			(xy 418.953005 -409.65604) (xy 418.937033 -409.590654) (xy 418.928991 -409.523827) (xy 414.525968 -409.523827)
			(xy 414.525968 -410.623701) (xy 421.128637 -410.623701) (xy 421.128638 -410.556275) (xy 421.136716 -410.489335)
			(xy 421.152755 -410.423845) (xy 421.176522 -410.360747) (xy 421.207677 -410.300951) (xy 421.24577 -410.245317)
			(xy 421.267636 -410.219652) (xy 421.27344 -410.212512) (xy 421.279949 -410.195317) (xy 421.280336 -410.186124)
			(xy 421.280336 -409.693872) (xy 421.279931 -409.684684) (xy 421.273413 -409.667501) (xy 421.267636 -409.660344)
			(xy 421.245783 -409.63467) (xy 421.207691 -409.579037) (xy 421.176538 -409.519243) (xy 421.152771 -409.456147)
			(xy 421.136734 -409.390659) (xy 421.128657 -409.323721) (xy 421.128656 -409.256297) (xy 421.136731 -409.189359)
			(xy 421.152766 -409.12387) (xy 421.176531 -409.060774) (xy 421.207682 -409.000978) (xy 421.245771 -408.945345)
			(xy 421.267636 -408.91968) (xy 421.273428 -408.912532) (xy 421.279945 -408.895343) (xy 421.280336 -408.886152)
			(xy 421.280336 -408.728672) (xy 421.280694 -408.718543) (xy 421.288458 -408.699832) (xy 421.302793 -408.685517)
			(xy 421.321515 -408.67778) (xy 421.331644 -408.677364) (xy 422.047924 -408.677364) (xy 422.05803 -408.677864)
			(xy 422.076702 -408.685603) (xy 422.090994 -408.699895) (xy 422.098735 -408.718566) (xy 422.099232 -408.728672)
			(xy 422.099232 -408.886152) (xy 422.09968 -408.895335) (xy 422.106169 -408.912519) (xy 422.111932 -408.91968)
			(xy 422.133807 -408.945336) (xy 422.171893 -409.000973) (xy 422.203041 -409.06077) (xy 422.226803 -409.123868)
			(xy 422.242837 -409.189358) (xy 422.250911 -409.256297) (xy 422.25091 -409.323721) (xy 422.242834 -409.39066)
			(xy 422.226798 -409.456149) (xy 422.203034 -409.519246) (xy 422.200617 -409.523886) (xy 423.328784 -409.523886)
			(xy 423.328787 -409.45646) (xy 423.336866 -409.389519) (xy 423.352905 -409.324029) (xy 423.376672 -409.26093)
			(xy 423.407826 -409.201133) (xy 423.445918 -409.145498) (xy 423.467784 -409.119832) (xy 423.47359 -409.112693)
			(xy 423.4801 -409.095498) (xy 423.480484 -409.086304) (xy 423.480484 -408.594052) (xy 423.480052 -408.584867)
			(xy 423.473554 -408.567682) (xy 423.467784 -408.560524) (xy 423.445913 -408.534865) (xy 423.407825 -408.479229)
			(xy 423.376676 -408.419432) (xy 423.352913 -408.356334) (xy 423.336878 -408.290845) (xy 423.328803 -408.223906)
			(xy 423.328804 -408.156482) (xy 423.336881 -408.089543) (xy 423.352916 -408.024054) (xy 423.376681 -407.960957)
			(xy 423.407832 -407.901161) (xy 423.44592 -407.845526) (xy 423.467784 -407.81986) (xy 423.473578 -407.812713)
			(xy 423.480095 -407.795524) (xy 423.480484 -407.786332) (xy 423.480484 -407.628852) (xy 423.480946 -407.618742)
			(xy 423.488696 -407.600066) (xy 423.503 -407.585774) (xy 423.521682 -407.578038) (xy 423.531792 -407.577544)
			(xy 424.248072 -407.577544) (xy 424.258172 -407.578106) (xy 424.276839 -407.585825) (xy 424.291133 -407.600097)
			(xy 424.298879 -407.618753) (xy 424.29938 -407.628852) (xy 424.29938 -407.786332) (xy 424.299779 -407.79552)
			(xy 424.306301 -407.812704) (xy 424.31208 -407.81986) (xy 424.333937 -407.845531) (xy 424.372027 -407.901165)
			(xy 424.403179 -407.96096) (xy 424.426945 -408.024056) (xy 424.442981 -408.089544) (xy 424.451058 -408.156482)
			(xy 424.451059 -408.223906) (xy 424.442984 -408.290844) (xy 424.426948 -408.356333) (xy 424.403184 -408.419429)
			(xy 424.372033 -408.479225) (xy 424.333944 -408.534859) (xy 424.31208 -408.560524) (xy 424.306288 -408.567673)
			(xy 424.299771 -408.584861) (xy 424.29938 -408.594052) (xy 424.29938 -409.086304) (xy 424.299792 -409.095491)
			(xy 424.306305 -409.112675) (xy 424.31208 -409.119832) (xy 424.333909 -409.145526) (xy 424.372 -409.201156)
			(xy 424.403154 -409.260948) (xy 424.426921 -409.324041) (xy 424.442959 -409.389527) (xy 424.451039 -409.456462)
			(xy 424.451042 -409.523884) (xy 424.442969 -409.59082) (xy 424.426937 -409.656307) (xy 424.403176 -409.719403)
			(xy 424.372028 -409.779198) (xy 424.333943 -409.834831) (xy 424.31208 -409.860496) (xy 424.3063 -409.867653)
			(xy 424.299776 -409.884835) (xy 424.29938 -409.894024) (xy 424.29938 -410.051504) (xy 424.298987 -410.061629)
			(xy 424.291234 -410.080337) (xy 424.27691 -410.094651) (xy 424.258197 -410.102393) (xy 424.248072 -410.102812)
			(xy 423.531792 -410.102812) (xy 423.521684 -410.102322) (xy 423.503008 -410.094584) (xy 423.488714 -410.080288)
			(xy 423.480978 -410.061612) (xy 423.480484 -410.051504) (xy 423.480484 -409.894024) (xy 423.480066 -409.884838)
			(xy 423.473558 -409.867653) (xy 423.467784 -409.860496) (xy 423.445885 -409.83486) (xy 423.407799 -409.779221)
			(xy 423.37665 -409.71942) (xy 423.352889 -409.65632) (xy 423.336856 -409.590827) (xy 423.328784 -409.523886)
			(xy 422.200617 -409.523886) (xy 422.171884 -409.579043) (xy 422.133796 -409.634678) (xy 422.111932 -409.660344)
			(xy 422.106126 -409.667482) (xy 422.099619 -409.684678) (xy 422.099232 -409.693872) (xy 422.099232 -410.186124)
			(xy 422.099646 -410.19531) (xy 422.106159 -410.212494) (xy 422.111932 -410.219652) (xy 422.133779 -410.245331)
			(xy 422.171866 -410.300964) (xy 422.203016 -410.360759) (xy 422.22678 -410.423854) (xy 422.242815 -410.489341)
			(xy 422.250892 -410.556277) (xy 422.250893 -410.623641) (xy 425.528957 -410.623641) (xy 425.528958 -410.556335)
			(xy 425.537003 -410.489512) (xy 425.552978 -410.424129) (xy 425.576652 -410.361123) (xy 425.607686 -410.301399)
			(xy 425.645636 -410.245812) (xy 425.667424 -410.22016) (xy 425.673223 -410.213017) (xy 425.679735 -410.195825)
			(xy 425.680124 -410.186632) (xy 425.680124 -409.693364) (xy 425.679726 -409.684176) (xy 425.673203 -409.666992)
			(xy 425.667424 -409.659836) (xy 425.645648 -409.634174) (xy 425.6077 -409.578589) (xy 425.576667 -409.518866)
			(xy 425.552994 -409.455863) (xy 425.537021 -409.390482) (xy 425.528976 -409.323661) (xy 425.528975 -409.256357)
			(xy 425.537018 -409.189536) (xy 425.552989 -409.124154) (xy 425.57666 -409.06115) (xy 425.607691 -409.001427)
			(xy 425.645637 -408.94584) (xy 425.667424 -408.920188) (xy 425.673211 -408.913036) (xy 425.679731 -408.895851)
			(xy 425.680124 -408.88666) (xy 425.680124 -408.728672) (xy 425.680499 -408.718513) (xy 425.688308 -408.699755)
			(xy 425.70272 -408.685432) (xy 425.721525 -408.677738) (xy 425.731686 -408.677364) (xy 426.447966 -408.677364)
			(xy 426.458093 -408.677855) (xy 426.476818 -408.685576) (xy 426.491177 -408.699862) (xy 426.498993 -408.718547)
			(xy 426.499528 -408.728672) (xy 426.499528 -408.88666) (xy 426.499951 -408.895846) (xy 426.506455 -408.913031)
			(xy 426.512228 -408.920188) (xy 426.534028 -408.94583) (xy 426.571979 -409.001417) (xy 426.603014 -409.061142)
			(xy 426.626687 -409.124148) (xy 426.64266 -409.189532) (xy 426.650704 -409.256356) (xy 426.650703 -409.323662)
			(xy 426.642657 -409.390486) (xy 426.626682 -409.45587) (xy 426.603006 -409.518875) (xy 426.600433 -409.523827)
			(xy 427.729079 -409.523827) (xy 427.729082 -409.456519) (xy 427.73713 -409.389693) (xy 427.753108 -409.324308)
			(xy 427.776786 -409.261302) (xy 427.807826 -409.201578) (xy 427.845781 -409.145992) (xy 427.867572 -409.12034)
			(xy 427.873385 -409.113207) (xy 427.879888 -409.096007) (xy 427.880272 -409.086812) (xy 427.880272 -408.593544)
			(xy 427.879847 -408.584358) (xy 427.873344 -408.567174) (xy 427.867572 -408.560016) (xy 427.845776 -408.534371)
			(xy 427.807825 -408.478784) (xy 427.77679 -408.41906) (xy 427.753116 -408.356054) (xy 427.737143 -408.290671)
			(xy 427.729099 -408.223847) (xy 427.7291 -408.156541) (xy 427.737145 -408.089717) (xy 427.75312 -408.024334)
			(xy 427.776795 -407.961329) (xy 427.807831 -407.901606) (xy 427.845783 -407.84602) (xy 427.867572 -407.820368)
			(xy 427.873373 -407.813227) (xy 427.879883 -407.796033) (xy 427.880272 -407.78684) (xy 427.880272 -407.628852)
			(xy 427.880682 -407.618698) (xy 427.888488 -407.59995) (xy 427.902887 -407.58563) (xy 427.921678 -407.577927)
			(xy 427.931834 -407.577544) (xy 428.648114 -407.577544) (xy 428.658242 -407.578015) (xy 428.676964 -407.585749)
			(xy 428.69132 -407.600039) (xy 428.699138 -407.618726) (xy 428.699676 -407.628852) (xy 428.699676 -407.78684)
			(xy 428.700072 -407.796029) (xy 428.706596 -407.813212) (xy 428.712376 -407.820368) (xy 428.734155 -407.846027)
			(xy 428.772104 -407.901613) (xy 428.803136 -407.961335) (xy 428.826809 -408.024339) (xy 428.842782 -408.08972)
			(xy 428.850827 -408.156542) (xy 428.850827 -408.223846) (xy 428.842784 -408.290668) (xy 428.826813 -408.356049)
			(xy 428.803141 -408.419054) (xy 428.77211 -408.478777) (xy 428.734163 -408.534364) (xy 428.712376 -408.560016)
			(xy 428.706587 -408.567167) (xy 428.700069 -408.584353) (xy 428.699676 -408.593544) (xy 428.699676 -409.086812)
			(xy 428.700086 -409.095999) (xy 428.7066 -409.113183) (xy 428.712376 -409.12034) (xy 428.734128 -409.146022)
			(xy 428.772077 -409.201604) (xy 428.803111 -409.261324) (xy 428.826785 -409.324324) (xy 428.84276 -409.389703)
			(xy 428.850806 -409.456522) (xy 428.85081 -409.523824) (xy 428.842769 -409.590644) (xy 428.826801 -409.656024)
			(xy 428.803133 -409.719027) (xy 428.772104 -409.778749) (xy 428.734161 -409.834335) (xy 428.712376 -409.859988)
			(xy 428.706557 -409.867117) (xy 428.700056 -409.88432) (xy 428.699676 -409.893516) (xy 428.699676 -410.051504)
			(xy 428.699281 -410.061661) (xy 428.69148 -410.080418) (xy 428.677074 -410.094742) (xy 428.658274 -410.102438)
			(xy 428.648114 -410.102812) (xy 427.931834 -410.102812) (xy 427.921716 -410.102247) (xy 427.903005 -410.09454)
			(xy 427.88865 -410.080278) (xy 427.88082 -410.061619) (xy 427.880272 -410.051504) (xy 427.880272 -409.893516)
			(xy 427.879861 -409.884329) (xy 427.873349 -409.867144) (xy 427.867572 -409.859988) (xy 427.845748 -409.834366)
			(xy 427.807798 -409.778776) (xy 427.776764 -409.719048) (xy 427.753092 -409.65604) (xy 427.73712 -409.590654)
			(xy 427.729079 -409.523827) (xy 426.600433 -409.523827) (xy 426.57197 -409.578598) (xy 426.534017 -409.634184)
			(xy 426.512228 -409.659836) (xy 426.506425 -409.666976) (xy 426.499916 -409.684171) (xy 426.499528 -409.693364)
			(xy 426.499528 -410.186632) (xy 426.499917 -410.195822) (xy 426.506445 -410.213006) (xy 426.512228 -410.22016)
			(xy 426.534001 -410.245825) (xy 426.571952 -410.301409) (xy 426.602988 -410.36113) (xy 426.626663 -410.424133)
			(xy 426.642638 -410.489514) (xy 426.650684 -410.556336) (xy 426.650686 -410.62364) (xy 426.650679 -410.623701)
			(xy 429.928725 -410.623701) (xy 429.928726 -410.556275) (xy 429.936804 -410.489336) (xy 429.952842 -410.423845)
			(xy 429.976609 -410.360748) (xy 430.007762 -410.300951) (xy 430.045854 -410.245317) (xy 430.06772 -410.219652)
			(xy 430.073522 -410.212511) (xy 430.080033 -410.195317) (xy 430.08042 -410.186124) (xy 430.08042 -409.693872)
			(xy 430.080019 -409.684684) (xy 430.073498 -409.6675) (xy 430.06772 -409.660344) (xy 430.045867 -409.634669)
			(xy 430.007777 -409.579037) (xy 429.976624 -409.519242) (xy 429.952859 -409.456146) (xy 429.936822 -409.390658)
			(xy 429.928745 -409.323721) (xy 429.928744 -409.256297) (xy 429.936819 -409.18936) (xy 429.952853 -409.123871)
			(xy 429.976617 -409.060775) (xy 430.007767 -409.000979) (xy 430.045856 -408.945345) (xy 430.06772 -408.91968)
			(xy 430.07351 -408.91253) (xy 430.080028 -408.895343) (xy 430.08042 -408.886152) (xy 430.08042 -408.728672)
			(xy 430.080863 -408.718559) (xy 430.088613 -408.699876) (xy 430.102923 -408.685582) (xy 430.121614 -408.677852)
			(xy 430.131728 -408.677364) (xy 430.848008 -408.677364) (xy 430.858113 -408.677878) (xy 430.876784 -408.685611)
			(xy 430.891077 -408.699899) (xy 430.898818 -408.718567) (xy 430.899316 -408.728672) (xy 430.899316 -408.886152)
			(xy 430.899745 -408.895337) (xy 430.906245 -408.912522) (xy 430.912016 -408.91968) (xy 430.933891 -408.945336)
			(xy 430.971979 -409.000972) (xy 431.003128 -409.06077) (xy 431.026891 -409.123868) (xy 431.042925 -409.189358)
			(xy 431.050999 -409.256297) (xy 431.050998 -409.323721) (xy 431.042922 -409.39066) (xy 431.026885 -409.456149)
			(xy 431.00312 -409.519247) (xy 431.000734 -409.523827) (xy 432.12887 -409.523827) (xy 432.128873 -409.456519)
			(xy 432.136921 -409.389693) (xy 432.152898 -409.324309) (xy 432.176576 -409.261303) (xy 432.207615 -409.201578)
			(xy 432.245569 -409.145992) (xy 432.26736 -409.12034) (xy 432.273172 -409.113206) (xy 432.279676 -409.096007)
			(xy 432.28006 -409.086812) (xy 432.28006 -408.593544) (xy 432.279615 -408.584361) (xy 432.273124 -408.567177)
			(xy 432.26736 -408.560016) (xy 432.245564 -408.53437) (xy 432.207614 -408.478784) (xy 432.17658 -408.419059)
			(xy 432.152907 -408.356054) (xy 432.136934 -408.290671) (xy 432.12889 -408.223847) (xy 432.128891 -408.156541)
			(xy 432.136936 -408.089717) (xy 432.15291 -408.024335) (xy 432.176585 -407.96133) (xy 432.20762 -407.901606)
			(xy 432.245571 -407.84602) (xy 432.26736 -407.820368) (xy 432.27316 -407.813226) (xy 432.279671 -407.796033)
			(xy 432.28006 -407.78684) (xy 432.28006 -407.628852) (xy 432.280482 -407.6187) (xy 432.288286 -407.599954)
			(xy 432.302681 -407.585634) (xy 432.321468 -407.577929) (xy 432.331622 -407.577544) (xy 433.047902 -407.577544)
			(xy 433.058029 -407.578025) (xy 433.076751 -407.585754) (xy 433.091108 -407.600042) (xy 433.098926 -407.618727)
			(xy 433.099464 -407.628852) (xy 433.099464 -407.78684) (xy 433.099863 -407.796028) (xy 433.106385 -407.813212)
			(xy 433.112164 -407.820368) (xy 433.133944 -407.846027) (xy 433.171893 -407.901612) (xy 433.202926 -407.961335)
			(xy 433.226599 -408.024339) (xy 433.242573 -408.08972) (xy 433.250618 -408.156542) (xy 433.250618 -408.223846)
			(xy 433.242575 -408.290668) (xy 433.226603 -408.35605) (xy 433.202931 -408.419054) (xy 433.171899 -408.478778)
			(xy 433.133951 -408.534364) (xy 433.112164 -408.560016) (xy 433.106374 -408.567165) (xy 433.099856 -408.584353)
			(xy 433.099464 -408.593544) (xy 433.099464 -409.086812) (xy 433.099876 -409.095999) (xy 433.106389 -409.113183)
			(xy 433.112164 -409.12034) (xy 433.133916 -409.146021) (xy 433.171866 -409.201604) (xy 433.2029 -409.261323)
			(xy 433.226575 -409.324324) (xy 433.24255 -409.389703) (xy 433.250597 -409.456522) (xy 433.250601 -409.523824)
			(xy 433.24256 -409.590644) (xy 433.226591 -409.656024) (xy 433.202922 -409.719027) (xy 433.171894 -409.77875)
			(xy 433.133949 -409.834336) (xy 433.112164 -409.859988) (xy 433.106343 -409.867116) (xy 433.099844 -409.88432)
			(xy 433.099464 -409.893516) (xy 433.099464 -410.051504) (xy 433.099081 -410.061663) (xy 433.091277 -410.080422)
			(xy 433.076868 -410.094747) (xy 433.058063 -410.10244) (xy 433.047902 -410.102812) (xy 432.331622 -410.102812)
			(xy 432.321503 -410.102257) (xy 432.302792 -410.094546) (xy 432.288437 -410.080281) (xy 432.280608 -410.06162)
			(xy 432.28006 -410.051504) (xy 432.28006 -409.893516) (xy 432.279629 -409.884331) (xy 432.273128 -409.867147)
			(xy 432.26736 -409.859988) (xy 432.245536 -409.834365) (xy 432.207587 -409.778775) (xy 432.176554 -409.719048)
			(xy 432.152882 -409.656039) (xy 432.136911 -409.590653) (xy 432.12887 -409.523827) (xy 431.000734 -409.523827)
			(xy 430.971969 -409.579043) (xy 430.93388 -409.634678) (xy 430.912016 -409.660344) (xy 430.90622 -409.66749)
			(xy 430.899705 -409.68468) (xy 430.899316 -409.693872) (xy 430.899316 -410.186124) (xy 430.899711 -410.195313)
			(xy 430.906235 -410.212497) (xy 430.912016 -410.219652) (xy 430.933864 -410.24533) (xy 430.971952 -410.300963)
			(xy 431.003102 -410.360758) (xy 431.026867 -410.423853) (xy 431.042903 -410.48934) (xy 431.05098 -410.556277)
			(xy 431.050981 -410.623641) (xy 434.329044 -410.623641) (xy 434.329046 -410.556335) (xy 434.337091 -410.489512)
			(xy 434.353065 -410.424129) (xy 434.376738 -410.361124) (xy 434.407772 -410.3014) (xy 434.44572 -410.245813)
			(xy 434.467508 -410.22016) (xy 434.473305 -410.213015) (xy 434.479819 -410.195824) (xy 434.480208 -410.186632)
			(xy 434.480208 -409.693364) (xy 434.479814 -409.684175) (xy 434.473289 -409.666991) (xy 434.467508 -409.659836)
			(xy 434.445733 -409.634174) (xy 434.407786 -409.578588) (xy 434.376754 -409.518866) (xy 434.353082 -409.455862)
			(xy 434.337109 -409.390482) (xy 434.329064 -409.323661) (xy 434.329063 -409.256357) (xy 434.337106 -409.189536)
			(xy 434.353076 -409.124155) (xy 434.376746 -409.061151) (xy 434.407777 -409.001427) (xy 434.445722 -408.945841)
			(xy 434.467508 -408.920188) (xy 434.473293 -408.913035) (xy 434.479814 -408.89585) (xy 434.480208 -408.88666)
			(xy 434.480208 -408.728672) (xy 434.480599 -408.718515) (xy 434.488405 -408.69976) (xy 434.502811 -408.685438)
			(xy 434.521611 -408.67774) (xy 434.53177 -408.677364) (xy 435.24805 -408.677364) (xy 435.258176 -408.677868)
			(xy 435.276901 -408.685584) (xy 435.29126 -408.699866) (xy 435.299077 -408.718548) (xy 435.299612 -408.728672)
			(xy 435.299612 -408.88666) (xy 435.300039 -408.895846) (xy 435.30654 -408.91303) (xy 435.312312 -408.920188)
			(xy 435.334113 -408.94583) (xy 435.372065 -409.001417) (xy 435.4031 -409.061141) (xy 435.426774 -409.124147)
			(xy 435.442748 -409.189531) (xy 435.450792 -409.256356) (xy 435.450791 -409.323662) (xy 435.442745 -409.390487)
			(xy 435.426769 -409.45587) (xy 435.403093 -409.518875) (xy 435.372055 -409.578599) (xy 435.334102 -409.634184)
			(xy 435.312312 -409.659836) (xy 435.306519 -409.666984) (xy 435.300002 -409.684172) (xy 435.299612 -409.693364)
			(xy 435.299612 -410.186632) (xy 435.300004 -410.195821) (xy 435.30653 -410.213006) (xy 435.312312 -410.22016)
			(xy 435.334085 -410.245824) (xy 435.372038 -410.301408) (xy 435.403075 -410.361129) (xy 435.42675 -410.424132)
			(xy 435.442726 -410.489514) (xy 435.450772 -410.556336) (xy 435.450774 -410.62364) (xy 435.44273 -410.690463)
			(xy 435.426758 -410.755845) (xy 435.403084 -410.818849) (xy 435.37205 -410.878571) (xy 435.3341 -410.934157)
			(xy 435.312312 -410.959808) (xy 435.306531 -410.966964) (xy 435.300007 -410.984146) (xy 435.299612 -410.993336)
			(xy 435.299612 -411.151324) (xy 435.299198 -411.161478) (xy 435.291397 -411.180229) (xy 435.276998 -411.194551)
			(xy 435.258206 -411.202252) (xy 435.24805 -411.202632) (xy 434.53177 -411.202632) (xy 434.521638 -411.202197)
			(xy 434.502911 -411.194454) (xy 434.488554 -411.180152) (xy 434.480741 -411.161454) (xy 434.480208 -411.151324)
			(xy 434.480208 -410.993336) (xy 434.479779 -410.984151) (xy 434.473278 -410.966966) (xy 434.467508 -410.959808)
			(xy 434.445706 -410.934168) (xy 434.407759 -410.878579) (xy 434.376728 -410.818854) (xy 434.353058 -410.755848)
			(xy 434.337087 -410.690464) (xy 434.329044 -410.623641) (xy 431.050981 -410.623641) (xy 431.050981 -410.623699)
			(xy 431.042907 -410.690636) (xy 431.026874 -410.756124) (xy 431.003112 -410.81922) (xy 430.971964 -410.879016)
			(xy 430.933878 -410.934651) (xy 430.912016 -410.960316) (xy 430.906232 -410.96747) (xy 430.899709 -410.984654)
			(xy 430.899316 -410.993844) (xy 430.899316 -411.151324) (xy 430.898835 -411.161432) (xy 430.891092 -411.180108)
			(xy 430.876795 -411.194401) (xy 430.858116 -411.202138) (xy 430.848008 -411.202632) (xy 430.131728 -411.202632)
			(xy 430.121611 -411.202162) (xy 430.102914 -411.194429) (xy 430.0886 -411.180129) (xy 430.080848 -411.16144)
			(xy 430.08042 -411.151324) (xy 430.08042 -410.993844) (xy 430.079984 -410.98466) (xy 430.073488 -410.967475)
			(xy 430.06772 -410.960316) (xy 430.04584 -410.934664) (xy 430.00775 -410.879028) (xy 429.976599 -410.81923)
			(xy 429.952835 -410.756132) (xy 429.9368 -410.690641) (xy 429.928725 -410.623701) (xy 426.650679 -410.623701)
			(xy 426.642643 -410.690462) (xy 426.62667 -410.755844) (xy 426.602998 -410.818848) (xy 426.571965 -410.878571)
			(xy 426.534016 -410.934156) (xy 426.512228 -410.959808) (xy 426.506437 -410.966957) (xy 426.499921 -410.984145)
			(xy 426.499528 -410.993336) (xy 426.499528 -411.151324) (xy 426.499099 -411.161476) (xy 426.4913 -411.180224)
			(xy 426.476907 -411.194545) (xy 426.45812 -411.202249) (xy 426.447966 -411.202632) (xy 425.731686 -411.202632)
			(xy 425.721555 -411.202184) (xy 425.702828 -411.194446) (xy 425.688472 -411.180148) (xy 425.680658 -411.161453)
			(xy 425.680124 -411.151324) (xy 425.680124 -410.993336) (xy 425.679691 -410.984151) (xy 425.673193 -410.966967)
			(xy 425.667424 -410.959808) (xy 425.645621 -410.934169) (xy 425.607674 -410.87858) (xy 425.576642 -410.818855)
			(xy 425.552971 -410.755848) (xy 425.536999 -410.690465) (xy 425.528957 -410.623641) (xy 422.250893 -410.623641)
			(xy 422.250893 -410.623699) (xy 422.242819 -410.690635) (xy 422.226787 -410.756123) (xy 422.203026 -410.819219)
			(xy 422.171879 -410.879015) (xy 422.133794 -410.93465) (xy 422.111932 -410.960316) (xy 422.106138 -410.967463)
			(xy 422.099624 -410.984652) (xy 422.099232 -410.993844) (xy 422.099232 -411.151324) (xy 422.098735 -411.16143)
			(xy 422.090996 -411.180103) (xy 422.076703 -411.194396) (xy 422.05803 -411.202135) (xy 422.047924 -411.202632)
			(xy 421.331644 -411.202632) (xy 421.321528 -411.202149) (xy 421.302832 -411.194421) (xy 421.288517 -411.180125)
			(xy 421.280765 -411.161439) (xy 421.280336 -411.151324) (xy 421.280336 -410.993844) (xy 421.279896 -410.98466)
			(xy 421.273402 -410.967476) (xy 421.267636 -410.960316) (xy 421.245755 -410.934664) (xy 421.207664 -410.879029)
			(xy 421.176512 -410.819231) (xy 421.152748 -410.756132) (xy 421.136712 -410.690641) (xy 421.128637 -410.623701)
			(xy 414.525968 -410.623701) (xy 414.525968 -417.021264) (xy 414.527428 -417.030391) (xy 414.535946 -417.046779)
			(xy 414.54975 -417.059048) (xy 414.567024 -417.065584) (xy 414.57626 -417.065968) (xy 465.600034 -417.065968)
			(xy 465.631197 -417.065456) (xy 465.692989 -417.057317) (xy 465.75319 -417.041181) (xy 465.81077 -417.017326)
			(xy 465.864744 -416.98616) (xy 465.914188 -416.948215) (xy 465.958256 -416.904141) (xy 465.996194 -416.854692)
			(xy 466.027354 -416.800714) (xy 466.051201 -416.743131) (xy 466.067329 -416.682928) (xy 466.07546 -416.621135)
			(xy 466.07603 -416.589972) (xy 466.07603 -410.697426) (xy 466.075569 -410.686698) (xy 466.066825 -410.667107)
			(xy 466.050819 -410.652822) (xy 466.040724 -410.649166) (xy 465.93252 -410.614622) (xy 465.901278 -410.625036)
			(xy 465.891626 -410.638752) (xy 465.830771 -410.7238) (xy 465.703208 -410.889549) (xy 465.569155 -411.050095)
			(xy 465.428824 -411.205182) (xy 465.282437 -411.354567) (xy 465.130225 -411.498013) (xy 464.97243 -411.635292)
			(xy 464.809301 -411.766189) (xy 464.641095 -411.890494) (xy 464.46808 -412.008013) (xy 464.290528 -412.11856)
			(xy 464.108721 -412.221958) (xy 463.922947 -412.318045) (xy 463.733498 -412.406669) (xy 463.540675 -412.487689)
			(xy 463.344782 -412.560978) (xy 463.146131 -412.626419) (xy 462.945034 -412.683909) (xy 462.74181 -412.733357)
			(xy 462.536781 -412.774685) (xy 462.33027 -412.807827) (xy 462.122605 -412.832731) (xy 461.914114 -412.849358)
			(xy 461.705127 -412.85768) (xy 461.60055 -412.858204) (xy 461.600042 -412.858204) (xy 461.498066 -412.857716)
			(xy 461.294268 -412.84981) (xy 461.09093 -412.834007) (xy 460.888357 -412.810331) (xy 460.686855 -412.778818)
			(xy 460.486726 -412.739515) (xy 460.288272 -412.692482) (xy 460.091791 -412.637789) (xy 459.897578 -412.575519)
			(xy 459.705926 -412.505765) (xy 459.517123 -412.428631) (xy 459.331452 -412.344235) (xy 459.149194 -412.252703)
			(xy 458.970622 -412.154172) (xy 458.796005 -412.048792) (xy 458.625605 -411.936719) (xy 458.45968 -411.818124)
			(xy 458.298477 -411.693184) (xy 458.142241 -411.562087) (xy 457.991205 -411.425031) (xy 457.845598 -411.282221)
			(xy 457.705637 -411.133873) (xy 457.571534 -410.980209) (xy 457.44349 -410.82146) (xy 457.321698 -410.657867)
			(xy 457.206341 -410.489673) (xy 457.097593 -410.317133) (xy 456.995617 -410.140507) (xy 456.900566 -409.960058)
			(xy 456.812584 -409.77606) (xy 456.731803 -409.588789) (xy 456.658343 -409.398526) (xy 456.592317 -409.205558)
			(xy 456.533823 -409.010174) (xy 456.482949 -408.81267) (xy 456.439771 -408.613341) (xy 456.404355 -408.412488)
			(xy 456.376754 -408.210413) (xy 456.357009 -408.00742) (xy 456.34515 -407.803813) (xy 456.341195 -407.5999)
			(xy 456.34515 -407.395987) (xy 456.357009 -407.19238) (xy 456.376754 -406.989387) (xy 456.404355 -406.787312)
			(xy 456.439771 -406.586459) (xy 456.482949 -406.38713) (xy 456.533823 -406.189626) (xy 456.592317 -405.994242)
			(xy 456.658343 -405.801274) (xy 456.731803 -405.611011) (xy 456.812584 -405.42374) (xy 456.900566 -405.239742)
			(xy 456.995617 -405.059293) (xy 457.097593 -404.882667) (xy 457.206341 -404.710127) (xy 457.321698 -404.541933)
			(xy 457.44349 -404.37834) (xy 457.571534 -404.219591) (xy 457.705637 -404.065927) (xy 457.845598 -403.917579)
			(xy 457.991205 -403.774769) (xy 458.142241 -403.637713) (xy 458.298477 -403.506616) (xy 458.45968 -403.381676)
			(xy 458.625605 -403.263081) (xy 458.796005 -403.151008) (xy 458.970622 -403.045628) (xy 459.149194 -402.947097)
			(xy 459.331452 -402.855565) (xy 459.517123 -402.771169) (xy 459.705926 -402.694035) (xy 459.897578 -402.624281)
			(xy 460.091791 -402.562011) (xy 460.288272 -402.507318) (xy 460.486726 -402.460285) (xy 460.686855 -402.420982)
			(xy 460.888357 -402.389469) (xy 461.09093 -402.365793) (xy 461.294268 -402.34999) (xy 461.498066 -402.342084)
			(xy 461.600042 -402.341588) (xy 461.60055 -402.341588) (xy 461.705126 -402.342106) (xy 461.914113 -402.350433)
			(xy 462.122604 -402.367063) (xy 462.330269 -402.39197) (xy 462.536778 -402.425114) (xy 462.741807 -402.466444)
			(xy 462.94503 -402.515894) (xy 463.146126 -402.573385) (xy 463.344777 -402.638827) (xy 463.540669 -402.712117)
			(xy 463.733492 -402.793137) (xy 463.92294 -402.881761) (xy 464.108715 -402.977848) (xy 464.290522 -403.081246)
			(xy 464.468074 -403.191791) (xy 464.64109 -403.309309) (xy 464.809296 -403.433613) (xy 464.972426 -403.564508)
			(xy 465.130223 -403.701785) (xy 465.282436 -403.845229) (xy 465.428825 -403.994611) (xy 465.569159 -404.149696)
			(xy 465.703214 -404.310239) (xy 465.830781 -404.475985) (xy 465.891626 -404.56104) (xy 465.901278 -404.574756)
			(xy 465.93252 -404.58517) (xy 466.040724 -404.550626) (xy 466.050721 -404.546809) (xy 466.066638 -404.532543)
			(xy 466.075404 -404.51305) (xy 466.07603 -404.502366) (xy 466.07603 -367.551462) (xy 466.075536 -367.541457)
			(xy 466.067871 -367.522973) (xy 466.05372 -367.508825) (xy 466.035235 -367.501162) (xy 466.02523 -367.500662)
			(xy 452.507604 -367.500662) (xy 452.496172 -367.501293) (xy 452.475561 -367.511191) (xy 452.461267 -367.529037)
			(xy 452.458074 -367.540032) (xy 452.451516 -367.566194) (xy 452.43203 -367.616485) (xy 452.405654 -367.663531)
			(xy 452.372916 -367.706393) (xy 452.334468 -367.744217) (xy 452.291075 -367.776249) (xy 452.243604 -367.80185)
			(xy 452.193 -367.82051) (xy 452.140272 -367.831857) (xy 452.086472 -367.835665) (xy 452.032672 -367.831857)
			(xy 451.979944 -367.82051) (xy 451.92934 -367.80185) (xy 451.881869 -367.776249) (xy 451.838476 -367.744217)
			(xy 451.800028 -367.706393) (xy 451.76729 -367.663531) (xy 451.740914 -367.616485) (xy 451.721428 -367.566194)
			(xy 451.71487 -367.540032) (xy 451.711689 -367.529027) (xy 451.697401 -367.511162) (xy 451.676778 -367.501263)
			(xy 451.66534 -367.500662) (xy 406.004268 -367.500662) (xy 405.993768 -367.501181) (xy 405.974517 -367.509577)
			(xy 405.960218 -367.524958) (xy 405.956262 -367.534698) (xy 405.946606 -367.560634) (xy 405.920876 -367.609631)
			(xy 405.888338 -367.654397) (xy 405.849674 -367.693993) (xy 405.805696 -367.727588) (xy 405.757326 -367.754478)
			(xy 405.705579 -367.774098) (xy 405.65154 -367.786038) (xy 405.596344 -367.790045) (xy 405.541148 -367.786038)
			(xy 405.487109 -367.774098) (xy 405.435362 -367.754478) (xy 405.386992 -367.727588) (xy 405.343014 -367.693993)
			(xy 405.30435 -367.654397) (xy 405.271812 -367.609631) (xy 405.246082 -367.560634) (xy 405.236426 -367.534698)
			(xy 405.232478 -367.524948) (xy 405.218191 -367.509541) (xy 405.198927 -367.50115) (xy 405.18842 -367.500662)
			(xy 271.887442 -367.500662) (xy 271.881433 -367.50083) (xy 271.86975 -367.503653) (xy 271.864328 -367.50625)
			(xy 271.841012 -367.51782) (xy 271.791961 -367.535237) (xy 271.740998 -367.545818) (xy 271.689068 -367.549366)
			(xy 271.637138 -367.545818) (xy 271.586175 -367.535237) (xy 271.537124 -367.51782) (xy 271.513808 -367.50625)
			(xy 271.50822 -367.503456) (xy 271.49679 -367.500662) (xy 268.042898 -367.500662) (xy 268.032829 -367.501087)
			(xy 268.014231 -367.508809) (xy 268.00683 -367.515648) (xy 267.118338 -368.40414) (xy 267.10034 -368.421425)
			(xy 267.059957 -368.450735) (xy 267.015491 -368.473377) (xy 266.968034 -368.488792) (xy 266.918751 -368.496604)
			(xy 266.893802 -368.497104) (xy 266.75588 -368.497104) (xy 266.745812 -368.497531) (xy 266.727213 -368.505251)
			(xy 266.719812 -368.51209) (xy 266.501372 -368.73053) (xy 266.501372 -368.732308) (xy 266.501372 -370.523704)
			(xy 286.928752 -370.523704) (xy 286.928753 -370.456278) (xy 286.936831 -370.389338) (xy 286.952869 -370.323848)
			(xy 286.976637 -370.26075) (xy 287.007792 -370.200954) (xy 287.045885 -370.14532) (xy 287.067752 -370.119656)
			(xy 287.073556 -370.112516) (xy 287.080065 -370.095321) (xy 287.080452 -370.086128) (xy 287.080452 -369.928902)
			(xy 287.080929 -369.918774) (xy 287.088658 -369.900051) (xy 287.102947 -369.885694) (xy 287.121634 -369.877877)
			(xy 287.13176 -369.87734) (xy 287.84804 -369.87734) (xy 287.858202 -369.87769) (xy 287.876963 -369.885506)
			(xy 287.891286 -369.899925) (xy 287.898977 -369.918738) (xy 287.899348 -369.928902) (xy 287.899348 -370.086128)
			(xy 287.899756 -370.095315) (xy 287.906273 -370.112499) (xy 287.912048 -370.119656) (xy 287.933902 -370.14533)
			(xy 287.971994 -370.200962) (xy 288.003149 -370.260757) (xy 288.026916 -370.323852) (xy 288.042954 -370.389341)
			(xy 288.051031 -370.456279) (xy 288.051032 -370.523644) (xy 291.329071 -370.523644) (xy 291.329073 -370.456338)
			(xy 291.337118 -370.389515) (xy 291.353092 -370.324132) (xy 291.376766 -370.261127) (xy 291.407801 -370.201403)
			(xy 291.445751 -370.145816) (xy 291.46754 -370.120164) (xy 291.473339 -370.113021) (xy 291.479851 -370.095829)
			(xy 291.48024 -370.086636) (xy 291.48024 -369.928902) (xy 291.480665 -369.91873) (xy 291.48845 -369.899935)
			(xy 291.502835 -369.88555) (xy 291.52163 -369.877765) (xy 291.531802 -369.87734) (xy 292.248082 -369.87734)
			(xy 292.258253 -369.877778) (xy 292.277047 -369.885558) (xy 292.291433 -369.899939) (xy 292.299218 -369.918731)
			(xy 292.299644 -369.928902) (xy 292.299644 -370.086636) (xy 292.30005 -370.095823) (xy 292.306568 -370.113007)
			(xy 292.312344 -370.120164) (xy 292.33412 -370.145826) (xy 292.372071 -370.20141) (xy 292.403105 -370.261132)
			(xy 292.426779 -370.324136) (xy 292.442754 -370.389517) (xy 292.450799 -370.456339) (xy 292.4508 -370.523643)
			(xy 292.450793 -370.523704) (xy 295.72884 -370.523704) (xy 295.728841 -370.456278) (xy 295.736918 -370.389339)
			(xy 295.752956 -370.323848) (xy 295.776723 -370.260751) (xy 295.807878 -370.200955) (xy 295.84597 -370.145321)
			(xy 295.867836 -370.119656) (xy 295.873638 -370.112515) (xy 295.880149 -370.095321) (xy 295.880536 -370.086128)
			(xy 295.880536 -369.928902) (xy 295.881028 -369.918776) (xy 295.888755 -369.900056) (xy 295.903039 -369.885699)
			(xy 295.92172 -369.877879) (xy 295.931844 -369.87734) (xy 296.648124 -369.87734) (xy 296.658285 -369.877703)
			(xy 296.677045 -369.885514) (xy 296.691369 -369.899929) (xy 296.699061 -369.918739) (xy 296.699432 -369.928902)
			(xy 296.699432 -370.086128) (xy 296.699844 -370.095315) (xy 296.706358 -370.112498) (xy 296.712132 -370.119656)
			(xy 296.733983 -370.145332) (xy 296.77207 -370.200965) (xy 296.803219 -370.26076) (xy 296.826983 -370.323856)
			(xy 296.843018 -370.389343) (xy 296.851095 -370.45628) (xy 296.851096 -370.523702) (xy 296.851096 -370.523704)
			(xy 300.128631 -370.523704) (xy 300.128632 -370.456278) (xy 300.136709 -370.389339) (xy 300.152747 -370.323849)
			(xy 300.176513 -370.260751) (xy 300.207667 -370.200955) (xy 300.245758 -370.145321) (xy 300.267624 -370.119656)
			(xy 300.273425 -370.112514) (xy 300.279936 -370.095321) (xy 300.280324 -370.086128) (xy 300.280324 -369.928902)
			(xy 300.280828 -369.918777) (xy 300.288552 -369.900059) (xy 300.302833 -369.885704) (xy 300.32151 -369.877882)
			(xy 300.331632 -369.87734) (xy 301.047912 -369.87734) (xy 301.058072 -369.877712) (xy 301.076832 -369.885519)
			(xy 301.091157 -369.899932) (xy 301.098849 -369.91874) (xy 301.09922 -369.928902) (xy 301.09922 -370.086128)
			(xy 301.099612 -370.095317) (xy 301.106138 -370.112502) (xy 301.11192 -370.119656) (xy 301.133771 -370.145331)
			(xy 301.171859 -370.200965) (xy 301.203009 -370.26076) (xy 301.226773 -370.323855) (xy 301.242809 -370.389343)
			(xy 301.250886 -370.45628) (xy 301.250887 -370.523644) (xy 330.92919 -370.523644) (xy 330.929191 -370.456338)
			(xy 330.937237 -370.389514) (xy 330.953212 -370.324131) (xy 330.976887 -370.261126) (xy 331.007923 -370.201402)
			(xy 331.045875 -370.145816) (xy 331.067664 -370.120164) (xy 331.073466 -370.113023) (xy 331.079976 -370.095829)
			(xy 331.080364 -370.086636) (xy 331.080364 -369.928902) (xy 331.080766 -369.918727) (xy 331.088555 -369.899928)
			(xy 331.102948 -369.885542) (xy 331.121751 -369.877761) (xy 331.131926 -369.87734) (xy 331.848206 -369.87734)
			(xy 331.858364 -369.877829) (xy 331.877134 -369.885605) (xy 331.891499 -369.899973) (xy 331.899273 -369.918744)
			(xy 331.899768 -369.928902) (xy 331.899768 -370.086636) (xy 331.900168 -370.095824) (xy 331.90669 -370.113008)
			(xy 331.912468 -370.120164) (xy 331.934244 -370.145826) (xy 331.972193 -370.201411) (xy 332.003226 -370.261133)
			(xy 332.026899 -370.324137) (xy 332.042873 -370.389518) (xy 332.050918 -370.456339) (xy 332.050919 -370.523643)
			(xy 332.050912 -370.523703) (xy 335.328983 -370.523703) (xy 335.328984 -370.456279) (xy 335.33706 -370.389341)
			(xy 335.353096 -370.323852) (xy 335.376859 -370.260754) (xy 335.408009 -370.200957) (xy 335.446097 -370.145322)
			(xy 335.46796 -370.119656) (xy 335.473765 -370.112517) (xy 335.480273 -370.095322) (xy 335.48066 -370.086128)
			(xy 335.48066 -369.928902) (xy 335.481129 -369.918773) (xy 335.48886 -369.900048) (xy 335.503152 -369.885691)
			(xy 335.521841 -369.877875) (xy 335.531968 -369.87734) (xy 336.248248 -369.87734) (xy 336.25841 -369.877683)
			(xy 336.277171 -369.885502) (xy 336.291494 -369.899923) (xy 336.299185 -369.918737) (xy 336.299556 -369.928902)
			(xy 336.299556 -370.086128) (xy 336.299963 -370.095315) (xy 336.30648 -370.112499) (xy 336.312256 -370.119656)
			(xy 336.33411 -370.14533) (xy 336.372202 -370.200962) (xy 336.403355 -370.260757) (xy 336.427122 -370.323853)
			(xy 336.44316 -370.389341) (xy 336.451237 -370.456279) (xy 336.451238 -370.523644) (xy 339.729277 -370.523644)
			(xy 339.729279 -370.456338) (xy 339.737324 -370.389514) (xy 339.753299 -370.324131) (xy 339.776973 -370.261126)
			(xy 339.808008 -370.201402) (xy 339.845959 -370.145816) (xy 339.867748 -370.120164) (xy 339.873548 -370.113022)
			(xy 339.880059 -370.095829) (xy 339.880448 -370.086636) (xy 339.880448 -369.928902) (xy 339.880866 -369.918729)
			(xy 339.888652 -369.899933) (xy 339.903039 -369.885547) (xy 339.921837 -369.877764) (xy 339.93201 -369.87734)
			(xy 340.64829 -369.87734) (xy 340.658461 -369.877772) (xy 340.677256 -369.885554) (xy 340.691641 -369.899937)
			(xy 340.699426 -369.918731) (xy 340.699852 -369.928902) (xy 340.699852 -370.086636) (xy 340.700256 -370.095824)
			(xy 340.706775 -370.113007) (xy 340.712552 -370.120164) (xy 340.734328 -370.145826) (xy 340.772278 -370.201411)
			(xy 340.803312 -370.261133) (xy 340.826986 -370.324136) (xy 340.84296 -370.389517) (xy 340.851005 -370.456339)
			(xy 340.851006 -370.523643) (xy 340.851006 -370.523644) (xy 344.129068 -370.523644) (xy 344.129069 -370.456338)
			(xy 344.137115 -370.389515) (xy 344.153089 -370.324132) (xy 344.176763 -370.261127) (xy 344.207797 -370.201403)
			(xy 344.245748 -370.145816) (xy 344.267536 -370.120164) (xy 344.273335 -370.113021) (xy 344.279847 -370.095829)
			(xy 344.280236 -370.086636) (xy 344.280236 -369.928902) (xy 344.280735 -369.918745) (xy 344.288508 -369.899976)
			(xy 344.302873 -369.885611) (xy 344.321641 -369.877836) (xy 344.331798 -369.87734) (xy 345.048078 -369.87734)
			(xy 345.058248 -369.877782) (xy 345.077043 -369.88556) (xy 345.091429 -369.89994) (xy 345.099214 -369.918732)
			(xy 345.09964 -369.928902) (xy 345.09964 -370.086636) (xy 345.100046 -370.095823) (xy 345.106564 -370.113007)
			(xy 345.11234 -370.120164) (xy 345.134116 -370.145826) (xy 345.172067 -370.20141) (xy 345.203102 -370.261132)
			(xy 345.226776 -370.324136) (xy 345.242751 -370.389517) (xy 345.250796 -370.456339) (xy 345.250797 -370.523643)
			(xy 345.250797 -370.523644) (xy 374.929099 -370.523644) (xy 374.9291 -370.456338) (xy 374.937146 -370.389514)
			(xy 374.953121 -370.32413) (xy 374.976797 -370.261125) (xy 375.007834 -370.201402) (xy 375.045787 -370.145816)
			(xy 375.067576 -370.120164) (xy 375.073368 -370.113015) (xy 375.079886 -370.095828) (xy 375.080276 -370.086636)
			(xy 375.080276 -369.928902) (xy 375.080666 -369.918726) (xy 375.088458 -369.899924) (xy 375.102854 -369.885538)
			(xy 375.121661 -369.877759) (xy 375.131838 -369.87734) (xy 375.848118 -369.87734) (xy 375.858277 -369.877818)
			(xy 375.877047 -369.885599) (xy 375.891412 -369.89997) (xy 375.899185 -369.918743) (xy 375.89968 -369.928902)
			(xy 375.89968 -370.086636) (xy 375.900077 -370.095824) (xy 375.9066 -370.113008) (xy 375.91238 -370.120164)
			(xy 375.934155 -370.145826) (xy 375.972103 -370.201412) (xy 376.003136 -370.261134) (xy 376.026809 -370.324137)
			(xy 376.042782 -370.389518) (xy 376.050827 -370.456339) (xy 376.050828 -370.523643) (xy 376.050821 -370.523703)
			(xy 379.328892 -370.523703) (xy 379.328893 -370.456279) (xy 379.336969 -370.38934) (xy 379.353005 -370.323851)
			(xy 379.376769 -370.260754) (xy 379.40792 -370.200957) (xy 379.446008 -370.145322) (xy 379.467872 -370.119656)
			(xy 379.473678 -370.112518) (xy 379.480185 -370.095322) (xy 379.480572 -370.086128) (xy 379.480572 -369.928902)
			(xy 379.481029 -369.918772) (xy 379.488762 -369.900044) (xy 379.503058 -369.885687) (xy 379.521752 -369.877873)
			(xy 379.53188 -369.87734) (xy 380.24816 -369.87734) (xy 380.258316 -369.877755) (xy 380.277076 -369.885545)
			(xy 380.291402 -369.899945) (xy 380.299096 -369.918743) (xy 380.299468 -369.928902) (xy 380.299468 -370.086128)
			(xy 380.299872 -370.095316) (xy 380.306391 -370.1125) (xy 380.312168 -370.119656) (xy 380.334021 -370.14533)
			(xy 380.372112 -370.200963) (xy 380.403265 -370.260758) (xy 380.427032 -370.323853) (xy 380.443069 -370.389342)
			(xy 380.451146 -370.456279) (xy 380.451147 -370.523644) (xy 383.729187 -370.523644) (xy 383.729188 -370.456338)
			(xy 383.737234 -370.389514) (xy 383.753209 -370.324131) (xy 383.776884 -370.261126) (xy 383.807919 -370.201402)
			(xy 383.845871 -370.145816) (xy 383.86766 -370.120164) (xy 383.873462 -370.113023) (xy 383.879972 -370.095829)
			(xy 383.88036 -370.086636) (xy 383.88036 -369.928902) (xy 383.880766 -369.918728) (xy 383.888554 -369.899929)
			(xy 383.902946 -369.885543) (xy 383.921748 -369.877762) (xy 383.931922 -369.87734) (xy 384.648202 -369.87734)
			(xy 384.65836 -369.877832) (xy 384.67713 -369.885607) (xy 384.691495 -369.899974) (xy 384.699269 -369.918744)
			(xy 384.699764 -369.928902) (xy 384.699764 -370.086636) (xy 384.700165 -370.095824) (xy 384.706686 -370.113008)
			(xy 384.712464 -370.120164) (xy 384.73424 -370.145826) (xy 384.772189 -370.201411) (xy 384.803222 -370.261133)
			(xy 384.826895 -370.324137) (xy 384.842869 -370.389518) (xy 384.850914 -370.456339) (xy 384.850915 -370.523643)
			(xy 384.850915 -370.523644) (xy 388.128977 -370.523644) (xy 388.128979 -370.456338) (xy 388.137024 -370.389514)
			(xy 388.152999 -370.324131) (xy 388.176673 -370.261126) (xy 388.207708 -370.201402) (xy 388.245659 -370.145816)
			(xy 388.267448 -370.120164) (xy 388.273248 -370.113022) (xy 388.279759 -370.095829) (xy 388.280148 -370.086636)
			(xy 388.280148 -369.928902) (xy 388.280566 -369.918729) (xy 388.288352 -369.899933) (xy 388.302739 -369.885547)
			(xy 388.321537 -369.877764) (xy 388.33171 -369.87734) (xy 389.04799 -369.87734) (xy 389.058161 -369.877772)
			(xy 389.076956 -369.885554) (xy 389.091341 -369.899937) (xy 389.099126 -369.918731) (xy 389.099552 -369.928902)
			(xy 389.099552 -370.086636) (xy 389.099956 -370.095824) (xy 389.106475 -370.113007) (xy 389.112252 -370.120164)
			(xy 389.134028 -370.145826) (xy 389.171978 -370.201411) (xy 389.203012 -370.261133) (xy 389.226686 -370.324136)
			(xy 389.24266 -370.389517) (xy 389.250705 -370.456339) (xy 389.250706 -370.523643) (xy 389.250706 -370.523644)
			(xy 418.929008 -370.523644) (xy 418.929009 -370.456338) (xy 418.937055 -370.389513) (xy 418.953031 -370.32413)
			(xy 418.976707 -370.261125) (xy 419.007745 -370.201401) (xy 419.045698 -370.145816) (xy 419.067488 -370.120164)
			(xy 419.073281 -370.113016) (xy 419.079798 -370.095828) (xy 419.080188 -370.086636) (xy 419.080188 -369.928902)
			(xy 419.080567 -369.918724) (xy 419.08836 -369.89992) (xy 419.10276 -369.885533) (xy 419.121572 -369.877757)
			(xy 419.13175 -369.87734) (xy 419.84803 -369.87734) (xy 419.85819 -369.877809) (xy 419.87696 -369.885593)
			(xy 419.891325 -369.899967) (xy 419.899098 -369.918742) (xy 419.899592 -369.928902) (xy 419.899592 -370.086636)
			(xy 419.899986 -370.095825) (xy 419.906511 -370.113009) (xy 419.912292 -370.120164) (xy 419.934067 -370.145826)
			(xy 419.972014 -370.201412) (xy 420.003046 -370.261134) (xy 420.026718 -370.324138) (xy 420.042691 -370.389518)
			(xy 420.050736 -370.456339) (xy 420.050737 -370.523643) (xy 420.05073 -370.523703) (xy 423.328801 -370.523703)
			(xy 423.328802 -370.456279) (xy 423.336878 -370.38934) (xy 423.352915 -370.323851) (xy 423.37668 -370.260753)
			(xy 423.407831 -370.200957) (xy 423.44592 -370.145322) (xy 423.467784 -370.119656) (xy 423.47358 -370.11251)
			(xy 423.480095 -370.09532) (xy 423.480484 -370.086128) (xy 423.480484 -369.928902) (xy 423.48093 -369.91877)
			(xy 423.488665 -369.900041) (xy 423.502964 -369.885683) (xy 423.521662 -369.877871) (xy 423.531792 -369.87734)
			(xy 424.248072 -369.87734) (xy 424.258229 -369.877745) (xy 424.276989 -369.885539) (xy 424.291315 -369.899942)
			(xy 424.299008 -369.918743) (xy 424.29938 -369.928902) (xy 424.29938 -370.086128) (xy 424.299781 -370.095316)
			(xy 424.306302 -370.1125) (xy 424.31208 -370.119656) (xy 424.333933 -370.145331) (xy 424.372023 -370.200963)
			(xy 424.403176 -370.260758) (xy 424.426941 -370.323854) (xy 424.442978 -370.389342) (xy 424.451055 -370.456279)
			(xy 424.451056 -370.523644) (xy 427.729096 -370.523644) (xy 427.729097 -370.456338) (xy 427.737143 -370.389514)
			(xy 427.753118 -370.32413) (xy 427.776794 -370.261125) (xy 427.80783 -370.201402) (xy 427.845783 -370.145816)
			(xy 427.867572 -370.120164) (xy 427.873375 -370.113024) (xy 427.879884 -370.095829) (xy 427.880272 -370.086636)
			(xy 427.880272 -369.928902) (xy 427.880666 -369.918726) (xy 427.888457 -369.899925) (xy 427.902852 -369.885539)
			(xy 427.921658 -369.87776) (xy 427.931834 -369.87734) (xy 428.648114 -369.87734) (xy 428.658273 -369.877822)
			(xy 428.677043 -369.885602) (xy 428.691407 -369.899971) (xy 428.699181 -369.918743) (xy 428.699676 -369.928902)
			(xy 428.699676 -370.086636) (xy 428.700074 -370.095824) (xy 428.706597 -370.113008) (xy 428.712376 -370.120164)
			(xy 428.734152 -370.145826) (xy 428.7721 -370.201411) (xy 428.803133 -370.261134) (xy 428.826806 -370.324137)
			(xy 428.842779 -370.389518) (xy 428.850824 -370.456339) (xy 428.850825 -370.523643) (xy 428.850825 -370.523644)
			(xy 432.128887 -370.523644) (xy 432.128888 -370.456338) (xy 432.136934 -370.389514) (xy 432.152909 -370.324131)
			(xy 432.176584 -370.261126) (xy 432.207619 -370.201402) (xy 432.245571 -370.145816) (xy 432.26736 -370.120164)
			(xy 432.273162 -370.113023) (xy 432.279672 -370.095829) (xy 432.28006 -370.086636) (xy 432.28006 -369.928902)
			(xy 432.280466 -369.918728) (xy 432.288254 -369.899929) (xy 432.302646 -369.885543) (xy 432.321448 -369.877762)
			(xy 432.331622 -369.87734) (xy 433.047902 -369.87734) (xy 433.05806 -369.877832) (xy 433.07683 -369.885607)
			(xy 433.091195 -369.899974) (xy 433.098969 -369.918744) (xy 433.099464 -369.928902) (xy 433.099464 -370.086636)
			(xy 433.099865 -370.095824) (xy 433.106386 -370.113008) (xy 433.112164 -370.120164) (xy 433.13394 -370.145826)
			(xy 433.171889 -370.201411) (xy 433.202922 -370.261133) (xy 433.226595 -370.324137) (xy 433.242569 -370.389518)
			(xy 433.250614 -370.456339) (xy 433.250615 -370.523643) (xy 433.242572 -370.590465) (xy 433.226601 -370.655846)
			(xy 433.20293 -370.71885) (xy 433.171898 -370.778573) (xy 433.133951 -370.83416) (xy 433.112164 -370.859812)
			(xy 433.106375 -370.866963) (xy 433.099857 -370.884149) (xy 433.099464 -370.89334) (xy 433.099464 -371.386862)
			(xy 433.099901 -371.396046) (xy 433.106397 -371.41323) (xy 433.112164 -371.42039) (xy 433.133966 -371.446031)
			(xy 433.171914 -371.501619) (xy 433.202946 -371.561344) (xy 433.226383 -371.623725) (xy 434.329029 -371.623725)
			(xy 434.329032 -371.556418) (xy 434.33708 -371.489593) (xy 434.353056 -371.424209) (xy 434.376732 -371.361203)
			(xy 434.407768 -371.301478) (xy 434.445719 -371.245891) (xy 434.467508 -371.220238) (xy 434.473314 -371.2131)
			(xy 434.479823 -371.195904) (xy 434.480208 -371.18671) (xy 434.480208 -371.028722) (xy 434.48075 -371.018569)
			(xy 434.488512 -370.999806) (xy 434.502863 -370.985441) (xy 434.521618 -370.977661) (xy 434.53177 -370.97716)
			(xy 435.24805 -370.97716) (xy 435.258221 -370.977605) (xy 435.277019 -370.985378) (xy 435.291406 -370.999758)
			(xy 435.299189 -371.018551) (xy 435.299612 -371.028722) (xy 435.299612 -371.18671) (xy 435.300015 -371.195898)
			(xy 435.306533 -371.213082) (xy 435.312312 -371.220238) (xy 435.334064 -371.24592) (xy 435.372017 -371.301501)
			(xy 435.403055 -371.36122) (xy 435.426732 -371.424221) (xy 435.442709 -371.4896) (xy 435.450757 -371.55642)
			(xy 435.45076 -371.623723) (xy 435.442719 -371.690544) (xy 435.426749 -371.755924) (xy 435.403078 -371.818928)
			(xy 435.372046 -371.87865) (xy 435.334099 -371.934235) (xy 435.312312 -371.959886) (xy 435.306498 -371.967019)
			(xy 435.299993 -371.984219) (xy 435.299612 -371.993414) (xy 435.299612 -372.486682) (xy 435.300028 -372.495869)
			(xy 435.306537 -372.513053) (xy 435.312312 -372.52021) (xy 435.334135 -372.545834) (xy 435.372086 -372.601423)
			(xy 435.40312 -372.66115) (xy 435.426793 -372.724159) (xy 435.442765 -372.789545) (xy 435.450807 -372.856371)
			(xy 435.450804 -372.92368) (xy 435.442756 -372.990506) (xy 435.426778 -373.05589) (xy 435.403099 -373.118896)
			(xy 435.372059 -373.178621) (xy 435.334103 -373.234206) (xy 435.312312 -373.259858) (xy 435.30651 -373.266999)
			(xy 435.299998 -373.284193) (xy 435.299612 -373.293386) (xy 435.299612 -373.451374) (xy 435.299213 -373.46155)
			(xy 435.291428 -373.480354) (xy 435.277034 -373.494741) (xy 435.258226 -373.502518) (xy 435.24805 -373.502936)
			(xy 434.53177 -373.502936) (xy 434.521607 -373.502491) (xy 434.502832 -373.494701) (xy 434.488467 -373.480321)
			(xy 434.480698 -373.461537) (xy 434.480208 -373.451374) (xy 434.480208 -373.293386) (xy 434.479803 -373.284198)
			(xy 434.473286 -373.267014) (xy 434.467508 -373.259858) (xy 434.445755 -373.234178) (xy 434.407807 -373.178595)
			(xy 434.376774 -373.118875) (xy 434.3531 -373.055874) (xy 434.337126 -372.990495) (xy 434.32908 -372.923676)
			(xy 434.329077 -372.856375) (xy 434.337117 -372.789555) (xy 434.353085 -372.724175) (xy 434.376753 -372.661172)
			(xy 434.40778 -372.601449) (xy 434.445723 -372.545863) (xy 434.467508 -372.52021) (xy 434.473326 -372.51308)
			(xy 434.479828 -372.495878) (xy 434.480208 -372.486682) (xy 434.480208 -371.993414) (xy 434.479789 -371.984228)
			(xy 434.473281 -371.967043) (xy 434.467508 -371.959886) (xy 434.445684 -371.934264) (xy 434.407738 -371.878673)
			(xy 434.376708 -371.818945) (xy 434.353039 -371.755936) (xy 434.33707 -371.690551) (xy 434.329029 -371.623725)
			(xy 433.226383 -371.623725) (xy 433.226618 -371.62435) (xy 433.24259 -371.689734) (xy 433.250633 -371.756557)
			(xy 433.250632 -371.823864) (xy 433.242586 -371.890687) (xy 433.226612 -371.95607) (xy 433.202938 -372.019075)
			(xy 433.171903 -372.078799) (xy 433.133953 -372.134386) (xy 433.112164 -372.160038) (xy 433.106364 -372.167181)
			(xy 433.099852 -372.184373) (xy 433.099464 -372.193566) (xy 433.099464 -372.351554) (xy 433.098999 -372.361722)
			(xy 433.091229 -372.380516) (xy 433.076856 -372.394902) (xy 433.05807 -372.402689) (xy 433.047902 -372.403116)
			(xy 432.331622 -372.403116) (xy 432.321446 -372.402717) (xy 432.302643 -372.394931) (xy 432.288256 -372.380537)
			(xy 432.280478 -372.36173) (xy 432.28006 -372.351554) (xy 432.28006 -372.193566) (xy 432.279653 -372.184379)
			(xy 432.273135 -372.167195) (xy 432.26736 -372.160038) (xy 432.245586 -372.134375) (xy 432.207635 -372.07879)
			(xy 432.1766 -372.019069) (xy 432.152925 -371.956065) (xy 432.136951 -371.890684) (xy 432.128905 -371.823863)
			(xy 432.128904 -371.756558) (xy 432.136947 -371.689736) (xy 432.152919 -371.624355) (xy 432.176591 -371.561351)
			(xy 432.207624 -371.501628) (xy 432.245573 -371.446042) (xy 432.26736 -371.42039) (xy 432.273151 -371.413241)
			(xy 432.279667 -371.396053) (xy 432.28006 -371.386862) (xy 432.28006 -370.89334) (xy 432.279617 -370.884157)
			(xy 432.273125 -370.866972) (xy 432.26736 -370.859812) (xy 432.24556 -370.83417) (xy 432.20761 -370.778582)
			(xy 432.176576 -370.718858) (xy 432.152903 -370.655852) (xy 432.136931 -370.590468) (xy 432.128887 -370.523644)
			(xy 428.850825 -370.523644) (xy 428.842782 -370.590464) (xy 428.826811 -370.655846) (xy 428.80314 -370.71885)
			(xy 428.772109 -370.778573) (xy 428.734163 -370.83416) (xy 428.712376 -370.859812) (xy 428.706589 -370.866964)
			(xy 428.700069 -370.884149) (xy 428.699676 -370.89334) (xy 428.699676 -371.386862) (xy 428.70011 -371.396047)
			(xy 428.706608 -371.413231) (xy 428.712376 -371.42039) (xy 428.734177 -371.446031) (xy 428.772125 -371.501619)
			(xy 428.803156 -371.561345) (xy 428.826615 -371.623785) (xy 429.928709 -371.623785) (xy 429.928713 -371.556358)
			(xy 429.936793 -371.489417) (xy 429.952833 -371.423925) (xy 429.976602 -371.360827) (xy 430.007759 -371.30103)
			(xy 430.045853 -371.245395) (xy 430.06772 -371.21973) (xy 430.073531 -371.212595) (xy 430.080036 -371.195397)
			(xy 430.08042 -371.186202) (xy 430.08042 -371.028722) (xy 430.080944 -371.018599) (xy 430.088661 -370.999882)
			(xy 430.102935 -370.985526) (xy 430.121608 -370.977702) (xy 430.131728 -370.97716) (xy 430.848008 -370.97716)
			(xy 430.858158 -370.977614) (xy 430.876902 -370.985405) (xy 430.891224 -370.999791) (xy 430.898931 -371.018571)
			(xy 430.899316 -371.028722) (xy 430.899316 -371.186202) (xy 430.899722 -371.19539) (xy 430.906238 -371.212574)
			(xy 430.912016 -371.21973) (xy 430.933842 -371.245426) (xy 430.971931 -371.301057) (xy 431.003082 -371.360849)
			(xy 431.026848 -371.423942) (xy 431.042886 -371.489427) (xy 431.050964 -371.556361) (xy 431.050968 -371.623782)
			(xy 431.042896 -371.690717) (xy 431.026865 -371.756204) (xy 431.003106 -371.819299) (xy 430.97196 -371.879094)
			(xy 430.933877 -371.934729) (xy 430.912016 -371.960394) (xy 430.906241 -371.967555) (xy 430.899713 -371.984733)
			(xy 430.899316 -371.993922) (xy 430.899316 -372.486174) (xy 430.899735 -372.49536) (xy 430.906242 -372.512545)
			(xy 430.912016 -372.519702) (xy 430.933913 -372.54534) (xy 430.971999 -372.600979) (xy 431.003148 -372.660779)
			(xy 431.026909 -372.723879) (xy 431.042942 -372.789371) (xy 431.051015 -372.856313) (xy 431.051012 -372.923739)
			(xy 431.042933 -372.990679) (xy 431.026894 -373.05617) (xy 431.003127 -373.119268) (xy 430.971973 -373.179065)
			(xy 430.933881 -373.2347) (xy 430.912016 -373.260366) (xy 430.906211 -373.267505) (xy 430.899701 -373.2847)
			(xy 430.899316 -373.293894) (xy 430.899316 -373.451374) (xy 430.898851 -373.461504) (xy 430.891124 -373.480233)
			(xy 430.87683 -373.494592) (xy 430.858136 -373.502405) (xy 430.848008 -373.502936) (xy 430.131728 -373.502936)
			(xy 430.12158 -373.502456) (xy 430.102835 -373.494677) (xy 430.088512 -373.480298) (xy 430.080805 -373.461523)
			(xy 430.08042 -373.451374) (xy 430.08042 -373.293894) (xy 430.080008 -373.284707) (xy 430.073495 -373.267523)
			(xy 430.06772 -373.260366) (xy 430.045889 -373.234674) (xy 430.007798 -373.179043) (xy 429.976644 -373.119251)
			(xy 429.952877 -373.056158) (xy 429.936839 -372.990672) (xy 429.92876 -372.923736) (xy 429.928757 -372.856315)
			(xy 429.93683 -372.789379) (xy 429.952862 -372.723891) (xy 429.976624 -372.660796) (xy 430.007771 -372.601)
			(xy 430.045857 -372.545367) (xy 430.06772 -372.519702) (xy 430.073501 -372.512546) (xy 430.080024 -372.495364)
			(xy 430.08042 -372.486174) (xy 430.08042 -371.993922) (xy 430.079995 -371.984737) (xy 430.073491 -371.967552)
			(xy 430.06772 -371.960394) (xy 430.045818 -371.93476) (xy 430.007729 -371.879121) (xy 429.976579 -371.819321)
			(xy 429.952816 -371.75622) (xy 429.936783 -371.690727) (xy 429.928709 -371.623785) (xy 428.826615 -371.623785)
			(xy 428.826828 -371.624351) (xy 428.842799 -371.689734) (xy 428.850842 -371.756558) (xy 428.850841 -371.823863)
			(xy 428.842795 -371.890687) (xy 428.826821 -371.95607) (xy 428.803148 -372.019075) (xy 428.772114 -372.078799)
			(xy 428.734164 -372.134386) (xy 428.712376 -372.160038) (xy 428.706578 -372.167182) (xy 428.700065 -372.184374)
			(xy 428.699676 -372.193566) (xy 428.699676 -372.351554) (xy 428.699199 -372.361721) (xy 428.691432 -372.380512)
			(xy 428.677062 -372.394898) (xy 428.65828 -372.402687) (xy 428.648114 -372.403116) (xy 427.931834 -372.403116)
			(xy 427.921659 -372.402707) (xy 427.902856 -372.394925) (xy 427.888469 -372.380534) (xy 427.880691 -372.361729)
			(xy 427.880272 -372.351554) (xy 427.880272 -372.193566) (xy 427.879884 -372.184376) (xy 427.873356 -372.167192)
			(xy 427.867572 -372.160038) (xy 427.845797 -372.134375) (xy 427.807846 -372.078791) (xy 427.77681 -372.019069)
			(xy 427.753135 -371.956066) (xy 427.73716 -371.890685) (xy 427.729114 -371.823863) (xy 427.729113 -371.756558)
			(xy 427.737156 -371.689736) (xy 427.753129 -371.624354) (xy 427.776801 -371.56135) (xy 427.807835 -371.501627)
			(xy 427.845784 -371.446042) (xy 427.867572 -371.42039) (xy 427.873364 -371.413242) (xy 427.879879 -371.396053)
			(xy 427.880272 -371.386862) (xy 427.880272 -370.89334) (xy 427.879849 -370.884154) (xy 427.873345 -370.866969)
			(xy 427.867572 -370.859812) (xy 427.845772 -370.83417) (xy 427.807821 -370.778583) (xy 427.776786 -370.718858)
			(xy 427.753113 -370.655852) (xy 427.73714 -370.590468) (xy 427.729096 -370.523644) (xy 424.451056 -370.523644)
			(xy 424.451056 -370.523703) (xy 424.442981 -370.59064) (xy 424.426947 -370.656129) (xy 424.403183 -370.719225)
			(xy 424.372033 -370.779021) (xy 424.333944 -370.834655) (xy 424.31208 -370.86032) (xy 424.30629 -370.86747)
			(xy 424.299772 -370.884657) (xy 424.29938 -370.893848) (xy 424.29938 -371.386354) (xy 424.299817 -371.395538)
			(xy 424.306312 -371.412723) (xy 424.31208 -371.419882) (xy 424.333958 -371.445536) (xy 424.372048 -371.501171)
			(xy 424.403199 -371.560969) (xy 424.426835 -371.623725) (xy 425.528941 -371.623725) (xy 425.528945 -371.556418)
			(xy 425.536992 -371.489593) (xy 425.552969 -371.424208) (xy 425.576645 -371.361202) (xy 425.607682 -371.301478)
			(xy 425.645634 -371.24589) (xy 425.667424 -371.220238) (xy 425.673232 -371.213101) (xy 425.679739 -371.195904)
			(xy 425.680124 -371.18671) (xy 425.680124 -371.028722) (xy 425.680582 -371.018554) (xy 425.688357 -370.999762)
			(xy 425.702732 -370.985377) (xy 425.721518 -370.977589) (xy 425.731686 -370.97716) (xy 426.447966 -370.97716)
			(xy 426.458138 -370.977592) (xy 426.476936 -370.98537) (xy 426.491323 -370.999754) (xy 426.499105 -371.01855)
			(xy 426.499528 -371.028722) (xy 426.499528 -371.18671) (xy 426.499927 -371.195898) (xy 426.506448 -371.213083)
			(xy 426.512228 -371.220238) (xy 426.533979 -371.24592) (xy 426.571931 -371.301502) (xy 426.602968 -371.361221)
			(xy 426.626645 -371.424221) (xy 426.642621 -371.4896) (xy 426.650669 -371.55642) (xy 426.650672 -371.623723)
			(xy 426.642631 -371.690543) (xy 426.626661 -371.755924) (xy 426.602991 -371.818927) (xy 426.571961 -371.878649)
			(xy 426.534014 -371.934234) (xy 426.512228 -371.959886) (xy 426.506404 -371.967011) (xy 426.499908 -371.984217)
			(xy 426.499528 -371.993414) (xy 426.499528 -372.486682) (xy 426.49994 -372.495869) (xy 426.506452 -372.513054)
			(xy 426.512228 -372.52021) (xy 426.53405 -372.545834) (xy 426.572 -372.601424) (xy 426.603034 -372.661151)
			(xy 426.626706 -372.724159) (xy 426.642678 -372.789545) (xy 426.65072 -372.856371) (xy 426.650717 -372.92368)
			(xy 426.642669 -372.990505) (xy 426.626691 -373.05589) (xy 426.603013 -373.118896) (xy 426.571974 -373.17862)
			(xy 426.534019 -373.234206) (xy 426.512228 -373.259858) (xy 426.506416 -373.266992) (xy 426.499912 -373.284191)
			(xy 426.499528 -373.293386) (xy 426.499528 -373.451374) (xy 426.499114 -373.461548) (xy 426.491331 -373.480349)
			(xy 426.476942 -373.494736) (xy 426.45814 -373.502515) (xy 426.447966 -373.502936) (xy 425.731686 -373.502936)
			(xy 425.72151 -373.502547) (xy 425.70271 -373.494752) (xy 425.688325 -373.480356) (xy 425.680545 -373.46155)
			(xy 425.680124 -373.451374) (xy 425.680124 -373.293386) (xy 425.679715 -373.284199) (xy 425.6732 -373.267015)
			(xy 425.667424 -373.259858) (xy 425.64567 -373.234178) (xy 425.607722 -373.178595) (xy 425.576688 -373.118875)
			(xy 425.553014 -373.055874) (xy 425.537039 -372.990496) (xy 425.528992 -372.923677) (xy 425.528989 -372.856375)
			(xy 425.53703 -372.789555) (xy 425.552999 -372.724174) (xy 425.576667 -372.661171) (xy 425.607695 -372.601449)
			(xy 425.645639 -372.545863) (xy 425.667424 -372.52021) (xy 425.673244 -372.513082) (xy 425.679744 -372.495878)
			(xy 425.680124 -372.486682) (xy 425.680124 -371.993414) (xy 425.679702 -371.984228) (xy 425.673196 -371.967044)
			(xy 425.667424 -371.959886) (xy 425.645599 -371.934264) (xy 425.607653 -371.878673) (xy 425.576622 -371.818945)
			(xy 425.552952 -371.755937) (xy 425.536982 -371.690551) (xy 425.528941 -371.623725) (xy 424.426835 -371.623725)
			(xy 424.426964 -371.624067) (xy 424.442999 -371.689558) (xy 424.451074 -371.756498) (xy 424.451072 -371.823923)
			(xy 424.442995 -371.890863) (xy 424.426957 -371.956353) (xy 424.403191 -372.01945) (xy 424.372037 -372.079247)
			(xy 424.333946 -372.134881) (xy 424.31208 -372.160546) (xy 424.306279 -372.167688) (xy 424.299768 -372.184881)
			(xy 424.29938 -372.194074) (xy 424.29938 -372.351554) (xy 424.298836 -372.361675) (xy 424.291127 -372.380392)
			(xy 424.276858 -372.394749) (xy 424.25819 -372.402573) (xy 424.248072 -372.403116) (xy 423.531792 -372.403116)
			(xy 423.521639 -372.402685) (xy 423.50289 -372.39489) (xy 423.488568 -372.380496) (xy 423.480865 -372.361709)
			(xy 423.480484 -372.351554) (xy 423.480484 -372.194074) (xy 423.48009 -372.184885) (xy 423.473565 -372.167701)
			(xy 423.467784 -372.160546) (xy 423.445934 -372.134869) (xy 423.407846 -372.079236) (xy 423.376696 -372.019441)
			(xy 423.352932 -371.956346) (xy 423.336896 -371.890858) (xy 423.328819 -371.823922) (xy 423.328818 -371.756499)
			(xy 423.336892 -371.689562) (xy 423.352925 -371.624074) (xy 423.376687 -371.560978) (xy 423.407835 -371.501182)
			(xy 423.445921 -371.445547) (xy 423.467784 -371.419882) (xy 423.473569 -371.412728) (xy 423.480091 -371.395544)
			(xy 423.480484 -371.386354) (xy 423.480484 -370.893848) (xy 423.480055 -370.884663) (xy 423.473555 -370.867478)
			(xy 423.467784 -370.86032) (xy 423.445909 -370.834664) (xy 423.407821 -370.779028) (xy 423.376672 -370.71923)
			(xy 423.352909 -370.656132) (xy 423.336875 -370.590642) (xy 423.328801 -370.523703) (xy 420.05073 -370.523703)
			(xy 420.042694 -370.590464) (xy 420.026724 -370.655845) (xy 420.003054 -370.718849) (xy 419.972023 -370.778573)
			(xy 419.934078 -370.834159) (xy 419.912292 -370.859812) (xy 419.906507 -370.866965) (xy 419.899986 -370.88415)
			(xy 419.899592 -370.89334) (xy 419.899592 -371.386862) (xy 419.900022 -371.396047) (xy 419.906522 -371.413231)
			(xy 419.912292 -371.42039) (xy 419.934093 -371.446031) (xy 419.972039 -371.50162) (xy 420.00307 -371.561345)
			(xy 420.026528 -371.623785) (xy 421.128621 -371.623785) (xy 421.128625 -371.556358) (xy 421.136705 -371.489416)
			(xy 421.152746 -371.423925) (xy 421.176516 -371.360826) (xy 421.207673 -371.301029) (xy 421.245769 -371.245395)
			(xy 421.267636 -371.21973) (xy 421.273449 -371.212597) (xy 421.279953 -371.195397) (xy 421.280336 -371.186202)
			(xy 421.280336 -371.028722) (xy 421.280844 -371.018597) (xy 421.288564 -370.999877) (xy 421.302844 -370.98552)
			(xy 421.321522 -370.9777) (xy 421.331644 -370.97716) (xy 422.047924 -370.97716) (xy 422.058075 -370.977601)
			(xy 422.07682 -370.985397) (xy 422.091141 -370.999787) (xy 422.098847 -371.018569) (xy 422.099232 -371.028722)
			(xy 422.099232 -371.186202) (xy 422.099656 -371.195387) (xy 422.106162 -371.212571) (xy 422.111932 -371.21973)
			(xy 422.133758 -371.245427) (xy 422.171845 -371.301057) (xy 422.202996 -371.36085) (xy 422.226761 -371.423942)
			(xy 422.242798 -371.489427) (xy 422.250876 -371.556361) (xy 422.25088 -371.623781) (xy 422.242808 -371.690717)
			(xy 422.226778 -371.756203) (xy 422.203019 -371.819298) (xy 422.171875 -371.879094) (xy 422.133793 -371.934728)
			(xy 422.111932 -371.960394) (xy 422.106147 -371.967547) (xy 422.099627 -371.984732) (xy 422.099232 -371.993922)
			(xy 422.099232 -372.486174) (xy 422.09967 -372.495358) (xy 422.106166 -372.512542) (xy 422.111932 -372.519702)
			(xy 422.133828 -372.54534) (xy 422.171914 -372.600979) (xy 422.203061 -372.66078) (xy 422.226822 -372.72388)
			(xy 422.242854 -372.789372) (xy 422.250927 -372.856313) (xy 422.250924 -372.923738) (xy 422.242845 -372.990678)
			(xy 422.226807 -373.056169) (xy 422.20304 -373.119267) (xy 422.171888 -373.179064) (xy 422.133797 -373.2347)
			(xy 422.111932 -373.260366) (xy 422.106117 -373.267498) (xy 422.099615 -373.284699) (xy 422.099232 -373.293894)
			(xy 422.099232 -373.451374) (xy 422.098751 -373.461503) (xy 422.091027 -373.480228) (xy 422.076738 -373.494587)
			(xy 422.05805 -373.502402) (xy 422.047924 -373.502936) (xy 421.331644 -373.502936) (xy 421.321497 -373.502443)
			(xy 421.302753 -373.494669) (xy 421.288429 -373.480294) (xy 421.280721 -373.461522) (xy 421.280336 -373.451374)
			(xy 421.280336 -373.293894) (xy 421.279921 -373.284708) (xy 421.27341 -373.267524) (xy 421.267636 -373.260366)
			(xy 421.245804 -373.234674) (xy 421.207712 -373.179044) (xy 421.176558 -373.119252) (xy 421.15279 -373.056158)
			(xy 421.136751 -372.990672) (xy 421.128672 -372.923736) (xy 421.128669 -372.856315) (xy 421.136742 -372.789378)
			(xy 421.152775 -372.72389) (xy 421.176537 -372.660795) (xy 421.207686 -372.601) (xy 421.245773 -372.545367)
			(xy 421.267636 -372.519702) (xy 421.273419 -372.512547) (xy 421.279941 -372.495364) (xy 421.280336 -372.486174)
			(xy 421.280336 -371.993922) (xy 421.279907 -371.984737) (xy 421.273406 -371.967553) (xy 421.267636 -371.960394)
			(xy 421.245733 -371.93476) (xy 421.207643 -371.879122) (xy 421.176492 -371.819322) (xy 421.152729 -371.756221)
			(xy 421.136695 -371.690727) (xy 421.128621 -371.623785) (xy 420.026528 -371.623785) (xy 420.026741 -371.624351)
			(xy 420.042712 -371.689734) (xy 420.050754 -371.756558) (xy 420.050753 -371.823863) (xy 420.042708 -371.890686)
			(xy 420.026734 -371.956069) (xy 420.003061 -372.019074) (xy 419.972028 -372.078798) (xy 419.93408 -372.134385)
			(xy 419.912292 -372.160038) (xy 419.906496 -372.167183) (xy 419.899981 -372.184374) (xy 419.899592 -372.193566)
			(xy 419.899592 -372.351554) (xy 419.899099 -372.361719) (xy 419.891335 -372.380507) (xy 419.876971 -372.394892)
			(xy 419.858194 -372.402684) (xy 419.84803 -372.403116) (xy 419.13175 -372.403116) (xy 419.121576 -372.402694)
			(xy 419.102773 -372.394917) (xy 419.088385 -372.38053) (xy 419.080607 -372.361728) (xy 419.080188 -372.351554)
			(xy 419.080188 -372.193566) (xy 419.079797 -372.184377) (xy 419.07327 -372.167192) (xy 419.067488 -372.160038)
			(xy 419.045713 -372.134375) (xy 419.00776 -372.078791) (xy 418.976724 -372.01907) (xy 418.953048 -371.956067)
			(xy 418.937072 -371.890685) (xy 418.929026 -371.823863) (xy 418.929025 -371.756558) (xy 418.937069 -371.689736)
			(xy 418.953042 -371.624354) (xy 418.976715 -371.561349) (xy 419.007749 -371.501627) (xy 419.0457 -371.446041)
			(xy 419.067488 -371.42039) (xy 419.07327 -371.413234) (xy 419.079794 -371.396052) (xy 419.080188 -371.386862)
			(xy 419.080188 -370.89334) (xy 419.079761 -370.884154) (xy 419.07326 -370.86697) (xy 419.067488 -370.859812)
			(xy 419.045687 -370.83417) (xy 419.007735 -370.778583) (xy 418.9767 -370.718859) (xy 418.953026 -370.655853)
			(xy 418.937052 -370.590469) (xy 418.929008 -370.523644) (xy 389.250706 -370.523644) (xy 389.242663 -370.590465)
			(xy 389.226691 -370.655847) (xy 389.203019 -370.718851) (xy 389.171987 -370.778574) (xy 389.134039 -370.83416)
			(xy 389.112252 -370.859812) (xy 389.106462 -370.866962) (xy 389.099945 -370.884149) (xy 389.099552 -370.89334)
			(xy 389.099552 -371.386862) (xy 389.099991 -371.396046) (xy 389.106486 -371.41323) (xy 389.112252 -371.42039)
			(xy 389.134054 -371.446031) (xy 389.172003 -371.501618) (xy 389.203036 -371.561344) (xy 389.226474 -371.623725)
			(xy 390.32912 -371.623725) (xy 390.329123 -371.556418) (xy 390.337171 -371.489593) (xy 390.353146 -371.42421)
			(xy 390.376822 -371.361204) (xy 390.407857 -371.301479) (xy 390.445807 -371.245891) (xy 390.467596 -371.220238)
			(xy 390.473401 -371.213099) (xy 390.479911 -371.195904) (xy 390.480296 -371.18671) (xy 390.480296 -371.028722)
			(xy 390.48085 -371.018571) (xy 390.48861 -370.99981) (xy 390.502956 -370.985446) (xy 390.521707 -370.977663)
			(xy 390.531858 -370.97716) (xy 391.248138 -370.97716) (xy 391.258301 -370.977603) (xy 391.277075 -370.985394)
			(xy 391.29144 -370.999775) (xy 391.299209 -371.018558) (xy 391.2997 -371.028722) (xy 391.2997 -371.18671)
			(xy 391.300106 -371.195898) (xy 391.306623 -371.213082) (xy 391.3124 -371.220238) (xy 391.334149 -371.245921)
			(xy 391.372097 -371.301504) (xy 391.403129 -371.361224) (xy 391.426803 -371.424224) (xy 391.442777 -371.489602)
			(xy 391.450824 -371.556421) (xy 391.450827 -371.623722) (xy 391.442787 -371.690541) (xy 391.42682 -371.755921)
			(xy 391.403153 -371.818924) (xy 391.372126 -371.878647) (xy 391.334184 -371.934233) (xy 391.3124 -371.959886)
			(xy 391.306584 -371.967018) (xy 391.300081 -371.984219) (xy 391.2997 -371.993414) (xy 391.2997 -372.486682)
			(xy 391.300119 -372.495868) (xy 391.306627 -372.513053) (xy 391.3124 -372.52021) (xy 391.33422 -372.545835)
			(xy 391.372165 -372.601426) (xy 391.403195 -372.661154) (xy 391.426864 -372.724162) (xy 391.442833 -372.789547)
			(xy 391.450874 -372.856372) (xy 391.450871 -372.923679) (xy 391.442824 -372.990503) (xy 391.426849 -373.055887)
			(xy 391.403174 -373.118893) (xy 391.372139 -373.178617) (xy 391.334189 -373.234205) (xy 391.3124 -373.259858)
			(xy 391.306596 -373.266998) (xy 391.300086 -373.284193) (xy 391.2997 -373.293386) (xy 391.2997 -373.451374)
			(xy 391.299146 -373.461525) (xy 391.291388 -373.480287) (xy 391.277041 -373.494652) (xy 391.258289 -373.502434)
			(xy 391.248138 -373.502936) (xy 390.531858 -373.502936) (xy 390.521694 -373.5025) (xy 390.502919 -373.494707)
			(xy 390.488555 -373.480324) (xy 390.480786 -373.461538) (xy 390.480296 -373.451374) (xy 390.480296 -373.293386)
			(xy 390.479893 -373.284198) (xy 390.473374 -373.267014) (xy 390.467596 -373.259858) (xy 390.445843 -373.234178)
			(xy 390.407896 -373.178594) (xy 390.376864 -373.118874) (xy 390.353191 -373.055874) (xy 390.337217 -372.990495)
			(xy 390.329171 -372.923676) (xy 390.329167 -372.856375) (xy 390.337208 -372.789555) (xy 390.353176 -372.724175)
			(xy 390.376843 -372.661173) (xy 390.40787 -372.60145) (xy 390.445812 -372.545863) (xy 390.467596 -372.52021)
			(xy 390.473413 -372.513079) (xy 390.479916 -372.495878) (xy 390.480296 -372.486682) (xy 390.480296 -371.993414)
			(xy 390.47988 -371.984227) (xy 390.47337 -371.967043) (xy 390.467596 -371.959886) (xy 390.445772 -371.934264)
			(xy 390.407827 -371.878672) (xy 390.376798 -371.818944) (xy 390.353129 -371.755936) (xy 390.33716 -371.69055)
			(xy 390.32912 -371.623725) (xy 389.226474 -371.623725) (xy 389.226709 -371.62435) (xy 389.242681 -371.689733)
			(xy 389.250724 -371.756557) (xy 389.250723 -371.823864) (xy 389.242677 -371.890687) (xy 389.226702 -371.956071)
			(xy 389.203028 -372.019076) (xy 389.171992 -372.0788) (xy 389.134041 -372.134386) (xy 389.112252 -372.160038)
			(xy 389.106451 -372.16718) (xy 389.09994 -372.184373) (xy 389.099552 -372.193566) (xy 389.099552 -372.351554)
			(xy 389.099098 -372.361724) (xy 389.091327 -372.380519) (xy 389.07695 -372.394906) (xy 389.05816 -372.402691)
			(xy 389.04799 -372.403116) (xy 388.33171 -372.403116) (xy 388.321533 -372.402727) (xy 388.30273 -372.394937)
			(xy 388.288343 -372.38054) (xy 388.280566 -372.361731) (xy 388.280148 -372.351554) (xy 388.280148 -372.193566)
			(xy 388.279743 -372.184378) (xy 388.273225 -372.167195) (xy 388.267448 -372.160038) (xy 388.245674 -372.134375)
			(xy 388.207724 -372.07879) (xy 388.17669 -372.019068) (xy 388.153016 -371.956065) (xy 388.137042 -371.890684)
			(xy 388.128996 -371.823863) (xy 388.128995 -371.756558) (xy 388.137038 -371.689737) (xy 388.15301 -371.624355)
			(xy 388.176681 -371.561351) (xy 388.207713 -371.501628) (xy 388.245661 -371.446042) (xy 388.267448 -371.42039)
			(xy 388.273237 -371.41324) (xy 388.279755 -371.396053) (xy 388.280148 -371.386862) (xy 388.280148 -370.89334)
			(xy 388.279708 -370.884156) (xy 388.273214 -370.866972) (xy 388.267448 -370.859812) (xy 388.245648 -370.83417)
			(xy 388.207699 -370.778582) (xy 388.176666 -370.718857) (xy 388.152993 -370.655851) (xy 388.137021 -370.590468)
			(xy 388.128977 -370.523644) (xy 384.850915 -370.523644) (xy 384.842872 -370.590465) (xy 384.826901 -370.655846)
			(xy 384.80323 -370.71885) (xy 384.772198 -370.778573) (xy 384.734251 -370.83416) (xy 384.712464 -370.859812)
			(xy 384.706675 -370.866963) (xy 384.700157 -370.884149) (xy 384.699764 -370.89334) (xy 384.699764 -371.386862)
			(xy 384.700201 -371.396046) (xy 384.706697 -371.41323) (xy 384.712464 -371.42039) (xy 384.734266 -371.446031)
			(xy 384.772214 -371.501619) (xy 384.803246 -371.561344) (xy 384.826706 -371.623785) (xy 385.9288 -371.623785)
			(xy 385.928804 -371.556358) (xy 385.936884 -371.489417) (xy 385.952923 -371.423926) (xy 385.976692 -371.360827)
			(xy 386.007848 -371.30103) (xy 386.045941 -371.245395) (xy 386.067808 -371.21973) (xy 386.073618 -371.212594)
			(xy 386.080124 -371.195396) (xy 386.080508 -371.186202) (xy 386.080508 -371.028722) (xy 386.081044 -371.018601)
			(xy 386.088758 -370.999886) (xy 386.103029 -370.98553) (xy 386.121698 -370.977704) (xy 386.131816 -370.97716)
			(xy 386.848096 -370.97716) (xy 386.858245 -370.977624) (xy 386.876989 -370.985411) (xy 386.891311 -370.999794)
			(xy 386.899019 -371.018571) (xy 386.899404 -371.028722) (xy 386.899404 -371.186202) (xy 386.899812 -371.195389)
			(xy 386.906327 -371.212574) (xy 386.912104 -371.21973) (xy 386.93393 -371.245426) (xy 386.97202 -371.301056)
			(xy 387.003172 -371.360848) (xy 387.026938 -371.423941) (xy 387.042976 -371.489426) (xy 387.051055 -371.556361)
			(xy 387.051059 -371.623782) (xy 387.042987 -371.690717) (xy 387.026955 -371.756204) (xy 387.003196 -371.8193)
			(xy 386.972049 -371.879095) (xy 386.933966 -371.934729) (xy 386.912104 -371.960394) (xy 386.906328 -371.967554)
			(xy 386.899801 -371.984733) (xy 386.899404 -371.993922) (xy 386.899404 -372.486174) (xy 386.899826 -372.49536)
			(xy 386.906331 -372.512545) (xy 386.912104 -372.519702) (xy 386.934001 -372.54534) (xy 386.972089 -372.600978)
			(xy 387.003238 -372.660778) (xy 387.027 -372.723879) (xy 387.043033 -372.789371) (xy 387.051106 -372.856312)
			(xy 387.051103 -372.923739) (xy 387.043024 -372.990679) (xy 387.026985 -373.05617) (xy 387.003217 -373.119268)
			(xy 386.972062 -373.179066) (xy 386.93397 -373.234701) (xy 386.912104 -373.260366) (xy 386.906297 -373.267504)
			(xy 386.899789 -373.2847) (xy 386.899404 -373.293894) (xy 386.899404 -373.451374) (xy 386.898854 -373.461494)
			(xy 386.891142 -373.480206) (xy 386.876876 -373.494562) (xy 386.858212 -373.50239) (xy 386.848096 -373.502936)
			(xy 386.131816 -373.502936) (xy 386.121667 -373.502466) (xy 386.102922 -373.494683) (xy 386.0886 -373.480301)
			(xy 386.080893 -373.461524) (xy 386.080508 -373.451374) (xy 386.080508 -373.293894) (xy 386.080099 -373.284707)
			(xy 386.073584 -373.267523) (xy 386.067808 -373.260366) (xy 386.045977 -373.234673) (xy 386.007887 -373.179043)
			(xy 385.976734 -373.119251) (xy 385.952968 -373.056157) (xy 385.93693 -372.990671) (xy 385.928851 -372.923736)
			(xy 385.928848 -372.856315) (xy 385.936921 -372.789379) (xy 385.952953 -372.723892) (xy 385.976713 -372.660796)
			(xy 386.007861 -372.601001) (xy 386.045946 -372.545367) (xy 386.067808 -372.519702) (xy 386.073587 -372.512544)
			(xy 386.080112 -372.495363) (xy 386.080508 -372.486174) (xy 386.080508 -371.993922) (xy 386.080085 -371.984736)
			(xy 386.07358 -371.967552) (xy 386.067808 -371.960394) (xy 386.045906 -371.93476) (xy 386.007818 -371.879121)
			(xy 385.976669 -371.819321) (xy 385.952906 -371.75622) (xy 385.936873 -371.690727) (xy 385.9288 -371.623785)
			(xy 384.826706 -371.623785) (xy 384.826918 -371.62435) (xy 384.84289 -371.689734) (xy 384.850933 -371.756557)
			(xy 384.850932 -371.823864) (xy 384.842886 -371.890687) (xy 384.826912 -371.95607) (xy 384.803238 -372.019075)
			(xy 384.772203 -372.078799) (xy 384.734253 -372.134386) (xy 384.712464 -372.160038) (xy 384.706664 -372.167181)
			(xy 384.700152 -372.184373) (xy 384.699764 -372.193566) (xy 384.699764 -372.351554) (xy 384.699299 -372.361722)
			(xy 384.691529 -372.380516) (xy 384.677156 -372.394902) (xy 384.65837 -372.402689) (xy 384.648202 -372.403116)
			(xy 383.931922 -372.403116) (xy 383.921746 -372.402717) (xy 383.902943 -372.394931) (xy 383.888556 -372.380537)
			(xy 383.880778 -372.36173) (xy 383.88036 -372.351554) (xy 383.88036 -372.193566) (xy 383.879953 -372.184379)
			(xy 383.873435 -372.167195) (xy 383.86766 -372.160038) (xy 383.845886 -372.134375) (xy 383.807935 -372.07879)
			(xy 383.7769 -372.019069) (xy 383.753225 -371.956065) (xy 383.737251 -371.890684) (xy 383.729205 -371.823863)
			(xy 383.729204 -371.756558) (xy 383.737247 -371.689736) (xy 383.753219 -371.624355) (xy 383.776891 -371.561351)
			(xy 383.807924 -371.501628) (xy 383.845873 -371.446042) (xy 383.86766 -371.42039) (xy 383.873451 -371.413241)
			(xy 383.879967 -371.396053) (xy 383.88036 -371.386862) (xy 383.88036 -370.89334) (xy 383.879917 -370.884157)
			(xy 383.873425 -370.866972) (xy 383.86766 -370.859812) (xy 383.84586 -370.83417) (xy 383.80791 -370.778582)
			(xy 383.776876 -370.718858) (xy 383.753203 -370.655852) (xy 383.737231 -370.590468) (xy 383.729187 -370.523644)
			(xy 380.451147 -370.523644) (xy 380.451147 -370.523703) (xy 380.443072 -370.590641) (xy 380.427037 -370.656129)
			(xy 380.403273 -370.719226) (xy 380.372122 -370.779022) (xy 380.334032 -370.834655) (xy 380.312168 -370.86032)
			(xy 380.306376 -370.867469) (xy 380.299859 -370.884657) (xy 380.299468 -370.893848) (xy 380.299468 -371.386354)
			(xy 380.299908 -371.395538) (xy 380.306402 -371.412722) (xy 380.312168 -371.419882) (xy 380.334047 -371.445535)
			(xy 380.372137 -371.501171) (xy 380.403289 -371.560968) (xy 380.426925 -371.623725) (xy 381.529032 -371.623725)
			(xy 381.529035 -371.556418) (xy 381.537083 -371.489593) (xy 381.553059 -371.424209) (xy 381.576735 -371.361203)
			(xy 381.607771 -371.301478) (xy 381.645723 -371.245891) (xy 381.667512 -371.220238) (xy 381.673319 -371.2131)
			(xy 381.679827 -371.195904) (xy 381.680212 -371.18671) (xy 381.680212 -371.028722) (xy 381.680751 -371.018569)
			(xy 381.688513 -370.999805) (xy 381.702865 -370.98544) (xy 381.721621 -370.97766) (xy 381.731774 -370.97716)
			(xy 382.448054 -370.97716) (xy 382.458225 -370.977602) (xy 382.477023 -370.985376) (xy 382.491411 -370.999757)
			(xy 382.499193 -371.018551) (xy 382.499616 -371.028722) (xy 382.499616 -371.18671) (xy 382.500018 -371.195898)
			(xy 382.506537 -371.213083) (xy 382.512316 -371.220238) (xy 382.534068 -371.24592) (xy 382.572021 -371.301501)
			(xy 382.603058 -371.36122) (xy 382.626735 -371.424221) (xy 382.642712 -371.4896) (xy 382.65076 -371.55642)
			(xy 382.650763 -371.623723) (xy 382.642722 -371.690544) (xy 382.626752 -371.755924) (xy 382.603081 -371.818927)
			(xy 382.57205 -371.87865) (xy 382.534103 -371.934234) (xy 382.512316 -371.959886) (xy 382.506502 -371.967019)
			(xy 382.499997 -371.984219) (xy 382.499616 -371.993414) (xy 382.499616 -372.486682) (xy 382.500031 -372.495869)
			(xy 382.506541 -372.513053) (xy 382.512316 -372.52021) (xy 382.534138 -372.545834) (xy 382.572089 -372.601424)
			(xy 382.603123 -372.661151) (xy 382.626796 -372.724159) (xy 382.642768 -372.789545) (xy 382.65081 -372.856371)
			(xy 382.650807 -372.92368) (xy 382.642759 -372.990506) (xy 382.626781 -373.05589) (xy 382.603103 -373.118896)
			(xy 382.572063 -373.17862) (xy 382.534107 -373.234206) (xy 382.512316 -373.259858) (xy 382.506514 -373.267)
			(xy 382.500002 -373.284193) (xy 382.499616 -373.293386) (xy 382.499616 -373.451374) (xy 382.499214 -373.46155)
			(xy 382.491429 -373.480352) (xy 382.477036 -373.49474) (xy 382.45823 -373.502517) (xy 382.448054 -373.502936)
			(xy 381.731774 -373.502936) (xy 381.721611 -373.502487) (xy 381.702837 -373.4947) (xy 381.688471 -373.48032)
			(xy 381.680702 -373.461537) (xy 381.680212 -373.451374) (xy 381.680212 -373.293386) (xy 381.679806 -373.284198)
			(xy 381.673289 -373.267014) (xy 381.667512 -373.259858) (xy 381.645758 -373.234178) (xy 381.60781 -373.178595)
			(xy 381.576777 -373.118875) (xy 381.553104 -373.055874) (xy 381.537129 -372.990496) (xy 381.529083 -372.923676)
			(xy 381.52908 -372.856375) (xy 381.53712 -372.789555) (xy 381.553088 -372.724175) (xy 381.576756 -372.661172)
			(xy 381.607784 -372.601449) (xy 381.645727 -372.545862) (xy 381.667512 -372.52021) (xy 381.673331 -372.51308)
			(xy 381.679832 -372.495878) (xy 381.680212 -372.486682) (xy 381.680212 -371.993414) (xy 381.679792 -371.984228)
			(xy 381.673285 -371.967044) (xy 381.667512 -371.959886) (xy 381.645688 -371.934264) (xy 381.607742 -371.878673)
			(xy 381.576712 -371.818945) (xy 381.553042 -371.755936) (xy 381.537073 -371.690551) (xy 381.529032 -371.623725)
			(xy 380.426925 -371.623725) (xy 380.427054 -371.624067) (xy 380.443089 -371.689558) (xy 380.451165 -371.756498)
			(xy 380.451163 -371.823923) (xy 380.443086 -371.890863) (xy 380.427048 -371.956353) (xy 380.403281 -372.019451)
			(xy 380.372126 -372.079247) (xy 380.334034 -372.134881) (xy 380.312168 -372.160546) (xy 380.306365 -372.167687)
			(xy 380.299855 -372.184881) (xy 380.299468 -372.194074) (xy 380.299468 -372.351554) (xy 380.298936 -372.361677)
			(xy 380.291225 -372.380395) (xy 380.276952 -372.394753) (xy 380.25828 -372.402575) (xy 380.24816 -372.403116)
			(xy 379.53188 -372.403116) (xy 379.521727 -372.402695) (xy 379.502977 -372.394896) (xy 379.488655 -372.3805)
			(xy 379.480953 -372.36171) (xy 379.480572 -372.351554) (xy 379.480572 -372.194074) (xy 379.480181 -372.184885)
			(xy 379.473655 -372.1677) (xy 379.467872 -372.160546) (xy 379.446023 -372.134869) (xy 379.407935 -372.079235)
			(xy 379.376786 -372.019441) (xy 379.353022 -371.956345) (xy 379.336986 -371.890858) (xy 379.32891 -371.823922)
			(xy 379.328909 -371.7565) (xy 379.336983 -371.689563) (xy 379.353016 -371.624075) (xy 379.376777 -371.560979)
			(xy 379.407925 -371.501183) (xy 379.44601 -371.445548) (xy 379.467872 -371.419882) (xy 379.473667 -371.412736)
			(xy 379.480181 -371.395546) (xy 379.480572 -371.386354) (xy 379.480572 -370.893848) (xy 379.480145 -370.884663)
			(xy 379.473644 -370.867478) (xy 379.467872 -370.86032) (xy 379.445997 -370.834664) (xy 379.407911 -370.779027)
			(xy 379.376762 -370.71923) (xy 379.353 -370.656132) (xy 379.336966 -370.590642) (xy 379.328892 -370.523703)
			(xy 376.050821 -370.523703) (xy 376.042785 -370.590464) (xy 376.026814 -370.655846) (xy 376.003143 -370.71885)
			(xy 375.972113 -370.778573) (xy 375.934166 -370.83416) (xy 375.91238 -370.859812) (xy 375.906594 -370.866964)
			(xy 375.900073 -370.884149) (xy 375.89968 -370.89334) (xy 375.89968 -371.386862) (xy 375.900113 -371.396047)
			(xy 375.906611 -371.413231) (xy 375.91238 -371.42039) (xy 375.934181 -371.446031) (xy 375.972128 -371.50162)
			(xy 376.00316 -371.561345) (xy 376.026618 -371.623785) (xy 377.128712 -371.623785) (xy 377.128716 -371.556358)
			(xy 377.136796 -371.489417) (xy 377.152836 -371.423925) (xy 377.176606 -371.360827) (xy 377.207762 -371.301029)
			(xy 377.245857 -371.245395) (xy 377.267724 -371.21973) (xy 377.273536 -371.212596) (xy 377.28004 -371.195397)
			(xy 377.280424 -371.186202) (xy 377.280424 -371.028722) (xy 377.280944 -371.018599) (xy 377.288662 -370.999881)
			(xy 377.302938 -370.985524) (xy 377.321612 -370.977702) (xy 377.331732 -370.97716) (xy 378.048012 -370.97716)
			(xy 378.058162 -370.977611) (xy 378.076907 -370.985403) (xy 378.091229 -370.99979) (xy 378.098935 -371.01857)
			(xy 378.09932 -371.028722) (xy 378.09932 -371.186202) (xy 378.099725 -371.19539) (xy 378.106242 -371.212574)
			(xy 378.11202 -371.21973) (xy 378.133846 -371.245426) (xy 378.171934 -371.301057) (xy 378.203086 -371.360849)
			(xy 378.226851 -371.423942) (xy 378.242889 -371.489427) (xy 378.250967 -371.556361) (xy 378.250971 -371.623782)
			(xy 378.242899 -371.690717) (xy 378.226868 -371.756204) (xy 378.203109 -371.819299) (xy 378.171964 -371.879094)
			(xy 378.133881 -371.934728) (xy 378.11202 -371.960394) (xy 378.106246 -371.967555) (xy 378.099717 -371.984733)
			(xy 378.09932 -371.993922) (xy 378.09932 -372.486174) (xy 378.099738 -372.49536) (xy 378.106246 -372.512545)
			(xy 378.11202 -372.519702) (xy 378.133917 -372.54534) (xy 378.172003 -372.600979) (xy 378.203151 -372.660779)
			(xy 378.226913 -372.723879) (xy 378.242945 -372.789372) (xy 378.251018 -372.856313) (xy 378.251015 -372.923739)
			(xy 378.242936 -372.990679) (xy 378.226897 -373.056169) (xy 378.20313 -373.119268) (xy 378.171977 -373.179065)
			(xy 378.133885 -373.2347) (xy 378.11202 -373.260366) (xy 378.106215 -373.267506) (xy 378.099705 -373.2847)
			(xy 378.09932 -373.293894) (xy 378.09932 -373.451374) (xy 378.098851 -373.461504) (xy 378.091125 -373.480232)
			(xy 378.076832 -373.494591) (xy 378.05814 -373.502404) (xy 378.048012 -373.502936) (xy 377.331732 -373.502936)
			(xy 377.321584 -373.502453) (xy 377.30284 -373.494675) (xy 377.288516 -373.480297) (xy 377.280809 -373.461523)
			(xy 377.280424 -373.451374) (xy 377.280424 -373.293894) (xy 377.280012 -373.284707) (xy 377.273499 -373.267523)
			(xy 377.267724 -373.260366) (xy 377.245893 -373.234674) (xy 377.207801 -373.179044) (xy 377.176648 -373.119251)
			(xy 377.152881 -373.056158) (xy 377.136842 -372.990672) (xy 377.128763 -372.923736) (xy 377.12876 -372.856315)
			(xy 377.136833 -372.789378) (xy 377.152865 -372.723891) (xy 377.176627 -372.660795) (xy 377.207775 -372.601)
			(xy 377.245861 -372.545367) (xy 377.267724 -372.519702) (xy 377.273505 -372.512546) (xy 377.280028 -372.495364)
			(xy 377.280424 -372.486174) (xy 377.280424 -371.993922) (xy 377.279998 -371.984737) (xy 377.273495 -371.967552)
			(xy 377.267724 -371.960394) (xy 377.245822 -371.93476) (xy 377.207733 -371.879122) (xy 377.176582 -371.819321)
			(xy 377.152819 -371.75622) (xy 377.136786 -371.690727) (xy 377.128712 -371.623785) (xy 376.026618 -371.623785)
			(xy 376.026831 -371.624351) (xy 376.042802 -371.689734) (xy 376.050845 -371.756558) (xy 376.050844 -371.823863)
			(xy 376.042799 -371.890687) (xy 376.026825 -371.956069) (xy 376.003151 -372.019074) (xy 375.972117 -372.078799)
			(xy 375.934168 -372.134386) (xy 375.91238 -372.160038) (xy 375.906582 -372.167182) (xy 375.900069 -372.184374)
			(xy 375.89968 -372.193566) (xy 375.89968 -372.351554) (xy 375.899199 -372.36172) (xy 375.891432 -372.380511)
			(xy 375.877064 -372.394896) (xy 375.858284 -372.402686) (xy 375.848118 -372.403116) (xy 375.131838 -372.403116)
			(xy 375.121663 -372.402704) (xy 375.102861 -372.394923) (xy 375.088473 -372.380533) (xy 375.080695 -372.361729)
			(xy 375.080276 -372.351554) (xy 375.080276 -372.193566) (xy 375.079887 -372.184376) (xy 375.073359 -372.167192)
			(xy 375.067576 -372.160038) (xy 375.045801 -372.134375) (xy 375.007849 -372.078791) (xy 374.976813 -372.019069)
			(xy 374.953138 -371.956066) (xy 374.937163 -371.890685) (xy 374.929117 -371.823863) (xy 374.929116 -371.756558)
			(xy 374.937159 -371.689736) (xy 374.953132 -371.624354) (xy 374.976805 -371.56135) (xy 375.007838 -371.501627)
			(xy 375.045788 -371.446042) (xy 375.067576 -371.42039) (xy 375.073357 -371.413233) (xy 375.079882 -371.396052)
			(xy 375.080276 -371.386862) (xy 375.080276 -370.89334) (xy 375.079852 -370.884154) (xy 375.073349 -370.866969)
			(xy 375.067576 -370.859812) (xy 375.045775 -370.83417) (xy 375.007825 -370.778583) (xy 374.97679 -370.718858)
			(xy 374.953116 -370.655852) (xy 374.937143 -370.590469) (xy 374.929099 -370.523644) (xy 345.250797 -370.523644)
			(xy 345.242754 -370.590465) (xy 345.226782 -370.655847) (xy 345.203109 -370.718851) (xy 345.172076 -370.778574)
			(xy 345.134128 -370.83416) (xy 345.11234 -370.859812) (xy 345.106548 -370.86696) (xy 345.100032 -370.884149)
			(xy 345.09964 -370.89334) (xy 345.09964 -371.386862) (xy 345.100082 -371.396046) (xy 345.106575 -371.41323)
			(xy 345.11234 -371.42039) (xy 345.134142 -371.446031) (xy 345.172092 -371.501618) (xy 345.203126 -371.561343)
			(xy 345.226564 -371.623726) (xy 346.329187 -371.623726) (xy 346.32919 -371.556417) (xy 346.337239 -371.489591)
			(xy 346.353217 -371.424206) (xy 346.376896 -371.3612) (xy 346.407936 -371.301476) (xy 346.445893 -371.24589)
			(xy 346.467684 -371.220238) (xy 346.473488 -371.213098) (xy 346.479999 -371.195904) (xy 346.480384 -371.18671)
			(xy 346.480384 -371.028722) (xy 346.480783 -371.018546) (xy 346.488569 -370.999743) (xy 346.502963 -370.985356)
			(xy 346.52177 -370.977578) (xy 346.531946 -370.97716) (xy 347.248226 -370.97716) (xy 347.258388 -370.977612)
			(xy 347.277162 -370.9854) (xy 347.291527 -370.999778) (xy 347.299297 -371.018559) (xy 347.299788 -371.028722)
			(xy 347.299788 -371.18671) (xy 347.300196 -371.195897) (xy 347.306711 -371.213082) (xy 347.312488 -371.220238)
			(xy 347.334237 -371.245921) (xy 347.372185 -371.301504) (xy 347.403219 -371.361224) (xy 347.426893 -371.424224)
			(xy 347.442867 -371.489602) (xy 347.450914 -371.556421) (xy 347.450918 -371.623722) (xy 347.442878 -371.690542)
			(xy 347.426909 -371.755921) (xy 347.403242 -371.818924) (xy 347.372215 -371.878647) (xy 347.334272 -371.934233)
			(xy 347.312488 -371.959886) (xy 347.306671 -371.967017) (xy 347.300169 -371.984218) (xy 347.299788 -371.993414)
			(xy 347.299788 -372.486682) (xy 347.30021 -372.495868) (xy 347.306716 -372.513052) (xy 347.312488 -372.52021)
			(xy 347.334308 -372.545835) (xy 347.372254 -372.601426) (xy 347.403285 -372.661154) (xy 347.426954 -372.724162)
			(xy 347.442924 -372.789547) (xy 347.450965 -372.856372) (xy 347.450962 -372.923679) (xy 347.442915 -372.990504)
			(xy 347.426939 -373.055887) (xy 347.403264 -373.118893) (xy 347.372228 -373.178618) (xy 347.334277 -373.234205)
			(xy 347.312488 -373.259858) (xy 347.306683 -373.266997) (xy 347.300174 -373.284192) (xy 347.299788 -373.293386)
			(xy 347.299788 -373.451374) (xy 347.299246 -373.461527) (xy 347.291485 -373.480291) (xy 347.277134 -373.494656)
			(xy 347.258378 -373.502436) (xy 347.248226 -373.502936) (xy 346.531946 -373.502936) (xy 346.521774 -373.502498)
			(xy 346.502975 -373.494723) (xy 346.488588 -373.480341) (xy 346.480806 -373.461546) (xy 346.480384 -373.451374)
			(xy 346.480384 -373.293386) (xy 346.479984 -373.284198) (xy 346.473464 -373.267013) (xy 346.467684 -373.259858)
			(xy 346.445928 -373.234179) (xy 346.407976 -373.178597) (xy 346.376938 -373.118878) (xy 346.353262 -373.055877)
			(xy 346.337285 -372.990498) (xy 346.329237 -372.923677) (xy 346.329234 -372.856374) (xy 346.337276 -372.789553)
			(xy 346.353247 -372.724172) (xy 346.376917 -372.661169) (xy 346.407949 -372.601447) (xy 346.445897 -372.545862)
			(xy 346.467684 -372.52021) (xy 346.473499 -372.513078) (xy 346.480003 -372.495877) (xy 346.480384 -372.486682)
			(xy 346.480384 -371.993414) (xy 346.479971 -371.984227) (xy 346.47346 -371.967042) (xy 346.467684 -371.959886)
			(xy 346.445858 -371.934265) (xy 346.407907 -371.878675) (xy 346.376873 -371.818948) (xy 346.3532 -371.755939)
			(xy 346.337229 -371.690553) (xy 346.329187 -371.623726) (xy 345.226564 -371.623726) (xy 345.226798 -371.624349)
			(xy 345.242771 -371.689733) (xy 345.250814 -371.756557) (xy 345.250813 -371.823864) (xy 345.242767 -371.890688)
			(xy 345.226792 -371.956071) (xy 345.203117 -372.019076) (xy 345.172081 -372.0788) (xy 345.134129 -372.134386)
			(xy 345.11234 -372.160038) (xy 345.106537 -372.167179) (xy 345.100028 -372.184373) (xy 345.09964 -372.193566)
			(xy 345.09964 -372.351554) (xy 345.099198 -372.361725) (xy 345.091424 -372.380523) (xy 345.077043 -372.394911)
			(xy 345.058249 -372.402693) (xy 345.048078 -372.403116) (xy 344.331798 -372.403116) (xy 344.321621 -372.402737)
			(xy 344.302817 -372.394942) (xy 344.288431 -372.380543) (xy 344.280654 -372.361732) (xy 344.280236 -372.351554)
			(xy 344.280236 -372.193566) (xy 344.279834 -372.184378) (xy 344.273314 -372.167194) (xy 344.267536 -372.160038)
			(xy 344.245762 -372.134374) (xy 344.207813 -372.078789) (xy 344.17678 -372.019067) (xy 344.153106 -371.956064)
			(xy 344.137132 -371.890684) (xy 344.129087 -371.823862) (xy 344.129086 -371.756559) (xy 344.137129 -371.689737)
			(xy 344.1531 -371.624356) (xy 344.176771 -371.561352) (xy 344.207803 -371.501629) (xy 344.245749 -371.446042)
			(xy 344.267536 -371.42039) (xy 344.273324 -371.413239) (xy 344.279843 -371.396053) (xy 344.280236 -371.386862)
			(xy 344.280236 -370.89334) (xy 344.279798 -370.884156) (xy 344.273303 -370.866972) (xy 344.267536 -370.859812)
			(xy 344.245736 -370.83417) (xy 344.207788 -370.778582) (xy 344.176756 -370.718857) (xy 344.153084 -370.655851)
			(xy 344.137112 -370.590468) (xy 344.129068 -370.523644) (xy 340.851006 -370.523644) (xy 340.842963 -370.590465)
			(xy 340.826991 -370.655847) (xy 340.803319 -370.718851) (xy 340.772287 -370.778574) (xy 340.734339 -370.83416)
			(xy 340.712552 -370.859812) (xy 340.706762 -370.866962) (xy 340.700245 -370.884149) (xy 340.699852 -370.89334)
			(xy 340.699852 -371.386862) (xy 340.700291 -371.396046) (xy 340.706786 -371.41323) (xy 340.712552 -371.42039)
			(xy 340.734354 -371.446031) (xy 340.772303 -371.501618) (xy 340.803336 -371.561344) (xy 340.826797 -371.623785)
			(xy 341.928891 -371.623785) (xy 341.928895 -371.556358) (xy 341.936974 -371.489417) (xy 341.953014 -371.423926)
			(xy 341.976782 -371.360828) (xy 342.007937 -371.301031) (xy 342.04603 -371.245395) (xy 342.067896 -371.21973)
			(xy 342.073704 -371.212593) (xy 342.080212 -371.195396) (xy 342.080596 -371.186202) (xy 342.080596 -371.028722)
			(xy 342.081143 -371.018602) (xy 342.088856 -370.99989) (xy 342.103123 -370.985534) (xy 342.121787 -370.977706)
			(xy 342.131904 -370.97716) (xy 342.848184 -370.97716) (xy 342.858332 -370.977634) (xy 342.877076 -370.985417)
			(xy 342.891399 -370.999797) (xy 342.899106 -371.018572) (xy 342.899492 -371.028722) (xy 342.899492 -371.186202)
			(xy 342.899903 -371.195389) (xy 342.906416 -371.212573) (xy 342.912192 -371.21973) (xy 342.934019 -371.245426)
			(xy 342.972109 -371.301056) (xy 343.003262 -371.360848) (xy 343.027029 -371.423941) (xy 343.043067 -371.489426)
			(xy 343.051146 -371.556361) (xy 343.05115 -371.623782) (xy 343.043077 -371.690718) (xy 343.027046 -371.756205)
			(xy 343.003285 -371.8193) (xy 342.972139 -371.879095) (xy 342.934054 -371.934729) (xy 342.912192 -371.960394)
			(xy 342.906415 -371.967553) (xy 342.899889 -371.984733) (xy 342.899492 -371.993922) (xy 342.899492 -372.486174)
			(xy 342.899917 -372.49536) (xy 342.90642 -372.512544) (xy 342.912192 -372.519702) (xy 342.93409 -372.54534)
			(xy 342.972178 -372.600978) (xy 343.003328 -372.660778) (xy 343.02709 -372.723878) (xy 343.043124 -372.789371)
			(xy 343.051197 -372.856312) (xy 343.051194 -372.923739) (xy 343.043114 -372.99068) (xy 343.027075 -373.056171)
			(xy 343.003307 -373.119269) (xy 342.972152 -373.179066) (xy 342.934058 -373.234701) (xy 342.912192 -373.260366)
			(xy 342.906384 -373.267503) (xy 342.899876 -373.2847) (xy 342.899492 -373.293894) (xy 342.899492 -373.451374)
			(xy 342.898953 -373.461495) (xy 342.89124 -373.48021) (xy 342.87697 -373.494566) (xy 342.858302 -373.502392)
			(xy 342.848184 -373.502936) (xy 342.131904 -373.502936) (xy 342.121755 -373.502476) (xy 342.103009 -373.494688)
			(xy 342.088687 -373.480304) (xy 342.080981 -373.461525) (xy 342.080596 -373.451374) (xy 342.080596 -373.293894)
			(xy 342.080189 -373.284706) (xy 342.073673 -373.267522) (xy 342.067896 -373.260366) (xy 342.046066 -373.234673)
			(xy 342.007976 -373.179042) (xy 341.976824 -373.11925) (xy 341.953058 -373.056157) (xy 341.937021 -372.990671)
			(xy 341.928942 -372.923736) (xy 341.928939 -372.856315) (xy 341.937011 -372.789379) (xy 341.953043 -372.723892)
			(xy 341.976803 -372.660797) (xy 342.00795 -372.601001) (xy 342.046034 -372.545367) (xy 342.067896 -372.519702)
			(xy 342.073674 -372.512543) (xy 342.0802 -372.495363) (xy 342.080596 -372.486174) (xy 342.080596 -371.993922)
			(xy 342.080176 -371.984736) (xy 342.073669 -371.967551) (xy 342.067896 -371.960394) (xy 342.045995 -371.934759)
			(xy 342.007908 -371.87912) (xy 341.976759 -371.81932) (xy 341.952997 -371.756219) (xy 341.936964 -371.690726)
			(xy 341.928891 -371.623785) (xy 340.826797 -371.623785) (xy 340.827009 -371.62435) (xy 340.842981 -371.689733)
			(xy 340.851024 -371.756557) (xy 340.851023 -371.823864) (xy 340.842977 -371.890687) (xy 340.827002 -371.956071)
			(xy 340.803328 -372.019076) (xy 340.772292 -372.0788) (xy 340.734341 -372.134386) (xy 340.712552 -372.160038)
			(xy 340.706751 -372.16718) (xy 340.70024 -372.184373) (xy 340.699852 -372.193566) (xy 340.699852 -372.351554)
			(xy 340.699398 -372.361724) (xy 340.691627 -372.380519) (xy 340.67725 -372.394906) (xy 340.65846 -372.402691)
			(xy 340.64829 -372.403116) (xy 339.93201 -372.403116) (xy 339.921833 -372.402727) (xy 339.90303 -372.394937)
			(xy 339.888643 -372.38054) (xy 339.880866 -372.361731) (xy 339.880448 -372.351554) (xy 339.880448 -372.193566)
			(xy 339.880043 -372.184378) (xy 339.873525 -372.167195) (xy 339.867748 -372.160038) (xy 339.845974 -372.134375)
			(xy 339.808024 -372.07879) (xy 339.77699 -372.019068) (xy 339.753316 -371.956065) (xy 339.737342 -371.890684)
			(xy 339.729296 -371.823863) (xy 339.729295 -371.756558) (xy 339.737338 -371.689737) (xy 339.75331 -371.624355)
			(xy 339.776981 -371.561351) (xy 339.808013 -371.501628) (xy 339.845961 -371.446042) (xy 339.867748 -371.42039)
			(xy 339.873537 -371.41324) (xy 339.880055 -371.396053) (xy 339.880448 -371.386862) (xy 339.880448 -370.89334)
			(xy 339.880008 -370.884156) (xy 339.873514 -370.866972) (xy 339.867748 -370.859812) (xy 339.845948 -370.83417)
			(xy 339.807999 -370.778582) (xy 339.776966 -370.718857) (xy 339.753293 -370.655851) (xy 339.737321 -370.590468)
			(xy 339.729277 -370.523644) (xy 336.451238 -370.523644) (xy 336.451238 -370.523703) (xy 336.443163 -370.590641)
			(xy 336.427128 -370.65613) (xy 336.403363 -370.719227) (xy 336.372211 -370.779022) (xy 336.334121 -370.834656)
			(xy 336.312256 -370.86032) (xy 336.306463 -370.867467) (xy 336.299947 -370.884656) (xy 336.299556 -370.893848)
			(xy 336.299556 -371.386354) (xy 336.299998 -371.395538) (xy 336.306491 -371.412722) (xy 336.312256 -371.419882)
			(xy 336.334135 -371.445535) (xy 336.372226 -371.50117) (xy 336.403379 -371.560968) (xy 336.427016 -371.623725)
			(xy 337.529123 -371.623725) (xy 337.529126 -371.556418) (xy 337.537174 -371.489593) (xy 337.55315 -371.424209)
			(xy 337.576825 -371.361204) (xy 337.60786 -371.301479) (xy 337.645811 -371.245891) (xy 337.6676 -371.220238)
			(xy 337.673405 -371.213099) (xy 337.679915 -371.195904) (xy 337.6803 -371.18671) (xy 337.6803 -371.028722)
			(xy 337.68085 -371.01857) (xy 337.68861 -370.999809) (xy 337.702958 -370.985444) (xy 337.721711 -370.977662)
			(xy 337.731862 -370.97716) (xy 338.448142 -370.97716) (xy 338.458305 -370.9776) (xy 338.477079 -370.985392)
			(xy 338.491444 -370.999774) (xy 338.499213 -371.018558) (xy 338.499704 -371.028722) (xy 338.499704 -371.18671)
			(xy 338.500109 -371.195898) (xy 338.506626 -371.213082) (xy 338.512404 -371.220238) (xy 338.534153 -371.245921)
			(xy 338.5721 -371.301504) (xy 338.603133 -371.361224) (xy 338.626806 -371.424224) (xy 338.64278 -371.489602)
			(xy 338.650827 -371.556421) (xy 338.65083 -371.623722) (xy 338.64279 -371.690541) (xy 338.626823 -371.755921)
			(xy 338.603156 -371.818924) (xy 338.57213 -371.878646) (xy 338.534188 -371.934233) (xy 338.512404 -371.959886)
			(xy 338.506589 -371.967018) (xy 338.500085 -371.984219) (xy 338.499704 -371.993414) (xy 338.499704 -372.486682)
			(xy 338.500122 -372.495868) (xy 338.50663 -372.513053) (xy 338.512404 -372.52021) (xy 338.534224 -372.545835)
			(xy 338.572169 -372.601427) (xy 338.603198 -372.661154) (xy 338.626867 -372.724162) (xy 338.642836 -372.789547)
			(xy 338.650877 -372.856372) (xy 338.650874 -372.923679) (xy 338.642827 -372.990503) (xy 338.626852 -373.055887)
			(xy 338.603177 -373.118892) (xy 338.572142 -373.178617) (xy 338.534192 -373.234205) (xy 338.512404 -373.259858)
			(xy 338.506601 -373.266999) (xy 338.50009 -373.284193) (xy 338.499704 -373.293386) (xy 338.499704 -373.451374)
			(xy 338.499147 -373.461525) (xy 338.491388 -373.480286) (xy 338.477043 -373.49465) (xy 338.458292 -373.502433)
			(xy 338.448142 -373.502936) (xy 337.731862 -373.502936) (xy 337.721699 -373.502497) (xy 337.702924 -373.494705)
			(xy 337.688559 -373.480323) (xy 337.68079 -373.461538) (xy 337.6803 -373.451374) (xy 337.6803 -373.293386)
			(xy 337.679896 -373.284198) (xy 337.673378 -373.267014) (xy 337.6676 -373.259858) (xy 337.645847 -373.234178)
			(xy 337.6079 -373.178595) (xy 337.576867 -373.118874) (xy 337.553194 -373.055874) (xy 337.53722 -372.990495)
			(xy 337.529174 -372.923676) (xy 337.52917 -372.856375) (xy 337.537211 -372.789555) (xy 337.553179 -372.724175)
			(xy 337.576846 -372.661172) (xy 337.607873 -372.601449) (xy 337.645816 -372.545863) (xy 337.6676 -372.52021)
			(xy 337.673417 -372.513079) (xy 337.67992 -372.495878) (xy 337.6803 -372.486682) (xy 337.6803 -371.993414)
			(xy 337.679883 -371.984228) (xy 337.673374 -371.967043) (xy 337.6676 -371.959886) (xy 337.645776 -371.934264)
			(xy 337.607831 -371.878672) (xy 337.576802 -371.818944) (xy 337.553133 -371.755936) (xy 337.537163 -371.69055)
			(xy 337.529123 -371.623725) (xy 336.427016 -371.623725) (xy 336.427144 -371.624066) (xy 336.44318 -371.689557)
			(xy 336.451256 -371.756498) (xy 336.451254 -371.823923) (xy 336.443176 -371.890863) (xy 336.427138 -371.956354)
			(xy 336.40337 -372.019451) (xy 336.372216 -372.079248) (xy 336.334122 -372.134881) (xy 336.312256 -372.160546)
			(xy 336.306452 -372.167686) (xy 336.299943 -372.184881) (xy 336.299556 -372.194074) (xy 336.299556 -372.351554)
			(xy 336.299036 -372.361678) (xy 336.291322 -372.380399) (xy 336.277046 -372.394757) (xy 336.258369 -372.402577)
			(xy 336.248248 -372.403116) (xy 335.531968 -372.403116) (xy 335.521814 -372.402705) (xy 335.503064 -372.394902)
			(xy 335.488742 -372.380502) (xy 335.481041 -372.36171) (xy 335.48066 -372.351554) (xy 335.48066 -372.194074)
			(xy 335.480249 -372.184887) (xy 335.473734 -372.167704) (xy 335.46796 -372.160546) (xy 335.446111 -372.134869)
			(xy 335.408025 -372.079235) (xy 335.376876 -372.01944) (xy 335.353112 -371.956345) (xy 335.337077 -371.890858)
			(xy 335.329001 -371.823921) (xy 335.329 -371.7565) (xy 335.337073 -371.689563) (xy 335.353106 -371.624075)
			(xy 335.376867 -371.560979) (xy 335.408014 -371.501183) (xy 335.446098 -371.445548) (xy 335.46796 -371.419882)
			(xy 335.473754 -371.412735) (xy 335.480269 -371.395546) (xy 335.48066 -371.386354) (xy 335.48066 -370.893848)
			(xy 335.480214 -370.884665) (xy 335.473724 -370.867481) (xy 335.46796 -370.86032) (xy 335.446086 -370.834664)
			(xy 335.408 -370.779027) (xy 335.376852 -370.719229) (xy 335.35309 -370.656131) (xy 335.337057 -370.590642)
			(xy 335.328983 -370.523703) (xy 332.050912 -370.523703) (xy 332.042876 -370.590465) (xy 332.026905 -370.655846)
			(xy 332.003233 -370.71885) (xy 331.972202 -370.778573) (xy 331.934255 -370.83416) (xy 331.912468 -370.859812)
			(xy 331.90668 -370.866963) (xy 331.900161 -370.884149) (xy 331.899768 -370.89334) (xy 331.899768 -371.386862)
			(xy 331.900204 -371.396046) (xy 331.906701 -371.41323) (xy 331.912468 -371.42039) (xy 331.934269 -371.446031)
			(xy 331.972217 -371.501619) (xy 332.00325 -371.561344) (xy 332.026709 -371.623785) (xy 333.128803 -371.623785)
			(xy 333.128807 -371.556358) (xy 333.136887 -371.489417) (xy 333.152927 -371.423926) (xy 333.176696 -371.360827)
			(xy 333.207851 -371.30103) (xy 333.245945 -371.245395) (xy 333.267812 -371.21973) (xy 333.273622 -371.212594)
			(xy 333.280128 -371.195397) (xy 333.280512 -371.186202) (xy 333.280512 -371.028722) (xy 333.281044 -371.0186)
			(xy 333.288759 -370.999885) (xy 333.303031 -370.985529) (xy 333.321701 -370.977704) (xy 333.33182 -370.97716)
			(xy 334.0481 -370.97716) (xy 334.058249 -370.977621) (xy 334.076994 -370.985409) (xy 334.091316 -370.999793)
			(xy 334.099023 -371.018571) (xy 334.099408 -371.028722) (xy 334.099408 -371.186202) (xy 334.099815 -371.195389)
			(xy 334.106331 -371.212574) (xy 334.112108 -371.21973) (xy 334.133934 -371.245426) (xy 334.172024 -371.301056)
			(xy 334.203176 -371.360848) (xy 334.226942 -371.423941) (xy 334.242979 -371.489426) (xy 334.251058 -371.556361)
			(xy 334.251062 -371.623782) (xy 334.24299 -371.690717) (xy 334.226958 -371.756204) (xy 334.203199 -371.819299)
			(xy 334.172053 -371.879095) (xy 334.133969 -371.934729) (xy 334.112108 -371.960394) (xy 334.106332 -371.967554)
			(xy 334.099805 -371.984733) (xy 334.099408 -371.993922) (xy 334.099408 -372.486174) (xy 334.099829 -372.49536)
			(xy 334.106335 -372.512545) (xy 334.112108 -372.519702) (xy 334.134005 -372.54534) (xy 334.172092 -372.600978)
			(xy 334.203241 -372.660779) (xy 334.227003 -372.723879) (xy 334.243036 -372.789371) (xy 334.251109 -372.856312)
			(xy 334.251106 -372.923739) (xy 334.243027 -372.990679) (xy 334.226988 -373.05617) (xy 334.20322 -373.119268)
			(xy 334.172066 -373.179065) (xy 334.133974 -373.234701) (xy 334.112108 -373.260366) (xy 334.106302 -373.267504)
			(xy 334.099793 -373.2847) (xy 334.099408 -373.293894) (xy 334.099408 -373.451374) (xy 334.098854 -373.461493)
			(xy 334.091143 -373.480205) (xy 334.076878 -373.49456) (xy 334.058216 -373.502389) (xy 334.0481 -373.502936)
			(xy 333.33182 -373.502936) (xy 333.321672 -373.502463) (xy 333.302927 -373.494681) (xy 333.288604 -373.4803)
			(xy 333.280897 -373.461524) (xy 333.280512 -373.451374) (xy 333.280512 -373.293894) (xy 333.280102 -373.284707)
			(xy 333.273588 -373.267523) (xy 333.267812 -373.260366) (xy 333.245981 -373.234673) (xy 333.20789 -373.179043)
			(xy 333.176738 -373.119251) (xy 333.152971 -373.056157) (xy 333.136933 -372.990672) (xy 333.128854 -372.923736)
			(xy 333.128851 -372.856315) (xy 333.136924 -372.789379) (xy 333.152956 -372.723891) (xy 333.176717 -372.660796)
			(xy 333.207864 -372.601001) (xy 333.24595 -372.545367) (xy 333.267812 -372.519702) (xy 333.273592 -372.512545)
			(xy 333.280116 -372.495363) (xy 333.280512 -372.486174) (xy 333.280512 -371.993922) (xy 333.280088 -371.984736)
			(xy 333.273584 -371.967552) (xy 333.267812 -371.960394) (xy 333.24591 -371.93476) (xy 333.207822 -371.879121)
			(xy 333.176672 -371.819321) (xy 333.15291 -371.75622) (xy 333.136876 -371.690727) (xy 333.128803 -371.623785)
			(xy 332.026709 -371.623785) (xy 332.026921 -371.62435) (xy 332.042893 -371.689734) (xy 332.050936 -371.756558)
			(xy 332.050935 -371.823864) (xy 332.042889 -371.890687) (xy 332.026915 -371.95607) (xy 332.003241 -372.019075)
			(xy 331.972207 -372.078799) (xy 331.934256 -372.134386) (xy 331.912468 -372.160038) (xy 331.906669 -372.167181)
			(xy 331.900156 -372.184373) (xy 331.899768 -372.193566) (xy 331.899768 -372.351554) (xy 331.899299 -372.361722)
			(xy 331.89153 -372.380514) (xy 331.877158 -372.394901) (xy 331.858373 -372.402688) (xy 331.848206 -372.403116)
			(xy 331.131926 -372.403116) (xy 331.12175 -372.402714) (xy 331.102948 -372.394929) (xy 331.08856 -372.380536)
			(xy 331.080783 -372.36173) (xy 331.080364 -372.351554) (xy 331.080364 -372.193566) (xy 331.079956 -372.184379)
			(xy 331.073439 -372.167195) (xy 331.067664 -372.160038) (xy 331.045889 -372.134375) (xy 331.007939 -372.078791)
			(xy 330.976903 -372.019069) (xy 330.953229 -371.956066) (xy 330.937254 -371.890684) (xy 330.929208 -371.823863)
			(xy 330.929207 -371.756558) (xy 330.93725 -371.689736) (xy 330.953222 -371.624355) (xy 330.976895 -371.561351)
			(xy 331.007928 -371.501628) (xy 331.045876 -371.446042) (xy 331.067664 -371.42039) (xy 331.073455 -371.413241)
			(xy 331.079971 -371.396053) (xy 331.080364 -371.386862) (xy 331.080364 -370.89334) (xy 331.07992 -370.884157)
			(xy 331.073428 -370.866973) (xy 331.067664 -370.859812) (xy 331.045864 -370.83417) (xy 331.007914 -370.778582)
			(xy 330.97688 -370.718858) (xy 330.953206 -370.655852) (xy 330.937234 -370.590468) (xy 330.92919 -370.523644)
			(xy 301.250887 -370.523644) (xy 301.250887 -370.523702) (xy 301.242812 -370.590639) (xy 301.226779 -370.656127)
			(xy 301.203017 -370.719224) (xy 301.171869 -370.77902) (xy 301.133783 -370.834654) (xy 301.11192 -370.86032)
			(xy 301.106135 -370.867473) (xy 301.099613 -370.884658) (xy 301.09922 -370.893848) (xy 301.09922 -371.386354)
			(xy 301.099648 -371.395539) (xy 301.106149 -371.412724) (xy 301.11192 -371.419882) (xy 301.133797 -371.445536)
			(xy 301.171884 -371.501173) (xy 301.203033 -371.560971) (xy 301.226688 -371.623785) (xy 302.328773 -371.623785)
			(xy 302.328777 -371.556358) (xy 302.336856 -371.489418) (xy 302.352895 -371.423927) (xy 302.376662 -371.360829)
			(xy 302.407815 -371.301031) (xy 302.445907 -371.245396) (xy 302.467772 -371.21973) (xy 302.47359 -371.2126)
			(xy 302.48009 -371.195398) (xy 302.480472 -371.186202) (xy 302.480472 -371.028722) (xy 302.480945 -371.018593)
			(xy 302.488672 -370.999866) (xy 302.502963 -370.985508) (xy 302.521653 -370.977693) (xy 302.53178 -370.97716)
			(xy 303.24806 -370.97716) (xy 303.258207 -370.977654) (xy 303.27695 -370.985429) (xy 303.291274 -370.999803)
			(xy 303.298982 -371.018574) (xy 303.299368 -371.028722) (xy 303.299368 -371.186202) (xy 303.299784 -371.195388)
			(xy 303.306294 -371.212572) (xy 303.312068 -371.21973) (xy 303.333896 -371.245425) (xy 303.371988 -371.301055)
			(xy 303.403142 -371.360847) (xy 303.42691 -371.42394) (xy 303.442949 -371.489425) (xy 303.451028 -371.556361)
			(xy 303.451031 -371.623782) (xy 303.442959 -371.690718) (xy 303.426926 -371.756206) (xy 303.403165 -371.819301)
			(xy 303.372017 -371.879096) (xy 303.333931 -371.934729) (xy 303.312068 -371.960394) (xy 303.306287 -371.96755)
			(xy 303.299764 -371.984732) (xy 303.299368 -371.993922) (xy 303.299368 -372.486174) (xy 303.299798 -372.495359)
			(xy 303.306299 -372.512543) (xy 303.312068 -372.519702) (xy 303.333966 -372.545339) (xy 303.372056 -372.600977)
			(xy 303.403207 -372.660777) (xy 303.426971 -372.723877) (xy 303.443005 -372.78937) (xy 303.451079 -372.856312)
			(xy 303.451076 -372.923739) (xy 303.442996 -372.99068) (xy 303.426956 -373.056172) (xy 303.403186 -373.11927)
			(xy 303.37203 -373.179067) (xy 303.333935 -373.234701) (xy 303.312068 -373.260366) (xy 303.306257 -373.267501)
			(xy 303.299752 -373.284699) (xy 303.299368 -373.293894) (xy 303.299368 -373.451374) (xy 303.298853 -373.461498)
			(xy 303.291135 -373.480217) (xy 303.276857 -373.494574) (xy 303.258181 -373.502396) (xy 303.24806 -373.502936)
			(xy 302.53178 -373.502936) (xy 302.521629 -373.502496) (xy 302.502883 -373.4947) (xy 302.488562 -373.48031)
			(xy 302.480856 -373.461527) (xy 302.480472 -373.451374) (xy 302.480472 -373.293894) (xy 302.480071 -373.284706)
			(xy 302.473552 -373.267521) (xy 302.467772 -373.260366) (xy 302.445942 -373.234673) (xy 302.407855 -373.179042)
			(xy 302.376704 -373.119249) (xy 302.352939 -373.056156) (xy 302.336902 -372.99067) (xy 302.328824 -372.923736)
			(xy 302.328821 -372.856315) (xy 302.336893 -372.78938) (xy 302.352924 -372.723893) (xy 302.376683 -372.660798)
			(xy 302.407828 -372.601002) (xy 302.445911 -372.545368) (xy 302.467772 -372.519702) (xy 302.473559 -372.51255)
			(xy 302.480077 -372.495364) (xy 302.480472 -372.486174) (xy 302.480472 -371.993922) (xy 302.480058 -371.984735)
			(xy 302.473548 -371.96755) (xy 302.467772 -371.960394) (xy 302.445872 -371.934759) (xy 302.407786 -371.87912)
			(xy 302.376638 -371.819319) (xy 302.352878 -371.756218) (xy 302.336846 -371.690726) (xy 302.328773 -371.623785)
			(xy 301.226688 -371.623785) (xy 301.226795 -371.624069) (xy 301.242829 -371.689559) (xy 301.250904 -371.756498)
			(xy 301.250903 -371.823923) (xy 301.242826 -371.890862) (xy 301.226789 -371.956351) (xy 301.203024 -372.019449)
			(xy 301.171873 -372.079245) (xy 301.133784 -372.13488) (xy 301.11192 -372.160546) (xy 301.106124 -372.167692)
			(xy 301.099608 -372.184882) (xy 301.09922 -372.194074) (xy 301.09922 -372.351554) (xy 301.098734 -372.361683)
			(xy 301.091014 -372.38041) (xy 301.076727 -372.39477) (xy 301.058038 -372.402583) (xy 301.047912 -372.403116)
			(xy 300.331632 -372.403116) (xy 300.321482 -372.402653) (xy 300.302733 -372.394871) (xy 300.288409 -372.380487)
			(xy 300.280705 -372.361706) (xy 300.280324 -372.351554) (xy 300.280324 -372.194074) (xy 300.279921 -372.184886)
			(xy 300.273402 -372.167702) (xy 300.267624 -372.160546) (xy 300.245773 -372.13487) (xy 300.207682 -372.079237)
			(xy 300.17653 -372.019443) (xy 300.152764 -371.956347) (xy 300.136726 -371.890859) (xy 300.128649 -371.823922)
			(xy 300.128648 -371.756499) (xy 300.136723 -371.689561) (xy 300.152757 -371.624073) (xy 300.176521 -371.560976)
			(xy 300.207671 -371.501181) (xy 300.24576 -371.445547) (xy 300.267624 -371.419882) (xy 300.273413 -371.412732)
			(xy 300.279932 -371.395545) (xy 300.280324 -371.386354) (xy 300.280324 -370.893848) (xy 300.279885 -370.884664)
			(xy 300.273391 -370.86748) (xy 300.267624 -370.86032) (xy 300.245747 -370.834665) (xy 300.207657 -370.779029)
			(xy 300.176506 -370.719232) (xy 300.152741 -370.656134) (xy 300.136706 -370.590643) (xy 300.128631 -370.523704)
			(xy 296.851096 -370.523704) (xy 296.843021 -370.590639) (xy 296.826988 -370.656127) (xy 296.803227 -370.719223)
			(xy 296.772079 -370.779019) (xy 296.733994 -370.834654) (xy 296.712132 -370.86032) (xy 296.706336 -370.867465)
			(xy 296.699823 -370.884656) (xy 296.699432 -370.893848) (xy 296.699432 -371.386354) (xy 296.699879 -371.395537)
			(xy 296.706369 -371.412721) (xy 296.712132 -371.419882) (xy 296.734009 -371.445536) (xy 296.772095 -371.501173)
			(xy 296.803243 -371.560971) (xy 296.826876 -371.623726) (xy 297.92898 -371.623726) (xy 297.928984 -371.556417)
			(xy 297.937032 -371.489591) (xy 297.95301 -371.424206) (xy 297.976689 -371.3612) (xy 298.007729 -371.301476)
			(xy 298.045685 -371.245889) (xy 298.067476 -371.220238) (xy 298.073279 -371.213097) (xy 298.07979 -371.195903)
			(xy 298.080176 -371.18671) (xy 298.080176 -371.028722) (xy 298.080583 -371.018547) (xy 298.088368 -370.999746)
			(xy 298.102759 -370.985359) (xy 298.121563 -370.97758) (xy 298.131738 -370.97716) (xy 298.848018 -370.97716)
			(xy 298.858193 -370.97755) (xy 298.876993 -370.985345) (xy 298.891378 -370.999741) (xy 298.899158 -371.018546)
			(xy 298.89958 -371.028722) (xy 298.89958 -371.18671) (xy 298.89999 -371.195897) (xy 298.906504 -371.213081)
			(xy 298.91228 -371.220238) (xy 298.93403 -371.245921) (xy 298.971978 -371.301504) (xy 299.003012 -371.361223)
			(xy 299.026686 -371.424224) (xy 299.042661 -371.489602) (xy 299.050708 -371.556421) (xy 299.050711 -371.623722)
			(xy 299.042671 -371.690542) (xy 299.026703 -371.755922) (xy 299.003035 -371.818925) (xy 298.972008 -371.878647)
			(xy 298.934065 -371.934233) (xy 298.91228 -371.959886) (xy 298.906462 -371.967016) (xy 298.899961 -371.984218)
			(xy 298.89958 -371.993414) (xy 298.89958 -372.486682) (xy 298.900003 -372.495868) (xy 298.906508 -372.513052)
			(xy 298.91228 -372.52021) (xy 298.934101 -372.545835) (xy 298.972047 -372.601426) (xy 299.003078 -372.661153)
			(xy 299.026748 -372.724161) (xy 299.042718 -372.789547) (xy 299.050759 -372.856372) (xy 299.050756 -372.923679)
			(xy 299.042709 -372.990504) (xy 299.026733 -373.055888) (xy 299.003057 -373.118894) (xy 298.972021 -373.178618)
			(xy 298.934069 -373.234206) (xy 298.91228 -373.259858) (xy 298.906474 -373.266996) (xy 298.899966 -373.284192)
			(xy 298.89958 -373.293386) (xy 298.89958 -373.451374) (xy 298.899115 -373.461542) (xy 298.891342 -373.480332)
			(xy 298.876969 -373.494717) (xy 298.858185 -373.502506) (xy 298.848018 -373.502936) (xy 298.131738 -373.502936)
			(xy 298.121566 -373.502504) (xy 298.102767 -373.494727) (xy 298.08838 -373.480343) (xy 298.080598 -373.461546)
			(xy 298.080176 -373.451374) (xy 298.080176 -373.293386) (xy 298.079778 -373.284197) (xy 298.073256 -373.267013)
			(xy 298.067476 -373.259858) (xy 298.045721 -373.234179) (xy 298.007768 -373.178597) (xy 297.976732 -373.118878)
			(xy 297.953055 -373.055877) (xy 297.937079 -372.990497) (xy 297.929031 -372.923677) (xy 297.929028 -372.856374)
			(xy 297.93707 -372.789553) (xy 297.95304 -372.724172) (xy 297.976711 -372.661169) (xy 298.007742 -372.601447)
			(xy 298.045689 -372.545862) (xy 298.067476 -372.52021) (xy 298.073291 -372.513077) (xy 298.079795 -372.495877)
			(xy 298.080176 -372.486682) (xy 298.080176 -371.993414) (xy 298.079765 -371.984227) (xy 298.073252 -371.967042)
			(xy 298.067476 -371.959886) (xy 298.04565 -371.934265) (xy 298.007699 -371.878675) (xy 297.976666 -371.818948)
			(xy 297.952993 -371.755939) (xy 297.937022 -371.690552) (xy 297.92898 -371.623726) (xy 296.826876 -371.623726)
			(xy 296.827005 -371.624069) (xy 296.843039 -371.689559) (xy 296.851113 -371.756498) (xy 296.851112 -371.823923)
			(xy 296.843035 -371.890861) (xy 296.826999 -371.956351) (xy 296.803235 -372.019448) (xy 296.772084 -372.079245)
			(xy 296.733996 -372.13488) (xy 296.712132 -372.160546) (xy 296.706325 -372.167684) (xy 296.699819 -372.18488)
			(xy 296.699432 -372.194074) (xy 296.699432 -372.351554) (xy 296.698935 -372.361681) (xy 296.691217 -372.380407)
			(xy 296.676933 -372.394765) (xy 296.658249 -372.402581) (xy 296.648124 -372.403116) (xy 295.931844 -372.403116)
			(xy 295.921695 -372.402643) (xy 295.902946 -372.394865) (xy 295.888622 -372.380484) (xy 295.880918 -372.361705)
			(xy 295.880536 -372.351554) (xy 295.880536 -372.194074) (xy 295.88013 -372.184887) (xy 295.873613 -372.167703)
			(xy 295.867836 -372.160546) (xy 295.845985 -372.13487) (xy 295.807893 -372.079238) (xy 295.77674 -372.019444)
			(xy 295.752973 -371.956348) (xy 295.736936 -371.89086) (xy 295.728858 -371.823922) (xy 295.728857 -371.756499)
			(xy 295.736932 -371.689561) (xy 295.752967 -371.624072) (xy 295.776731 -371.560976) (xy 295.807882 -371.50118)
			(xy 295.845972 -371.445547) (xy 295.867836 -371.419882) (xy 295.873627 -371.412733) (xy 295.880144 -371.395545)
			(xy 295.880536 -371.386354) (xy 295.880536 -370.893848) (xy 295.880095 -370.884664) (xy 295.873602 -370.86748)
			(xy 295.867836 -370.86032) (xy 295.845959 -370.834665) (xy 295.807868 -370.77903) (xy 295.776716 -370.719233)
			(xy 295.752951 -370.656134) (xy 295.736915 -370.590644) (xy 295.72884 -370.523704) (xy 292.450793 -370.523704)
			(xy 292.442757 -370.590465) (xy 292.426785 -370.655847) (xy 292.403113 -370.718851) (xy 292.37208 -370.778574)
			(xy 292.334131 -370.83416) (xy 292.312344 -370.859812) (xy 292.306553 -370.866961) (xy 292.300036 -370.884149)
			(xy 292.299644 -370.89334) (xy 292.299644 -371.386862) (xy 292.300085 -371.396046) (xy 292.306578 -371.41323)
			(xy 292.312344 -371.42039) (xy 292.334146 -371.44603) (xy 292.372096 -371.501618) (xy 292.403129 -371.561343)
			(xy 292.42659 -371.623785) (xy 293.528685 -371.623785) (xy 293.528689 -371.556358) (xy 293.536768 -371.489418)
			(xy 293.552807 -371.423927) (xy 293.576575 -371.360828) (xy 293.60773 -371.301031) (xy 293.645822 -371.245395)
			(xy 293.667688 -371.21973) (xy 293.673495 -371.212592) (xy 293.680004 -371.195396) (xy 293.680388 -371.186202)
			(xy 293.680388 -371.028722) (xy 293.680943 -371.018603) (xy 293.688654 -370.999892) (xy 293.702919 -370.985537)
			(xy 293.72158 -370.977708) (xy 293.731696 -370.97716) (xy 294.447976 -370.97716) (xy 294.458124 -370.97764)
			(xy 294.476868 -370.98542) (xy 294.491191 -370.999799) (xy 294.498898 -371.018573) (xy 294.499284 -371.028722)
			(xy 294.499284 -371.186202) (xy 294.499697 -371.195389) (xy 294.506209 -371.212573) (xy 294.511984 -371.21973)
			(xy 294.533811 -371.245426) (xy 294.571902 -371.301056) (xy 294.603055 -371.360847) (xy 294.626822 -371.42394)
			(xy 294.642861 -371.489426) (xy 294.65094 -371.556361) (xy 294.650944 -371.623782) (xy 294.642871 -371.690718)
			(xy 294.626839 -371.756205) (xy 294.603079 -371.8193) (xy 294.571932 -371.879095) (xy 294.533846 -371.934729)
			(xy 294.511984 -371.960394) (xy 294.506206 -371.967552) (xy 294.499681 -371.984733) (xy 294.499284 -371.993922)
			(xy 294.499284 -372.486174) (xy 294.49971 -372.495359) (xy 294.506213 -372.512544) (xy 294.511984 -372.519702)
			(xy 294.533882 -372.545339) (xy 294.571971 -372.600978) (xy 294.603121 -372.660777) (xy 294.626884 -372.723878)
			(xy 294.642917 -372.789371) (xy 294.650991 -372.856312) (xy 294.650988 -372.923739) (xy 294.642908 -372.99068)
			(xy 294.626869 -373.056171) (xy 294.6031 -373.119269) (xy 294.571944 -373.179066) (xy 294.533851 -373.234701)
			(xy 294.511984 -373.260366) (xy 294.506175 -373.267502) (xy 294.499668 -373.2847) (xy 294.499284 -373.293894)
			(xy 294.499284 -373.451374) (xy 294.498753 -373.461496) (xy 294.491038 -373.480212) (xy 294.476766 -373.494569)
			(xy 294.458095 -373.502393) (xy 294.447976 -373.502936) (xy 293.731696 -373.502936) (xy 293.721546 -373.502482)
			(xy 293.702801 -373.494692) (xy 293.688479 -373.480306) (xy 293.680773 -373.461526) (xy 293.680388 -373.451374)
			(xy 293.680388 -373.293894) (xy 293.679983 -373.284706) (xy 293.673466 -373.267522) (xy 293.667688 -373.260366)
			(xy 293.645858 -373.234673) (xy 293.607769 -373.179042) (xy 293.576617 -373.11925) (xy 293.552852 -373.056156)
			(xy 293.536814 -372.990671) (xy 293.528736 -372.923736) (xy 293.528733 -372.856315) (xy 293.536805 -372.789379)
			(xy 293.552837 -372.723892) (xy 293.576597 -372.660797) (xy 293.607743 -372.601002) (xy 293.645826 -372.545367)
			(xy 293.667688 -372.519702) (xy 293.673465 -372.512543) (xy 293.679992 -372.495363) (xy 293.680388 -372.486174)
			(xy 293.680388 -371.993922) (xy 293.67997 -371.984736) (xy 293.673462 -371.967551) (xy 293.667688 -371.960394)
			(xy 293.645787 -371.934759) (xy 293.6077 -371.87912) (xy 293.576552 -371.81932) (xy 293.55279 -371.756219)
			(xy 293.536758 -371.690726) (xy 293.528685 -371.623785) (xy 292.42659 -371.623785) (xy 292.426802 -371.624349)
			(xy 292.442775 -371.689733) (xy 292.450818 -371.756557) (xy 292.450817 -371.823864) (xy 292.442771 -371.890688)
			(xy 292.426796 -371.956071) (xy 292.403121 -372.019076) (xy 292.372085 -372.0788) (xy 292.334133 -372.134386)
			(xy 292.312344 -372.160038) (xy 292.306542 -372.167179) (xy 292.300032 -372.184373) (xy 292.299644 -372.193566)
			(xy 292.299644 -372.351554) (xy 292.299198 -372.361725) (xy 292.291425 -372.380522) (xy 292.277046 -372.394909)
			(xy 292.258253 -372.402693) (xy 292.248082 -372.403116) (xy 291.531802 -372.403116) (xy 291.521625 -372.402733)
			(xy 291.502821 -372.394941) (xy 291.488435 -372.380542) (xy 291.480658 -372.361732) (xy 291.48024 -372.351554)
			(xy 291.48024 -372.193566) (xy 291.479837 -372.184378) (xy 291.473317 -372.167194) (xy 291.46754 -372.160038)
			(xy 291.445766 -372.134374) (xy 291.407817 -372.07879) (xy 291.376783 -372.019068) (xy 291.353109 -371.956065)
			(xy 291.337135 -371.890684) (xy 291.32909 -371.823862) (xy 291.329089 -371.756559) (xy 291.337132 -371.689737)
			(xy 291.353103 -371.624356) (xy 291.376774 -371.561352) (xy 291.407806 -371.501628) (xy 291.445753 -371.446042)
			(xy 291.46754 -371.42039) (xy 291.473328 -371.413239) (xy 291.479847 -371.396053) (xy 291.48024 -371.386862)
			(xy 291.48024 -370.89334) (xy 291.479801 -370.884156) (xy 291.473306 -370.866972) (xy 291.46754 -370.859812)
			(xy 291.44574 -370.83417) (xy 291.407792 -370.778582) (xy 291.376759 -370.718857) (xy 291.353087 -370.655851)
			(xy 291.337115 -370.590468) (xy 291.329071 -370.523644) (xy 288.051032 -370.523644) (xy 288.051032 -370.523703)
			(xy 288.042957 -370.590641) (xy 288.026921 -370.65613) (xy 288.003156 -370.719227) (xy 287.972004 -370.779022)
			(xy 287.933913 -370.834656) (xy 287.912048 -370.86032) (xy 287.906254 -370.867467) (xy 287.899739 -370.884656)
			(xy 287.899348 -370.893848) (xy 287.899348 -371.386354) (xy 287.899792 -371.395537) (xy 287.906284 -371.412721)
			(xy 287.912048 -371.419882) (xy 287.933928 -371.445535) (xy 287.972019 -371.50117) (xy 288.003172 -371.560967)
			(xy 288.02681 -371.623726) (xy 289.128893 -371.623726) (xy 289.128896 -371.556417) (xy 289.136945 -371.489591)
			(xy 289.152924 -371.424206) (xy 289.176603 -371.3612) (xy 289.207644 -371.301475) (xy 289.2456 -371.245889)
			(xy 289.267392 -371.220238) (xy 289.273196 -371.213098) (xy 289.279707 -371.195904) (xy 289.280092 -371.18671)
			(xy 289.280092 -371.028722) (xy 289.28065 -371.018571) (xy 289.288409 -370.999811) (xy 289.302754 -370.985447)
			(xy 289.321504 -370.977663) (xy 289.331654 -370.97716) (xy 290.047934 -370.97716) (xy 290.058097 -370.977606)
			(xy 290.076871 -370.985396) (xy 290.091236 -370.999776) (xy 290.099005 -371.018559) (xy 290.099496 -371.028722)
			(xy 290.099496 -371.18671) (xy 290.099902 -371.195898) (xy 290.106419 -371.213082) (xy 290.112196 -371.220238)
			(xy 290.133945 -371.245921) (xy 290.171893 -371.301504) (xy 290.202926 -371.361224) (xy 290.226599 -371.424224)
			(xy 290.242574 -371.489602) (xy 290.250621 -371.556421) (xy 290.250624 -371.623722) (xy 290.242584 -371.690542)
			(xy 290.226616 -371.755921) (xy 290.202949 -371.818924) (xy 290.171922 -371.878647) (xy 290.13398 -371.934233)
			(xy 290.112196 -371.959886) (xy 290.10638 -371.967017) (xy 290.099877 -371.984218) (xy 290.099496 -371.993414)
			(xy 290.099496 -372.486682) (xy 290.099916 -372.495868) (xy 290.106423 -372.513053) (xy 290.112196 -372.52021)
			(xy 290.134016 -372.545835) (xy 290.171962 -372.601426) (xy 290.202991 -372.661154) (xy 290.226661 -372.724162)
			(xy 290.24263 -372.789547) (xy 290.250671 -372.856372) (xy 290.250668 -372.923679) (xy 290.242621 -372.990503)
			(xy 290.226646 -373.055887) (xy 290.202971 -373.118893) (xy 290.171935 -373.178618) (xy 290.133985 -373.234205)
			(xy 290.112196 -373.259858) (xy 290.106392 -373.266998) (xy 290.099882 -373.284192) (xy 290.099496 -373.293386)
			(xy 290.099496 -373.451374) (xy 290.098946 -373.461526) (xy 290.091187 -373.480288) (xy 290.076838 -373.494653)
			(xy 290.058085 -373.502435) (xy 290.047934 -373.502936) (xy 289.331654 -373.502936) (xy 289.32149 -373.502504)
			(xy 289.302715 -373.494709) (xy 289.28835 -373.480325) (xy 289.280582 -373.461539) (xy 289.280092 -373.451374)
			(xy 289.280092 -373.293386) (xy 289.27969 -373.284198) (xy 289.273171 -373.267014) (xy 289.267392 -373.259858)
			(xy 289.245636 -373.234179) (xy 289.207683 -373.178598) (xy 289.176645 -373.118878) (xy 289.152968 -373.055877)
			(xy 289.136991 -372.990498) (xy 289.128943 -372.923677) (xy 289.12894 -372.856374) (xy 289.136982 -372.789553)
			(xy 289.152953 -372.724172) (xy 289.176624 -372.661168) (xy 289.207656 -372.601446) (xy 289.245605 -372.545861)
			(xy 289.267392 -372.52021) (xy 289.273208 -372.513079) (xy 289.279711 -372.495878) (xy 289.280092 -372.486682)
			(xy 289.280092 -371.993414) (xy 289.279677 -371.984227) (xy 289.273167 -371.967043) (xy 289.267392 -371.959886)
			(xy 289.245565 -371.934265) (xy 289.207614 -371.878676) (xy 289.17658 -371.818948) (xy 289.152907 -371.755939)
			(xy 289.136935 -371.690553) (xy 289.128893 -371.623726) (xy 288.02681 -371.623726) (xy 288.026938 -371.624066)
			(xy 288.042974 -371.689557) (xy 288.05105 -371.756498) (xy 288.051048 -371.823923) (xy 288.04297 -371.890864)
			(xy 288.026932 -371.956354) (xy 288.003164 -372.019452) (xy 287.972008 -372.079248) (xy 287.933915 -372.134882)
			(xy 287.912048 -372.160546) (xy 287.906243 -372.167685) (xy 287.899735 -372.18488) (xy 287.899348 -372.194074)
			(xy 287.899348 -372.351554) (xy 287.898835 -372.361679) (xy 287.89112 -372.380402) (xy 287.876842 -372.39476)
			(xy 287.858162 -372.402579) (xy 287.84804 -372.403116) (xy 287.13176 -372.403116) (xy 287.121605 -372.402711)
			(xy 287.102855 -372.394906) (xy 287.088534 -372.380504) (xy 287.080833 -372.361711) (xy 287.080452 -372.351554)
			(xy 287.080452 -372.194074) (xy 287.080043 -372.184887) (xy 287.073527 -372.167703) (xy 287.067752 -372.160546)
			(xy 287.0459 -372.13487) (xy 287.007807 -372.079238) (xy 286.976653 -372.019444) (xy 286.952886 -371.956349)
			(xy 286.936848 -371.89086) (xy 286.92877 -371.823922) (xy 286.928769 -371.756499) (xy 286.936844 -371.68956)
			(xy 286.95288 -371.624072) (xy 286.976645 -371.560975) (xy 287.007797 -371.50118) (xy 287.045887 -371.445546)
			(xy 287.067752 -371.419882) (xy 287.073545 -371.412735) (xy 287.08006 -371.395546) (xy 287.080452 -371.386354)
			(xy 287.080452 -370.893848) (xy 287.080007 -370.884665) (xy 287.073516 -370.867481) (xy 287.067752 -370.86032)
			(xy 287.045874 -370.834665) (xy 287.007783 -370.779031) (xy 286.97663 -370.719233) (xy 286.952864 -370.656135)
			(xy 286.936828 -370.590644) (xy 286.928752 -370.523704) (xy 266.501372 -370.523704) (xy 266.501372 -377.582176)
			(xy 266.500885 -377.607127) (xy 266.493084 -377.656414) (xy 266.47767 -377.703875) (xy 266.455022 -377.748341)
			(xy 266.425698 -377.788717) (xy 266.408408 -377.806712) (xy 265.993118 -378.222002) (xy 265.975118 -378.239283)
			(xy 265.934733 -378.268585) (xy 265.890267 -378.291219) (xy 265.84281 -378.306629) (xy 265.79353 -378.314436)
			(xy 265.768582 -378.314966) (xy 243.004086 -378.314966) (xy 242.979134 -378.314483) (xy 242.929841 -378.306691)
			(xy 242.882374 -378.291283) (xy 242.837902 -378.268641) (xy 242.797519 -378.239321) (xy 242.77955 -378.222002)
			(xy 242.203732 -377.646184) (xy 242.186446 -377.628186) (xy 242.157132 -377.587804) (xy 242.134486 -377.543339)
			(xy 242.119065 -377.495881) (xy 242.111247 -377.446598) (xy 242.110768 -377.421648) (xy 242.110768 -377.180602)
			(xy 242.110345 -377.170532) (xy 242.102627 -377.15193) (xy 242.095782 -377.144534) (xy 242.00104 -377.049792)
			(xy 241.993638 -377.042956) (xy 241.97504 -377.035244) (xy 241.964972 -377.034806) (xy 236.209586 -377.034806)
			(xy 236.184632 -377.034349) (xy 236.135337 -377.026554) (xy 236.087868 -377.011143) (xy 236.043395 -376.988496)
			(xy 236.003012 -376.95917) (xy 235.98505 -376.941842) (xy 235.566712 -376.523504) (xy 235.549426 -376.505506)
			(xy 235.520111 -376.465124) (xy 235.497464 -376.420659) (xy 235.482041 -376.373202) (xy 235.47422 -376.323918)
			(xy 235.473748 -376.298968) (xy 235.473748 -368.60607) (xy 235.474232 -368.581118) (xy 235.482027 -368.531827)
			(xy 235.497437 -368.484363) (xy 235.520081 -368.439892) (xy 235.549403 -368.399512) (xy 235.566712 -368.381534)
			(xy 235.993178 -367.955068) (xy 236.011176 -367.937784) (xy 236.051559 -367.908475) (xy 236.096025 -367.885835)
			(xy 236.143482 -367.870421) (xy 236.192765 -367.862612) (xy 236.217714 -367.862104) (xy 266.741148 -367.862104)
			(xy 266.751214 -367.861672) (xy 266.769806 -367.853946) (xy 266.777216 -367.847118) (xy 267.665708 -366.958626)
			(xy 267.683706 -366.94134) (xy 267.724088 -366.912025) (xy 267.768553 -366.889379) (xy 267.81601 -366.873957)
			(xy 267.865294 -366.866138) (xy 267.890244 -366.865662) (xy 271.438878 -366.865662) (xy 271.446753 -366.865375)
			(xy 271.461763 -366.860601) (xy 271.468342 -366.856264) (xy 271.489932 -366.841477) (xy 271.53635 -366.817318)
			(xy 271.585635 -366.799729) (xy 271.636862 -366.789043) (xy 271.689068 -366.785458) (xy 271.741274 -366.789043)
			(xy 271.792501 -366.799729) (xy 271.841786 -366.817318) (xy 271.888204 -366.841477) (xy 271.909794 -366.856264)
			(xy 271.916379 -366.860593) (xy 271.931383 -366.865383) (xy 271.939258 -366.865662) (xy 455.622152 -366.865662)
			(xy 455.649584 -366.843818) (xy 455.653648 -366.826546) (xy 455.660663 -366.799014) (xy 455.681734 -366.746251)
			(xy 455.710397 -366.697197) (xy 455.746017 -366.652937) (xy 455.787808 -366.614448) (xy 455.834846 -366.582584)
			(xy 455.886088 -366.558047) (xy 455.940403 -366.541382) (xy 455.996589 -366.532956) (xy 456.053403 -366.532956)
			(xy 456.109589 -366.541382) (xy 456.163904 -366.558047) (xy 456.215146 -366.582584) (xy 456.262184 -366.614448)
			(xy 456.303975 -366.652937) (xy 456.339595 -366.697197) (xy 456.368258 -366.746251) (xy 456.389329 -366.799014)
			(xy 456.396344 -366.826546) (xy 456.400408 -366.843818) (xy 456.42784 -366.865662) (xy 458.429868 -366.865662)
			(xy 458.4573 -366.843818) (xy 458.461364 -366.826546) (xy 458.468379 -366.799014) (xy 458.48945 -366.746251)
			(xy 458.518113 -366.697197) (xy 458.553733 -366.652937) (xy 458.595524 -366.614448) (xy 458.642562 -366.582584)
			(xy 458.693804 -366.558047) (xy 458.748119 -366.541382) (xy 458.804305 -366.532956) (xy 458.861119 -366.532956)
			(xy 458.917305 -366.541382) (xy 458.97162 -366.558047) (xy 459.022862 -366.582584) (xy 459.0699 -366.614448)
			(xy 459.111691 -366.652937) (xy 459.147311 -366.697197) (xy 459.175974 -366.746251) (xy 459.197045 -366.799014)
			(xy 459.20406 -366.826546) (xy 459.208124 -366.843818) (xy 459.235556 -366.865662) (xy 466.02523 -366.865662)
			(xy 466.035245 -366.865237) (xy 466.053745 -366.85756) (xy 466.067898 -366.843387) (xy 466.07555 -366.824877)
			(xy 466.07603 -366.814862) (xy 466.07603 -316.782196) (xy 466.075668 -316.773118) (xy 466.069325 -316.756108)
			(xy 466.057412 -316.742408) (xy 466.049614 -316.737746) (xy 465.95919 -316.68847) (xy 465.93125 -316.689486)
			(xy 465.91982 -316.696852) (xy 465.85211 -316.739573) (xy 465.713263 -316.81932) (xy 465.570794 -316.8924)
			(xy 465.425024 -316.95865) (xy 465.276279 -317.017921) (xy 465.124893 -317.070078) (xy 464.971207 -317.115007)
			(xy 464.815565 -317.152605) (xy 464.658316 -317.182788) (xy 464.499815 -317.205489) (xy 464.340416 -317.220656)
			(xy 464.180477 -317.228256) (xy 464.100418 -317.228728) (xy 464.09991 -317.228728) (xy 464.018255 -317.228243)
			(xy 463.855136 -317.220353) (xy 463.692588 -317.204592) (xy 463.530992 -317.180996) (xy 463.370724 -317.14962)
			(xy 463.21216 -317.110538) (xy 463.055668 -317.06384) (xy 462.901616 -317.009637) (xy 462.750362 -316.948054)
			(xy 462.602261 -316.879235) (xy 462.457657 -316.803341) (xy 462.316888 -316.72055) (xy 462.180284 -316.631054)
			(xy 462.048163 -316.535063) (xy 461.920835 -316.432801) (xy 461.798595 -316.324507) (xy 461.681731 -316.210433)
			(xy 461.570514 -316.090847) (xy 461.465205 -315.966027) (xy 461.366049 -315.836264) (xy 461.273278 -315.701863)
			(xy 461.187109 -315.563136) (xy 461.107743 -315.420409) (xy 461.035365 -315.274013) (xy 460.970145 -315.124292)
			(xy 460.912234 -314.971595) (xy 460.861768 -314.816278) (xy 460.818866 -314.658704) (xy 460.783626 -314.499241)
			(xy 460.756131 -314.338262) (xy 460.736447 -314.176143) (xy 460.724617 -314.013262) (xy 460.720671 -313.85)
			(xy 460.724617 -313.686738) (xy 460.736447 -313.523857) (xy 460.756131 -313.361737) (xy 460.783626 -313.200759)
			(xy 460.818866 -313.041296) (xy 460.861768 -312.883722) (xy 460.912234 -312.728405) (xy 460.970145 -312.575708)
			(xy 461.035365 -312.425987) (xy 461.107743 -312.279591) (xy 461.187109 -312.136864) (xy 461.273278 -311.998137)
			(xy 461.366049 -311.863736) (xy 461.465205 -311.733973) (xy 461.570514 -311.609153) (xy 461.681731 -311.489567)
			(xy 461.798595 -311.375493) (xy 461.920835 -311.267199) (xy 462.048163 -311.164937) (xy 462.180284 -311.068946)
			(xy 462.316888 -310.97945) (xy 462.457657 -310.896659) (xy 462.602261 -310.820765) (xy 462.750362 -310.751946)
			(xy 462.901616 -310.690363) (xy 463.055668 -310.63616) (xy 463.21216 -310.589462) (xy 463.370724 -310.55038)
			(xy 463.530992 -310.519004) (xy 463.692588 -310.495408) (xy 463.855136 -310.479647) (xy 464.018255 -310.471757)
			(xy 464.09991 -310.471312) (xy 464.100418 -310.471312) (xy 464.180478 -310.471787) (xy 464.340417 -310.479383)
			(xy 464.499816 -310.494546) (xy 464.658319 -310.517244) (xy 464.815568 -310.547425) (xy 464.971211 -310.585022)
			(xy 465.124898 -310.629949) (xy 465.276284 -310.682106) (xy 465.42503 -310.741377) (xy 465.570801 -310.807627)
			(xy 465.713269 -310.880709) (xy 465.852116 -310.960457) (xy 465.91982 -311.003188) (xy 465.93125 -311.010554)
			(xy 465.95919 -311.01157) (xy 466.049614 -310.962294) (xy 466.057381 -310.957602) (xy 466.069246 -310.943887)
			(xy 466.075617 -310.926909) (xy 466.07603 -310.917844) (xy 466.07603 -246.488458) (xy 466.075545 -246.457292)
			(xy 466.067413 -246.395492) (xy 466.051278 -246.335284) (xy 466.02742 -246.277699) (xy 465.996245 -246.223723)
			(xy 465.958287 -246.17428) (xy 465.936584 -246.151908) (xy 463.546698 -243.762276) (xy 463.539303 -243.755422)
			(xy 463.520704 -243.747676) (xy 463.51063 -243.74729) (xy 463.492088 -243.750846) (xy 463.464222 -243.76103)
			(xy 463.405925 -243.772014) (xy 463.376264 -243.77269) (xy 447.06413 -243.77269) (xy 447.039178 -243.772228)
			(xy 446.989887 -243.764426) (xy 446.942425 -243.749008) (xy 446.897958 -243.726355) (xy 446.857583 -243.697024)
			(xy 446.839594 -243.679726) (xy 445.739774 -242.579906) (xy 445.732374 -242.573063) (xy 445.713776 -242.565337)
			(xy 445.703706 -242.56492) (xy 380.30912 -242.56492) (xy 380.299057 -242.565358) (xy 380.280475 -242.573095)
			(xy 380.273052 -242.579906) (xy 380.253422 -242.598997) (xy 380.209676 -242.631929) (xy 380.161673 -242.658271)
			(xy 380.110398 -242.677484) (xy 380.056904 -242.689171) (xy 380.002288 -242.693093) (xy 379.947672 -242.689171)
			(xy 379.894178 -242.677484) (xy 379.842903 -242.658271) (xy 379.7949 -242.631929) (xy 379.751154 -242.598997)
			(xy 379.731524 -242.579906) (xy 379.724122 -242.573071) (xy 379.705523 -242.565363) (xy 379.695456 -242.56492)
			(xy 262.786114 -242.56492) (xy 262.749538 -242.580414) (xy 262.729843 -242.599959) (xy 262.685811 -242.633721)
			(xy 262.637353 -242.660749) (xy 262.585491 -242.680473) (xy 262.531319 -242.692476) (xy 262.47598 -242.696506)
			(xy 262.420641 -242.692476) (xy 262.366469 -242.680473) (xy 262.314607 -242.660749) (xy 262.266149 -242.633721)
			(xy 262.222117 -242.599959) (xy 262.202422 -242.580414) (xy 262.165846 -242.56492) (xy 257.461004 -242.56492)
			(xy 257.448587 -242.565538) (xy 257.426619 -242.577121) (xy 257.419094 -242.587018) (xy 257.402585 -242.610352)
			(xy 257.363723 -242.652266) (xy 257.319045 -242.687916) (xy 257.269551 -242.716507) (xy 257.216348 -242.737398)
			(xy 257.160624 -242.750122) (xy 257.103626 -242.754395) (xy 257.046628 -242.750122) (xy 256.990904 -242.737398)
			(xy 256.937701 -242.716507) (xy 256.888207 -242.687916) (xy 256.843529 -242.652266) (xy 256.804667 -242.610352)
			(xy 256.788158 -242.587018) (xy 256.780638 -242.577111) (xy 256.75867 -242.565505) (xy 256.746248 -242.56492)
			(xy 148.185124 -242.56492) (xy 148.159978 -242.58143) (xy 148.153882 -242.595654) (xy 148.142426 -242.620962)
			(xy 148.11327 -242.668247) (xy 148.077568 -242.710806) (xy 148.036073 -242.74774) (xy 147.989664 -242.77827)
			(xy 147.939319 -242.80175) (xy 147.886102 -242.817685) (xy 147.831138 -242.825737) (xy 147.775586 -242.825737)
			(xy 147.720622 -242.817685) (xy 147.667405 -242.80175) (xy 147.61706 -242.77827) (xy 147.570651 -242.74774)
			(xy 147.529156 -242.710806) (xy 147.493454 -242.668247) (xy 147.464298 -242.620962) (xy 147.452842 -242.595654)
			(xy 147.446746 -242.58143) (xy 147.4216 -242.56492) (xy 147.016724 -242.56492) (xy 146.991578 -242.58143)
			(xy 146.985482 -242.595654) (xy 146.974026 -242.620962) (xy 146.94487 -242.668247) (xy 146.909168 -242.710806)
			(xy 146.867673 -242.74774) (xy 146.821264 -242.77827) (xy 146.770919 -242.80175) (xy 146.717702 -242.817685)
			(xy 146.662738 -242.825737) (xy 146.607186 -242.825737) (xy 146.552222 -242.817685) (xy 146.499005 -242.80175)
			(xy 146.44866 -242.77827) (xy 146.402251 -242.74774) (xy 146.360756 -242.710806) (xy 146.325054 -242.668247)
			(xy 146.295898 -242.620962) (xy 146.284442 -242.595654) (xy 146.278346 -242.58143) (xy 146.2532 -242.56492)
			(xy 96.253808 -242.56492) (xy 96.228916 -242.571524) (xy 96.204365 -242.584753) (xy 96.152279 -242.604683)
			(xy 96.097846 -242.616814) (xy 96.042226 -242.620887) (xy 95.986606 -242.616814) (xy 95.932173 -242.604683)
			(xy 95.880087 -242.584753) (xy 95.855536 -242.571524) (xy 95.830644 -242.56492) (xy 94.218506 -242.56492)
			(xy 94.193614 -242.571524) (xy 94.168926 -242.584938) (xy 94.116507 -242.605162) (xy 94.061687 -242.617475)
			(xy 94.005654 -242.621609) (xy 93.949621 -242.617475) (xy 93.894801 -242.605162) (xy 93.842382 -242.584938)
			(xy 93.817694 -242.571524) (xy 93.792802 -242.56492) (xy 71.91502 -242.56492) (xy 71.905578 -242.565416)
			(xy 71.887996 -242.57233) (xy 71.88073 -242.578382) (xy 71.859506 -242.597142) (xy 71.812553 -242.628829)
			(xy 71.761431 -242.653224) (xy 71.707264 -242.669792) (xy 71.651242 -242.678168) (xy 71.594598 -242.678168)
			(xy 71.538576 -242.669792) (xy 71.484409 -242.653224) (xy 71.433287 -242.628829) (xy 71.386334 -242.597142)
			(xy 71.36511 -242.578382) (xy 71.357907 -242.572227) (xy 71.340287 -242.565299) (xy 71.33082 -242.56492)
			(xy 5.004562 -242.56492) (xy 4.959096 -242.593114) (xy 4.922262 -242.666556) (xy 4.842655 -242.810305)
			(xy 4.756434 -242.950187) (xy 4.663785 -243.085897) (xy 4.56491 -243.21714) (xy 4.460024 -243.343632)
			(xy 4.349356 -243.465096) (xy 4.291584 -243.523516) (xy 1.663446 -246.151654) (xy 1.641773 -246.174052)
			(xy 1.603834 -246.223499) (xy 1.572669 -246.277474) (xy 1.548812 -246.335052) (xy 1.53267 -246.395251)
			(xy 1.524519 -246.457041) (xy 1.524 -246.488204) (xy 1.524 -270.89989) (xy 24.898611 -270.89989)
			(xy 24.902617 -270.704835) (xy 24.914627 -270.510109) (xy 24.934622 -270.31604) (xy 24.962567 -270.122956)
			(xy 24.998416 -269.931181) (xy 25.042108 -269.741041) (xy 25.093569 -269.552854) (xy 25.152713 -269.366939)
			(xy 25.21944 -269.183608) (xy 25.293637 -269.003172) (xy 25.375179 -268.825934) (xy 25.46393 -268.652193)
			(xy 25.559738 -268.482242) (xy 25.662443 -268.316368) (xy 25.771871 -268.15485) (xy 25.887838 -267.997961)
			(xy 26.010149 -267.845966) (xy 26.138596 -267.69912) (xy 26.272964 -267.557671) (xy 26.413026 -267.421858)
			(xy 26.558545 -267.291909) (xy 26.709277 -267.168045) (xy 26.864967 -267.050473) (xy 27.025353 -266.939393)
			(xy 27.190164 -266.83499) (xy 27.359122 -266.737442) (xy 27.531943 -266.646913) (xy 27.708335 -266.563555)
			(xy 27.888 -266.487509) (xy 28.070635 -266.418904) (xy 28.255934 -266.357854) (xy 28.443582 -266.304464)
			(xy 28.633264 -266.258822) (xy 28.824661 -266.221006) (xy 29.017448 -266.19108) (xy 29.211301 -266.169094)
			(xy 29.405894 -266.155085) (xy 29.600897 -266.149077) (xy 29.795983 -266.15108) (xy 29.990822 -266.161091)
			(xy 30.185086 -266.179092) (xy 30.378447 -266.205054) (xy 30.57058 -266.238932) (xy 30.761159 -266.280669)
			(xy 30.949864 -266.330196) (xy 31.136377 -266.387428) (xy 31.320383 -266.452269) (xy 31.501571 -266.52461)
			(xy 31.679637 -266.604328) (xy 31.85428 -266.69129) (xy 32.025206 -266.785349) (xy 32.192125 -266.886345)
			(xy 32.354758 -266.99411) (xy 32.512829 -267.10846) (xy 32.666072 -267.229203) (xy 32.814229 -267.356137)
			(xy 32.95705 -267.489045) (xy 33.094294 -267.627705) (xy 33.22573 -267.771883) (xy 33.351135 -267.921336)
			(xy 33.470299 -268.07581) (xy 33.58302 -268.235047) (xy 33.689109 -268.398778) (xy 33.788387 -268.566725)
			(xy 33.880685 -268.738608) (xy 33.96585 -268.914134) (xy 34.043736 -269.093009) (xy 34.114213 -269.274931)
			(xy 34.177161 -269.459593) (xy 34.232476 -269.646683) (xy 34.280062 -269.835887) (xy 34.319841 -270.026884)
			(xy 34.351745 -270.219354) (xy 34.37572 -270.412972) (xy 34.391726 -270.60741) (xy 34.399735 -270.802342)
			(xy 34.400236 -270.89989) (xy 34.399735 -270.997438) (xy 34.391726 -271.19237) (xy 34.37572 -271.386808)
			(xy 34.351745 -271.580426) (xy 34.319841 -271.772896) (xy 34.280062 -271.963893) (xy 34.232476 -272.153097)
			(xy 34.177161 -272.340187) (xy 34.114213 -272.524849) (xy 34.043736 -272.706771) (xy 33.96585 -272.885646)
			(xy 33.880685 -273.061172) (xy 33.788387 -273.233055) (xy 33.689109 -273.401002) (xy 33.58302 -273.564733)
			(xy 33.470299 -273.72397) (xy 33.351135 -273.878444) (xy 33.22573 -274.027897) (xy 33.094294 -274.172075)
			(xy 32.95705 -274.310735) (xy 32.814229 -274.443643) (xy 32.666072 -274.570577) (xy 32.512829 -274.69132)
			(xy 32.354758 -274.80567) (xy 32.192125 -274.913435) (xy 32.025206 -275.014431) (xy 31.85428 -275.10849)
			(xy 31.679637 -275.195452) (xy 31.501571 -275.27517) (xy 31.320383 -275.347511) (xy 31.136377 -275.412352)
			(xy 30.949864 -275.469584) (xy 30.761159 -275.519111) (xy 30.57058 -275.560848) (xy 30.378447 -275.594726)
			(xy 30.185086 -275.620688) (xy 29.990822 -275.638689) (xy 29.795983 -275.6487) (xy 29.600897 -275.650703)
			(xy 29.405894 -275.644695) (xy 29.211301 -275.630686) (xy 29.017448 -275.6087) (xy 28.824661 -275.578774)
			(xy 28.633264 -275.540958) (xy 28.443582 -275.495316) (xy 28.255934 -275.441926) (xy 28.070635 -275.380876)
			(xy 27.888 -275.312271) (xy 27.708335 -275.236225) (xy 27.531943 -275.152867) (xy 27.359122 -275.062338)
			(xy 27.190164 -274.96479) (xy 27.025353 -274.860387) (xy 26.864967 -274.749307) (xy 26.709277 -274.631735)
			(xy 26.558545 -274.507871) (xy 26.413026 -274.377922) (xy 26.272964 -274.242109) (xy 26.138596 -274.10066)
			(xy 26.010149 -273.953814) (xy 25.887838 -273.801819) (xy 25.771871 -273.64493) (xy 25.662443 -273.483412)
			(xy 25.559738 -273.317538) (xy 25.46393 -273.147587) (xy 25.375179 -272.973846) (xy 25.293637 -272.796608)
			(xy 25.21944 -272.616172) (xy 25.152713 -272.432841) (xy 25.093569 -272.246926) (xy 25.042108 -272.058739)
			(xy 24.998416 -271.868599) (xy 24.962567 -271.676824) (xy 24.934622 -271.48374) (xy 24.914627 -271.289671)
			(xy 24.902617 -271.094945) (xy 24.898611 -270.89989) (xy 1.524 -270.89989) (xy 1.524 -301.410116)
			(xy 16.770865 -301.410116) (xy 16.774873 -301.24559) (xy 16.786886 -301.081455) (xy 16.806876 -300.918099)
			(xy 16.834796 -300.75591) (xy 16.870579 -300.595273) (xy 16.914141 -300.436569) (xy 16.965379 -300.280174)
			(xy 17.02417 -300.126459) (xy 17.090375 -299.975788) (xy 17.163838 -299.82852) (xy 17.244383 -299.685003)
			(xy 17.331821 -299.545577) (xy 17.425943 -299.410575) (xy 17.526527 -299.280315) (xy 17.633333 -299.155106)
			(xy 17.746109 -299.035246) (xy 17.864587 -298.92102) (xy 17.988485 -298.812697) (xy 18.117511 -298.710534)
			(xy 18.251357 -298.614775) (xy 18.389708 -298.525647) (xy 18.532233 -298.443359) (xy 18.678596 -298.368109)
			(xy 18.828449 -298.300074) (xy 18.981437 -298.239415) (xy 19.137197 -298.186278) (xy 19.295359 -298.140786)
			(xy 19.455549 -298.10305) (xy 19.617386 -298.073157) (xy 19.780486 -298.051179) (xy 19.944463 -298.037168)
			(xy 20.108927 -298.031158) (xy 20.27349 -298.033161) (xy 20.437759 -298.043175) (xy 20.601346 -298.061175)
			(xy 20.763863 -298.087118) (xy 20.924924 -298.120943) (xy 21.084147 -298.162569) (xy 21.241154 -298.211898)
			(xy 21.395574 -298.268813) (xy 21.547039 -298.333179) (xy 21.695191 -298.404843) (xy 21.839679 -298.483635)
			(xy 21.980158 -298.569369) (xy 22.116297 -298.66184) (xy 22.247772 -298.76083) (xy 22.374272 -298.866104)
			(xy 22.495496 -298.977412) (xy 22.611157 -299.09449) (xy 22.72098 -299.21706) (xy 22.727388 -299.224954)
			(xy 36.043616 -299.224954) (xy 36.044009 -299.203033) (xy 36.049872 -299.159582) (xy 36.0553 -299.13834)
			(xy 36.057078 -299.131736) (xy 36.057078 -297.417998) (xy 36.0553 -297.411394) (xy 36.049868 -297.390152)
			(xy 36.044006 -297.346702) (xy 36.043616 -297.32478) (xy 36.044014 -297.302859) (xy 36.049874 -297.259409)
			(xy 36.0553 -297.238166) (xy 36.057078 -297.231562) (xy 36.057078 -294.566848) (xy 36.0553 -294.560244)
			(xy 36.050082 -294.539295) (xy 36.044475 -294.496487) (xy 36.044124 -294.4749) (xy 36.044448 -294.453311)
			(xy 36.050052 -294.4105) (xy 36.0553 -294.389556) (xy 36.057078 -294.382952) (xy 36.057078 -292.666928)
			(xy 36.0553 -292.660324) (xy 36.050078 -292.639375) (xy 36.044474 -292.596567) (xy 36.044124 -292.57498)
			(xy 36.044444 -292.553391) (xy 36.050051 -292.510579) (xy 36.0553 -292.489636) (xy 36.057078 -292.483032)
			(xy 36.057078 -291.716714) (xy 36.0553 -291.71011) (xy 36.050075 -291.689162) (xy 36.044473 -291.646353)
			(xy 36.044124 -291.624766) (xy 36.044441 -291.603177) (xy 36.05005 -291.560365) (xy 36.0553 -291.539422)
			(xy 36.057078 -291.532818) (xy 36.057078 -290.766754) (xy 36.0553 -290.76015) (xy 36.050083 -290.7392)
			(xy 36.044476 -290.696393) (xy 36.044124 -290.674806) (xy 36.044449 -290.653217) (xy 36.050052 -290.610406)
			(xy 36.0553 -290.589462) (xy 36.057078 -290.582858) (xy 36.057078 -289.816794) (xy 36.0553 -289.81019)
			(xy 36.050072 -289.789243) (xy 36.044472 -289.746433) (xy 36.044124 -289.724846) (xy 36.044437 -289.703257)
			(xy 36.050048 -289.660445) (xy 36.0553 -289.639502) (xy 36.057078 -289.632898) (xy 36.057078 -288.866834)
			(xy 36.0553 -288.86023) (xy 36.054538 -288.85769) (xy 36.054538 -288.857182) (xy 36.049642 -288.836833)
			(xy 36.044415 -288.795306) (xy 36.044124 -288.774378) (xy 36.044417 -288.752662) (xy 36.050025 -288.709594)
			(xy 36.0553 -288.688526) (xy 36.057078 -288.681922) (xy 36.057078 -287.916874) (xy 36.0553 -287.91027)
			(xy 36.050087 -287.889319) (xy 36.044477 -287.846512) (xy 36.044124 -287.824926) (xy 36.044453 -287.803337)
			(xy 36.050053 -287.760526) (xy 36.0553 -287.739582) (xy 36.057078 -287.732978) (xy 36.057078 -286.966914)
			(xy 36.0553 -286.96031) (xy 36.050075 -286.939362) (xy 36.044473 -286.896553) (xy 36.044124 -286.874966)
			(xy 36.044441 -286.853377) (xy 36.05005 -286.810565) (xy 36.0553 -286.789622) (xy 36.057078 -286.783018)
			(xy 36.057078 -286.0167) (xy 36.0553 -286.010096) (xy 36.050073 -285.989149) (xy 36.044472 -285.946339)
			(xy 36.044124 -285.924752) (xy 36.044438 -285.903163) (xy 36.050049 -285.860351) (xy 36.0553 -285.839408)
			(xy 36.057078 -285.832804) (xy 36.057078 -285.06674) (xy 36.0553 -285.060136) (xy 36.05008 -285.039187)
			(xy 36.044475 -284.996379) (xy 36.044124 -284.974792) (xy 36.044446 -284.953203) (xy 36.050051 -284.910392)
			(xy 36.0553 -284.889448) (xy 36.057078 -284.882844) (xy 36.057078 -284.11678) (xy 36.0553 -284.110176)
			(xy 36.050088 -284.089225) (xy 36.044477 -284.046418) (xy 36.044124 -284.024832) (xy 36.044454 -284.003243)
			(xy 36.050054 -283.960432) (xy 36.0553 -283.939488) (xy 36.057078 -283.932884) (xy 36.057078 -283.16682)
			(xy 36.0553 -283.160216) (xy 36.050076 -283.139268) (xy 36.044474 -283.096459) (xy 36.044124 -283.074872)
			(xy 36.044442 -283.053283) (xy 36.05005 -283.010471) (xy 36.0553 -282.989528) (xy 36.057078 -282.982924)
			(xy 36.057078 -282.21686) (xy 36.0553 -282.210256) (xy 36.050084 -282.189306) (xy 36.044476 -282.146499)
			(xy 36.044124 -282.124912) (xy 36.04445 -282.103323) (xy 36.050053 -282.060512) (xy 36.0553 -282.039568)
			(xy 36.057078 -282.032964) (xy 36.057078 -281.2669) (xy 36.0553 -281.260296) (xy 36.050073 -281.239349)
			(xy 36.044472 -281.196539) (xy 36.044124 -281.174952) (xy 36.044438 -281.153363) (xy 36.050049 -281.110551)
			(xy 36.0553 -281.089608) (xy 36.057078 -281.083004) (xy 36.057078 -280.316686) (xy 36.0553 -280.310082)
			(xy 36.050089 -280.289131) (xy 36.044478 -280.246324) (xy 36.044124 -280.224738) (xy 36.044455 -280.20315)
			(xy 36.050054 -280.160338) (xy 36.0553 -280.139394) (xy 36.057078 -280.13279) (xy 36.057078 -279.366726)
			(xy 36.0553 -279.360122) (xy 36.050078 -279.339174) (xy 36.044474 -279.296365) (xy 36.044124 -279.274778)
			(xy 36.044443 -279.253189) (xy 36.05005 -279.210377) (xy 36.0553 -279.189434) (xy 36.057078 -279.18283)
			(xy 36.057078 -278.416766) (xy 36.0553 -278.410162) (xy 36.050085 -278.389212) (xy 36.044477 -278.346404)
			(xy 36.044124 -278.324818) (xy 36.044451 -278.303229) (xy 36.050053 -278.260418) (xy 36.0553 -278.239474)
			(xy 36.057078 -278.23287) (xy 36.057078 -277.466806) (xy 36.0553 -277.460202) (xy 36.050074 -277.439254)
			(xy 36.044473 -277.396445) (xy 36.044124 -277.374858) (xy 36.044439 -277.353269) (xy 36.050049 -277.310457)
			(xy 36.0553 -277.289514) (xy 36.057078 -277.28291) (xy 36.057078 -276.516846) (xy 36.0553 -276.510242)
			(xy 36.050081 -276.489293) (xy 36.044475 -276.446485) (xy 36.044124 -276.424898) (xy 36.044447 -276.403309)
			(xy 36.050052 -276.360498) (xy 36.0553 -276.339554) (xy 36.057078 -276.33295) (xy 36.057078 -275.566886)
			(xy 36.0553 -275.560282) (xy 36.050089 -275.539331) (xy 36.044478 -275.496524) (xy 36.044124 -275.474938)
			(xy 36.044455 -275.45335) (xy 36.050054 -275.410538) (xy 36.0553 -275.389594) (xy 36.057078 -275.38299)
			(xy 36.057078 -272.53819) (xy 36.057578 -272.513241) (xy 36.065391 -272.463958) (xy 36.080807 -272.416501)
			(xy 36.103448 -272.372035) (xy 36.132757 -272.331652) (xy 36.150042 -272.313654) (xy 36.698428 -271.765268)
			(xy 36.716401 -271.747952) (xy 36.756781 -271.718624) (xy 36.801251 -271.695974) (xy 36.848717 -271.680561)
			(xy 36.898011 -271.672763) (xy 36.922964 -271.672304) (xy 84.844382 -271.672304) (xy 84.855307 -271.671772)
			(xy 84.875182 -271.662689) (xy 84.882736 -271.654778) (xy 84.94014 -271.588738) (xy 84.94649 -271.567402)
			(xy 84.944966 -271.556734) (xy 84.930472 -271.448248) (xy 84.910277 -271.230286) (xy 84.900148 -271.011624)
			(xy 84.8995 -270.902176) (xy 84.8995 -270.89989) (xy 84.899994 -270.802981) (xy 84.9079 -270.609323)
			(xy 84.923698 -270.416149) (xy 84.947362 -270.22378) (xy 84.978853 -270.032537) (xy 85.018118 -269.842737)
			(xy 85.065092 -269.654697) (xy 85.119697 -269.468729) (xy 85.181842 -269.285143) (xy 85.251424 -269.104245)
			(xy 85.328326 -268.926335) (xy 85.412421 -268.751711) (xy 85.503568 -268.580661) (xy 85.601617 -268.413472)
			(xy 85.706403 -268.250421) (xy 85.817753 -268.09178) (xy 85.935481 -267.937813) (xy 86.059391 -267.788776)
			(xy 86.189277 -267.644917) (xy 86.324923 -267.506476) (xy 86.466102 -267.373682) (xy 86.612581 -267.246758)
			(xy 86.764114 -267.125914) (xy 86.920451 -267.011351) (xy 87.08133 -266.903261) (xy 87.246485 -266.801822)
			(xy 87.415639 -266.707204) (xy 87.588512 -266.619565) (xy 87.764816 -266.53905) (xy 87.944257 -266.465793)
			(xy 88.126537 -266.399916) (xy 88.311352 -266.341528) (xy 88.498395 -266.290728) (xy 88.687355 -266.247599)
			(xy 88.877916 -266.212214) (xy 89.069762 -266.184631) (xy 89.262573 -266.164895) (xy 89.456029 -266.153041)
			(xy 89.649808 -266.149088) (xy 89.843587 -266.153041) (xy 90.037043 -266.164895) (xy 90.229854 -266.184631)
			(xy 90.4217 -266.212214) (xy 90.612261 -266.247599) (xy 90.801221 -266.290728) (xy 90.988264 -266.341528)
			(xy 91.173079 -266.399916) (xy 91.355359 -266.465793) (xy 91.5348 -266.53905) (xy 91.711104 -266.619565)
			(xy 91.883977 -266.707204) (xy 92.053131 -266.801822) (xy 92.218286 -266.903261) (xy 92.379165 -267.011351)
			(xy 92.535502 -267.125914) (xy 92.687035 -267.246758) (xy 92.833514 -267.373682) (xy 92.974693 -267.506476)
			(xy 93.110339 -267.644917) (xy 93.240225 -267.788776) (xy 93.364135 -267.937813) (xy 93.481863 -268.09178)
			(xy 93.593213 -268.250421) (xy 93.697999 -268.413472) (xy 93.796048 -268.580661) (xy 93.887195 -268.751711)
			(xy 93.97129 -268.926335) (xy 94.048192 -269.104245) (xy 94.117774 -269.285143) (xy 94.179919 -269.468729)
			(xy 94.234524 -269.654697) (xy 94.281498 -269.842737) (xy 94.320763 -270.032537) (xy 94.352254 -270.22378)
			(xy 94.375918 -270.416149) (xy 94.391716 -270.609323) (xy 94.399622 -270.802981) (xy 94.400116 -270.89989)
			(xy 94.400116 -270.902176) (xy 94.399461 -271.011624) (xy 94.389325 -271.230284) (xy 94.369133 -271.448247)
			(xy 94.35465 -271.556734) (xy 94.353126 -271.567402) (xy 94.359476 -271.588738) (xy 94.41688 -271.654778)
			(xy 94.424418 -271.662709) (xy 94.444304 -271.671787) (xy 94.455234 -271.672304) (xy 130.632962 -271.672304)
			(xy 130.643032 -271.671884) (xy 130.661632 -271.664162) (xy 130.66903 -271.657318) (xy 132.33019 -269.996158)
			(xy 132.348178 -269.978859) (xy 132.388554 -269.949529) (xy 132.433021 -269.926876) (xy 132.480483 -269.911459)
			(xy 132.529774 -269.903656) (xy 132.554726 -269.903194) (xy 140.896594 -269.903194) (xy 140.920194 -269.903628)
			(xy 140.96687 -269.910649) (xy 140.989558 -269.917164) (xy 140.999718 -269.920466) (xy 141.020546 -269.917926)
			(xy 141.103604 -269.870174) (xy 141.11605 -269.853156) (xy 141.118336 -269.842742) (xy 141.140395 -269.748371)
			(xy 141.1912 -269.561321) (xy 141.249591 -269.376498) (xy 141.315473 -269.194211) (xy 141.388735 -269.014763)
			(xy 141.469255 -268.838452) (xy 141.5569 -268.665573) (xy 141.651523 -268.496412) (xy 141.752967 -268.331251)
			(xy 141.861063 -268.170366) (xy 141.975632 -268.014023) (xy 142.096482 -267.862484) (xy 142.223412 -267.716)
			(xy 142.356212 -267.574815) (xy 142.49466 -267.439164) (xy 142.638525 -267.309273) (xy 142.787569 -267.185358)
			(xy 142.941543 -267.067626) (xy 143.100191 -266.956271) (xy 143.263249 -266.851481) (xy 143.430445 -266.753428)
			(xy 143.601502 -266.662277) (xy 143.776134 -266.578179) (xy 143.954051 -266.501273) (xy 144.134957 -266.431688)
			(xy 144.318551 -266.36954) (xy 144.504526 -266.314933) (xy 144.692574 -266.267956) (xy 144.882382 -266.228688)
			(xy 145.073634 -266.197195) (xy 145.266011 -266.173529) (xy 145.459193 -266.15773) (xy 145.652858 -266.149823)
			(xy 145.749772 -266.149328) (xy 145.84796 -266.14982) (xy 146.044169 -266.157935) (xy 146.239875 -266.174151)
			(xy 146.434744 -266.198441) (xy 146.628443 -266.230764) (xy 146.82064 -266.271064) (xy 147.011007 -266.319272)
			(xy 147.19922 -266.375307) (xy 147.384956 -266.439072) (xy 147.567898 -266.510458) (xy 147.747733 -266.589344)
			(xy 147.924155 -266.675594) (xy 148.096862 -266.769062) (xy 148.265559 -266.869587) (xy 148.429957 -266.976998)
			(xy 148.589775 -267.091112) (xy 148.744741 -267.211732) (xy 148.89459 -267.338654) (xy 149.039066 -267.47166)
			(xy 149.177921 -267.610523) (xy 149.31092 -267.755006) (xy 149.437833 -267.904862) (xy 149.558445 -268.059835)
			(xy 149.67255 -268.21966) (xy 149.779951 -268.384064) (xy 149.880467 -268.552766) (xy 149.973925 -268.725478)
			(xy 150.060166 -268.901904) (xy 150.139042 -269.081744) (xy 150.210418 -269.26469) (xy 150.274173 -269.45043)
			(xy 150.330197 -269.638646) (xy 150.378395 -269.829016) (xy 150.418685 -270.021215) (xy 150.450997 -270.214915)
			(xy 150.475276 -270.409785) (xy 150.491482 -270.605492) (xy 150.499585 -270.801702) (xy 150.50008 -270.89989)
			(xy 200.998589 -270.89989) (xy 201.002595 -270.704835) (xy 201.014605 -270.510109) (xy 201.0346 -270.31604)
			(xy 201.062545 -270.122956) (xy 201.098394 -269.931181) (xy 201.142086 -269.741041) (xy 201.193547 -269.552854)
			(xy 201.252691 -269.366939) (xy 201.319418 -269.183608) (xy 201.393615 -269.003172) (xy 201.475157 -268.825934)
			(xy 201.563908 -268.652193) (xy 201.659716 -268.482242) (xy 201.762421 -268.316368) (xy 201.871849 -268.15485)
			(xy 201.987816 -267.997961) (xy 202.110127 -267.845966) (xy 202.238574 -267.69912) (xy 202.372942 -267.557671)
			(xy 202.513004 -267.421858) (xy 202.658523 -267.291909) (xy 202.809255 -267.168045) (xy 202.964945 -267.050473)
			(xy 203.125331 -266.939393) (xy 203.290142 -266.83499) (xy 203.4591 -266.737442) (xy 203.631921 -266.646913)
			(xy 203.808313 -266.563555) (xy 203.987978 -266.487509) (xy 204.170613 -266.418904) (xy 204.355912 -266.357854)
			(xy 204.54356 -266.304464) (xy 204.733242 -266.258822) (xy 204.924639 -266.221006) (xy 205.117426 -266.19108)
			(xy 205.311279 -266.169094) (xy 205.505872 -266.155085) (xy 205.700875 -266.149077) (xy 205.895961 -266.15108)
			(xy 206.0908 -266.161091) (xy 206.285064 -266.179092) (xy 206.478425 -266.205054) (xy 206.670558 -266.238932)
			(xy 206.861137 -266.280669) (xy 207.049842 -266.330196) (xy 207.236355 -266.387428) (xy 207.420361 -266.452269)
			(xy 207.601549 -266.52461) (xy 207.779615 -266.604328) (xy 207.954258 -266.69129) (xy 208.125184 -266.785349)
			(xy 208.292103 -266.886345) (xy 208.454736 -266.99411) (xy 208.612807 -267.10846) (xy 208.76605 -267.229203)
			(xy 208.914207 -267.356137) (xy 209.057028 -267.489045) (xy 209.194272 -267.627705) (xy 209.325708 -267.771883)
			(xy 209.451113 -267.921336) (xy 209.570277 -268.07581) (xy 209.682998 -268.235047) (xy 209.789087 -268.398778)
			(xy 209.888365 -268.566725) (xy 209.980663 -268.738608) (xy 210.065828 -268.914134) (xy 210.143714 -269.093009)
			(xy 210.214191 -269.274931) (xy 210.277139 -269.459593) (xy 210.332454 -269.646683) (xy 210.38004 -269.835887)
			(xy 210.419819 -270.026884) (xy 210.451723 -270.219354) (xy 210.475698 -270.412972) (xy 210.491704 -270.60741)
			(xy 210.499713 -270.802342) (xy 210.500214 -270.89989) (xy 257.098807 -270.89989) (xy 257.102813 -270.704835)
			(xy 257.114823 -270.510109) (xy 257.134818 -270.31604) (xy 257.162763 -270.122956) (xy 257.198612 -269.931181)
			(xy 257.242304 -269.741041) (xy 257.293765 -269.552854) (xy 257.352909 -269.366939) (xy 257.419636 -269.183608)
			(xy 257.493833 -269.003172) (xy 257.575375 -268.825934) (xy 257.664126 -268.652193) (xy 257.759934 -268.482242)
			(xy 257.862639 -268.316368) (xy 257.972067 -268.15485) (xy 258.088034 -267.997961) (xy 258.210345 -267.845966)
			(xy 258.338792 -267.69912) (xy 258.47316 -267.557671) (xy 258.613222 -267.421858) (xy 258.758741 -267.291909)
			(xy 258.909473 -267.168045) (xy 259.065163 -267.050473) (xy 259.225549 -266.939393) (xy 259.39036 -266.83499)
			(xy 259.559318 -266.737442) (xy 259.732139 -266.646913) (xy 259.908531 -266.563555) (xy 260.088196 -266.487509)
			(xy 260.270831 -266.418904) (xy 260.45613 -266.357854) (xy 260.643778 -266.304464) (xy 260.83346 -266.258822)
			(xy 261.024857 -266.221006) (xy 261.217644 -266.19108) (xy 261.411497 -266.169094) (xy 261.60609 -266.155085)
			(xy 261.801093 -266.149077) (xy 261.996179 -266.15108) (xy 262.191018 -266.161091) (xy 262.385282 -266.179092)
			(xy 262.578643 -266.205054) (xy 262.770776 -266.238932) (xy 262.961355 -266.280669) (xy 263.15006 -266.330196)
			(xy 263.336573 -266.387428) (xy 263.520579 -266.452269) (xy 263.701767 -266.52461) (xy 263.879833 -266.604328)
			(xy 264.054476 -266.69129) (xy 264.225402 -266.785349) (xy 264.392321 -266.886345) (xy 264.554954 -266.99411)
			(xy 264.713025 -267.10846) (xy 264.866268 -267.229203) (xy 265.014425 -267.356137) (xy 265.157246 -267.489045)
			(xy 265.29449 -267.627705) (xy 265.425926 -267.771883) (xy 265.551331 -267.921336) (xy 265.670495 -268.07581)
			(xy 265.783216 -268.235047) (xy 265.889305 -268.398778) (xy 265.988583 -268.566725) (xy 266.080881 -268.738608)
			(xy 266.166046 -268.914134) (xy 266.243932 -269.093009) (xy 266.314409 -269.274931) (xy 266.377357 -269.459593)
			(xy 266.432672 -269.646683) (xy 266.480258 -269.835887) (xy 266.520037 -270.026884) (xy 266.551941 -270.219354)
			(xy 266.575916 -270.412972) (xy 266.591922 -270.60741) (xy 266.599931 -270.802342) (xy 266.600432 -270.89989)
			(xy 266.599931 -270.997438) (xy 266.591922 -271.19237) (xy 266.575916 -271.386808) (xy 266.551941 -271.580426)
			(xy 266.520037 -271.772896) (xy 266.480258 -271.963893) (xy 266.432672 -272.153097) (xy 266.377357 -272.340187)
			(xy 266.314409 -272.524849) (xy 266.243932 -272.706771) (xy 266.166046 -272.885646) (xy 266.080881 -273.061172)
			(xy 265.988583 -273.233055) (xy 265.889305 -273.401002) (xy 265.783216 -273.564733) (xy 265.670495 -273.72397)
			(xy 265.551331 -273.878444) (xy 265.425926 -274.027897) (xy 265.29449 -274.172075) (xy 265.157246 -274.310735)
			(xy 265.014425 -274.443643) (xy 264.866268 -274.570577) (xy 264.713025 -274.69132) (xy 264.554954 -274.80567)
			(xy 264.392321 -274.913435) (xy 264.225402 -275.014431) (xy 264.054476 -275.10849) (xy 263.879833 -275.195452)
			(xy 263.701767 -275.27517) (xy 263.520579 -275.347511) (xy 263.336573 -275.412352) (xy 263.15006 -275.469584)
			(xy 262.961355 -275.519111) (xy 262.770776 -275.560848) (xy 262.578643 -275.594726) (xy 262.385282 -275.620688)
			(xy 262.191018 -275.638689) (xy 261.996179 -275.6487) (xy 261.801093 -275.650703) (xy 261.60609 -275.644695)
			(xy 261.411497 -275.630686) (xy 261.217644 -275.6087) (xy 261.024857 -275.578774) (xy 260.83346 -275.540958)
			(xy 260.643778 -275.495316) (xy 260.45613 -275.441926) (xy 260.270831 -275.380876) (xy 260.088196 -275.312271)
			(xy 259.908531 -275.236225) (xy 259.732139 -275.152867) (xy 259.559318 -275.062338) (xy 259.39036 -274.96479)
			(xy 259.225549 -274.860387) (xy 259.065163 -274.749307) (xy 258.909473 -274.631735) (xy 258.758741 -274.507871)
			(xy 258.613222 -274.377922) (xy 258.47316 -274.242109) (xy 258.338792 -274.10066) (xy 258.210345 -273.953814)
			(xy 258.088034 -273.801819) (xy 257.972067 -273.64493) (xy 257.862639 -273.483412) (xy 257.759934 -273.317538)
			(xy 257.664126 -273.147587) (xy 257.575375 -272.973846) (xy 257.493833 -272.796608) (xy 257.419636 -272.616172)
			(xy 257.352909 -272.432841) (xy 257.293765 -272.246926) (xy 257.242304 -272.058739) (xy 257.198612 -271.868599)
			(xy 257.162763 -271.676824) (xy 257.134818 -271.48374) (xy 257.114823 -271.289671) (xy 257.102813 -271.094945)
			(xy 257.098807 -270.89989) (xy 210.500214 -270.89989) (xy 210.499713 -270.997438) (xy 210.491704 -271.19237)
			(xy 210.475698 -271.386808) (xy 210.451723 -271.580426) (xy 210.419819 -271.772896) (xy 210.38004 -271.963893)
			(xy 210.332454 -272.153097) (xy 210.277139 -272.340187) (xy 210.214191 -272.524849) (xy 210.143714 -272.706771)
			(xy 210.065828 -272.885646) (xy 209.980663 -273.061172) (xy 209.888365 -273.233055) (xy 209.789087 -273.401002)
			(xy 209.682998 -273.564733) (xy 209.570277 -273.72397) (xy 209.451113 -273.878444) (xy 209.325708 -274.027897)
			(xy 209.194272 -274.172075) (xy 209.057028 -274.310735) (xy 208.914207 -274.443643) (xy 208.76605 -274.570577)
			(xy 208.612807 -274.69132) (xy 208.454736 -274.80567) (xy 208.292103 -274.913435) (xy 208.125184 -275.014431)
			(xy 207.954258 -275.10849) (xy 207.779615 -275.195452) (xy 207.601549 -275.27517) (xy 207.420361 -275.347511)
			(xy 207.236355 -275.412352) (xy 207.049842 -275.469584) (xy 206.861137 -275.519111) (xy 206.670558 -275.560848)
			(xy 206.478425 -275.594726) (xy 206.285064 -275.620688) (xy 206.0908 -275.638689) (xy 205.895961 -275.6487)
			(xy 205.700875 -275.650703) (xy 205.505872 -275.644695) (xy 205.311279 -275.630686) (xy 205.117426 -275.6087)
			(xy 204.924639 -275.578774) (xy 204.733242 -275.540958) (xy 204.54356 -275.495316) (xy 204.355912 -275.441926)
			(xy 204.170613 -275.380876) (xy 203.987978 -275.312271) (xy 203.808313 -275.236225) (xy 203.631921 -275.152867)
			(xy 203.4591 -275.062338) (xy 203.290142 -274.96479) (xy 203.125331 -274.860387) (xy 202.964945 -274.749307)
			(xy 202.809255 -274.631735) (xy 202.658523 -274.507871) (xy 202.513004 -274.377922) (xy 202.372942 -274.242109)
			(xy 202.238574 -274.10066) (xy 202.110127 -273.953814) (xy 201.987816 -273.801819) (xy 201.871849 -273.64493)
			(xy 201.762421 -273.483412) (xy 201.659716 -273.317538) (xy 201.563908 -273.147587) (xy 201.475157 -272.973846)
			(xy 201.393615 -272.796608) (xy 201.319418 -272.616172) (xy 201.252691 -272.432841) (xy 201.193547 -272.246926)
			(xy 201.142086 -272.058739) (xy 201.098394 -271.868599) (xy 201.062545 -271.676824) (xy 201.0346 -271.48374)
			(xy 201.014605 -271.289671) (xy 201.002595 -271.094945) (xy 200.998589 -270.89989) (xy 150.50008 -270.89989)
			(xy 150.499478 -271.009719) (xy 150.489377 -271.229145) (xy 150.46915 -271.447869) (xy 150.454614 -271.556734)
			(xy 150.45309 -271.567402) (xy 150.45944 -271.588738) (xy 150.516844 -271.654778) (xy 150.524397 -271.662692)
			(xy 150.544271 -271.67178) (xy 150.555198 -271.672304) (xy 198.205344 -271.672304) (xy 198.223806 -271.672584)
			(xy 198.260477 -271.676909) (xy 198.278496 -271.68094) (xy 198.284338 -271.68221) (xy 198.340472 -271.68221)
			(xy 198.36542 -271.682725) (xy 198.414703 -271.690532) (xy 198.46216 -271.705944) (xy 198.506627 -271.728582)
			(xy 198.54701 -271.75789) (xy 198.565008 -271.775174) (xy 199.249538 -272.459704) (xy 199.266843 -272.477687)
			(xy 199.296173 -272.518064) (xy 199.318824 -272.562532) (xy 199.33424 -272.609996) (xy 199.342041 -272.659287)
			(xy 199.342502 -272.68424) (xy 199.342502 -289.632136) (xy 199.34428 -289.638486) (xy 199.349644 -289.659671)
			(xy 199.355377 -289.702995) (xy 199.35571 -289.724846) (xy 199.35537 -289.746696) (xy 199.349631 -289.790018)
			(xy 199.34428 -289.811206) (xy 199.342502 -289.817556) (xy 199.342502 -290.582096) (xy 199.34428 -290.588446)
			(xy 199.349636 -290.609633) (xy 199.355374 -290.652955) (xy 199.35571 -290.674806) (xy 199.355362 -290.696656)
			(xy 199.349628 -290.739978) (xy 199.34428 -290.761166) (xy 199.342502 -290.767516) (xy 199.342502 -291.532056)
			(xy 199.34428 -291.538406) (xy 199.349648 -291.55959) (xy 199.355378 -291.602915) (xy 199.35571 -291.624766)
			(xy 199.355354 -291.646616) (xy 199.349626 -291.689938) (xy 199.34428 -291.711126) (xy 199.342502 -291.717476)
			(xy 199.342502 -292.48227) (xy 199.34428 -292.48862) (xy 199.34965 -292.509804) (xy 199.355379 -292.553129)
			(xy 199.35571 -292.57498) (xy 199.355357 -292.59683) (xy 199.349627 -292.640152) (xy 199.34428 -292.66134)
			(xy 199.342502 -292.66769) (xy 199.342502 -293.43223) (xy 199.34428 -293.43858) (xy 199.349643 -293.459765)
			(xy 199.355376 -293.503089) (xy 199.35571 -293.52494) (xy 199.355369 -293.54679) (xy 199.349631 -293.590112)
			(xy 199.34428 -293.6113) (xy 199.342502 -293.61765) (xy 199.342502 -294.38219) (xy 199.34428 -294.38854)
			(xy 199.349635 -294.409727) (xy 199.355374 -294.453049) (xy 199.35571 -294.4749) (xy 199.355361 -294.49675)
			(xy 199.349628 -294.540072) (xy 199.34428 -294.56126) (xy 199.342502 -294.56761) (xy 199.342502 -296.28211)
			(xy 199.34428 -296.28846) (xy 199.349639 -296.309646) (xy 199.355375 -296.352969) (xy 199.35571 -296.37482)
			(xy 199.355365 -296.39667) (xy 199.349629 -296.439992) (xy 199.34428 -296.46118) (xy 199.342502 -296.46753)
			(xy 199.342502 -297.23207) (xy 199.34428 -297.23842) (xy 199.34965 -297.259604) (xy 199.355379 -297.302929)
			(xy 199.35571 -297.32478) (xy 199.355357 -297.34663) (xy 199.352267 -297.369992) (xy 248.970807 -297.369992)
			(xy 248.974815 -297.205466) (xy 248.986828 -297.041331) (xy 249.006818 -296.877975) (xy 249.034738 -296.715786)
			(xy 249.070521 -296.555149) (xy 249.114083 -296.396445) (xy 249.165321 -296.24005) (xy 249.224112 -296.086335)
			(xy 249.290317 -295.935664) (xy 249.36378 -295.788396) (xy 249.444325 -295.644879) (xy 249.531763 -295.505453)
			(xy 249.625885 -295.370451) (xy 249.726469 -295.240191) (xy 249.833275 -295.114982) (xy 249.946051 -294.995122)
			(xy 250.064529 -294.880896) (xy 250.188427 -294.772573) (xy 250.317453 -294.67041) (xy 250.451299 -294.574651)
			(xy 250.58965 -294.485523) (xy 250.732175 -294.403235) (xy 250.878538 -294.327985) (xy 251.028391 -294.25995)
			(xy 251.181379 -294.199291) (xy 251.337139 -294.146154) (xy 251.495301 -294.100662) (xy 251.655491 -294.062926)
			(xy 251.817328 -294.033033) (xy 251.980428 -294.011055) (xy 252.144405 -293.997044) (xy 252.308869 -293.991034)
			(xy 252.473432 -293.993037) (xy 252.637701 -294.003051) (xy 252.801288 -294.021051) (xy 252.963805 -294.046994)
			(xy 253.124866 -294.080819) (xy 253.284089 -294.122445) (xy 253.441096 -294.171774) (xy 253.595516 -294.228689)
			(xy 253.746981 -294.293055) (xy 253.895133 -294.364719) (xy 254.039621 -294.443511) (xy 254.1801 -294.529245)
			(xy 254.316239 -294.621716) (xy 254.447714 -294.720706) (xy 254.574214 -294.82598) (xy 254.695438 -294.937288)
			(xy 254.811099 -295.054366) (xy 254.920922 -295.176936) (xy 255.024648 -295.304708) (xy 255.12203 -295.437379)
			(xy 255.212837 -295.574634) (xy 255.296853 -295.716147) (xy 255.37388 -295.861583) (xy 255.443735 -296.010596)
			(xy 255.506252 -296.162834) (xy 255.561282 -296.317935) (xy 255.608696 -296.475532) (xy 255.64838 -296.63525)
			(xy 255.680242 -296.796711) (xy 255.704204 -296.959531) (xy 255.72021 -297.123326) (xy 255.728223 -297.287705)
			(xy 255.728724 -297.369992) (xy 255.728223 -297.452279) (xy 255.72021 -297.616658) (xy 255.704204 -297.780453)
			(xy 255.680242 -297.943273) (xy 255.64838 -298.104734) (xy 255.608696 -298.264452) (xy 255.561282 -298.422049)
			(xy 255.506252 -298.57715) (xy 255.443735 -298.729388) (xy 255.37388 -298.878401) (xy 255.296853 -299.023837)
			(xy 255.212837 -299.16535) (xy 255.173403 -299.224954) (xy 268.243812 -299.224954) (xy 268.244172 -299.202842)
			(xy 268.250029 -299.159007) (xy 268.255496 -299.137578) (xy 268.257274 -299.130974) (xy 268.257274 -297.41876)
			(xy 268.255496 -297.412156) (xy 268.250032 -297.390726) (xy 268.244167 -297.346892) (xy 268.243812 -297.32478)
			(xy 268.244157 -297.302667) (xy 268.250024 -297.258832) (xy 268.255496 -297.237404) (xy 268.257274 -297.2308)
			(xy 268.257274 -294.56761) (xy 268.255496 -294.56126) (xy 268.250141 -294.540073) (xy 268.244402 -294.496751)
			(xy 268.244066 -294.4749) (xy 268.244413 -294.45305) (xy 268.250147 -294.409728) (xy 268.255496 -294.38854)
			(xy 268.257274 -294.38219) (xy 268.257274 -292.66769) (xy 268.255496 -292.66134) (xy 268.250137 -292.640154)
			(xy 268.244401 -292.596831) (xy 268.244066 -292.57498) (xy 268.244409 -292.55313) (xy 268.250146 -292.509808)
			(xy 268.255496 -292.48862) (xy 268.257274 -292.48227) (xy 268.257274 -291.717476) (xy 268.255496 -291.711126)
			(xy 268.250134 -291.68994) (xy 268.2444 -291.646617) (xy 268.244066 -291.624766) (xy 268.244406 -291.602916)
			(xy 268.250145 -291.559594) (xy 268.255496 -291.538406) (xy 268.257274 -291.532056) (xy 268.257274 -290.767516)
			(xy 268.255496 -290.761166) (xy 268.250142 -290.739979) (xy 268.244403 -290.696657) (xy 268.244066 -290.674806)
			(xy 268.244414 -290.652956) (xy 268.250147 -290.609634) (xy 268.255496 -290.588446) (xy 268.257274 -290.582096)
			(xy 268.257274 -289.817556) (xy 268.255496 -289.811206) (xy 268.25013 -289.790021) (xy 268.244399 -289.746697)
			(xy 268.244066 -289.724846) (xy 268.244422 -289.702996) (xy 268.25015 -289.659674) (xy 268.255496 -289.638486)
			(xy 268.257274 -289.632136) (xy 268.257274 -288.867596) (xy 268.255496 -288.861246) (xy 268.250138 -288.84006)
			(xy 268.244401 -288.796737) (xy 268.244066 -288.774886) (xy 268.24441 -288.753036) (xy 268.250146 -288.709714)
			(xy 268.255496 -288.688526) (xy 268.257274 -288.682176) (xy 268.257274 -287.917636) (xy 268.255496 -287.911286)
			(xy 268.250126 -287.890102) (xy 268.244397 -287.846777) (xy 268.244066 -287.824926) (xy 268.244418 -287.803076)
			(xy 268.250149 -287.759754) (xy 268.255496 -287.738566) (xy 268.257274 -287.732216) (xy 268.257274 -286.967676)
			(xy 268.255496 -286.961326) (xy 268.250134 -286.94014) (xy 268.2444 -286.896817) (xy 268.244066 -286.874966)
			(xy 268.244382 -286.853377) (xy 268.249991 -286.810565) (xy 268.255242 -286.789622) (xy 268.25702 -286.783018)
			(xy 268.25702 -286.0167) (xy 268.255242 -286.010096) (xy 268.250015 -285.989148) (xy 268.244414 -285.946339)
			(xy 268.244066 -285.924752) (xy 268.244379 -285.903163) (xy 268.24999 -285.860351) (xy 268.255242 -285.839408)
			(xy 268.25702 -285.832804) (xy 268.25702 -285.06674) (xy 268.255242 -285.060136) (xy 268.250023 -285.039187)
			(xy 268.244417 -284.996379) (xy 268.244066 -284.974792) (xy 268.244387 -284.953203) (xy 268.249993 -284.910391)
			(xy 268.255242 -284.889448) (xy 268.25702 -284.882844) (xy 268.25702 -284.11678) (xy 268.255242 -284.110176)
			(xy 268.250031 -284.089225) (xy 268.24442 -284.046418) (xy 268.244066 -284.024832) (xy 268.244394 -284.003243)
			(xy 268.249995 -283.960432) (xy 268.255242 -283.939488) (xy 268.25702 -283.932884) (xy 268.25702 -283.16682)
			(xy 268.255242 -283.160216) (xy 268.250019 -283.139268) (xy 268.244416 -283.096459) (xy 268.244066 -283.074872)
			(xy 268.244383 -283.053283) (xy 268.249991 -283.010471) (xy 268.255242 -282.989528) (xy 268.25702 -282.982924)
			(xy 268.25702 -282.21686) (xy 268.255242 -282.210256) (xy 268.250027 -282.189306) (xy 268.244418 -282.146499)
			(xy 268.244066 -282.124912) (xy 268.244391 -282.103323) (xy 268.249994 -282.060512) (xy 268.255242 -282.039568)
			(xy 268.25702 -282.032964) (xy 268.25702 -281.2669) (xy 268.255242 -281.260296) (xy 268.250015 -281.239348)
			(xy 268.244414 -281.196539) (xy 268.244066 -281.174952) (xy 268.244379 -281.153363) (xy 268.24999 -281.110551)
			(xy 268.255242 -281.089608) (xy 268.25702 -281.083004) (xy 268.25702 -280.316686) (xy 268.255242 -280.310082)
			(xy 268.250032 -280.289131) (xy 268.24442 -280.246324) (xy 268.244066 -280.224738) (xy 268.244396 -280.203149)
			(xy 268.249996 -280.160338) (xy 268.255242 -280.139394) (xy 268.25702 -280.13279) (xy 268.25702 -279.366726)
			(xy 268.255242 -279.360122) (xy 268.25002 -279.339173) (xy 268.244416 -279.296365) (xy 268.244066 -279.274778)
			(xy 268.244384 -279.253189) (xy 268.249992 -279.210377) (xy 268.255242 -279.189434) (xy 268.25702 -279.18283)
			(xy 268.25702 -278.416766) (xy 268.255242 -278.410162) (xy 268.250028 -278.389212) (xy 268.244419 -278.346404)
			(xy 268.244066 -278.324818) (xy 268.244392 -278.303229) (xy 268.249994 -278.260418) (xy 268.255242 -278.239474)
			(xy 268.25702 -278.23287) (xy 268.25702 -277.466806) (xy 268.255242 -277.460202) (xy 268.250017 -277.439254)
			(xy 268.244415 -277.396445) (xy 268.244066 -277.374858) (xy 268.24438 -277.353269) (xy 268.249991 -277.310457)
			(xy 268.255242 -277.289514) (xy 268.25702 -277.28291) (xy 268.25702 -276.516846) (xy 268.255242 -276.510242)
			(xy 268.250024 -276.489292) (xy 268.244417 -276.446485) (xy 268.244066 -276.424898) (xy 268.244388 -276.403309)
			(xy 268.249993 -276.360497) (xy 268.255242 -276.339554) (xy 268.25702 -276.33295) (xy 268.25702 -275.566886)
			(xy 268.255242 -275.560282) (xy 268.250032 -275.539331) (xy 268.24442 -275.496524) (xy 268.244066 -275.474938)
			(xy 268.244396 -275.453349) (xy 268.249996 -275.410538) (xy 268.255242 -275.389594) (xy 268.25702 -275.38299)
			(xy 268.25702 -272.53819) (xy 268.257537 -272.513242) (xy 268.265348 -272.463961) (xy 268.280761 -272.416504)
			(xy 268.303398 -272.372038) (xy 268.332702 -272.331654) (xy 268.349984 -272.313654) (xy 268.89837 -271.765268)
			(xy 268.916369 -271.74798) (xy 268.956741 -271.718648) (xy 269.001205 -271.695993) (xy 269.048666 -271.680573)
			(xy 269.097955 -271.672767) (xy 269.122906 -271.672304) (xy 272.559526 -271.672304) (xy 272.569633 -271.671831)
			(xy 272.588301 -271.664082) (xy 272.602551 -271.649747) (xy 272.60677 -271.640554) (xy 272.60677 -271.6403)
			(xy 272.617778 -271.614094) (xy 272.646425 -271.565002) (xy 272.682038 -271.520704) (xy 272.723831 -271.482182)
			(xy 272.770877 -271.450287) (xy 272.822136 -271.425727) (xy 272.876471 -271.409045) (xy 272.932681 -271.400611)
			(xy 272.989519 -271.400611) (xy 273.045729 -271.409045) (xy 273.100064 -271.425727) (xy 273.151323 -271.450287)
			(xy 273.198369 -271.482182) (xy 273.240162 -271.520704) (xy 273.275775 -271.565002) (xy 273.304422 -271.614094)
			(xy 273.31543 -271.6403) (xy 273.31543 -271.640554) (xy 273.319588 -271.649796) (xy 273.333828 -271.664196)
			(xy 273.352545 -271.671929) (xy 273.362674 -271.672304) (xy 317.044324 -271.672304) (xy 317.055252 -271.671795)
			(xy 317.075127 -271.662696) (xy 317.082678 -271.654778) (xy 317.140082 -271.588738) (xy 317.146432 -271.567402)
			(xy 317.144908 -271.556734) (xy 317.130333 -271.447872) (xy 317.110021 -271.229149) (xy 317.099834 -271.009722)
			(xy 317.099188 -270.89989) (xy 317.099682 -270.802975) (xy 317.107588 -270.609307) (xy 317.123387 -270.416123)
			(xy 317.147052 -270.223744) (xy 317.178545 -270.03249) (xy 317.217812 -269.84268) (xy 317.264789 -269.65463)
			(xy 317.319397 -269.468652) (xy 317.381546 -269.285057) (xy 317.451131 -269.104149) (xy 317.528037 -268.92623)
			(xy 317.612136 -268.751596) (xy 317.703289 -268.580537) (xy 317.801343 -268.413339) (xy 317.906135 -268.25028)
			(xy 318.01749 -268.09163) (xy 318.135224 -267.937655) (xy 318.259141 -267.78861) (xy 318.389034 -267.644743)
			(xy 318.524687 -267.506294) (xy 318.665874 -267.373494) (xy 318.81236 -267.246563) (xy 318.963902 -267.125712)
			(xy 319.120247 -267.011143) (xy 319.281135 -266.903047) (xy 319.446298 -266.801603) (xy 319.615462 -266.70698)
			(xy 319.788344 -266.619336) (xy 319.964657 -266.538816) (xy 320.144108 -266.465555) (xy 320.326398 -266.399675)
			(xy 320.511223 -266.341285) (xy 320.698276 -266.290482) (xy 320.887245 -266.247351) (xy 321.077817 -266.211963)
			(xy 321.269673 -266.184379) (xy 321.462495 -266.164642) (xy 321.655961 -266.152787) (xy 321.84975 -266.148834)
			(xy 322.043539 -266.152787) (xy 322.237005 -266.164642) (xy 322.429827 -266.184379) (xy 322.621683 -266.211963)
			(xy 322.812255 -266.247351) (xy 323.001224 -266.290482) (xy 323.188277 -266.341285) (xy 323.373102 -266.399675)
			(xy 323.555392 -266.465555) (xy 323.734843 -266.538816) (xy 323.911156 -266.619336) (xy 324.084038 -266.70698)
			(xy 324.253202 -266.801603) (xy 324.418365 -266.903047) (xy 324.579253 -267.011143) (xy 324.735598 -267.125712)
			(xy 324.88714 -267.246563) (xy 325.033626 -267.373494) (xy 325.174813 -267.506294) (xy 325.310466 -267.644743)
			(xy 325.440359 -267.78861) (xy 325.564276 -267.937655) (xy 325.68201 -268.09163) (xy 325.793365 -268.25028)
			(xy 325.898157 -268.413339) (xy 325.996211 -268.580537) (xy 326.087364 -268.751596) (xy 326.171463 -268.92623)
			(xy 326.248369 -269.104149) (xy 326.317954 -269.285057) (xy 326.380103 -269.468652) (xy 326.434711 -269.65463)
			(xy 326.481688 -269.84268) (xy 326.520955 -270.03249) (xy 326.552448 -270.223744) (xy 326.576113 -270.416123)
			(xy 326.591912 -270.609307) (xy 326.599818 -270.802975) (xy 326.600312 -270.89989) (xy 326.599669 -271.009722)
			(xy 326.589491 -271.22915) (xy 326.569175 -271.447873) (xy 326.554592 -271.556734) (xy 326.553068 -271.567402)
			(xy 326.559418 -271.588738) (xy 326.616822 -271.654778) (xy 326.624343 -271.662728) (xy 326.644242 -271.671795)
			(xy 326.655176 -271.672304) (xy 362.833158 -271.672304) (xy 362.843228 -271.671882) (xy 362.861827 -271.664162)
			(xy 362.869226 -271.657318) (xy 364.530386 -269.996158) (xy 364.548376 -269.978861) (xy 364.588751 -269.949531)
			(xy 364.633217 -269.926878) (xy 364.68068 -269.911459) (xy 364.72997 -269.903656) (xy 364.754922 -269.903194)
			(xy 373.096282 -269.903194) (xy 373.119945 -269.903633) (xy 373.166749 -269.910644) (xy 373.1895 -269.917164)
			(xy 373.19966 -269.920466) (xy 373.220488 -269.917926) (xy 373.294402 -269.875254) (xy 373.303225 -269.869709)
			(xy 373.315678 -269.853022) (xy 373.318532 -269.842996) (xy 373.318532 -269.842488) (xy 373.340591 -269.748123)
			(xy 373.391394 -269.561084) (xy 373.449783 -269.376273) (xy 373.515661 -269.193997) (xy 373.588919 -269.01456)
			(xy 373.669436 -268.83826) (xy 373.757076 -268.665392) (xy 373.851694 -268.496241) (xy 373.953133 -268.331091)
			(xy 374.061224 -268.170216) (xy 374.175787 -268.013883) (xy 374.29663 -267.862354) (xy 374.423554 -267.715879)
			(xy 374.556347 -267.574703) (xy 374.694787 -267.439062) (xy 374.838645 -267.309179) (xy 374.987681 -267.185273)
			(xy 375.141646 -267.067549) (xy 375.300286 -266.956202) (xy 375.463335 -266.851419) (xy 375.630522 -266.753374)
			(xy 375.801569 -266.662229) (xy 375.976191 -266.578137) (xy 376.154098 -266.501237) (xy 376.334994 -266.431658)
			(xy 376.518577 -266.369515) (xy 376.704541 -266.314912) (xy 376.892579 -266.26794) (xy 377.082376 -266.228676)
			(xy 377.273616 -266.197187) (xy 377.465981 -266.173524) (xy 377.659152 -266.157727) (xy 377.852806 -266.149822)
			(xy 377.949714 -266.149328) (xy 378.047904 -266.149832) (xy 378.244116 -266.157947) (xy 378.439825 -266.174165)
			(xy 378.634696 -266.198456) (xy 378.828398 -266.23078) (xy 379.020598 -266.27108) (xy 379.210968 -266.319289)
			(xy 379.399184 -266.375324) (xy 379.584923 -266.439088) (xy 379.767868 -266.510474) (xy 379.947708 -266.589359)
			(xy 380.124133 -266.675609) (xy 380.296844 -266.769076) (xy 380.465544 -266.8696) (xy 380.629947 -266.977009)
			(xy 380.78977 -267.091121) (xy 380.944741 -267.21174) (xy 381.094595 -267.33866) (xy 381.239077 -267.471665)
			(xy 381.377938 -267.610526) (xy 381.510942 -267.755008) (xy 381.637862 -267.904862) (xy 381.758481 -268.059833)
			(xy 381.872593 -268.219656) (xy 381.980002 -268.384059) (xy 382.080526 -268.55276) (xy 382.173993 -268.72547)
			(xy 382.260242 -268.901896) (xy 382.339127 -269.081735) (xy 382.410513 -269.264681) (xy 382.474278 -269.45042)
			(xy 382.530312 -269.638636) (xy 382.578521 -269.829006) (xy 382.618821 -270.021206) (xy 382.651144 -270.214908)
			(xy 382.675436 -270.409779) (xy 382.691653 -270.605488) (xy 382.699769 -270.8017) (xy 382.700276 -270.89989)
			(xy 433.198785 -270.89989) (xy 433.202791 -270.704835) (xy 433.214801 -270.510109) (xy 433.234796 -270.31604)
			(xy 433.262741 -270.122956) (xy 433.29859 -269.931181) (xy 433.342282 -269.741041) (xy 433.393743 -269.552854)
			(xy 433.452887 -269.366939) (xy 433.519614 -269.183608) (xy 433.593811 -269.003172) (xy 433.675353 -268.825934)
			(xy 433.764104 -268.652193) (xy 433.859912 -268.482242) (xy 433.962617 -268.316368) (xy 434.072045 -268.15485)
			(xy 434.188012 -267.997961) (xy 434.310323 -267.845966) (xy 434.43877 -267.69912) (xy 434.573138 -267.557671)
			(xy 434.7132 -267.421858) (xy 434.858719 -267.291909) (xy 435.009451 -267.168045) (xy 435.165141 -267.050473)
			(xy 435.325527 -266.939393) (xy 435.490338 -266.83499) (xy 435.659296 -266.737442) (xy 435.832117 -266.646913)
			(xy 436.008509 -266.563555) (xy 436.188174 -266.487509) (xy 436.370809 -266.418904) (xy 436.556108 -266.357854)
			(xy 436.743756 -266.304464) (xy 436.933438 -266.258822) (xy 437.124835 -266.221006) (xy 437.317622 -266.19108)
			(xy 437.511475 -266.169094) (xy 437.706068 -266.155085) (xy 437.901071 -266.149077) (xy 438.096157 -266.15108)
			(xy 438.290996 -266.161091) (xy 438.48526 -266.179092) (xy 438.678621 -266.205054) (xy 438.870754 -266.238932)
			(xy 439.061333 -266.280669) (xy 439.250038 -266.330196) (xy 439.436551 -266.387428) (xy 439.620557 -266.452269)
			(xy 439.801745 -266.52461) (xy 439.979811 -266.604328) (xy 440.154454 -266.69129) (xy 440.32538 -266.785349)
			(xy 440.492299 -266.886345) (xy 440.654932 -266.99411) (xy 440.813003 -267.10846) (xy 440.966246 -267.229203)
			(xy 441.114403 -267.356137) (xy 441.257224 -267.489045) (xy 441.394468 -267.627705) (xy 441.525904 -267.771883)
			(xy 441.651309 -267.921336) (xy 441.770473 -268.07581) (xy 441.883194 -268.235047) (xy 441.989283 -268.398778)
			(xy 442.088561 -268.566725) (xy 442.180859 -268.738608) (xy 442.266024 -268.914134) (xy 442.34391 -269.093009)
			(xy 442.414387 -269.274931) (xy 442.477335 -269.459593) (xy 442.53265 -269.646683) (xy 442.580236 -269.835887)
			(xy 442.620015 -270.026884) (xy 442.651919 -270.219354) (xy 442.675894 -270.412972) (xy 442.6919 -270.60741)
			(xy 442.699909 -270.802342) (xy 442.70041 -270.89989) (xy 442.699909 -270.997438) (xy 442.6919 -271.19237)
			(xy 442.675894 -271.386808) (xy 442.651919 -271.580426) (xy 442.620015 -271.772896) (xy 442.580236 -271.963893)
			(xy 442.53265 -272.153097) (xy 442.477335 -272.340187) (xy 442.414387 -272.524849) (xy 442.34391 -272.706771)
			(xy 442.266024 -272.885646) (xy 442.180859 -273.061172) (xy 442.088561 -273.233055) (xy 441.989283 -273.401002)
			(xy 441.883194 -273.564733) (xy 441.770473 -273.72397) (xy 441.651309 -273.878444) (xy 441.525904 -274.027897)
			(xy 441.394468 -274.172075) (xy 441.257224 -274.310735) (xy 441.114403 -274.443643) (xy 440.966246 -274.570577)
			(xy 440.813003 -274.69132) (xy 440.654932 -274.80567) (xy 440.492299 -274.913435) (xy 440.32538 -275.014431)
			(xy 440.154454 -275.10849) (xy 439.979811 -275.195452) (xy 439.801745 -275.27517) (xy 439.620557 -275.347511)
			(xy 439.436551 -275.412352) (xy 439.250038 -275.469584) (xy 439.061333 -275.519111) (xy 438.870754 -275.560848)
			(xy 438.678621 -275.594726) (xy 438.48526 -275.620688) (xy 438.290996 -275.638689) (xy 438.096157 -275.6487)
			(xy 437.901071 -275.650703) (xy 437.706068 -275.644695) (xy 437.511475 -275.630686) (xy 437.317622 -275.6087)
			(xy 437.124835 -275.578774) (xy 436.933438 -275.540958) (xy 436.743756 -275.495316) (xy 436.556108 -275.441926)
			(xy 436.370809 -275.380876) (xy 436.188174 -275.312271) (xy 436.008509 -275.236225) (xy 435.832117 -275.152867)
			(xy 435.659296 -275.062338) (xy 435.490338 -274.96479) (xy 435.325527 -274.860387) (xy 435.165141 -274.749307)
			(xy 435.009451 -274.631735) (xy 434.858719 -274.507871) (xy 434.7132 -274.377922) (xy 434.573138 -274.242109)
			(xy 434.43877 -274.10066) (xy 434.310323 -273.953814) (xy 434.188012 -273.801819) (xy 434.072045 -273.64493)
			(xy 433.962617 -273.483412) (xy 433.859912 -273.317538) (xy 433.764104 -273.147587) (xy 433.675353 -272.973846)
			(xy 433.593811 -272.796608) (xy 433.519614 -272.616172) (xy 433.452887 -272.432841) (xy 433.393743 -272.246926)
			(xy 433.342282 -272.058739) (xy 433.29859 -271.868599) (xy 433.262741 -271.676824) (xy 433.234796 -271.48374)
			(xy 433.214801 -271.289671) (xy 433.202791 -271.094945) (xy 433.198785 -270.89989) (xy 382.700276 -270.89989)
			(xy 382.699633 -271.009722) (xy 382.689455 -271.22915) (xy 382.66914 -271.447873) (xy 382.654556 -271.556734)
			(xy 382.653032 -271.567402) (xy 382.659382 -271.588738) (xy 382.716786 -271.654778) (xy 382.724322 -271.662711)
			(xy 382.744209 -271.671788) (xy 382.75514 -271.672304) (xy 430.40554 -271.672304) (xy 430.424002 -271.672585)
			(xy 430.460673 -271.676909) (xy 430.478692 -271.68094) (xy 430.484534 -271.68221) (xy 430.540414 -271.68221)
			(xy 430.565364 -271.682698) (xy 430.614647 -271.690512) (xy 430.662105 -271.705931) (xy 430.706571 -271.728574)
			(xy 430.746953 -271.757888) (xy 430.76495 -271.775174) (xy 431.44948 -272.459704) (xy 431.466773 -272.477697)
			(xy 431.496097 -272.518073) (xy 431.518745 -272.562539) (xy 431.534158 -272.610001) (xy 431.541958 -272.659289)
			(xy 431.542444 -272.68424) (xy 431.542444 -288.682176) (xy 431.544222 -288.688526) (xy 431.549575 -288.709714)
			(xy 431.555315 -288.753035) (xy 431.555652 -288.774886) (xy 431.555302 -288.796736) (xy 431.54957 -288.840058)
			(xy 431.544222 -288.861246) (xy 431.542444 -288.867596) (xy 431.542444 -289.632136) (xy 431.544222 -289.638486)
			(xy 431.549587 -289.659671) (xy 431.555319 -289.702995) (xy 431.555652 -289.724846) (xy 431.555314 -289.746696)
			(xy 431.549574 -289.790018) (xy 431.544222 -289.811206) (xy 431.542444 -289.817556) (xy 431.542444 -290.582096)
			(xy 431.544222 -290.588446) (xy 431.549579 -290.609633) (xy 431.555316 -290.652955) (xy 431.555652 -290.674806)
			(xy 431.555306 -290.696656) (xy 431.549571 -290.739978) (xy 431.544222 -290.761166) (xy 431.542444 -290.767516)
			(xy 431.542444 -291.532056) (xy 431.544222 -291.538406) (xy 431.54959 -291.55959) (xy 431.55532 -291.602915)
			(xy 431.555652 -291.624766) (xy 431.555298 -291.646616) (xy 431.549569 -291.689938) (xy 431.544222 -291.711126)
			(xy 431.542444 -291.717476) (xy 431.542444 -292.48227) (xy 431.544222 -292.48862) (xy 431.549593 -292.509803)
			(xy 431.555321 -292.553129) (xy 431.555652 -292.57498) (xy 431.555301 -292.59683) (xy 431.54957 -292.640152)
			(xy 431.544222 -292.66134) (xy 431.542444 -292.66769) (xy 431.542444 -293.43223) (xy 431.544222 -293.43858)
			(xy 431.549585 -293.459765) (xy 431.555318 -293.503089) (xy 431.555652 -293.52494) (xy 431.555313 -293.54679)
			(xy 431.549573 -293.590112) (xy 431.544222 -293.6113) (xy 431.542444 -293.61765) (xy 431.542444 -294.38219)
			(xy 431.544222 -294.38854) (xy 431.549578 -294.409727) (xy 431.555316 -294.453049) (xy 431.555652 -294.4749)
			(xy 431.555305 -294.49675) (xy 431.549571 -294.540072) (xy 431.544222 -294.56126) (xy 431.542444 -294.56761)
			(xy 431.542444 -296.28211) (xy 431.544222 -296.28846) (xy 431.549582 -296.309646) (xy 431.555317 -296.352969)
			(xy 431.555652 -296.37482) (xy 431.555309 -296.39667) (xy 431.549572 -296.439992) (xy 431.544222 -296.46118)
			(xy 431.542444 -296.46753) (xy 431.542444 -297.23207) (xy 431.544222 -297.23842) (xy 431.549593 -297.259603)
			(xy 431.555321 -297.302929) (xy 431.555652 -297.32478) (xy 431.555301 -297.34663) (xy 431.54957 -297.389952)
			(xy 431.544222 -297.41114) (xy 431.542444 -297.41749) (xy 431.542444 -298.18203) (xy 431.544222 -298.18838)
			(xy 431.549585 -298.209565) (xy 431.555318 -298.252889) (xy 431.555652 -298.27474) (xy 431.555313 -298.29659)
			(xy 431.549573 -298.339912) (xy 431.544222 -298.3611) (xy 431.542444 -298.36745) (xy 431.542444 -299.132244)
			(xy 431.544222 -299.138594) (xy 431.549588 -299.159779) (xy 431.555319 -299.203103) (xy 431.555652 -299.224954)
			(xy 431.555296 -299.246804) (xy 431.549568 -299.290126) (xy 431.544222 -299.311314) (xy 431.542444 -299.317664)
			(xy 431.542444 -300.082204) (xy 431.544222 -300.088554) (xy 431.54958 -300.10974) (xy 431.555317 -300.153063)
			(xy 431.555652 -300.174914) (xy 431.555308 -300.196764) (xy 431.549572 -300.240086) (xy 431.544222 -300.261274)
			(xy 431.542444 -300.267624) (xy 431.542444 -301.032164) (xy 431.544222 -301.038514) (xy 431.549592 -301.059698)
			(xy 431.555321 -301.103023) (xy 431.555652 -301.124874) (xy 431.5553 -301.146724) (xy 431.549569 -301.190046)
			(xy 431.544222 -301.211234) (xy 431.542444 -301.217584) (xy 431.542444 -301.982124) (xy 431.544222 -301.988474)
			(xy 431.549584 -302.009659) (xy 431.555318 -302.052983) (xy 431.555652 -302.074834) (xy 431.555311 -302.096684)
			(xy 431.549573 -302.140006) (xy 431.544222 -302.161194) (xy 431.542444 -302.167544) (xy 431.542444 -308.61)
			(xy 444.070747 -308.61) (xy 444.074755 -308.445474) (xy 444.086768 -308.281339) (xy 444.106758 -308.117983)
			(xy 444.134678 -307.955794) (xy 444.170461 -307.795157) (xy 444.214023 -307.636453) (xy 444.265261 -307.480058)
			(xy 444.324052 -307.326343) (xy 444.390257 -307.175672) (xy 444.46372 -307.028404) (xy 444.544265 -306.884887)
			(xy 444.631703 -306.745461) (xy 444.725825 -306.610459) (xy 444.826409 -306.480199) (xy 444.933215 -306.35499)
			(xy 445.045991 -306.23513) (xy 445.164469 -306.120904) (xy 445.288367 -306.012581) (xy 445.417393 -305.910418)
			(xy 445.551239 -305.814659) (xy 445.68959 -305.725531) (xy 445.832115 -305.643243) (xy 445.978478 -305.567993)
			(xy 446.128331 -305.499958) (xy 446.281319 -305.439299) (xy 446.437079 -305.386162) (xy 446.595241 -305.34067)
			(xy 446.755431 -305.302934) (xy 446.917268 -305.273041) (xy 447.080368 -305.251063) (xy 447.244345 -305.237052)
			(xy 447.408809 -305.231042) (xy 447.573372 -305.233045) (xy 447.737641 -305.243059) (xy 447.901228 -305.261059)
			(xy 448.063745 -305.287002) (xy 448.224806 -305.320827) (xy 448.384029 -305.362453) (xy 448.541036 -305.411782)
			(xy 448.695456 -305.468697) (xy 448.846921 -305.533063) (xy 448.995073 -305.604727) (xy 449.139561 -305.683519)
			(xy 449.28004 -305.769253) (xy 449.416179 -305.861724) (xy 449.547654 -305.960714) (xy 449.674154 -306.065988)
			(xy 449.795378 -306.177296) (xy 449.911039 -306.294374) (xy 450.020862 -306.416944) (xy 450.124588 -306.544716)
			(xy 450.22197 -306.677387) (xy 450.312777 -306.814642) (xy 450.396793 -306.956155) (xy 450.47382 -307.101591)
			(xy 450.543675 -307.250604) (xy 450.606192 -307.402842) (xy 450.661222 -307.557943) (xy 450.676197 -307.607716)
			(xy 462.556604 -307.607716) (xy 462.560677 -307.552057) (xy 462.572812 -307.497584) (xy 462.592748 -307.445458)
			(xy 462.620062 -307.39679) (xy 462.65417 -307.352618) (xy 462.694347 -307.313883) (xy 462.739735 -307.281411)
			(xy 462.789367 -307.255893) (xy 462.842187 -307.237874) (xy 462.897066 -307.227737) (xy 462.952837 -307.225699)
			(xy 463.008311 -307.231802) (xy 463.062304 -307.245918) (xy 463.113667 -307.267745) (xy 463.161305 -307.296818)
			(xy 463.204201 -307.332517) (xy 463.241443 -307.374081) (xy 463.272237 -307.420625) (xy 463.295925 -307.471156)
			(xy 463.312003 -307.524598) (xy 463.320129 -307.579812) (xy 463.320638 -307.607716) (xy 463.320129 -307.63562)
			(xy 463.312003 -307.690834) (xy 463.295925 -307.744276) (xy 463.272237 -307.794807) (xy 463.241443 -307.841351)
			(xy 463.204201 -307.882915) (xy 463.161305 -307.918614) (xy 463.113667 -307.947687) (xy 463.062304 -307.969514)
			(xy 463.008311 -307.98363) (xy 462.952837 -307.989733) (xy 462.897066 -307.987695) (xy 462.842187 -307.977558)
			(xy 462.789367 -307.959539) (xy 462.739735 -307.934021) (xy 462.694347 -307.901549) (xy 462.65417 -307.862814)
			(xy 462.620062 -307.818642) (xy 462.592748 -307.769974) (xy 462.572812 -307.717848) (xy 462.560677 -307.663375)
			(xy 462.556604 -307.607716) (xy 450.676197 -307.607716) (xy 450.708636 -307.71554) (xy 450.74832 -307.875258)
			(xy 450.780182 -308.036719) (xy 450.804144 -308.199539) (xy 450.82015 -308.363334) (xy 450.828163 -308.527713)
			(xy 450.828664 -308.61) (xy 450.828163 -308.692287) (xy 450.828163 -308.692296) (xy 462.556604 -308.692296)
			(xy 462.560677 -308.636637) (xy 462.572812 -308.582164) (xy 462.592748 -308.530038) (xy 462.620062 -308.48137)
			(xy 462.65417 -308.437198) (xy 462.694347 -308.398463) (xy 462.739735 -308.365991) (xy 462.789367 -308.340473)
			(xy 462.842187 -308.322454) (xy 462.897066 -308.312317) (xy 462.952837 -308.310279) (xy 463.008311 -308.316382)
			(xy 463.062304 -308.330498) (xy 463.113667 -308.352325) (xy 463.161305 -308.381398) (xy 463.204201 -308.417097)
			(xy 463.241443 -308.458661) (xy 463.272237 -308.505205) (xy 463.295925 -308.555736) (xy 463.312003 -308.609178)
			(xy 463.320129 -308.664392) (xy 463.320638 -308.692296) (xy 463.320129 -308.7202) (xy 463.312003 -308.775414)
			(xy 463.295925 -308.828856) (xy 463.272237 -308.879387) (xy 463.241443 -308.925931) (xy 463.204201 -308.967495)
			(xy 463.161305 -309.003194) (xy 463.113667 -309.032267) (xy 463.062304 -309.054094) (xy 463.008311 -309.06821)
			(xy 462.952837 -309.074313) (xy 462.897066 -309.072275) (xy 462.842187 -309.062138) (xy 462.789367 -309.044119)
			(xy 462.739735 -309.018601) (xy 462.694347 -308.986129) (xy 462.65417 -308.947394) (xy 462.620062 -308.903222)
			(xy 462.592748 -308.854554) (xy 462.572812 -308.802428) (xy 462.560677 -308.747955) (xy 462.556604 -308.692296)
			(xy 450.828163 -308.692296) (xy 450.82015 -308.856666) (xy 450.804144 -309.020461) (xy 450.780182 -309.183281)
			(xy 450.74832 -309.344742) (xy 450.708636 -309.50446) (xy 450.661222 -309.662057) (xy 450.606192 -309.817158)
			(xy 450.543675 -309.969396) (xy 450.47382 -310.118409) (xy 450.396793 -310.263845) (xy 450.312777 -310.405358)
			(xy 450.22197 -310.542613) (xy 450.124588 -310.675284) (xy 450.020862 -310.803056) (xy 449.911039 -310.925626)
			(xy 449.795378 -311.042704) (xy 449.674154 -311.154012) (xy 449.547654 -311.259286) (xy 449.416179 -311.358276)
			(xy 449.28004 -311.450747) (xy 449.139561 -311.536481) (xy 448.995073 -311.615273) (xy 448.846921 -311.686937)
			(xy 448.695456 -311.751303) (xy 448.541036 -311.808218) (xy 448.384029 -311.857547) (xy 448.224806 -311.899173)
			(xy 448.063745 -311.932998) (xy 447.901228 -311.958941) (xy 447.737641 -311.976941) (xy 447.573372 -311.986955)
			(xy 447.408809 -311.988958) (xy 447.244345 -311.982948) (xy 447.080368 -311.968937) (xy 446.917268 -311.946959)
			(xy 446.755431 -311.917066) (xy 446.595241 -311.87933) (xy 446.437079 -311.833838) (xy 446.281319 -311.780701)
			(xy 446.128331 -311.720042) (xy 445.978478 -311.652007) (xy 445.832115 -311.576757) (xy 445.68959 -311.494469)
			(xy 445.551239 -311.405341) (xy 445.417393 -311.309582) (xy 445.288367 -311.207419) (xy 445.164469 -311.099096)
			(xy 445.045991 -310.98487) (xy 444.933215 -310.86501) (xy 444.826409 -310.739801) (xy 444.725825 -310.609541)
			(xy 444.631703 -310.474539) (xy 444.544265 -310.335113) (xy 444.46372 -310.191596) (xy 444.390257 -310.044328)
			(xy 444.324052 -309.893657) (xy 444.265261 -309.739942) (xy 444.214023 -309.583547) (xy 444.170461 -309.424843)
			(xy 444.134678 -309.264206) (xy 444.106758 -309.102017) (xy 444.086768 -308.938661) (xy 444.074755 -308.774526)
			(xy 444.070747 -308.61) (xy 431.542444 -308.61) (xy 431.542444 -318.213232) (xy 431.542698 -318.224916)
			(xy 431.542698 -320.900044) (xy 433.198785 -320.900044) (xy 433.202791 -320.704989) (xy 433.214801 -320.510263)
			(xy 433.234796 -320.316194) (xy 433.262741 -320.12311) (xy 433.29859 -319.931335) (xy 433.342282 -319.741195)
			(xy 433.393743 -319.553008) (xy 433.452887 -319.367093) (xy 433.519614 -319.183762) (xy 433.593811 -319.003326)
			(xy 433.675353 -318.826088) (xy 433.764104 -318.652347) (xy 433.859912 -318.482396) (xy 433.962617 -318.316522)
			(xy 434.072045 -318.155004) (xy 434.188012 -317.998115) (xy 434.310323 -317.84612) (xy 434.43877 -317.699274)
			(xy 434.573138 -317.557825) (xy 434.7132 -317.422012) (xy 434.858719 -317.292063) (xy 435.009451 -317.168199)
			(xy 435.165141 -317.050627) (xy 435.325527 -316.939547) (xy 435.490338 -316.835144) (xy 435.659296 -316.737596)
			(xy 435.832117 -316.647067) (xy 436.008509 -316.563709) (xy 436.188174 -316.487663) (xy 436.370809 -316.419058)
			(xy 436.556108 -316.358008) (xy 436.743756 -316.304618) (xy 436.933438 -316.258976) (xy 437.124835 -316.22116)
			(xy 437.317622 -316.191234) (xy 437.511475 -316.169248) (xy 437.706068 -316.155239) (xy 437.901071 -316.149231)
			(xy 438.096157 -316.151234) (xy 438.290996 -316.161245) (xy 438.48526 -316.179246) (xy 438.678621 -316.205208)
			(xy 438.870754 -316.239086) (xy 439.061333 -316.280823) (xy 439.250038 -316.33035) (xy 439.436551 -316.387582)
			(xy 439.620557 -316.452423) (xy 439.801745 -316.524764) (xy 439.979811 -316.604482) (xy 440.154454 -316.691444)
			(xy 440.32538 -316.785503) (xy 440.492299 -316.886499) (xy 440.654932 -316.994264) (xy 440.813003 -317.108614)
			(xy 440.966246 -317.229357) (xy 441.114403 -317.356291) (xy 441.257224 -317.489199) (xy 441.394468 -317.627859)
			(xy 441.525904 -317.772037) (xy 441.651309 -317.92149) (xy 441.770473 -318.075964) (xy 441.883194 -318.235201)
			(xy 441.989283 -318.398932) (xy 442.088561 -318.566879) (xy 442.180859 -318.738762) (xy 442.266024 -318.914288)
			(xy 442.34391 -319.093163) (xy 442.414387 -319.275085) (xy 442.477335 -319.459747) (xy 442.53265 -319.646837)
			(xy 442.580236 -319.836041) (xy 442.620015 -320.027038) (xy 442.651919 -320.219508) (xy 442.675894 -320.413126)
			(xy 442.6919 -320.607564) (xy 442.699909 -320.802496) (xy 442.70041 -320.900044) (xy 442.699909 -320.997592)
			(xy 442.6919 -321.192524) (xy 442.675894 -321.386962) (xy 442.651919 -321.58058) (xy 442.620015 -321.77305)
			(xy 442.580236 -321.964047) (xy 442.53265 -322.153251) (xy 442.477335 -322.340341) (xy 442.414387 -322.525003)
			(xy 442.34391 -322.706925) (xy 442.266024 -322.8858) (xy 442.180859 -323.061326) (xy 442.088561 -323.233209)
			(xy 441.989283 -323.401156) (xy 441.883194 -323.564887) (xy 441.770473 -323.724124) (xy 441.651309 -323.878598)
			(xy 441.525904 -324.028051) (xy 441.394468 -324.172229) (xy 441.257224 -324.310889) (xy 441.114403 -324.443797)
			(xy 440.966246 -324.570731) (xy 440.813003 -324.691474) (xy 440.654932 -324.805824) (xy 440.492299 -324.913589)
			(xy 440.32538 -325.014585) (xy 440.154454 -325.108644) (xy 439.979811 -325.195606) (xy 439.801745 -325.275324)
			(xy 439.620557 -325.347665) (xy 439.436551 -325.412506) (xy 439.250038 -325.469738) (xy 439.061333 -325.519265)
			(xy 438.870754 -325.561002) (xy 438.678621 -325.59488) (xy 438.48526 -325.620842) (xy 438.290996 -325.638843)
			(xy 438.096157 -325.648854) (xy 437.901071 -325.650857) (xy 437.706068 -325.644849) (xy 437.511475 -325.63084)
			(xy 437.317622 -325.608854) (xy 437.124835 -325.578928) (xy 436.933438 -325.541112) (xy 436.743756 -325.49547)
			(xy 436.556108 -325.44208) (xy 436.370809 -325.38103) (xy 436.188174 -325.312425) (xy 436.008509 -325.236379)
			(xy 435.832117 -325.153021) (xy 435.659296 -325.062492) (xy 435.490338 -324.964944) (xy 435.325527 -324.860541)
			(xy 435.165141 -324.749461) (xy 435.009451 -324.631889) (xy 434.858719 -324.508025) (xy 434.7132 -324.378076)
			(xy 434.573138 -324.242263) (xy 434.43877 -324.100814) (xy 434.310323 -323.953968) (xy 434.188012 -323.801973)
			(xy 434.072045 -323.645084) (xy 433.962617 -323.483566) (xy 433.859912 -323.317692) (xy 433.764104 -323.147741)
			(xy 433.675353 -322.974) (xy 433.593811 -322.796762) (xy 433.519614 -322.616326) (xy 433.452887 -322.432995)
			(xy 433.393743 -322.24708) (xy 433.342282 -322.058893) (xy 433.29859 -321.868753) (xy 433.262741 -321.676978)
			(xy 433.234796 -321.483894) (xy 433.214801 -321.289825) (xy 433.202791 -321.095099) (xy 433.198785 -320.900044)
			(xy 431.542698 -320.900044) (xy 431.542698 -326.560434) (xy 431.542952 -326.572118) (xy 431.542952 -336.935064)
			(xy 431.542477 -336.960014) (xy 431.534657 -337.009297) (xy 431.519235 -337.056754) (xy 431.496588 -337.10122)
			(xy 431.467274 -337.141602) (xy 431.449988 -337.1596) (xy 430.210214 -338.399374) (xy 430.192213 -338.416657)
			(xy 430.151839 -338.445983) (xy 430.107375 -338.468633) (xy 430.059915 -338.484048) (xy 430.010628 -338.491851)
			(xy 429.985678 -338.492338) (xy 269.13205 -338.492338) (xy 269.1071 -338.491858) (xy 269.057817 -338.48404)
			(xy 269.01036 -338.468619) (xy 268.965894 -338.445974) (xy 268.925512 -338.41666) (xy 268.907514 -338.399374)
			(xy 268.350238 -337.842098) (xy 268.332949 -337.824102) (xy 268.303623 -337.783727) (xy 268.280975 -337.739261)
			(xy 268.26556 -337.6918) (xy 268.25776 -337.642513) (xy 268.257274 -337.617562) (xy 268.257274 -299.318934)
			(xy 268.255496 -299.31233) (xy 268.250011 -299.290905) (xy 268.244148 -299.247068) (xy 268.243812 -299.224954)
			(xy 255.173403 -299.224954) (xy 255.12203 -299.302605) (xy 255.024648 -299.435276) (xy 254.920922 -299.563048)
			(xy 254.811099 -299.685618) (xy 254.695438 -299.802696) (xy 254.574214 -299.914004) (xy 254.447714 -300.019278)
			(xy 254.316239 -300.118268) (xy 254.1801 -300.210739) (xy 254.039621 -300.296473) (xy 253.895133 -300.375265)
			(xy 253.746981 -300.446929) (xy 253.595516 -300.511295) (xy 253.441096 -300.56821) (xy 253.284089 -300.617539)
			(xy 253.124866 -300.659165) (xy 252.963805 -300.69299) (xy 252.801288 -300.718933) (xy 252.637701 -300.736933)
			(xy 252.473432 -300.746947) (xy 252.308869 -300.74895) (xy 252.144405 -300.74294) (xy 251.980428 -300.728929)
			(xy 251.817328 -300.706951) (xy 251.655491 -300.677058) (xy 251.495301 -300.639322) (xy 251.337139 -300.59383)
			(xy 251.181379 -300.540693) (xy 251.028391 -300.480034) (xy 250.878538 -300.411999) (xy 250.732175 -300.336749)
			(xy 250.58965 -300.254461) (xy 250.451299 -300.165333) (xy 250.317453 -300.069574) (xy 250.188427 -299.967411)
			(xy 250.064529 -299.859088) (xy 249.946051 -299.744862) (xy 249.833275 -299.625002) (xy 249.726469 -299.499793)
			(xy 249.625885 -299.369533) (xy 249.531763 -299.234531) (xy 249.444325 -299.095105) (xy 249.36378 -298.951588)
			(xy 249.290317 -298.80432) (xy 249.224112 -298.653649) (xy 249.165321 -298.499934) (xy 249.114083 -298.343539)
			(xy 249.070521 -298.184835) (xy 249.034738 -298.024198) (xy 249.006818 -297.862009) (xy 248.986828 -297.698653)
			(xy 248.974815 -297.534518) (xy 248.970807 -297.369992) (xy 199.352267 -297.369992) (xy 199.349627 -297.389952)
			(xy 199.34428 -297.41114) (xy 199.342502 -297.41749) (xy 199.342502 -298.18203) (xy 199.34428 -298.18838)
			(xy 199.349643 -298.209565) (xy 199.355376 -298.252889) (xy 199.35571 -298.27474) (xy 199.355369 -298.29659)
			(xy 199.349631 -298.339912) (xy 199.34428 -298.3611) (xy 199.342502 -298.36745) (xy 199.342502 -299.132244)
			(xy 199.34428 -299.138594) (xy 199.349645 -299.159779) (xy 199.355377 -299.203103) (xy 199.35571 -299.224954)
			(xy 199.355352 -299.246804) (xy 199.349625 -299.290126) (xy 199.34428 -299.311314) (xy 199.342502 -299.317664)
			(xy 199.342502 -300.082204) (xy 199.34428 -300.088554) (xy 199.349638 -300.109741) (xy 199.355375 -300.153063)
			(xy 199.35571 -300.174914) (xy 199.355364 -300.196764) (xy 199.349629 -300.240086) (xy 199.34428 -300.261274)
			(xy 199.342502 -300.267624) (xy 199.342502 -301.032164) (xy 199.34428 -301.038514) (xy 199.349649 -301.059698)
			(xy 199.355379 -301.103023) (xy 199.35571 -301.124874) (xy 199.355356 -301.146724) (xy 199.349626 -301.190046)
			(xy 199.34428 -301.211234) (xy 199.342502 -301.217584) (xy 199.342502 -301.982124) (xy 199.34428 -301.988474)
			(xy 199.349641 -302.00966) (xy 199.355376 -302.052983) (xy 199.35571 -302.074834) (xy 199.355368 -302.096684)
			(xy 199.34963 -302.140006) (xy 199.34428 -302.161194) (xy 199.342502 -302.167544) (xy 199.342502 -307.484272)
			(xy 231.935526 -307.484272) (xy 231.939599 -307.428613) (xy 231.951734 -307.37414) (xy 231.97167 -307.322014)
			(xy 231.998984 -307.273346) (xy 232.033092 -307.229174) (xy 232.073269 -307.190439) (xy 232.118657 -307.157967)
			(xy 232.168289 -307.132449) (xy 232.221109 -307.11443) (xy 232.275988 -307.104293) (xy 232.331759 -307.102255)
			(xy 232.387233 -307.108358) (xy 232.441226 -307.122474) (xy 232.492589 -307.144301) (xy 232.540227 -307.173374)
			(xy 232.583123 -307.209073) (xy 232.620365 -307.250637) (xy 232.651159 -307.297181) (xy 232.674847 -307.347712)
			(xy 232.690925 -307.401154) (xy 232.699051 -307.456368) (xy 232.69956 -307.484272) (xy 248.185684 -307.484272)
			(xy 248.189757 -307.428613) (xy 248.201892 -307.37414) (xy 248.221828 -307.322014) (xy 248.249142 -307.273346)
			(xy 248.28325 -307.229174) (xy 248.323427 -307.190439) (xy 248.368815 -307.157967) (xy 248.418447 -307.132449)
			(xy 248.471267 -307.11443) (xy 248.526146 -307.104293) (xy 248.581917 -307.102255) (xy 248.637391 -307.108358)
			(xy 248.691384 -307.122474) (xy 248.742747 -307.144301) (xy 248.790385 -307.173374) (xy 248.833281 -307.209073)
			(xy 248.870523 -307.250637) (xy 248.901317 -307.297181) (xy 248.925005 -307.347712) (xy 248.941083 -307.401154)
			(xy 248.949209 -307.456368) (xy 248.949718 -307.484272) (xy 248.949209 -307.512176) (xy 248.941083 -307.56739)
			(xy 248.925005 -307.620832) (xy 248.901317 -307.671363) (xy 248.870523 -307.717907) (xy 248.833281 -307.759471)
			(xy 248.790385 -307.79517) (xy 248.742747 -307.824243) (xy 248.691384 -307.84607) (xy 248.637391 -307.860186)
			(xy 248.581917 -307.866289) (xy 248.526146 -307.864251) (xy 248.471267 -307.854114) (xy 248.418447 -307.836095)
			(xy 248.368815 -307.810577) (xy 248.323427 -307.778105) (xy 248.28325 -307.73937) (xy 248.249142 -307.695198)
			(xy 248.221828 -307.64653) (xy 248.201892 -307.594404) (xy 248.189757 -307.539931) (xy 248.185684 -307.484272)
			(xy 232.69956 -307.484272) (xy 232.699051 -307.512176) (xy 232.690925 -307.56739) (xy 232.674847 -307.620832)
			(xy 232.651159 -307.671363) (xy 232.620365 -307.717907) (xy 232.583123 -307.759471) (xy 232.540227 -307.79517)
			(xy 232.492589 -307.824243) (xy 232.441226 -307.84607) (xy 232.387233 -307.860186) (xy 232.331759 -307.866289)
			(xy 232.275988 -307.864251) (xy 232.221109 -307.854114) (xy 232.168289 -307.836095) (xy 232.118657 -307.810577)
			(xy 232.073269 -307.778105) (xy 232.033092 -307.73937) (xy 231.998984 -307.695198) (xy 231.97167 -307.64653)
			(xy 231.951734 -307.594404) (xy 231.939599 -307.539931) (xy 231.935526 -307.484272) (xy 199.342502 -307.484272)
			(xy 199.342502 -311.179972) (xy 213.610705 -311.179972) (xy 213.614713 -311.015446) (xy 213.626726 -310.851311)
			(xy 213.646716 -310.687955) (xy 213.674636 -310.525766) (xy 213.710419 -310.365129) (xy 213.753981 -310.206425)
			(xy 213.805219 -310.05003) (xy 213.86401 -309.896315) (xy 213.930215 -309.745644) (xy 214.003678 -309.598376)
			(xy 214.084223 -309.454859) (xy 214.171661 -309.315433) (xy 214.265783 -309.180431) (xy 214.366367 -309.050171)
			(xy 214.473173 -308.924962) (xy 214.585949 -308.805102) (xy 214.704427 -308.690876) (xy 214.828325 -308.582553)
			(xy 214.957351 -308.48039) (xy 215.091197 -308.384631) (xy 215.229548 -308.295503) (xy 215.372073 -308.213215)
			(xy 215.518436 -308.137965) (xy 215.668289 -308.06993) (xy 215.821277 -308.009271) (xy 215.977037 -307.956134)
			(xy 216.135199 -307.910642) (xy 216.295389 -307.872906) (xy 216.457226 -307.843013) (xy 216.620326 -307.821035)
			(xy 216.784303 -307.807024) (xy 216.948767 -307.801014) (xy 217.11333 -307.803017) (xy 217.277599 -307.813031)
			(xy 217.441186 -307.831031) (xy 217.603703 -307.856974) (xy 217.764764 -307.890799) (xy 217.923987 -307.932425)
			(xy 218.080994 -307.981754) (xy 218.235414 -308.038669) (xy 218.386879 -308.103035) (xy 218.535031 -308.174699)
			(xy 218.679519 -308.253491) (xy 218.819998 -308.339225) (xy 218.956137 -308.431696) (xy 219.087612 -308.530686)
			(xy 219.133473 -308.568852) (xy 231.935526 -308.568852) (xy 231.939599 -308.513193) (xy 231.951734 -308.45872)
			(xy 231.97167 -308.406594) (xy 231.998984 -308.357926) (xy 232.033092 -308.313754) (xy 232.073269 -308.275019)
			(xy 232.118657 -308.242547) (xy 232.168289 -308.217029) (xy 232.221109 -308.19901) (xy 232.275988 -308.188873)
			(xy 232.331759 -308.186835) (xy 232.387233 -308.192938) (xy 232.441226 -308.207054) (xy 232.492589 -308.228881)
			(xy 232.540227 -308.257954) (xy 232.583123 -308.293653) (xy 232.620365 -308.335217) (xy 232.651159 -308.381761)
			(xy 232.674847 -308.432292) (xy 232.690925 -308.485734) (xy 232.699051 -308.540948) (xy 232.69956 -308.568852)
			(xy 248.185684 -308.568852) (xy 248.189757 -308.513193) (xy 248.201892 -308.45872) (xy 248.221828 -308.406594)
			(xy 248.249142 -308.357926) (xy 248.28325 -308.313754) (xy 248.323427 -308.275019) (xy 248.368815 -308.242547)
			(xy 248.418447 -308.217029) (xy 248.471267 -308.19901) (xy 248.526146 -308.188873) (xy 248.581917 -308.186835)
			(xy 248.637391 -308.192938) (xy 248.691384 -308.207054) (xy 248.742747 -308.228881) (xy 248.790385 -308.257954)
			(xy 248.833281 -308.293653) (xy 248.870523 -308.335217) (xy 248.901317 -308.381761) (xy 248.925005 -308.432292)
			(xy 248.941083 -308.485734) (xy 248.949209 -308.540948) (xy 248.949718 -308.568852) (xy 248.949209 -308.596756)
			(xy 248.941083 -308.65197) (xy 248.925005 -308.705412) (xy 248.901317 -308.755943) (xy 248.870523 -308.802487)
			(xy 248.833281 -308.844051) (xy 248.790385 -308.87975) (xy 248.742747 -308.908823) (xy 248.691384 -308.93065)
			(xy 248.637391 -308.944766) (xy 248.581917 -308.950869) (xy 248.526146 -308.948831) (xy 248.471267 -308.938694)
			(xy 248.418447 -308.920675) (xy 248.368815 -308.895157) (xy 248.323427 -308.862685) (xy 248.28325 -308.82395)
			(xy 248.249142 -308.779778) (xy 248.221828 -308.73111) (xy 248.201892 -308.678984) (xy 248.189757 -308.624511)
			(xy 248.185684 -308.568852) (xy 232.69956 -308.568852) (xy 232.699051 -308.596756) (xy 232.690925 -308.65197)
			(xy 232.674847 -308.705412) (xy 232.651159 -308.755943) (xy 232.620365 -308.802487) (xy 232.583123 -308.844051)
			(xy 232.540227 -308.87975) (xy 232.492589 -308.908823) (xy 232.441226 -308.93065) (xy 232.387233 -308.944766)
			(xy 232.331759 -308.950869) (xy 232.275988 -308.948831) (xy 232.221109 -308.938694) (xy 232.168289 -308.920675)
			(xy 232.118657 -308.895157) (xy 232.073269 -308.862685) (xy 232.033092 -308.82395) (xy 231.998984 -308.779778)
			(xy 231.97167 -308.73111) (xy 231.951734 -308.678984) (xy 231.939599 -308.624511) (xy 231.935526 -308.568852)
			(xy 219.133473 -308.568852) (xy 219.214112 -308.63596) (xy 219.335336 -308.747268) (xy 219.450997 -308.864346)
			(xy 219.56082 -308.986916) (xy 219.664546 -309.114688) (xy 219.761928 -309.247359) (xy 219.852735 -309.384614)
			(xy 219.936751 -309.526127) (xy 220.013778 -309.671563) (xy 220.083633 -309.820576) (xy 220.14615 -309.972814)
			(xy 220.20118 -310.127915) (xy 220.248594 -310.285512) (xy 220.288278 -310.44523) (xy 220.32014 -310.606691)
			(xy 220.344102 -310.769511) (xy 220.360108 -310.933306) (xy 220.368121 -311.097685) (xy 220.368622 -311.179972)
			(xy 220.368121 -311.262259) (xy 220.360108 -311.426638) (xy 220.344102 -311.590433) (xy 220.32014 -311.753253)
			(xy 220.288278 -311.914714) (xy 220.248594 -312.074432) (xy 220.20118 -312.232029) (xy 220.14615 -312.38713)
			(xy 220.083633 -312.539368) (xy 220.013778 -312.688381) (xy 219.936751 -312.833817) (xy 219.852735 -312.97533)
			(xy 219.761928 -313.112585) (xy 219.664546 -313.245256) (xy 219.56082 -313.373028) (xy 219.450997 -313.495598)
			(xy 219.335336 -313.612676) (xy 219.214112 -313.723984) (xy 219.087612 -313.829258) (xy 218.956137 -313.928248)
			(xy 218.819998 -314.020719) (xy 218.679519 -314.106453) (xy 218.535031 -314.185245) (xy 218.386879 -314.256909)
			(xy 218.235414 -314.321275) (xy 218.080994 -314.37819) (xy 217.923987 -314.427519) (xy 217.764764 -314.469145)
			(xy 217.603703 -314.50297) (xy 217.441186 -314.528913) (xy 217.277599 -314.546913) (xy 217.11333 -314.556927)
			(xy 216.948767 -314.55893) (xy 216.784303 -314.55292) (xy 216.620326 -314.538909) (xy 216.457226 -314.516931)
			(xy 216.295389 -314.487038) (xy 216.135199 -314.449302) (xy 215.977037 -314.40381) (xy 215.821277 -314.350673)
			(xy 215.668289 -314.290014) (xy 215.518436 -314.221979) (xy 215.372073 -314.146729) (xy 215.229548 -314.064441)
			(xy 215.091197 -313.975313) (xy 214.957351 -313.879554) (xy 214.828325 -313.777391) (xy 214.704427 -313.669068)
			(xy 214.585949 -313.554842) (xy 214.473173 -313.434982) (xy 214.366367 -313.309773) (xy 214.265783 -313.179513)
			(xy 214.171661 -313.044511) (xy 214.084223 -312.905085) (xy 214.003678 -312.761568) (xy 213.930215 -312.6143)
			(xy 213.86401 -312.463629) (xy 213.805219 -312.309914) (xy 213.753981 -312.153519) (xy 213.710419 -311.994815)
			(xy 213.674636 -311.834178) (xy 213.646716 -311.671989) (xy 213.626726 -311.508633) (xy 213.614713 -311.344498)
			(xy 213.610705 -311.179972) (xy 199.342502 -311.179972) (xy 199.342502 -318.213232) (xy 199.342756 -318.224916)
			(xy 199.342756 -320.900044) (xy 200.998589 -320.900044) (xy 201.002595 -320.704989) (xy 201.014605 -320.510263)
			(xy 201.0346 -320.316194) (xy 201.062545 -320.12311) (xy 201.098394 -319.931335) (xy 201.142086 -319.741195)
			(xy 201.193547 -319.553008) (xy 201.252691 -319.367093) (xy 201.319418 -319.183762) (xy 201.393615 -319.003326)
			(xy 201.475157 -318.826088) (xy 201.563908 -318.652347) (xy 201.659716 -318.482396) (xy 201.762421 -318.316522)
			(xy 201.871849 -318.155004) (xy 201.987816 -317.998115) (xy 202.110127 -317.84612) (xy 202.238574 -317.699274)
			(xy 202.372942 -317.557825) (xy 202.513004 -317.422012) (xy 202.658523 -317.292063) (xy 202.809255 -317.168199)
			(xy 202.964945 -317.050627) (xy 203.125331 -316.939547) (xy 203.290142 -316.835144) (xy 203.4591 -316.737596)
			(xy 203.631921 -316.647067) (xy 203.808313 -316.563709) (xy 203.987978 -316.487663) (xy 204.170613 -316.419058)
			(xy 204.355912 -316.358008) (xy 204.54356 -316.304618) (xy 204.733242 -316.258976) (xy 204.924639 -316.22116)
			(xy 205.117426 -316.191234) (xy 205.311279 -316.169248) (xy 205.505872 -316.155239) (xy 205.700875 -316.149231)
			(xy 205.895961 -316.151234) (xy 206.0908 -316.161245) (xy 206.285064 -316.179246) (xy 206.478425 -316.205208)
			(xy 206.670558 -316.239086) (xy 206.861137 -316.280823) (xy 207.049842 -316.33035) (xy 207.236355 -316.387582)
			(xy 207.420361 -316.452423) (xy 207.601549 -316.524764) (xy 207.779615 -316.604482) (xy 207.954258 -316.691444)
			(xy 208.125184 -316.785503) (xy 208.292103 -316.886499) (xy 208.454736 -316.994264) (xy 208.612807 -317.108614)
			(xy 208.76605 -317.229357) (xy 208.914207 -317.356291) (xy 209.057028 -317.489199) (xy 209.194272 -317.627859)
			(xy 209.325708 -317.772037) (xy 209.451113 -317.92149) (xy 209.570277 -318.075964) (xy 209.682998 -318.235201)
			(xy 209.789087 -318.398932) (xy 209.888365 -318.566879) (xy 209.980663 -318.738762) (xy 210.065828 -318.914288)
			(xy 210.143714 -319.093163) (xy 210.214191 -319.275085) (xy 210.277139 -319.459747) (xy 210.332454 -319.646837)
			(xy 210.38004 -319.836041) (xy 210.419819 -320.027038) (xy 210.451723 -320.219508) (xy 210.475698 -320.413126)
			(xy 210.491704 -320.607564) (xy 210.499713 -320.802496) (xy 210.500214 -320.900044) (xy 257.098807 -320.900044)
			(xy 257.102813 -320.704989) (xy 257.114823 -320.510263) (xy 257.134818 -320.316194) (xy 257.162763 -320.12311)
			(xy 257.198612 -319.931335) (xy 257.242304 -319.741195) (xy 257.293765 -319.553008) (xy 257.352909 -319.367093)
			(xy 257.419636 -319.183762) (xy 257.493833 -319.003326) (xy 257.575375 -318.826088) (xy 257.664126 -318.652347)
			(xy 257.759934 -318.482396) (xy 257.862639 -318.316522) (xy 257.972067 -318.155004) (xy 258.088034 -317.998115)
			(xy 258.210345 -317.84612) (xy 258.338792 -317.699274) (xy 258.47316 -317.557825) (xy 258.613222 -317.422012)
			(xy 258.758741 -317.292063) (xy 258.909473 -317.168199) (xy 259.065163 -317.050627) (xy 259.225549 -316.939547)
			(xy 259.39036 -316.835144) (xy 259.559318 -316.737596) (xy 259.732139 -316.647067) (xy 259.908531 -316.563709)
			(xy 260.088196 -316.487663) (xy 260.270831 -316.419058) (xy 260.45613 -316.358008) (xy 260.643778 -316.304618)
			(xy 260.83346 -316.258976) (xy 261.024857 -316.22116) (xy 261.217644 -316.191234) (xy 261.411497 -316.169248)
			(xy 261.60609 -316.155239) (xy 261.801093 -316.149231) (xy 261.996179 -316.151234) (xy 262.191018 -316.161245)
			(xy 262.385282 -316.179246) (xy 262.578643 -316.205208) (xy 262.770776 -316.239086) (xy 262.961355 -316.280823)
			(xy 263.15006 -316.33035) (xy 263.336573 -316.387582) (xy 263.520579 -316.452423) (xy 263.701767 -316.524764)
			(xy 263.879833 -316.604482) (xy 264.054476 -316.691444) (xy 264.225402 -316.785503) (xy 264.392321 -316.886499)
			(xy 264.554954 -316.994264) (xy 264.713025 -317.108614) (xy 264.866268 -317.229357) (xy 265.014425 -317.356291)
			(xy 265.157246 -317.489199) (xy 265.29449 -317.627859) (xy 265.425926 -317.772037) (xy 265.551331 -317.92149)
			(xy 265.670495 -318.075964) (xy 265.783216 -318.235201) (xy 265.889305 -318.398932) (xy 265.988583 -318.566879)
			(xy 266.080881 -318.738762) (xy 266.166046 -318.914288) (xy 266.243932 -319.093163) (xy 266.314409 -319.275085)
			(xy 266.377357 -319.459747) (xy 266.432672 -319.646837) (xy 266.480258 -319.836041) (xy 266.520037 -320.027038)
			(xy 266.551941 -320.219508) (xy 266.575916 -320.413126) (xy 266.591922 -320.607564) (xy 266.599931 -320.802496)
			(xy 266.600432 -320.900044) (xy 266.599931 -320.997592) (xy 266.591922 -321.192524) (xy 266.575916 -321.386962)
			(xy 266.551941 -321.58058) (xy 266.520037 -321.77305) (xy 266.480258 -321.964047) (xy 266.432672 -322.153251)
			(xy 266.377357 -322.340341) (xy 266.314409 -322.525003) (xy 266.243932 -322.706925) (xy 266.166046 -322.8858)
			(xy 266.080881 -323.061326) (xy 265.988583 -323.233209) (xy 265.889305 -323.401156) (xy 265.783216 -323.564887)
			(xy 265.670495 -323.724124) (xy 265.551331 -323.878598) (xy 265.425926 -324.028051) (xy 265.29449 -324.172229)
			(xy 265.157246 -324.310889) (xy 265.014425 -324.443797) (xy 264.866268 -324.570731) (xy 264.713025 -324.691474)
			(xy 264.554954 -324.805824) (xy 264.392321 -324.913589) (xy 264.225402 -325.014585) (xy 264.054476 -325.108644)
			(xy 263.879833 -325.195606) (xy 263.701767 -325.275324) (xy 263.520579 -325.347665) (xy 263.336573 -325.412506)
			(xy 263.15006 -325.469738) (xy 262.961355 -325.519265) (xy 262.770776 -325.561002) (xy 262.578643 -325.59488)
			(xy 262.385282 -325.620842) (xy 262.191018 -325.638843) (xy 261.996179 -325.648854) (xy 261.801093 -325.650857)
			(xy 261.60609 -325.644849) (xy 261.411497 -325.63084) (xy 261.217644 -325.608854) (xy 261.024857 -325.578928)
			(xy 260.83346 -325.541112) (xy 260.643778 -325.49547) (xy 260.45613 -325.44208) (xy 260.270831 -325.38103)
			(xy 260.088196 -325.312425) (xy 259.908531 -325.236379) (xy 259.732139 -325.153021) (xy 259.559318 -325.062492)
			(xy 259.39036 -324.964944) (xy 259.225549 -324.860541) (xy 259.065163 -324.749461) (xy 258.909473 -324.631889)
			(xy 258.758741 -324.508025) (xy 258.613222 -324.378076) (xy 258.47316 -324.242263) (xy 258.338792 -324.100814)
			(xy 258.210345 -323.953968) (xy 258.088034 -323.801973) (xy 257.972067 -323.645084) (xy 257.862639 -323.483566)
			(xy 257.759934 -323.317692) (xy 257.664126 -323.147741) (xy 257.575375 -322.974) (xy 257.493833 -322.796762)
			(xy 257.419636 -322.616326) (xy 257.352909 -322.432995) (xy 257.293765 -322.24708) (xy 257.242304 -322.058893)
			(xy 257.198612 -321.868753) (xy 257.162763 -321.676978) (xy 257.134818 -321.483894) (xy 257.114823 -321.289825)
			(xy 257.102813 -321.095099) (xy 257.098807 -320.900044) (xy 210.500214 -320.900044) (xy 210.499713 -320.997592)
			(xy 210.491704 -321.192524) (xy 210.475698 -321.386962) (xy 210.451723 -321.58058) (xy 210.419819 -321.77305)
			(xy 210.38004 -321.964047) (xy 210.332454 -322.153251) (xy 210.277139 -322.340341) (xy 210.214191 -322.525003)
			(xy 210.143714 -322.706925) (xy 210.065828 -322.8858) (xy 209.980663 -323.061326) (xy 209.888365 -323.233209)
			(xy 209.789087 -323.401156) (xy 209.682998 -323.564887) (xy 209.570277 -323.724124) (xy 209.451113 -323.878598)
			(xy 209.325708 -324.028051) (xy 209.194272 -324.172229) (xy 209.057028 -324.310889) (xy 208.914207 -324.443797)
			(xy 208.76605 -324.570731) (xy 208.612807 -324.691474) (xy 208.454736 -324.805824) (xy 208.292103 -324.913589)
			(xy 208.125184 -325.014585) (xy 207.954258 -325.108644) (xy 207.779615 -325.195606) (xy 207.601549 -325.275324)
			(xy 207.420361 -325.347665) (xy 207.236355 -325.412506) (xy 207.049842 -325.469738) (xy 206.861137 -325.519265)
			(xy 206.670558 -325.561002) (xy 206.478425 -325.59488) (xy 206.285064 -325.620842) (xy 206.0908 -325.638843)
			(xy 205.895961 -325.648854) (xy 205.700875 -325.650857) (xy 205.505872 -325.644849) (xy 205.311279 -325.63084)
			(xy 205.117426 -325.608854) (xy 204.924639 -325.578928) (xy 204.733242 -325.541112) (xy 204.54356 -325.49547)
			(xy 204.355912 -325.44208) (xy 204.170613 -325.38103) (xy 203.987978 -325.312425) (xy 203.808313 -325.236379)
			(xy 203.631921 -325.153021) (xy 203.4591 -325.062492) (xy 203.290142 -324.964944) (xy 203.125331 -324.860541)
			(xy 202.964945 -324.749461) (xy 202.809255 -324.631889) (xy 202.658523 -324.508025) (xy 202.513004 -324.378076)
			(xy 202.372942 -324.242263) (xy 202.238574 -324.100814) (xy 202.110127 -323.953968) (xy 201.987816 -323.801973)
			(xy 201.871849 -323.645084) (xy 201.762421 -323.483566) (xy 201.659716 -323.317692) (xy 201.563908 -323.147741)
			(xy 201.475157 -322.974) (xy 201.393615 -322.796762) (xy 201.319418 -322.616326) (xy 201.252691 -322.432995)
			(xy 201.193547 -322.24708) (xy 201.142086 -322.058893) (xy 201.098394 -321.868753) (xy 201.062545 -321.676978)
			(xy 201.0346 -321.483894) (xy 201.014605 -321.289825) (xy 201.002595 -321.095099) (xy 200.998589 -320.900044)
			(xy 199.342756 -320.900044) (xy 199.342756 -336.935064) (xy 199.34228 -336.960014) (xy 199.33446 -337.009297)
			(xy 199.319038 -337.056754) (xy 199.296392 -337.10122) (xy 199.267078 -337.141602) (xy 199.249792 -337.1596)
			(xy 199.143366 -337.266026) (xy 234.403392 -337.266026) (xy 234.403392 -336.402426) (xy 234.403882 -336.372458)
			(xy 234.411705 -336.313036) (xy 234.427218 -336.255143) (xy 234.450154 -336.19977) (xy 234.480121 -336.147864)
			(xy 234.516608 -336.100314) (xy 234.558988 -336.057934) (xy 234.606538 -336.021447) (xy 234.658444 -335.99148)
			(xy 234.713817 -335.968544) (xy 234.77171 -335.953031) (xy 234.831132 -335.945208) (xy 234.891068 -335.945208)
			(xy 234.95049 -335.953031) (xy 235.008383 -335.968544) (xy 235.063756 -335.99148) (xy 235.115662 -336.021447)
			(xy 235.163212 -336.057934) (xy 235.205592 -336.100314) (xy 235.242079 -336.147864) (xy 235.272046 -336.19977)
			(xy 235.294982 -336.255143) (xy 235.310495 -336.313036) (xy 235.318318 -336.372458) (xy 235.318808 -336.402426)
			(xy 235.318808 -337.266026) (xy 235.318318 -337.295994) (xy 235.310495 -337.355416) (xy 235.294982 -337.413309)
			(xy 235.272046 -337.468682) (xy 235.242079 -337.520588) (xy 235.205592 -337.568138) (xy 235.163212 -337.610518)
			(xy 235.115662 -337.647005) (xy 235.063756 -337.676972) (xy 235.008383 -337.699908) (xy 234.95049 -337.715421)
			(xy 234.891068 -337.723244) (xy 234.831132 -337.723244) (xy 234.77171 -337.715421) (xy 234.713817 -337.699908)
			(xy 234.658444 -337.676972) (xy 234.606538 -337.647005) (xy 234.558988 -337.610518) (xy 234.516608 -337.568138)
			(xy 234.480121 -337.520588) (xy 234.450154 -337.468682) (xy 234.427218 -337.413309) (xy 234.411705 -337.355416)
			(xy 234.403882 -337.295994) (xy 234.403392 -337.266026) (xy 199.143366 -337.266026) (xy 198.010018 -338.399374)
			(xy 197.992015 -338.416655) (xy 197.951641 -338.445982) (xy 197.907178 -338.468632) (xy 197.859719 -338.484048)
			(xy 197.810432 -338.49185) (xy 197.785482 -338.492338) (xy 36.931854 -338.492338) (xy 36.906904 -338.491856)
			(xy 36.857621 -338.484038) (xy 36.810164 -338.468618) (xy 36.765698 -338.445973) (xy 36.725316 -338.41666)
			(xy 36.707318 -338.399374) (xy 36.150042 -337.842098) (xy 36.132754 -337.824101) (xy 36.103428 -337.783726)
			(xy 36.080779 -337.739261) (xy 36.065365 -337.6918) (xy 36.057564 -337.642513) (xy 36.057078 -337.617562)
			(xy 36.057078 -299.318172) (xy 36.0553 -299.311568) (xy 36.049863 -299.290328) (xy 36.044004 -299.246876)
			(xy 36.043616 -299.224954) (xy 22.727388 -299.224954) (xy 22.824706 -299.344832) (xy 22.922088 -299.477503)
			(xy 23.012895 -299.614758) (xy 23.096911 -299.756271) (xy 23.173938 -299.901707) (xy 23.243793 -300.05072)
			(xy 23.30631 -300.202958) (xy 23.36134 -300.358059) (xy 23.408754 -300.515656) (xy 23.448438 -300.675374)
			(xy 23.4803 -300.836835) (xy 23.504262 -300.999655) (xy 23.520268 -301.16345) (xy 23.528281 -301.327829)
			(xy 23.528782 -301.410116) (xy 23.528281 -301.492403) (xy 23.520268 -301.656782) (xy 23.504262 -301.820577)
			(xy 23.4803 -301.983397) (xy 23.448438 -302.144858) (xy 23.408754 -302.304576) (xy 23.36134 -302.462173)
			(xy 23.30631 -302.617274) (xy 23.243793 -302.769512) (xy 23.173938 -302.918525) (xy 23.096911 -303.063961)
			(xy 23.012895 -303.205474) (xy 22.922088 -303.342729) (xy 22.824706 -303.4754) (xy 22.72098 -303.603172)
			(xy 22.611157 -303.725742) (xy 22.495496 -303.84282) (xy 22.374272 -303.954128) (xy 22.247772 -304.059402)
			(xy 22.116297 -304.158392) (xy 21.980158 -304.250863) (xy 21.839679 -304.336597) (xy 21.695191 -304.415389)
			(xy 21.547039 -304.487053) (xy 21.395574 -304.551419) (xy 21.241154 -304.608334) (xy 21.084147 -304.657663)
			(xy 20.924924 -304.699289) (xy 20.763863 -304.733114) (xy 20.601346 -304.759057) (xy 20.437759 -304.777057)
			(xy 20.27349 -304.787071) (xy 20.108927 -304.789074) (xy 19.944463 -304.783064) (xy 19.780486 -304.769053)
			(xy 19.617386 -304.747075) (xy 19.455549 -304.717182) (xy 19.295359 -304.679446) (xy 19.137197 -304.633954)
			(xy 18.981437 -304.580817) (xy 18.828449 -304.520158) (xy 18.678596 -304.452123) (xy 18.532233 -304.376873)
			(xy 18.389708 -304.294585) (xy 18.251357 -304.205457) (xy 18.117511 -304.109698) (xy 17.988485 -304.007535)
			(xy 17.864587 -303.899212) (xy 17.746109 -303.784986) (xy 17.633333 -303.665126) (xy 17.526527 -303.539917)
			(xy 17.425943 -303.409657) (xy 17.331821 -303.274655) (xy 17.244383 -303.135229) (xy 17.163838 -302.991712)
			(xy 17.090375 -302.844444) (xy 17.02417 -302.693773) (xy 16.965379 -302.540058) (xy 16.914141 -302.383663)
			(xy 16.870579 -302.224959) (xy 16.834796 -302.064322) (xy 16.806876 -301.902133) (xy 16.786886 -301.738777)
			(xy 16.774873 -301.574642) (xy 16.770865 -301.410116) (xy 1.524 -301.410116) (xy 1.524 -305.19751)
			(xy 17.638266 -305.19751) (xy 17.642339 -305.141851) (xy 17.654474 -305.087378) (xy 17.67441 -305.035252)
			(xy 17.701724 -304.986584) (xy 17.735832 -304.942412) (xy 17.776009 -304.903677) (xy 17.821397 -304.871205)
			(xy 17.871029 -304.845687) (xy 17.923849 -304.827668) (xy 17.978728 -304.817531) (xy 18.034499 -304.815493)
			(xy 18.089973 -304.821596) (xy 18.143966 -304.835712) (xy 18.195329 -304.857539) (xy 18.242967 -304.886612)
			(xy 18.285863 -304.922311) (xy 18.323105 -304.963875) (xy 18.353899 -305.010419) (xy 18.377587 -305.06095)
			(xy 18.393665 -305.114392) (xy 18.401791 -305.169606) (xy 18.4023 -305.19751) (xy 18.401791 -305.225414)
			(xy 18.393665 -305.280628) (xy 18.377587 -305.33407) (xy 18.353899 -305.384601) (xy 18.323105 -305.431145)
			(xy 18.285863 -305.472709) (xy 18.242967 -305.508408) (xy 18.195329 -305.537481) (xy 18.143966 -305.559308)
			(xy 18.089973 -305.573424) (xy 18.034499 -305.579527) (xy 17.978728 -305.577489) (xy 17.923849 -305.567352)
			(xy 17.871029 -305.549333) (xy 17.821397 -305.523815) (xy 17.776009 -305.491343) (xy 17.735832 -305.452608)
			(xy 17.701724 -305.408436) (xy 17.67441 -305.359768) (xy 17.654474 -305.307642) (xy 17.642339 -305.253169)
			(xy 17.638266 -305.19751) (xy 1.524 -305.19751) (xy 1.524 -306.28209) (xy 17.638266 -306.28209) (xy 17.642339 -306.226431)
			(xy 17.654474 -306.171958) (xy 17.67441 -306.119832) (xy 17.701724 -306.071164) (xy 17.735832 -306.026992)
			(xy 17.776009 -305.988257) (xy 17.821397 -305.955785) (xy 17.871029 -305.930267) (xy 17.923849 -305.912248)
			(xy 17.978728 -305.902111) (xy 18.034499 -305.900073) (xy 18.089973 -305.906176) (xy 18.143966 -305.920292)
			(xy 18.195329 -305.942119) (xy 18.242967 -305.971192) (xy 18.285863 -306.006891) (xy 18.323105 -306.048455)
			(xy 18.353899 -306.094999) (xy 18.377587 -306.14553) (xy 18.393665 -306.198972) (xy 18.401791 -306.254186)
			(xy 18.4023 -306.28209) (xy 18.401791 -306.309994) (xy 18.393665 -306.365208) (xy 18.377587 -306.41865)
			(xy 18.353899 -306.469181) (xy 18.323105 -306.515725) (xy 18.285863 -306.557289) (xy 18.242967 -306.592988)
			(xy 18.195329 -306.622061) (xy 18.143966 -306.643888) (xy 18.089973 -306.658004) (xy 18.034499 -306.664107)
			(xy 17.978728 -306.662069) (xy 17.923849 -306.651932) (xy 17.871029 -306.633913) (xy 17.821397 -306.608395)
			(xy 17.776009 -306.575923) (xy 17.735832 -306.537188) (xy 17.701724 -306.493016) (xy 17.67441 -306.444348)
			(xy 17.654474 -306.392222) (xy 17.642339 -306.337749) (xy 17.638266 -306.28209) (xy 1.524 -306.28209)
			(xy 1.524 -308.477666) (xy 1.524327 -308.486785) (xy 1.530648 -308.503889) (xy 1.542597 -308.517662)
			(xy 1.550416 -308.52237) (xy 1.64084 -308.571646) (xy 1.66878 -308.57063) (xy 1.68021 -308.563264)
			(xy 1.74792 -308.520543) (xy 1.886767 -308.440797) (xy 2.029236 -308.367717) (xy 2.175007 -308.301468)
			(xy 2.323752 -308.242198) (xy 2.475137 -308.19004) (xy 2.628824 -308.145112) (xy 2.784466 -308.107515)
			(xy 2.941714 -308.077332) (xy 3.100215 -308.054632) (xy 3.259614 -308.039465) (xy 3.419553 -308.031866)
			(xy 3.499612 -308.031388) (xy 3.50012 -308.031388) (xy 3.581774 -308.031881) (xy 3.744892 -308.039771)
			(xy 3.907438 -308.055533) (xy 4.069032 -308.079129) (xy 4.229298 -308.110505) (xy 4.387861 -308.149587)
			(xy 4.544351 -308.196284) (xy 4.698401 -308.250488) (xy 4.849653 -308.31207) (xy 4.997754 -308.380889)
			(xy 5.142356 -308.456782) (xy 5.283123 -308.539573) (xy 5.419725 -308.629068) (xy 5.551844 -308.725058)
			(xy 5.679172 -308.827319) (xy 5.80141 -308.935613) (xy 5.918273 -309.049685) (xy 6.029489 -309.169271)
			(xy 6.134797 -309.29409) (xy 6.233951 -309.423851) (xy 6.326721 -309.558251) (xy 6.412889 -309.696977)
			(xy 6.492254 -309.839703) (xy 6.564631 -309.986097) (xy 6.629851 -310.135817) (xy 6.687761 -310.288512)
			(xy 6.738226 -310.443828) (xy 6.781128 -310.6014) (xy 6.816367 -310.760861) (xy 6.843862 -310.921838)
			(xy 6.863546 -311.083956) (xy 6.875375 -311.246835) (xy 6.879322 -311.410096) (xy 6.875375 -311.573357)
			(xy 6.863546 -311.736236) (xy 6.843862 -311.898354) (xy 6.816367 -312.059331) (xy 6.781128 -312.218792)
			(xy 6.738226 -312.376364) (xy 6.687761 -312.53168) (xy 6.629851 -312.684375) (xy 6.564631 -312.834095)
			(xy 6.492254 -312.980489) (xy 6.412889 -313.123215) (xy 6.326721 -313.261941) (xy 6.233951 -313.396341)
			(xy 6.134797 -313.526102) (xy 6.029489 -313.650921) (xy 5.918273 -313.770507) (xy 5.80141 -313.884579)
			(xy 5.679172 -313.992873) (xy 5.551844 -314.095134) (xy 5.419725 -314.191124) (xy 5.283123 -314.280619)
			(xy 5.142356 -314.36341) (xy 4.997754 -314.439303) (xy 4.849653 -314.508122) (xy 4.698401 -314.569704)
			(xy 4.544351 -314.623908) (xy 4.387861 -314.670605) (xy 4.229298 -314.709687) (xy 4.069032 -314.741063)
			(xy 3.907438 -314.764659) (xy 3.744892 -314.780421) (xy 3.581774 -314.788311) (xy 3.50012 -314.788804)
			(xy 3.499612 -314.788804) (xy 3.419553 -314.788328) (xy 3.259614 -314.780732) (xy 3.100214 -314.765567)
			(xy 2.941712 -314.742868) (xy 2.784464 -314.712686) (xy 2.628821 -314.675089) (xy 2.475135 -314.630161)
			(xy 2.323749 -314.578002) (xy 2.175004 -314.518731) (xy 2.029234 -314.45248) (xy 1.886766 -314.379398)
			(xy 1.747921 -314.299648) (xy 1.68021 -314.256928) (xy 1.66878 -314.249562) (xy 1.64084 -314.248546)
			(xy 1.550416 -314.297822) (xy 1.542626 -314.302548) (xy 1.53075 -314.31635) (xy 1.524421 -314.333422)
			(xy 1.524 -314.342526) (xy 1.524 -320.900044) (xy 24.898611 -320.900044) (xy 24.902617 -320.704989)
			(xy 24.914627 -320.510263) (xy 24.934622 -320.316194) (xy 24.962567 -320.12311) (xy 24.998416 -319.931335)
			(xy 25.042108 -319.741195) (xy 25.093569 -319.553008) (xy 25.152713 -319.367093) (xy 25.21944 -319.183762)
			(xy 25.293637 -319.003326) (xy 25.375179 -318.826088) (xy 25.46393 -318.652347) (xy 25.559738 -318.482396)
			(xy 25.662443 -318.316522) (xy 25.771871 -318.155004) (xy 25.887838 -317.998115) (xy 26.010149 -317.84612)
			(xy 26.138596 -317.699274) (xy 26.272964 -317.557825) (xy 26.413026 -317.422012) (xy 26.558545 -317.292063)
			(xy 26.709277 -317.168199) (xy 26.864967 -317.050627) (xy 27.025353 -316.939547) (xy 27.190164 -316.835144)
			(xy 27.359122 -316.737596) (xy 27.531943 -316.647067) (xy 27.708335 -316.563709) (xy 27.888 -316.487663)
			(xy 28.070635 -316.419058) (xy 28.255934 -316.358008) (xy 28.443582 -316.304618) (xy 28.633264 -316.258976)
			(xy 28.824661 -316.22116) (xy 29.017448 -316.191234) (xy 29.211301 -316.169248) (xy 29.405894 -316.155239)
			(xy 29.600897 -316.149231) (xy 29.795983 -316.151234) (xy 29.990822 -316.161245) (xy 30.185086 -316.179246)
			(xy 30.378447 -316.205208) (xy 30.57058 -316.239086) (xy 30.761159 -316.280823) (xy 30.949864 -316.33035)
			(xy 31.136377 -316.387582) (xy 31.320383 -316.452423) (xy 31.501571 -316.524764) (xy 31.679637 -316.604482)
			(xy 31.85428 -316.691444) (xy 32.025206 -316.785503) (xy 32.192125 -316.886499) (xy 32.354758 -316.994264)
			(xy 32.512829 -317.108614) (xy 32.666072 -317.229357) (xy 32.814229 -317.356291) (xy 32.95705 -317.489199)
			(xy 33.094294 -317.627859) (xy 33.22573 -317.772037) (xy 33.351135 -317.92149) (xy 33.470299 -318.075964)
			(xy 33.58302 -318.235201) (xy 33.689109 -318.398932) (xy 33.788387 -318.566879) (xy 33.880685 -318.738762)
			(xy 33.96585 -318.914288) (xy 34.043736 -319.093163) (xy 34.114213 -319.275085) (xy 34.177161 -319.459747)
			(xy 34.232476 -319.646837) (xy 34.280062 -319.836041) (xy 34.319841 -320.027038) (xy 34.351745 -320.219508)
			(xy 34.37572 -320.413126) (xy 34.391726 -320.607564) (xy 34.399735 -320.802496) (xy 34.400236 -320.900044)
			(xy 34.399735 -320.997592) (xy 34.391726 -321.192524) (xy 34.37572 -321.386962) (xy 34.351745 -321.58058)
			(xy 34.319841 -321.77305) (xy 34.280062 -321.964047) (xy 34.232476 -322.153251) (xy 34.177161 -322.340341)
			(xy 34.114213 -322.525003) (xy 34.043736 -322.706925) (xy 33.96585 -322.8858) (xy 33.880685 -323.061326)
			(xy 33.788387 -323.233209) (xy 33.689109 -323.401156) (xy 33.58302 -323.564887) (xy 33.470299 -323.724124)
			(xy 33.351135 -323.878598) (xy 33.22573 -324.028051) (xy 33.094294 -324.172229) (xy 32.95705 -324.310889)
			(xy 32.814229 -324.443797) (xy 32.666072 -324.570731) (xy 32.512829 -324.691474) (xy 32.354758 -324.805824)
			(xy 32.192125 -324.913589) (xy 32.025206 -325.014585) (xy 31.85428 -325.108644) (xy 31.679637 -325.195606)
			(xy 31.501571 -325.275324) (xy 31.320383 -325.347665) (xy 31.136377 -325.412506) (xy 30.949864 -325.469738)
			(xy 30.761159 -325.519265) (xy 30.57058 -325.561002) (xy 30.378447 -325.59488) (xy 30.185086 -325.620842)
			(xy 29.990822 -325.638843) (xy 29.795983 -325.648854) (xy 29.600897 -325.650857) (xy 29.405894 -325.644849)
			(xy 29.211301 -325.63084) (xy 29.017448 -325.608854) (xy 28.824661 -325.578928) (xy 28.633264 -325.541112)
			(xy 28.443582 -325.49547) (xy 28.255934 -325.44208) (xy 28.070635 -325.38103) (xy 27.888 -325.312425)
			(xy 27.708335 -325.236379) (xy 27.531943 -325.153021) (xy 27.359122 -325.062492) (xy 27.190164 -324.964944)
			(xy 27.025353 -324.860541) (xy 26.864967 -324.749461) (xy 26.709277 -324.631889) (xy 26.558545 -324.508025)
			(xy 26.413026 -324.378076) (xy 26.272964 -324.242263) (xy 26.138596 -324.100814) (xy 26.010149 -323.953968)
			(xy 25.887838 -323.801973) (xy 25.771871 -323.645084) (xy 25.662443 -323.483566) (xy 25.559738 -323.317692)
			(xy 25.46393 -323.147741) (xy 25.375179 -322.974) (xy 25.293637 -322.796762) (xy 25.21944 -322.616326)
			(xy 25.152713 -322.432995) (xy 25.093569 -322.24708) (xy 25.042108 -322.058893) (xy 24.998416 -321.868753)
			(xy 24.962567 -321.676978) (xy 24.934622 -321.483894) (xy 24.914627 -321.289825) (xy 24.902617 -321.095099)
			(xy 24.898611 -320.900044) (xy 1.524 -320.900044) (xy 1.524 -342.466769) (xy 18.951172 -342.466769)
			(xy 18.951172 -342.412231) (xy 18.958934 -342.358247) (xy 18.974299 -342.305917) (xy 18.996956 -342.256307)
			(xy 19.026441 -342.210426) (xy 19.062157 -342.169208) (xy 19.103374 -342.133493) (xy 19.149255 -342.104007)
			(xy 19.198865 -342.08135) (xy 19.251195 -342.065985) (xy 19.305179 -342.058223) (xy 19.332448 -342.057736)
			(xy 20.196048 -342.057736) (xy 20.223319 -342.058203) (xy 20.277306 -342.065965) (xy 20.329638 -342.081331)
			(xy 20.379252 -342.103989) (xy 20.425135 -342.133476) (xy 20.466355 -342.169193) (xy 20.502073 -342.210413)
			(xy 20.53156 -342.256297) (xy 20.554218 -342.30591) (xy 20.569584 -342.358242) (xy 20.577347 -342.412229)
			(xy 20.577347 -342.466771) (xy 20.577347 -342.466772) (xy 22.0601 -342.466772) (xy 22.0601 -342.412228)
			(xy 22.067862 -342.358241) (xy 22.083229 -342.305907) (xy 22.105887 -342.256293) (xy 22.135375 -342.210409)
			(xy 22.171094 -342.169188) (xy 22.212315 -342.133471) (xy 22.2582 -342.103983) (xy 22.307815 -342.081326)
			(xy 22.360148 -342.06596) (xy 22.414136 -342.058199) (xy 22.441408 -342.057736) (xy 23.305008 -342.057736)
			(xy 23.332277 -342.058227) (xy 23.386259 -342.06599) (xy 23.438588 -342.081355) (xy 23.488197 -342.104012)
			(xy 23.534076 -342.133498) (xy 23.575293 -342.169213) (xy 23.611007 -342.21043) (xy 23.640492 -342.256311)
			(xy 23.663147 -342.30592) (xy 23.678512 -342.358249) (xy 23.686274 -342.412231) (xy 23.686274 -342.466768)
			(xy 25.169122 -342.466768) (xy 25.169122 -342.412232) (xy 25.176883 -342.358251) (xy 25.192247 -342.305924)
			(xy 25.214901 -342.256315) (xy 25.244384 -342.210436) (xy 25.280096 -342.169219) (xy 25.32131 -342.133503)
			(xy 25.367187 -342.104016) (xy 25.416794 -342.081358) (xy 25.46912 -342.06599) (xy 25.5231 -342.058225)
			(xy 25.550368 -342.057736) (xy 26.413968 -342.057736) (xy 26.44124 -342.058201) (xy 26.49523 -342.06596)
			(xy 26.547567 -342.081323) (xy 26.597184 -342.103979) (xy 26.643071 -342.133465) (xy 26.684295 -342.169183)
			(xy 26.720015 -342.210403) (xy 26.749506 -342.256288) (xy 26.772166 -342.305903) (xy 26.787533 -342.358238)
			(xy 26.795296 -342.412228) (xy 26.795296 -342.466772) (xy 28.278 -342.466772) (xy 28.278 -342.412228)
			(xy 28.285762 -342.358238) (xy 28.30113 -342.305903) (xy 28.32379 -342.256288) (xy 28.35328 -342.210402)
			(xy 28.389001 -342.169181) (xy 28.430225 -342.133464) (xy 28.476112 -342.103977) (xy 28.525729 -342.08132)
			(xy 28.578065 -342.065957) (xy 28.632056 -342.058198) (xy 28.659328 -342.057736) (xy 29.522928 -342.057736)
			(xy 29.550196 -342.058228) (xy 29.604176 -342.065993) (xy 29.656502 -342.081361) (xy 29.706109 -342.104019)
			(xy 29.751986 -342.133505) (xy 29.7932 -342.16922) (xy 29.828912 -342.210437) (xy 29.858395 -342.256316)
			(xy 29.881049 -342.305924) (xy 29.896413 -342.358251) (xy 29.904174 -342.412232) (xy 29.904174 -342.466768)
			(xy 29.904174 -342.466769) (xy 31.387022 -342.466769) (xy 31.387022 -342.412231) (xy 31.394784 -342.358248)
			(xy 31.410149 -342.305919) (xy 31.432804 -342.25631) (xy 31.462289 -342.210429) (xy 31.498003 -342.169212)
			(xy 31.53922 -342.133496) (xy 31.585099 -342.10401) (xy 31.634708 -342.081353) (xy 31.687036 -342.065986)
			(xy 31.741019 -342.058223) (xy 31.768288 -342.057736) (xy 32.631888 -342.057736) (xy 32.659159 -342.058203)
			(xy 32.713147 -342.065963) (xy 32.765481 -342.081329) (xy 32.815096 -342.103985) (xy 32.86098 -342.133472)
			(xy 32.902202 -342.16919) (xy 32.93792 -342.21041) (xy 32.967409 -342.256294) (xy 32.990067 -342.305908)
			(xy 33.005434 -342.358241) (xy 33.013196 -342.412229) (xy 33.013196 -342.466771) (xy 33.013196 -342.466773)
			(xy 34.4959 -342.466773) (xy 34.4959 -342.412227) (xy 34.503663 -342.358235) (xy 34.519032 -342.305899)
			(xy 34.541693 -342.256282) (xy 34.571185 -342.210396) (xy 34.606908 -342.169174) (xy 34.648134 -342.133456)
			(xy 34.694024 -342.10397) (xy 34.743644 -342.081315) (xy 34.795982 -342.065953) (xy 34.849975 -342.058196)
			(xy 34.877248 -342.057736) (xy 35.740848 -342.057736) (xy 35.768115 -342.05823) (xy 35.822093 -342.065997)
			(xy 35.874417 -342.081366) (xy 35.92402 -342.104025) (xy 35.969895 -342.133512) (xy 36.011107 -342.169227)
			(xy 36.046817 -342.210443) (xy 36.076298 -342.256322) (xy 36.098951 -342.305928) (xy 36.114313 -342.358254)
			(xy 36.122074 -342.412233) (xy 36.122074 -342.466767) (xy 36.122073 -342.466772) (xy 37.6049 -342.466772)
			(xy 37.6049 -342.412228) (xy 37.612662 -342.358241) (xy 37.628029 -342.305907) (xy 37.650687 -342.256293)
			(xy 37.680175 -342.210409) (xy 37.715894 -342.169188) (xy 37.757115 -342.133471) (xy 37.803 -342.103983)
			(xy 37.852615 -342.081326) (xy 37.904948 -342.06596) (xy 37.958936 -342.058199) (xy 37.986208 -342.057736)
			(xy 38.849808 -342.057736) (xy 38.877077 -342.058227) (xy 38.931059 -342.06599) (xy 38.983388 -342.081355)
			(xy 39.032997 -342.104012) (xy 39.078876 -342.133498) (xy 39.120093 -342.169213) (xy 39.155807 -342.21043)
			(xy 39.185292 -342.256311) (xy 39.207947 -342.30592) (xy 39.223312 -342.358249) (xy 39.231074 -342.412231)
			(xy 39.231074 -342.466768) (xy 40.713922 -342.466768) (xy 40.713922 -342.412232) (xy 40.721683 -342.358251)
			(xy 40.737047 -342.305924) (xy 40.759701 -342.256315) (xy 40.789184 -342.210436) (xy 40.824896 -342.169219)
			(xy 40.86611 -342.133503) (xy 40.911987 -342.104016) (xy 40.961594 -342.081358) (xy 41.01392 -342.06599)
			(xy 41.0679 -342.058225) (xy 41.095168 -342.057736) (xy 41.958768 -342.057736) (xy 41.98604 -342.058201)
			(xy 42.04003 -342.06596) (xy 42.092367 -342.081323) (xy 42.141984 -342.103979) (xy 42.187871 -342.133465)
			(xy 42.229095 -342.169183) (xy 42.264815 -342.210403) (xy 42.294306 -342.256288) (xy 42.316966 -342.305903)
			(xy 42.332333 -342.358238) (xy 42.340096 -342.412228) (xy 42.340096 -342.466772) (xy 43.8228 -342.466772)
			(xy 43.8228 -342.412228) (xy 43.830562 -342.358238) (xy 43.84593 -342.305903) (xy 43.86859 -342.256288)
			(xy 43.89808 -342.210402) (xy 43.933801 -342.169181) (xy 43.975025 -342.133464) (xy 44.020912 -342.103977)
			(xy 44.070529 -342.08132) (xy 44.122865 -342.065957) (xy 44.176856 -342.058198) (xy 44.204128 -342.057736)
			(xy 45.067728 -342.057736) (xy 45.094996 -342.058228) (xy 45.148976 -342.065993) (xy 45.201302 -342.081361)
			(xy 45.250909 -342.104019) (xy 45.296786 -342.133505) (xy 45.338 -342.16922) (xy 45.373712 -342.210437)
			(xy 45.403195 -342.256316) (xy 45.425849 -342.305924) (xy 45.441213 -342.358251) (xy 45.448974 -342.412232)
			(xy 45.448974 -342.466768) (xy 45.448974 -342.466769) (xy 46.931822 -342.466769) (xy 46.931822 -342.412231)
			(xy 46.939584 -342.358248) (xy 46.954949 -342.305919) (xy 46.977604 -342.25631) (xy 47.007089 -342.210429)
			(xy 47.042803 -342.169212) (xy 47.08402 -342.133496) (xy 47.129899 -342.10401) (xy 47.179508 -342.081353)
			(xy 47.231836 -342.065986) (xy 47.285819 -342.058223) (xy 47.313088 -342.057736) (xy 48.176688 -342.057736)
			(xy 48.203959 -342.058203) (xy 48.257947 -342.065963) (xy 48.310281 -342.081329) (xy 48.359896 -342.103985)
			(xy 48.40578 -342.133472) (xy 48.447002 -342.16919) (xy 48.48272 -342.21041) (xy 48.512209 -342.256294)
			(xy 48.534867 -342.305908) (xy 48.550234 -342.358241) (xy 48.557996 -342.412229) (xy 48.557996 -342.466771)
			(xy 48.557996 -342.466773) (xy 50.0407 -342.466773) (xy 50.0407 -342.412227) (xy 50.048463 -342.358235)
			(xy 50.063832 -342.305899) (xy 50.086493 -342.256282) (xy 50.115985 -342.210396) (xy 50.151708 -342.169174)
			(xy 50.192934 -342.133456) (xy 50.238824 -342.10397) (xy 50.288444 -342.081315) (xy 50.340782 -342.065953)
			(xy 50.394775 -342.058196) (xy 50.422048 -342.057736) (xy 51.285648 -342.057736) (xy 51.312915 -342.05823)
			(xy 51.366893 -342.065997) (xy 51.419217 -342.081366) (xy 51.46882 -342.104025) (xy 51.514695 -342.133512)
			(xy 51.555907 -342.169227) (xy 51.591617 -342.210443) (xy 51.621098 -342.256322) (xy 51.643751 -342.305928)
			(xy 51.659113 -342.358254) (xy 51.666874 -342.412233) (xy 51.666874 -342.466767) (xy 51.666873 -342.466773)
			(xy 60.9909 -342.466773) (xy 60.9909 -342.412227) (xy 60.998663 -342.358236) (xy 61.014031 -342.3059)
			(xy 61.036692 -342.256284) (xy 61.066184 -342.210398) (xy 61.101906 -342.169176) (xy 61.143131 -342.133459)
			(xy 61.18902 -342.103972) (xy 61.238639 -342.081317) (xy 61.290977 -342.065954) (xy 61.344969 -342.058197)
			(xy 61.372242 -342.057736) (xy 62.235842 -342.057736) (xy 62.263109 -342.058229) (xy 62.317088 -342.065996)
			(xy 62.369412 -342.081365) (xy 62.419017 -342.104023) (xy 62.464892 -342.13351) (xy 62.506105 -342.169225)
			(xy 62.541815 -342.210441) (xy 62.571297 -342.25632) (xy 62.59395 -342.305927) (xy 62.609313 -342.358253)
			(xy 62.617074 -342.412233) (xy 62.617074 -342.466767) (xy 62.617073 -342.466771) (xy 64.099899 -342.466771)
			(xy 64.099899 -342.412229) (xy 64.107662 -342.358241) (xy 64.123028 -342.305908) (xy 64.145686 -342.256295)
			(xy 64.175174 -342.210411) (xy 64.210892 -342.16919) (xy 64.252112 -342.133473) (xy 64.297997 -342.103985)
			(xy 64.34761 -342.081327) (xy 64.399943 -342.065961) (xy 64.453931 -342.058199) (xy 64.481202 -342.057736)
			(xy 65.344802 -342.057736) (xy 65.372071 -342.058227) (xy 65.426054 -342.065988) (xy 65.478383 -342.081354)
			(xy 65.527993 -342.10401) (xy 65.573873 -342.133496) (xy 65.615091 -342.169211) (xy 65.650805 -342.210428)
			(xy 65.680291 -342.256309) (xy 65.702947 -342.305919) (xy 65.718312 -342.358248) (xy 65.726074 -342.412231)
			(xy 65.726074 -342.466768) (xy 67.208922 -342.466768) (xy 67.208922 -342.412232) (xy 67.216683 -342.358252)
			(xy 67.232047 -342.305925) (xy 67.2547 -342.256317) (xy 67.284183 -342.210438) (xy 67.319894 -342.169221)
			(xy 67.361107 -342.133505) (xy 67.406984 -342.104018) (xy 67.456589 -342.08136) (xy 67.508914 -342.065991)
			(xy 67.562894 -342.058225) (xy 67.590162 -342.057736) (xy 68.453762 -342.057736) (xy 68.481035 -342.058201)
			(xy 68.535025 -342.065959) (xy 68.587362 -342.081321) (xy 68.63698 -342.103977) (xy 68.682868 -342.133463)
			(xy 68.724093 -342.16918) (xy 68.759814 -342.210401) (xy 68.789305 -342.256287) (xy 68.811965 -342.305902)
			(xy 68.827333 -342.358237) (xy 68.835096 -342.412227) (xy 68.835096 -342.466772) (xy 70.3178 -342.466772)
			(xy 70.3178 -342.412228) (xy 70.325562 -342.358239) (xy 70.34093 -342.305904) (xy 70.363589 -342.256289)
			(xy 70.393079 -342.210404) (xy 70.428799 -342.169183) (xy 70.470022 -342.133466) (xy 70.515909 -342.103979)
			(xy 70.565525 -342.081322) (xy 70.61786 -342.065958) (xy 70.67185 -342.058198) (xy 70.699122 -342.057736)
			(xy 71.562722 -342.057736) (xy 71.58999 -342.058228) (xy 71.643971 -342.065992) (xy 71.696298 -342.081359)
			(xy 71.745905 -342.104017) (xy 71.791783 -342.133503) (xy 71.832998 -342.169218) (xy 71.86871 -342.210435)
			(xy 71.898194 -342.256314) (xy 71.920848 -342.305923) (xy 71.936213 -342.35825) (xy 71.943974 -342.412232)
			(xy 71.943974 -342.466768) (xy 71.943974 -342.466769) (xy 73.426822 -342.466769) (xy 73.426822 -342.412231)
			(xy 73.434584 -342.358249) (xy 73.449948 -342.305921) (xy 73.472603 -342.256311) (xy 73.502087 -342.210431)
			(xy 73.537801 -342.169214) (xy 73.579017 -342.133498) (xy 73.624896 -342.104012) (xy 73.674504 -342.081354)
			(xy 73.726831 -342.065987) (xy 73.780813 -342.058224) (xy 73.808082 -342.057736) (xy 74.671682 -342.057736)
			(xy 74.698954 -342.058202) (xy 74.752942 -342.065962) (xy 74.805277 -342.081327) (xy 74.854892 -342.103983)
			(xy 74.900778 -342.13347) (xy 74.942 -342.169188) (xy 74.977719 -342.210408) (xy 75.007208 -342.256292)
			(xy 75.029867 -342.305906) (xy 75.045234 -342.35824) (xy 75.052996 -342.412228) (xy 75.052996 -342.466772)
			(xy 75.052996 -342.466773) (xy 76.5357 -342.466773) (xy 76.5357 -342.412227) (xy 76.543463 -342.358236)
			(xy 76.558831 -342.3059) (xy 76.581492 -342.256284) (xy 76.610984 -342.210398) (xy 76.646706 -342.169176)
			(xy 76.687931 -342.133459) (xy 76.73382 -342.103972) (xy 76.783439 -342.081317) (xy 76.835777 -342.065954)
			(xy 76.889769 -342.058197) (xy 76.917042 -342.057736) (xy 77.780642 -342.057736) (xy 77.807909 -342.058229)
			(xy 77.861888 -342.065996) (xy 77.914212 -342.081365) (xy 77.963817 -342.104023) (xy 78.009692 -342.13351)
			(xy 78.050905 -342.169225) (xy 78.086615 -342.210441) (xy 78.116097 -342.25632) (xy 78.13875 -342.305927)
			(xy 78.154113 -342.358253) (xy 78.161874 -342.412233) (xy 78.161874 -342.466767) (xy 78.161873 -342.466771)
			(xy 79.644699 -342.466771) (xy 79.644699 -342.412229) (xy 79.652462 -342.358241) (xy 79.667828 -342.305908)
			(xy 79.690486 -342.256295) (xy 79.719974 -342.210411) (xy 79.755692 -342.16919) (xy 79.796912 -342.133473)
			(xy 79.842797 -342.103985) (xy 79.89241 -342.081327) (xy 79.944743 -342.065961) (xy 79.998731 -342.058199)
			(xy 80.026002 -342.057736) (xy 80.889602 -342.057736) (xy 80.916871 -342.058227) (xy 80.970854 -342.065988)
			(xy 81.023183 -342.081354) (xy 81.072793 -342.10401) (xy 81.118673 -342.133496) (xy 81.159891 -342.169211)
			(xy 81.195605 -342.210428) (xy 81.225091 -342.256309) (xy 81.247747 -342.305919) (xy 81.263112 -342.358248)
			(xy 81.270874 -342.412231) (xy 81.270874 -342.466768) (xy 82.753722 -342.466768) (xy 82.753722 -342.412232)
			(xy 82.761483 -342.358252) (xy 82.776847 -342.305925) (xy 82.7995 -342.256317) (xy 82.828983 -342.210438)
			(xy 82.864694 -342.169221) (xy 82.905907 -342.133505) (xy 82.951784 -342.104018) (xy 83.001389 -342.08136)
			(xy 83.053714 -342.065991) (xy 83.107694 -342.058225) (xy 83.134962 -342.057736) (xy 83.998562 -342.057736)
			(xy 84.025835 -342.058201) (xy 84.079825 -342.065959) (xy 84.132162 -342.081321) (xy 84.18178 -342.103977)
			(xy 84.227668 -342.133463) (xy 84.268893 -342.16918) (xy 84.304614 -342.210401) (xy 84.334105 -342.256287)
			(xy 84.356765 -342.305902) (xy 84.372133 -342.358237) (xy 84.379896 -342.412227) (xy 84.379896 -342.466772)
			(xy 85.8626 -342.466772) (xy 85.8626 -342.412228) (xy 85.870362 -342.358239) (xy 85.88573 -342.305904)
			(xy 85.908389 -342.256289) (xy 85.937879 -342.210404) (xy 85.973599 -342.169183) (xy 86.014822 -342.133466)
			(xy 86.060709 -342.103979) (xy 86.110325 -342.081322) (xy 86.16266 -342.065958) (xy 86.21665 -342.058198)
			(xy 86.243922 -342.057736) (xy 87.107522 -342.057736) (xy 87.13479 -342.058228) (xy 87.188771 -342.065992)
			(xy 87.241098 -342.081359) (xy 87.290705 -342.104017) (xy 87.336583 -342.133503) (xy 87.377798 -342.169218)
			(xy 87.41351 -342.210435) (xy 87.442994 -342.256314) (xy 87.465648 -342.305923) (xy 87.481013 -342.35825)
			(xy 87.488774 -342.412232) (xy 87.488774 -342.466768) (xy 87.488774 -342.466769) (xy 88.971622 -342.466769)
			(xy 88.971622 -342.412231) (xy 88.979384 -342.358249) (xy 88.994748 -342.305921) (xy 89.017403 -342.256311)
			(xy 89.046887 -342.210431) (xy 89.082601 -342.169214) (xy 89.123817 -342.133498) (xy 89.169696 -342.104012)
			(xy 89.219304 -342.081354) (xy 89.271631 -342.065987) (xy 89.325613 -342.058224) (xy 89.352882 -342.057736)
			(xy 90.216482 -342.057736) (xy 90.243754 -342.058202) (xy 90.297742 -342.065962) (xy 90.350077 -342.081327)
			(xy 90.399692 -342.103983) (xy 90.445578 -342.13347) (xy 90.4868 -342.169188) (xy 90.522519 -342.210408)
			(xy 90.552008 -342.256292) (xy 90.574667 -342.305906) (xy 90.590034 -342.35824) (xy 90.597796 -342.412228)
			(xy 90.597796 -342.466772) (xy 90.597796 -342.466773) (xy 92.0805 -342.466773) (xy 92.0805 -342.412227)
			(xy 92.088263 -342.358236) (xy 92.103631 -342.3059) (xy 92.126292 -342.256284) (xy 92.155784 -342.210398)
			(xy 92.191506 -342.169176) (xy 92.232731 -342.133459) (xy 92.27862 -342.103972) (xy 92.328239 -342.081317)
			(xy 92.380577 -342.065954) (xy 92.434569 -342.058197) (xy 92.461842 -342.057736) (xy 93.325442 -342.057736)
			(xy 93.352709 -342.058229) (xy 93.406688 -342.065996) (xy 93.459012 -342.081365) (xy 93.508617 -342.104023)
			(xy 93.554492 -342.13351) (xy 93.595705 -342.169225) (xy 93.631415 -342.210441) (xy 93.660897 -342.25632)
			(xy 93.68355 -342.305927) (xy 93.698913 -342.358253) (xy 93.706674 -342.412233) (xy 93.706674 -342.466767)
			(xy 93.698913 -342.520747) (xy 93.68355 -342.573073) (xy 93.660897 -342.62268) (xy 93.631415 -342.668559)
			(xy 93.60914 -342.694268) (xy 102.35157 -342.694268) (xy 102.35157 -342.634332) (xy 102.359393 -342.574909)
			(xy 102.374905 -342.517016) (xy 102.397841 -342.461642) (xy 102.427809 -342.409736) (xy 102.464294 -342.362185)
			(xy 102.506675 -342.319804) (xy 102.554224 -342.283316) (xy 102.60613 -342.253347) (xy 102.661502 -342.23041)
			(xy 102.719395 -342.214896) (xy 102.778818 -342.207071) (xy 102.808786 -342.20658) (xy 103.672386 -342.20658)
			(xy 103.702355 -342.207072) (xy 103.76178 -342.214894) (xy 103.819676 -342.230405) (xy 103.875051 -342.253341)
			(xy 103.926959 -342.283309) (xy 103.974512 -342.319796) (xy 104.016895 -342.362178) (xy 104.053383 -342.409729)
			(xy 104.083352 -342.461636) (xy 104.085479 -342.466772) (xy 111.4808 -342.466772) (xy 111.4808 -342.412228)
			(xy 111.488562 -342.358241) (xy 111.503929 -342.305907) (xy 111.526587 -342.256293) (xy 111.556075 -342.210409)
			(xy 111.591794 -342.169188) (xy 111.633015 -342.133471) (xy 111.6789 -342.103983) (xy 111.728515 -342.081326)
			(xy 111.780848 -342.06596) (xy 111.834836 -342.058199) (xy 111.862108 -342.057736) (xy 112.725708 -342.057736)
			(xy 112.752977 -342.058227) (xy 112.806959 -342.06599) (xy 112.859288 -342.081355) (xy 112.908897 -342.104012)
			(xy 112.954776 -342.133498) (xy 112.995993 -342.169213) (xy 113.031707 -342.21043) (xy 113.061192 -342.256311)
			(xy 113.083847 -342.30592) (xy 113.099212 -342.358249) (xy 113.106974 -342.412231) (xy 113.106974 -342.466768)
			(xy 114.589822 -342.466768) (xy 114.589822 -342.412232) (xy 114.597583 -342.358251) (xy 114.612947 -342.305924)
			(xy 114.635601 -342.256315) (xy 114.665084 -342.210436) (xy 114.700796 -342.169219) (xy 114.74201 -342.133503)
			(xy 114.787887 -342.104016) (xy 114.837494 -342.081358) (xy 114.88982 -342.06599) (xy 114.9438 -342.058225)
			(xy 114.971068 -342.057736) (xy 115.834668 -342.057736) (xy 115.86194 -342.058201) (xy 115.91593 -342.06596)
			(xy 115.968267 -342.081323) (xy 116.017884 -342.103979) (xy 116.063771 -342.133465) (xy 116.104995 -342.169183)
			(xy 116.140715 -342.210403) (xy 116.170206 -342.256288) (xy 116.192866 -342.305903) (xy 116.208233 -342.358238)
			(xy 116.215996 -342.412228) (xy 116.215996 -342.466772) (xy 117.6987 -342.466772) (xy 117.6987 -342.412228)
			(xy 117.706462 -342.358238) (xy 117.72183 -342.305903) (xy 117.74449 -342.256288) (xy 117.77398 -342.210402)
			(xy 117.809701 -342.169181) (xy 117.850925 -342.133464) (xy 117.896812 -342.103977) (xy 117.946429 -342.08132)
			(xy 117.998765 -342.065957) (xy 118.052756 -342.058198) (xy 118.080028 -342.057736) (xy 118.943628 -342.057736)
			(xy 118.970896 -342.058228) (xy 119.024876 -342.065993) (xy 119.077202 -342.081361) (xy 119.126809 -342.104019)
			(xy 119.172686 -342.133505) (xy 119.2139 -342.16922) (xy 119.249612 -342.210437) (xy 119.279095 -342.256316)
			(xy 119.301749 -342.305924) (xy 119.317113 -342.358251) (xy 119.324874 -342.412232) (xy 119.324874 -342.466768)
			(xy 119.324874 -342.466769) (xy 120.807722 -342.466769) (xy 120.807722 -342.412231) (xy 120.815484 -342.358248)
			(xy 120.830849 -342.305919) (xy 120.853504 -342.25631) (xy 120.882989 -342.210429) (xy 120.918703 -342.169212)
			(xy 120.95992 -342.133496) (xy 121.005799 -342.10401) (xy 121.055408 -342.081353) (xy 121.107736 -342.065986)
			(xy 121.161719 -342.058223) (xy 121.188988 -342.057736) (xy 122.052588 -342.057736) (xy 122.079859 -342.058203)
			(xy 122.133847 -342.065963) (xy 122.186181 -342.081329) (xy 122.235796 -342.103985) (xy 122.28168 -342.133472)
			(xy 122.322902 -342.16919) (xy 122.35862 -342.21041) (xy 122.388109 -342.256294) (xy 122.410767 -342.305908)
			(xy 122.426134 -342.358241) (xy 122.433896 -342.412229) (xy 122.433896 -342.466771) (xy 122.433896 -342.466773)
			(xy 123.9166 -342.466773) (xy 123.9166 -342.412227) (xy 123.924363 -342.358235) (xy 123.939732 -342.305899)
			(xy 123.962393 -342.256282) (xy 123.991885 -342.210396) (xy 124.027608 -342.169174) (xy 124.068834 -342.133456)
			(xy 124.114724 -342.10397) (xy 124.164344 -342.081315) (xy 124.216682 -342.065953) (xy 124.270675 -342.058196)
			(xy 124.297948 -342.057736) (xy 125.161548 -342.057736) (xy 125.188815 -342.05823) (xy 125.242793 -342.065997)
			(xy 125.295117 -342.081366) (xy 125.34472 -342.104025) (xy 125.390595 -342.133512) (xy 125.431807 -342.169227)
			(xy 125.467517 -342.210443) (xy 125.496998 -342.256322) (xy 125.519651 -342.305928) (xy 125.535013 -342.358254)
			(xy 125.542774 -342.412233) (xy 125.542774 -342.466767) (xy 125.542773 -342.466772) (xy 127.0256 -342.466772)
			(xy 127.0256 -342.412228) (xy 127.033362 -342.358241) (xy 127.048729 -342.305907) (xy 127.071387 -342.256293)
			(xy 127.100875 -342.210409) (xy 127.136594 -342.169188) (xy 127.177815 -342.133471) (xy 127.2237 -342.103983)
			(xy 127.273315 -342.081326) (xy 127.325648 -342.06596) (xy 127.379636 -342.058199) (xy 127.406908 -342.057736)
			(xy 128.270508 -342.057736) (xy 128.297777 -342.058227) (xy 128.351759 -342.06599) (xy 128.404088 -342.081355)
			(xy 128.453697 -342.104012) (xy 128.499576 -342.133498) (xy 128.540793 -342.169213) (xy 128.576507 -342.21043)
			(xy 128.605992 -342.256311) (xy 128.628647 -342.30592) (xy 128.644012 -342.358249) (xy 128.651774 -342.412231)
			(xy 128.651774 -342.466768) (xy 130.134622 -342.466768) (xy 130.134622 -342.412232) (xy 130.142383 -342.358251)
			(xy 130.157747 -342.305924) (xy 130.180401 -342.256315) (xy 130.209884 -342.210436) (xy 130.245596 -342.169219)
			(xy 130.28681 -342.133503) (xy 130.332687 -342.104016) (xy 130.382294 -342.081358) (xy 130.43462 -342.06599)
			(xy 130.4886 -342.058225) (xy 130.515868 -342.057736) (xy 131.379468 -342.057736) (xy 131.40674 -342.058201)
			(xy 131.46073 -342.06596) (xy 131.513067 -342.081323) (xy 131.562684 -342.103979) (xy 131.608571 -342.133465)
			(xy 131.649795 -342.169183) (xy 131.685515 -342.210403) (xy 131.715006 -342.256288) (xy 131.737666 -342.305903)
			(xy 131.753033 -342.358238) (xy 131.760796 -342.412228) (xy 131.760796 -342.466772) (xy 133.2435 -342.466772)
			(xy 133.2435 -342.412228) (xy 133.251262 -342.358238) (xy 133.26663 -342.305903) (xy 133.28929 -342.256288)
			(xy 133.31878 -342.210402) (xy 133.354501 -342.169181) (xy 133.395725 -342.133464) (xy 133.441612 -342.103977)
			(xy 133.491229 -342.08132) (xy 133.543565 -342.065957) (xy 133.597556 -342.058198) (xy 133.624828 -342.057736)
			(xy 134.488428 -342.057736) (xy 134.515696 -342.058228) (xy 134.569676 -342.065993) (xy 134.622002 -342.081361)
			(xy 134.671609 -342.104019) (xy 134.717486 -342.133505) (xy 134.7587 -342.16922) (xy 134.794412 -342.210437)
			(xy 134.823895 -342.256316) (xy 134.846549 -342.305924) (xy 134.861913 -342.358251) (xy 134.869674 -342.412232)
			(xy 134.869674 -342.466768) (xy 134.869674 -342.466769) (xy 136.352522 -342.466769) (xy 136.352522 -342.412231)
			(xy 136.360284 -342.358248) (xy 136.375649 -342.305919) (xy 136.398304 -342.25631) (xy 136.427789 -342.210429)
			(xy 136.463503 -342.169212) (xy 136.50472 -342.133496) (xy 136.550599 -342.10401) (xy 136.600208 -342.081353)
			(xy 136.652536 -342.065986) (xy 136.706519 -342.058223) (xy 136.733788 -342.057736) (xy 137.597388 -342.057736)
			(xy 137.624659 -342.058203) (xy 137.678647 -342.065963) (xy 137.730981 -342.081329) (xy 137.780596 -342.103985)
			(xy 137.82648 -342.133472) (xy 137.867702 -342.16919) (xy 137.90342 -342.21041) (xy 137.932909 -342.256294)
			(xy 137.955567 -342.305908) (xy 137.970934 -342.358241) (xy 137.978696 -342.412229) (xy 137.978696 -342.466771)
			(xy 137.978696 -342.466773) (xy 139.4614 -342.466773) (xy 139.4614 -342.412227) (xy 139.469163 -342.358235)
			(xy 139.484532 -342.305899) (xy 139.507193 -342.256282) (xy 139.536685 -342.210396) (xy 139.572408 -342.169174)
			(xy 139.613634 -342.133456) (xy 139.659524 -342.10397) (xy 139.709144 -342.081315) (xy 139.761482 -342.065953)
			(xy 139.815475 -342.058196) (xy 139.842748 -342.057736) (xy 140.706348 -342.057736) (xy 140.733615 -342.05823)
			(xy 140.787593 -342.065997) (xy 140.839917 -342.081366) (xy 140.88952 -342.104025) (xy 140.935395 -342.133512)
			(xy 140.976607 -342.169227) (xy 141.012317 -342.210443) (xy 141.041798 -342.256322) (xy 141.064451 -342.305928)
			(xy 141.079813 -342.358254) (xy 141.087574 -342.412233) (xy 141.087574 -342.466767) (xy 141.087573 -342.466772)
			(xy 142.5704 -342.466772) (xy 142.5704 -342.412228) (xy 142.578162 -342.358241) (xy 142.593529 -342.305907)
			(xy 142.616187 -342.256293) (xy 142.645675 -342.210409) (xy 142.681394 -342.169188) (xy 142.722615 -342.133471)
			(xy 142.7685 -342.103983) (xy 142.818115 -342.081326) (xy 142.870448 -342.06596) (xy 142.924436 -342.058199)
			(xy 142.951708 -342.057736) (xy 143.815308 -342.057736) (xy 143.842577 -342.058227) (xy 143.896559 -342.06599)
			(xy 143.948888 -342.081355) (xy 143.998497 -342.104012) (xy 144.044376 -342.133498) (xy 144.085593 -342.169213)
			(xy 144.121307 -342.21043) (xy 144.150792 -342.256311) (xy 144.173447 -342.30592) (xy 144.188812 -342.358249)
			(xy 144.196574 -342.412231) (xy 144.196574 -342.466768) (xy 164.913822 -342.466768) (xy 164.913822 -342.412232)
			(xy 164.921583 -342.35825) (xy 164.936947 -342.305923) (xy 164.959602 -342.256314) (xy 164.989085 -342.210434)
			(xy 165.024797 -342.169217) (xy 165.066012 -342.133502) (xy 165.11189 -342.104015) (xy 165.161496 -342.081357)
			(xy 165.213823 -342.065989) (xy 165.267804 -342.058224) (xy 165.295072 -342.057736) (xy 166.158672 -342.057736)
			(xy 166.185944 -342.058202) (xy 166.239934 -342.06596) (xy 166.29227 -342.081324) (xy 166.341886 -342.10398)
			(xy 166.387773 -342.133467) (xy 166.428996 -342.169184) (xy 166.464716 -342.210405) (xy 166.494207 -342.256289)
			(xy 166.516866 -342.305904) (xy 166.532234 -342.358239) (xy 166.539996 -342.412228) (xy 166.539996 -342.466772)
			(xy 166.539996 -342.466773) (xy 168.0227 -342.466773) (xy 168.0227 -342.412227) (xy 168.030463 -342.358237)
			(xy 168.045831 -342.305902) (xy 168.068491 -342.256286) (xy 168.097981 -342.210401) (xy 168.133702 -342.16918)
			(xy 168.174927 -342.133462) (xy 168.220815 -342.103975) (xy 168.270432 -342.081319) (xy 168.322769 -342.065956)
			(xy 168.376759 -342.058197) (xy 168.404032 -342.057736) (xy 169.267632 -342.057736) (xy 169.2949 -342.058229)
			(xy 169.34888 -342.065994) (xy 169.401205 -342.081362) (xy 169.450811 -342.10402) (xy 169.496688 -342.133506)
			(xy 169.537901 -342.169222) (xy 169.573613 -342.210438) (xy 169.603095 -342.256317) (xy 169.625749 -342.305925)
			(xy 169.641113 -342.358252) (xy 169.648874 -342.412232) (xy 169.648874 -342.466768) (xy 169.648874 -342.466769)
			(xy 171.131722 -342.466769) (xy 171.131722 -342.412231) (xy 171.139484 -342.358248) (xy 171.154849 -342.305918)
			(xy 171.177505 -342.256309) (xy 171.20699 -342.210428) (xy 171.242705 -342.16921) (xy 171.283921 -342.133495)
			(xy 171.329802 -342.104009) (xy 171.379411 -342.081352) (xy 171.43174 -342.065986) (xy 171.485723 -342.058223)
			(xy 171.512992 -342.057736) (xy 172.376592 -342.057736) (xy 172.403863 -342.058203) (xy 172.457851 -342.065964)
			(xy 172.510184 -342.08133) (xy 172.559798 -342.103987) (xy 172.605682 -342.133474) (xy 172.646903 -342.169191)
			(xy 172.682621 -342.210411) (xy 172.71211 -342.256295) (xy 172.734768 -342.305908) (xy 172.750134 -342.358241)
			(xy 172.757896 -342.412229) (xy 172.757896 -342.466767) (xy 174.240722 -342.466767) (xy 174.240722 -342.412233)
			(xy 174.248483 -342.358253) (xy 174.263846 -342.305927) (xy 174.286499 -342.25632) (xy 174.31598 -342.210441)
			(xy 174.35169 -342.169224) (xy 174.392902 -342.133509) (xy 174.438778 -342.104022) (xy 174.488382 -342.081363)
			(xy 174.540706 -342.065993) (xy 174.594685 -342.058226) (xy 174.621952 -342.057736) (xy 175.485552 -342.057736)
			(xy 175.512825 -342.0582) (xy 175.566817 -342.065957) (xy 175.619155 -342.081319) (xy 175.668774 -342.103974)
			(xy 175.714663 -342.13346) (xy 175.755889 -342.169177) (xy 175.791612 -342.210398) (xy 175.821103 -342.256284)
			(xy 175.843764 -342.3059) (xy 175.859133 -342.358236) (xy 175.866896 -342.412227) (xy 175.866896 -342.466772)
			(xy 177.3496 -342.466772) (xy 177.3496 -342.412228) (xy 177.357362 -342.35824) (xy 177.372729 -342.305906)
			(xy 177.395388 -342.256292) (xy 177.424876 -342.210407) (xy 177.460595 -342.169187) (xy 177.501817 -342.133469)
			(xy 177.547703 -342.103982) (xy 177.597317 -342.081325) (xy 177.649652 -342.065959) (xy 177.70364 -342.058199)
			(xy 177.730912 -342.057736) (xy 178.594512 -342.057736) (xy 178.621781 -342.058227) (xy 178.675763 -342.06599)
			(xy 178.728091 -342.081357) (xy 178.777699 -342.104013) (xy 178.823578 -342.133499) (xy 178.864794 -342.169214)
			(xy 178.900508 -342.210432) (xy 178.929992 -342.256312) (xy 178.952648 -342.305921) (xy 178.968012 -342.358249)
			(xy 178.975774 -342.412231) (xy 178.975774 -342.466768) (xy 180.458622 -342.466768) (xy 180.458622 -342.412232)
			(xy 180.466383 -342.35825) (xy 180.481747 -342.305923) (xy 180.504402 -342.256314) (xy 180.533885 -342.210434)
			(xy 180.569597 -342.169217) (xy 180.610812 -342.133502) (xy 180.65669 -342.104015) (xy 180.706296 -342.081357)
			(xy 180.758623 -342.065989) (xy 180.812604 -342.058224) (xy 180.839872 -342.057736) (xy 181.703472 -342.057736)
			(xy 181.730744 -342.058202) (xy 181.784734 -342.06596) (xy 181.83707 -342.081324) (xy 181.886686 -342.10398)
			(xy 181.932573 -342.133467) (xy 181.973796 -342.169184) (xy 182.009516 -342.210405) (xy 182.039007 -342.256289)
			(xy 182.061666 -342.305904) (xy 182.077034 -342.358239) (xy 182.084796 -342.412228) (xy 182.084796 -342.466772)
			(xy 182.084796 -342.466773) (xy 183.5675 -342.466773) (xy 183.5675 -342.412227) (xy 183.575263 -342.358237)
			(xy 183.590631 -342.305902) (xy 183.613291 -342.256286) (xy 183.642781 -342.210401) (xy 183.678502 -342.16918)
			(xy 183.719727 -342.133462) (xy 183.765615 -342.103975) (xy 183.815232 -342.081319) (xy 183.867569 -342.065956)
			(xy 183.921559 -342.058197) (xy 183.948832 -342.057736) (xy 184.812432 -342.057736) (xy 184.8397 -342.058229)
			(xy 184.89368 -342.065994) (xy 184.946005 -342.081362) (xy 184.995611 -342.10402) (xy 185.041488 -342.133506)
			(xy 185.082701 -342.169222) (xy 185.118413 -342.210438) (xy 185.147895 -342.256317) (xy 185.170549 -342.305925)
			(xy 185.185913 -342.358252) (xy 185.193674 -342.412232) (xy 185.193674 -342.466768) (xy 185.193674 -342.466769)
			(xy 186.676522 -342.466769) (xy 186.676522 -342.412231) (xy 186.684284 -342.358248) (xy 186.699649 -342.305918)
			(xy 186.722305 -342.256309) (xy 186.75179 -342.210428) (xy 186.787505 -342.16921) (xy 186.828721 -342.133495)
			(xy 186.874602 -342.104009) (xy 186.924211 -342.081352) (xy 186.97654 -342.065986) (xy 187.030523 -342.058223)
			(xy 187.057792 -342.057736) (xy 187.921392 -342.057736) (xy 187.948663 -342.058203) (xy 188.002651 -342.065964)
			(xy 188.054984 -342.08133) (xy 188.104598 -342.103987) (xy 188.150482 -342.133474) (xy 188.191703 -342.169191)
			(xy 188.227421 -342.210411) (xy 188.25691 -342.256295) (xy 188.279568 -342.305908) (xy 188.294934 -342.358241)
			(xy 188.302696 -342.412229) (xy 188.302696 -342.466767) (xy 189.785522 -342.466767) (xy 189.785522 -342.412233)
			(xy 189.793283 -342.358253) (xy 189.808646 -342.305927) (xy 189.831299 -342.25632) (xy 189.86078 -342.210441)
			(xy 189.89649 -342.169224) (xy 189.937702 -342.133509) (xy 189.983578 -342.104022) (xy 190.033182 -342.081363)
			(xy 190.085506 -342.065993) (xy 190.139485 -342.058226) (xy 190.166752 -342.057736) (xy 191.030352 -342.057736)
			(xy 191.057625 -342.0582) (xy 191.111617 -342.065957) (xy 191.163955 -342.081319) (xy 191.213574 -342.103974)
			(xy 191.259463 -342.13346) (xy 191.300689 -342.169177) (xy 191.336412 -342.210398) (xy 191.365903 -342.256284)
			(xy 191.388564 -342.3059) (xy 191.403933 -342.358236) (xy 191.411696 -342.412227) (xy 191.411696 -342.466772)
			(xy 192.8944 -342.466772) (xy 192.8944 -342.412228) (xy 192.902162 -342.35824) (xy 192.917529 -342.305906)
			(xy 192.940188 -342.256292) (xy 192.969676 -342.210407) (xy 193.005395 -342.169187) (xy 193.046617 -342.133469)
			(xy 193.092503 -342.103982) (xy 193.142117 -342.081325) (xy 193.194452 -342.065959) (xy 193.24844 -342.058199)
			(xy 193.275712 -342.057736) (xy 194.139312 -342.057736) (xy 194.166581 -342.058227) (xy 194.220563 -342.06599)
			(xy 194.272891 -342.081357) (xy 194.322499 -342.104013) (xy 194.368378 -342.133499) (xy 194.409594 -342.169214)
			(xy 194.445308 -342.210432) (xy 194.474792 -342.256312) (xy 194.497448 -342.305921) (xy 194.512812 -342.358249)
			(xy 194.520574 -342.412231) (xy 194.520574 -342.466768) (xy 196.003422 -342.466768) (xy 196.003422 -342.412232)
			(xy 196.011183 -342.35825) (xy 196.026547 -342.305923) (xy 196.049202 -342.256314) (xy 196.078685 -342.210434)
			(xy 196.114397 -342.169217) (xy 196.155612 -342.133502) (xy 196.20149 -342.104015) (xy 196.251096 -342.081357)
			(xy 196.303423 -342.065989) (xy 196.357404 -342.058224) (xy 196.384672 -342.057736) (xy 197.248272 -342.057736)
			(xy 197.275544 -342.058202) (xy 197.28821 -342.060022) (xy 255.91262 -342.060022) (xy 255.91262 -341.196422)
			(xy 255.91311 -341.166438) (xy 255.920938 -341.106982) (xy 255.936459 -341.049057) (xy 255.959408 -340.993653)
			(xy 255.989392 -340.941719) (xy 256.025898 -340.894143) (xy 256.068303 -340.851738) (xy 256.115879 -340.815232)
			(xy 256.167813 -340.785248) (xy 256.223217 -340.762299) (xy 256.281142 -340.746778) (xy 256.340598 -340.73895)
			(xy 256.400566 -340.73895) (xy 256.460022 -340.746778) (xy 256.517947 -340.762299) (xy 256.573351 -340.785248)
			(xy 256.625285 -340.815232) (xy 256.672861 -340.851738) (xy 256.715266 -340.894143) (xy 256.751772 -340.941719)
			(xy 256.781756 -340.993653) (xy 256.804705 -341.049057) (xy 256.820226 -341.106982) (xy 256.828054 -341.166438)
			(xy 256.828544 -341.196422) (xy 256.828544 -342.060022) (xy 256.828054 -342.090006) (xy 256.820226 -342.149462)
			(xy 256.804705 -342.207387) (xy 256.781756 -342.262791) (xy 256.751772 -342.314725) (xy 256.715266 -342.362301)
			(xy 256.672861 -342.404706) (xy 256.625285 -342.441212) (xy 256.581015 -342.466771) (xy 267.515799 -342.466771)
			(xy 267.515799 -342.412229) (xy 267.523562 -342.358241) (xy 267.538928 -342.305908) (xy 267.561586 -342.256295)
			(xy 267.591074 -342.210411) (xy 267.626792 -342.16919) (xy 267.668012 -342.133473) (xy 267.713897 -342.103985)
			(xy 267.76351 -342.081327) (xy 267.815843 -342.065961) (xy 267.869831 -342.058199) (xy 267.897102 -342.057736)
			(xy 268.760702 -342.057736) (xy 268.787971 -342.058227) (xy 268.841954 -342.065988) (xy 268.894283 -342.081354)
			(xy 268.943893 -342.10401) (xy 268.989773 -342.133496) (xy 269.030991 -342.169211) (xy 269.066705 -342.210428)
			(xy 269.096191 -342.256309) (xy 269.118847 -342.305919) (xy 269.134212 -342.358248) (xy 269.141974 -342.412231)
			(xy 269.141974 -342.466768) (xy 270.624822 -342.466768) (xy 270.624822 -342.412232) (xy 270.632583 -342.358252)
			(xy 270.647947 -342.305925) (xy 270.6706 -342.256317) (xy 270.700083 -342.210438) (xy 270.735794 -342.169221)
			(xy 270.777007 -342.133505) (xy 270.822884 -342.104018) (xy 270.872489 -342.08136) (xy 270.924814 -342.065991)
			(xy 270.978794 -342.058225) (xy 271.006062 -342.057736) (xy 271.869662 -342.057736) (xy 271.896935 -342.058201)
			(xy 271.950925 -342.065959) (xy 272.003262 -342.081321) (xy 272.05288 -342.103977) (xy 272.098768 -342.133463)
			(xy 272.139993 -342.16918) (xy 272.175714 -342.210401) (xy 272.205205 -342.256287) (xy 272.227865 -342.305902)
			(xy 272.243233 -342.358237) (xy 272.250996 -342.412227) (xy 272.250996 -342.466772) (xy 273.7337 -342.466772)
			(xy 273.7337 -342.412228) (xy 273.741462 -342.358239) (xy 273.75683 -342.305904) (xy 273.779489 -342.256289)
			(xy 273.808979 -342.210404) (xy 273.844699 -342.169183) (xy 273.885922 -342.133466) (xy 273.931809 -342.103979)
			(xy 273.981425 -342.081322) (xy 274.03376 -342.065958) (xy 274.08775 -342.058198) (xy 274.115022 -342.057736)
			(xy 274.978622 -342.057736) (xy 275.00589 -342.058228) (xy 275.059871 -342.065992) (xy 275.112198 -342.081359)
			(xy 275.161805 -342.104017) (xy 275.207683 -342.133503) (xy 275.248898 -342.169218) (xy 275.28461 -342.210435)
			(xy 275.314094 -342.256314) (xy 275.336748 -342.305923) (xy 275.352113 -342.35825) (xy 275.359874 -342.412232)
			(xy 275.359874 -342.466768) (xy 275.359874 -342.466769) (xy 276.842722 -342.466769) (xy 276.842722 -342.412231)
			(xy 276.850484 -342.358249) (xy 276.865848 -342.305921) (xy 276.888503 -342.256311) (xy 276.917987 -342.210431)
			(xy 276.953701 -342.169214) (xy 276.994917 -342.133498) (xy 277.040796 -342.104012) (xy 277.090404 -342.081354)
			(xy 277.142731 -342.065987) (xy 277.196713 -342.058224) (xy 277.223982 -342.057736) (xy 278.087582 -342.057736)
			(xy 278.114854 -342.058202) (xy 278.168842 -342.065962) (xy 278.221177 -342.081327) (xy 278.270792 -342.103983)
			(xy 278.316678 -342.13347) (xy 278.3579 -342.169188) (xy 278.393619 -342.210408) (xy 278.423108 -342.256292)
			(xy 278.445767 -342.305906) (xy 278.461134 -342.35824) (xy 278.468896 -342.412228) (xy 278.468896 -342.466772)
			(xy 278.468896 -342.466773) (xy 279.9516 -342.466773) (xy 279.9516 -342.412227) (xy 279.959363 -342.358236)
			(xy 279.974731 -342.3059) (xy 279.997392 -342.256284) (xy 280.026884 -342.210398) (xy 280.062606 -342.169176)
			(xy 280.103831 -342.133459) (xy 280.14972 -342.103972) (xy 280.199339 -342.081317) (xy 280.251677 -342.065954)
			(xy 280.305669 -342.058197) (xy 280.332942 -342.057736) (xy 281.196542 -342.057736) (xy 281.223809 -342.058229)
			(xy 281.277788 -342.065996) (xy 281.330112 -342.081365) (xy 281.379717 -342.104023) (xy 281.425592 -342.13351)
			(xy 281.466805 -342.169225) (xy 281.502515 -342.210441) (xy 281.531997 -342.25632) (xy 281.55465 -342.305927)
			(xy 281.570013 -342.358253) (xy 281.577774 -342.412233) (xy 281.577774 -342.466767) (xy 281.577773 -342.466771)
			(xy 283.060599 -342.466771) (xy 283.060599 -342.412229) (xy 283.068362 -342.358241) (xy 283.083728 -342.305908)
			(xy 283.106386 -342.256295) (xy 283.135874 -342.210411) (xy 283.171592 -342.16919) (xy 283.212812 -342.133473)
			(xy 283.258697 -342.103985) (xy 283.30831 -342.081327) (xy 283.360643 -342.065961) (xy 283.414631 -342.058199)
			(xy 283.441902 -342.057736) (xy 284.305502 -342.057736) (xy 284.332771 -342.058227) (xy 284.386754 -342.065988)
			(xy 284.439083 -342.081354) (xy 284.488693 -342.10401) (xy 284.534573 -342.133496) (xy 284.575791 -342.169211)
			(xy 284.611505 -342.210428) (xy 284.640991 -342.256309) (xy 284.663647 -342.305919) (xy 284.679012 -342.358248)
			(xy 284.686774 -342.412231) (xy 284.686774 -342.466768) (xy 286.169622 -342.466768) (xy 286.169622 -342.412232)
			(xy 286.177383 -342.358252) (xy 286.192747 -342.305925) (xy 286.2154 -342.256317) (xy 286.244883 -342.210438)
			(xy 286.280594 -342.169221) (xy 286.321807 -342.133505) (xy 286.367684 -342.104018) (xy 286.417289 -342.08136)
			(xy 286.469614 -342.065991) (xy 286.523594 -342.058225) (xy 286.550862 -342.057736) (xy 287.414462 -342.057736)
			(xy 287.441735 -342.058201) (xy 287.495725 -342.065959) (xy 287.548062 -342.081321) (xy 287.59768 -342.103977)
			(xy 287.643568 -342.133463) (xy 287.684793 -342.16918) (xy 287.720514 -342.210401) (xy 287.750005 -342.256287)
			(xy 287.772665 -342.305902) (xy 287.788033 -342.358237) (xy 287.795796 -342.412227) (xy 287.795796 -342.466772)
			(xy 289.2785 -342.466772) (xy 289.2785 -342.412228) (xy 289.286262 -342.358239) (xy 289.30163 -342.305904)
			(xy 289.324289 -342.256289) (xy 289.353779 -342.210404) (xy 289.389499 -342.169183) (xy 289.430722 -342.133466)
			(xy 289.476609 -342.103979) (xy 289.526225 -342.081322) (xy 289.57856 -342.065958) (xy 289.63255 -342.058198)
			(xy 289.659822 -342.057736) (xy 290.523422 -342.057736) (xy 290.55069 -342.058228) (xy 290.604671 -342.065992)
			(xy 290.656998 -342.081359) (xy 290.706605 -342.104017) (xy 290.752483 -342.133503) (xy 290.793698 -342.169218)
			(xy 290.82941 -342.210435) (xy 290.858894 -342.256314) (xy 290.881548 -342.305923) (xy 290.896913 -342.35825)
			(xy 290.904674 -342.412232) (xy 290.904674 -342.466768) (xy 290.904674 -342.466769) (xy 292.387522 -342.466769)
			(xy 292.387522 -342.412231) (xy 292.395284 -342.358249) (xy 292.410648 -342.305921) (xy 292.433303 -342.256311)
			(xy 292.462787 -342.210431) (xy 292.498501 -342.169214) (xy 292.539717 -342.133498) (xy 292.585596 -342.104012)
			(xy 292.635204 -342.081354) (xy 292.687531 -342.065987) (xy 292.741513 -342.058224) (xy 292.768782 -342.057736)
			(xy 293.632382 -342.057736) (xy 293.659654 -342.058202) (xy 293.713642 -342.065962) (xy 293.765977 -342.081327)
			(xy 293.815592 -342.103983) (xy 293.861478 -342.13347) (xy 293.9027 -342.169188) (xy 293.938419 -342.210408)
			(xy 293.967908 -342.256292) (xy 293.990567 -342.305906) (xy 294.005934 -342.35824) (xy 294.013696 -342.412228)
			(xy 294.013696 -342.466772) (xy 294.013696 -342.466773) (xy 295.4964 -342.466773) (xy 295.4964 -342.412227)
			(xy 295.504163 -342.358236) (xy 295.519531 -342.3059) (xy 295.542192 -342.256284) (xy 295.571684 -342.210398)
			(xy 295.607406 -342.169176) (xy 295.648631 -342.133459) (xy 295.69452 -342.103972) (xy 295.744139 -342.081317)
			(xy 295.796477 -342.065954) (xy 295.850469 -342.058197) (xy 295.877742 -342.057736) (xy 296.741342 -342.057736)
			(xy 296.768609 -342.058229) (xy 296.822588 -342.065996) (xy 296.874912 -342.081365) (xy 296.924517 -342.104023)
			(xy 296.970392 -342.13351) (xy 297.011605 -342.169225) (xy 297.047315 -342.210441) (xy 297.076797 -342.25632)
			(xy 297.09945 -342.305927) (xy 297.114813 -342.358253) (xy 297.122574 -342.412233) (xy 297.122574 -342.466767)
			(xy 297.122573 -342.466771) (xy 298.605399 -342.466771) (xy 298.605399 -342.412229) (xy 298.613162 -342.358241)
			(xy 298.628528 -342.305908) (xy 298.651186 -342.256295) (xy 298.680674 -342.210411) (xy 298.716392 -342.16919)
			(xy 298.757612 -342.133473) (xy 298.803497 -342.103985) (xy 298.85311 -342.081327) (xy 298.905443 -342.065961)
			(xy 298.959431 -342.058199) (xy 298.986702 -342.057736) (xy 299.850302 -342.057736) (xy 299.877571 -342.058227)
			(xy 299.931554 -342.065988) (xy 299.983883 -342.081354) (xy 300.033493 -342.10401) (xy 300.079373 -342.133496)
			(xy 300.120591 -342.169211) (xy 300.156305 -342.210428) (xy 300.185791 -342.256309) (xy 300.208447 -342.305919)
			(xy 300.223812 -342.358248) (xy 300.231574 -342.412231) (xy 300.231574 -342.466769) (xy 300.231574 -342.466771)
			(xy 312.1215 -342.466771) (xy 312.1215 -342.412229) (xy 312.129262 -342.358241) (xy 312.144628 -342.305908)
			(xy 312.167286 -342.256294) (xy 312.196774 -342.21041) (xy 312.232493 -342.16919) (xy 312.273713 -342.133472)
			(xy 312.319598 -342.103984) (xy 312.369212 -342.081327) (xy 312.421545 -342.065961) (xy 312.475533 -342.058199)
			(xy 312.502804 -342.057736) (xy 313.366404 -342.057736) (xy 313.393673 -342.058227) (xy 313.447656 -342.065989)
			(xy 313.499985 -342.081354) (xy 313.549594 -342.104011) (xy 313.595474 -342.133497) (xy 313.636691 -342.169212)
			(xy 313.672406 -342.210429) (xy 313.701891 -342.256309) (xy 313.724547 -342.305919) (xy 313.739912 -342.358248)
			(xy 313.747674 -342.412231) (xy 313.747674 -342.466768) (xy 315.230522 -342.466768) (xy 315.230522 -342.412232)
			(xy 315.238283 -342.358251) (xy 315.253647 -342.305924) (xy 315.2763 -342.256316) (xy 315.305783 -342.210437)
			(xy 315.341495 -342.16922) (xy 315.382708 -342.133505) (xy 315.428585 -342.104018) (xy 315.478191 -342.081359)
			(xy 315.530516 -342.065991) (xy 315.584496 -342.058225) (xy 315.611764 -342.057736) (xy 316.475364 -342.057736)
			(xy 316.502637 -342.058201) (xy 316.556627 -342.065959) (xy 316.608964 -342.081322) (xy 316.658581 -342.103977)
			(xy 316.704469 -342.133464) (xy 316.745693 -342.169181) (xy 316.781414 -342.210402) (xy 316.810905 -342.256287)
			(xy 316.833565 -342.305902) (xy 316.848933 -342.358238) (xy 316.856696 -342.412228) (xy 316.856696 -342.466772)
			(xy 318.3394 -342.466772) (xy 318.3394 -342.412228) (xy 318.347162 -342.358239) (xy 318.36253 -342.305904)
			(xy 318.385189 -342.256289) (xy 318.414679 -342.210404) (xy 318.4504 -342.169183) (xy 318.491623 -342.133465)
			(xy 318.53751 -342.103978) (xy 318.587126 -342.081322) (xy 318.639462 -342.065957) (xy 318.693452 -342.058198)
			(xy 318.720724 -342.057736) (xy 319.584324 -342.057736) (xy 319.611592 -342.058228) (xy 319.665573 -342.065992)
			(xy 319.717899 -342.08136) (xy 319.767506 -342.104017) (xy 319.813384 -342.133504) (xy 319.854598 -342.169219)
			(xy 319.890311 -342.210435) (xy 319.919794 -342.256315) (xy 319.942449 -342.305923) (xy 319.957813 -342.358251)
			(xy 319.965574 -342.412232) (xy 319.965574 -342.466768) (xy 319.965574 -342.466769) (xy 321.448422 -342.466769)
			(xy 321.448422 -342.412231) (xy 321.456184 -342.358249) (xy 321.471548 -342.30592) (xy 321.494203 -342.256311)
			(xy 321.523688 -342.21043) (xy 321.559402 -342.169213) (xy 321.600618 -342.133498) (xy 321.646497 -342.104011)
			(xy 321.696105 -342.081354) (xy 321.748433 -342.065987) (xy 321.802415 -342.058224) (xy 321.829684 -342.057736)
			(xy 322.693284 -342.057736) (xy 322.720556 -342.058202) (xy 322.774544 -342.065963) (xy 322.826878 -342.081327)
			(xy 322.876493 -342.103984) (xy 322.922379 -342.133471) (xy 322.9636 -342.169188) (xy 322.999319 -342.210409)
			(xy 323.028808 -342.256293) (xy 323.051467 -342.305907) (xy 323.066834 -342.35824) (xy 323.074596 -342.412228)
			(xy 323.074596 -342.466772) (xy 323.074596 -342.466773) (xy 324.5573 -342.466773) (xy 324.5573 -342.412227)
			(xy 324.565063 -342.358236) (xy 324.580432 -342.305899) (xy 324.603092 -342.256283) (xy 324.632584 -342.210397)
			(xy 324.668307 -342.169176) (xy 324.709532 -342.133458) (xy 324.755422 -342.103971) (xy 324.805041 -342.081316)
			(xy 324.857379 -342.065954) (xy 324.911371 -342.058196) (xy 324.938644 -342.057736) (xy 325.802244 -342.057736)
			(xy 325.829511 -342.058229) (xy 325.88349 -342.065996) (xy 325.935814 -342.081365) (xy 325.985418 -342.104024)
			(xy 326.031293 -342.133511) (xy 326.072505 -342.169226) (xy 326.108216 -342.210442) (xy 326.137697 -342.256321)
			(xy 326.16035 -342.305928) (xy 326.175713 -342.358253) (xy 326.183474 -342.412233) (xy 326.183474 -342.466767)
			(xy 326.183473 -342.466771) (xy 327.6663 -342.466771) (xy 327.6663 -342.412229) (xy 327.674062 -342.358241)
			(xy 327.689428 -342.305908) (xy 327.712086 -342.256294) (xy 327.741574 -342.21041) (xy 327.777293 -342.16919)
			(xy 327.818513 -342.133472) (xy 327.864398 -342.103984) (xy 327.914012 -342.081327) (xy 327.966345 -342.065961)
			(xy 328.020333 -342.058199) (xy 328.047604 -342.057736) (xy 328.911204 -342.057736) (xy 328.938473 -342.058227)
			(xy 328.992456 -342.065989) (xy 329.044785 -342.081354) (xy 329.094394 -342.104011) (xy 329.140274 -342.133497)
			(xy 329.181491 -342.169212) (xy 329.217206 -342.210429) (xy 329.246691 -342.256309) (xy 329.269347 -342.305919)
			(xy 329.284712 -342.358248) (xy 329.292474 -342.412231) (xy 329.292474 -342.466768) (xy 330.775322 -342.466768)
			(xy 330.775322 -342.412232) (xy 330.783083 -342.358251) (xy 330.798447 -342.305924) (xy 330.8211 -342.256316)
			(xy 330.850583 -342.210437) (xy 330.886295 -342.16922) (xy 330.927508 -342.133505) (xy 330.973385 -342.104018)
			(xy 331.022991 -342.081359) (xy 331.075316 -342.065991) (xy 331.129296 -342.058225) (xy 331.156564 -342.057736)
			(xy 332.020164 -342.057736) (xy 332.047437 -342.058201) (xy 332.101427 -342.065959) (xy 332.153764 -342.081322)
			(xy 332.203381 -342.103977) (xy 332.249269 -342.133464) (xy 332.290493 -342.169181) (xy 332.326214 -342.210402)
			(xy 332.355705 -342.256287) (xy 332.378365 -342.305902) (xy 332.393733 -342.358238) (xy 332.401496 -342.412228)
			(xy 332.401496 -342.466772) (xy 333.8842 -342.466772) (xy 333.8842 -342.412228) (xy 333.891962 -342.358239)
			(xy 333.90733 -342.305904) (xy 333.929989 -342.256289) (xy 333.959479 -342.210404) (xy 333.9952 -342.169183)
			(xy 334.036423 -342.133465) (xy 334.08231 -342.103978) (xy 334.131926 -342.081322) (xy 334.184262 -342.065957)
			(xy 334.238252 -342.058198) (xy 334.265524 -342.057736) (xy 335.129124 -342.057736) (xy 335.156392 -342.058228)
			(xy 335.210373 -342.065992) (xy 335.262699 -342.08136) (xy 335.312306 -342.104017) (xy 335.358184 -342.133504)
			(xy 335.399398 -342.169219) (xy 335.435111 -342.210435) (xy 335.464594 -342.256315) (xy 335.487249 -342.305923)
			(xy 335.502613 -342.358251) (xy 335.510374 -342.412232) (xy 335.510374 -342.466768) (xy 335.510374 -342.466769)
			(xy 336.993222 -342.466769) (xy 336.993222 -342.412231) (xy 337.000984 -342.358249) (xy 337.016348 -342.30592)
			(xy 337.039003 -342.256311) (xy 337.068488 -342.21043) (xy 337.104202 -342.169213) (xy 337.145418 -342.133498)
			(xy 337.191297 -342.104011) (xy 337.240905 -342.081354) (xy 337.293233 -342.065987) (xy 337.347215 -342.058224)
			(xy 337.374484 -342.057736) (xy 338.238084 -342.057736) (xy 338.265356 -342.058202) (xy 338.319344 -342.065963)
			(xy 338.371678 -342.081327) (xy 338.421293 -342.103984) (xy 338.467179 -342.133471) (xy 338.5084 -342.169188)
			(xy 338.544119 -342.210409) (xy 338.573608 -342.256293) (xy 338.596267 -342.305907) (xy 338.611634 -342.35824)
			(xy 338.619396 -342.412228) (xy 338.619396 -342.466772) (xy 338.619396 -342.466773) (xy 340.1021 -342.466773)
			(xy 340.1021 -342.412227) (xy 340.109863 -342.358236) (xy 340.125232 -342.305899) (xy 340.147892 -342.256283)
			(xy 340.177384 -342.210397) (xy 340.213107 -342.169176) (xy 340.254332 -342.133458) (xy 340.300222 -342.103971)
			(xy 340.349841 -342.081316) (xy 340.402179 -342.065954) (xy 340.456171 -342.058196) (xy 340.483444 -342.057736)
			(xy 341.347044 -342.057736) (xy 341.374311 -342.058229) (xy 341.42829 -342.065996) (xy 341.480614 -342.081365)
			(xy 341.530218 -342.104024) (xy 341.576093 -342.133511) (xy 341.617305 -342.169226) (xy 341.653016 -342.210442)
			(xy 341.682497 -342.256321) (xy 341.70515 -342.305928) (xy 341.720513 -342.358253) (xy 341.728274 -342.412233)
			(xy 341.728274 -342.466767) (xy 341.728273 -342.466771) (xy 343.2111 -342.466771) (xy 343.2111 -342.412229)
			(xy 343.218862 -342.358241) (xy 343.234228 -342.305908) (xy 343.256886 -342.256294) (xy 343.286374 -342.21041)
			(xy 343.322093 -342.16919) (xy 343.363313 -342.133472) (xy 343.409198 -342.103984) (xy 343.458812 -342.081327)
			(xy 343.511145 -342.065961) (xy 343.565133 -342.058199) (xy 343.592404 -342.057736) (xy 344.456004 -342.057736)
			(xy 344.483273 -342.058227) (xy 344.537256 -342.065989) (xy 344.589585 -342.081354) (xy 344.639194 -342.104011)
			(xy 344.685074 -342.133497) (xy 344.726291 -342.169212) (xy 344.762006 -342.210429) (xy 344.791491 -342.256309)
			(xy 344.814147 -342.305919) (xy 344.829512 -342.358248) (xy 344.837274 -342.412231) (xy 344.837274 -342.466769)
			(xy 370.806722 -342.466769) (xy 370.806722 -342.412231) (xy 370.814484 -342.358249) (xy 370.829848 -342.305921)
			(xy 370.852503 -342.256312) (xy 370.881987 -342.210432) (xy 370.9177 -342.169214) (xy 370.958916 -342.133499)
			(xy 371.004794 -342.104012) (xy 371.054402 -342.081355) (xy 371.10673 -342.065988) (xy 371.160711 -342.058224)
			(xy 371.18798 -342.057736) (xy 372.05158 -342.057736) (xy 372.078852 -342.058202) (xy 372.132841 -342.065962)
			(xy 372.185175 -342.081326) (xy 372.234791 -342.103983) (xy 372.280677 -342.13347) (xy 372.321899 -342.169187)
			(xy 372.357618 -342.210407) (xy 372.387108 -342.256292) (xy 372.409767 -342.305906) (xy 372.425134 -342.35824)
			(xy 372.432896 -342.412228) (xy 372.432896 -342.466772) (xy 372.432896 -342.466773) (xy 373.9156 -342.466773)
			(xy 373.9156 -342.412227) (xy 373.923363 -342.358236) (xy 373.938731 -342.3059) (xy 373.961392 -342.256284)
			(xy 373.990883 -342.210398) (xy 374.026605 -342.169177) (xy 374.06783 -342.133459) (xy 374.113719 -342.103973)
			(xy 374.163338 -342.081317) (xy 374.215676 -342.065954) (xy 374.269667 -342.058197) (xy 374.29694 -342.057736)
			(xy 375.16054 -342.057736) (xy 375.187807 -342.058229) (xy 375.241786 -342.065995) (xy 375.294111 -342.081364)
			(xy 375.343716 -342.104022) (xy 375.389591 -342.133509) (xy 375.430804 -342.169224) (xy 375.466515 -342.210441)
			(xy 375.495997 -342.256319) (xy 375.51865 -342.305927) (xy 375.534013 -342.358253) (xy 375.541774 -342.412233)
			(xy 375.541774 -342.466767) (xy 375.541774 -342.46677) (xy 377.024622 -342.46677) (xy 377.024622 -342.41223)
			(xy 377.032384 -342.358247) (xy 377.04775 -342.305917) (xy 377.070406 -342.256306) (xy 377.099892 -342.210425)
			(xy 377.135607 -342.169207) (xy 377.176825 -342.133492) (xy 377.222706 -342.104006) (xy 377.272317 -342.08135)
			(xy 377.324647 -342.065984) (xy 377.37863 -342.058222) (xy 377.4059 -342.057736) (xy 378.2695 -342.057736)
			(xy 378.296769 -342.058226) (xy 378.350753 -342.065988) (xy 378.403082 -342.081353) (xy 378.452692 -342.104009)
			(xy 378.498572 -342.133495) (xy 378.53979 -342.16921) (xy 378.575505 -342.210428) (xy 378.604991 -342.256308)
			(xy 378.627647 -342.305918) (xy 378.643012 -342.358247) (xy 378.650774 -342.412231) (xy 378.650774 -342.466768)
			(xy 380.133622 -342.466768) (xy 380.133622 -342.412232) (xy 380.141383 -342.358252) (xy 380.156746 -342.305925)
			(xy 380.1794 -342.256318) (xy 380.208882 -342.210438) (xy 380.244593 -342.169222) (xy 380.285806 -342.133506)
			(xy 380.331682 -342.104019) (xy 380.381288 -342.08136) (xy 380.433613 -342.065991) (xy 380.487592 -342.058225)
			(xy 380.51486 -342.057736) (xy 381.37846 -342.057736) (xy 381.405733 -342.058201) (xy 381.459724 -342.065958)
			(xy 381.512061 -342.081321) (xy 381.561679 -342.103976) (xy 381.607567 -342.133463) (xy 381.648792 -342.16918)
			(xy 381.684513 -342.210401) (xy 381.714005 -342.256286) (xy 381.736665 -342.305902) (xy 381.752033 -342.358237)
			(xy 381.759796 -342.412227) (xy 381.759796 -342.466772) (xy 383.2425 -342.466772) (xy 383.2425 -342.412228)
			(xy 383.250262 -342.358239) (xy 383.26563 -342.305904) (xy 383.288289 -342.25629) (xy 383.317778 -342.210405)
			(xy 383.353498 -342.169184) (xy 383.394721 -342.133466) (xy 383.440607 -342.103979) (xy 383.490223 -342.081323)
			(xy 383.542559 -342.065958) (xy 383.596548 -342.058198) (xy 383.62382 -342.057736) (xy 384.48742 -342.057736)
			(xy 384.514688 -342.058228) (xy 384.568669 -342.065992) (xy 384.620996 -342.081359) (xy 384.670604 -342.104016)
			(xy 384.716482 -342.133502) (xy 384.757697 -342.169217) (xy 384.79341 -342.210434) (xy 384.822894 -342.256314)
			(xy 384.845548 -342.305922) (xy 384.860913 -342.35825) (xy 384.868674 -342.412232) (xy 384.868674 -342.466768)
			(xy 384.868674 -342.466769) (xy 386.351522 -342.466769) (xy 386.351522 -342.412231) (xy 386.359284 -342.358249)
			(xy 386.374648 -342.305921) (xy 386.397303 -342.256312) (xy 386.426787 -342.210432) (xy 386.4625 -342.169214)
			(xy 386.503716 -342.133499) (xy 386.549594 -342.104012) (xy 386.599202 -342.081355) (xy 386.65153 -342.065988)
			(xy 386.705511 -342.058224) (xy 386.73278 -342.057736) (xy 387.59638 -342.057736) (xy 387.623652 -342.058202)
			(xy 387.677641 -342.065962) (xy 387.729975 -342.081326) (xy 387.779591 -342.103983) (xy 387.825477 -342.13347)
			(xy 387.866699 -342.169187) (xy 387.902418 -342.210407) (xy 387.931908 -342.256292) (xy 387.954567 -342.305906)
			(xy 387.969934 -342.35824) (xy 387.977696 -342.412228) (xy 387.977696 -342.466772) (xy 387.977696 -342.466773)
			(xy 389.4604 -342.466773) (xy 389.4604 -342.412227) (xy 389.468163 -342.358236) (xy 389.483531 -342.3059)
			(xy 389.506192 -342.256284) (xy 389.535683 -342.210398) (xy 389.571405 -342.169177) (xy 389.61263 -342.133459)
			(xy 389.658519 -342.103973) (xy 389.708138 -342.081317) (xy 389.760476 -342.065954) (xy 389.814467 -342.058197)
			(xy 389.84174 -342.057736) (xy 390.70534 -342.057736) (xy 390.732607 -342.058229) (xy 390.786586 -342.065995)
			(xy 390.838911 -342.081364) (xy 390.888516 -342.104022) (xy 390.934391 -342.133509) (xy 390.975604 -342.169224)
			(xy 391.011315 -342.210441) (xy 391.040797 -342.256319) (xy 391.06345 -342.305927) (xy 391.078813 -342.358253)
			(xy 391.086574 -342.412233) (xy 391.086574 -342.466767) (xy 391.086574 -342.46677) (xy 392.569422 -342.46677)
			(xy 392.569422 -342.41223) (xy 392.577184 -342.358247) (xy 392.59255 -342.305917) (xy 392.615206 -342.256306)
			(xy 392.644692 -342.210425) (xy 392.680407 -342.169207) (xy 392.721625 -342.133492) (xy 392.767506 -342.104006)
			(xy 392.817117 -342.08135) (xy 392.869447 -342.065984) (xy 392.92343 -342.058222) (xy 392.9507 -342.057736)
			(xy 393.8143 -342.057736) (xy 393.841569 -342.058226) (xy 393.895553 -342.065988) (xy 393.947882 -342.081353)
			(xy 393.997492 -342.104009) (xy 394.043372 -342.133495) (xy 394.08459 -342.16921) (xy 394.120305 -342.210428)
			(xy 394.149791 -342.256308) (xy 394.172447 -342.305918) (xy 394.187812 -342.358247) (xy 394.195574 -342.412231)
			(xy 394.195574 -342.466768) (xy 395.678422 -342.466768) (xy 395.678422 -342.412232) (xy 395.686183 -342.358252)
			(xy 395.701546 -342.305925) (xy 395.7242 -342.256318) (xy 395.753682 -342.210438) (xy 395.789393 -342.169222)
			(xy 395.830606 -342.133506) (xy 395.876482 -342.104019) (xy 395.926088 -342.08136) (xy 395.978413 -342.065991)
			(xy 396.032392 -342.058225) (xy 396.05966 -342.057736) (xy 396.92326 -342.057736) (xy 396.950533 -342.058201)
			(xy 397.004524 -342.065958) (xy 397.056861 -342.081321) (xy 397.106479 -342.103976) (xy 397.152367 -342.133463)
			(xy 397.193592 -342.16918) (xy 397.229313 -342.210401) (xy 397.258805 -342.256286) (xy 397.281465 -342.305902)
			(xy 397.296833 -342.358237) (xy 397.304596 -342.412227) (xy 397.304596 -342.466772) (xy 398.7873 -342.466772)
			(xy 398.7873 -342.412228) (xy 398.795062 -342.358239) (xy 398.81043 -342.305904) (xy 398.833089 -342.25629)
			(xy 398.862578 -342.210405) (xy 398.898298 -342.169184) (xy 398.939521 -342.133466) (xy 398.985407 -342.103979)
			(xy 399.035023 -342.081323) (xy 399.087359 -342.065958) (xy 399.141348 -342.058198) (xy 399.16862 -342.057736)
			(xy 400.03222 -342.057736) (xy 400.059488 -342.058228) (xy 400.113469 -342.065992) (xy 400.165796 -342.081359)
			(xy 400.215404 -342.104016) (xy 400.261282 -342.133502) (xy 400.302497 -342.169217) (xy 400.33821 -342.210434)
			(xy 400.367694 -342.256314) (xy 400.390348 -342.305922) (xy 400.405713 -342.35825) (xy 400.413474 -342.412232)
			(xy 400.413474 -342.466768) (xy 400.413474 -342.466769) (xy 401.896322 -342.466769) (xy 401.896322 -342.412231)
			(xy 401.904084 -342.358249) (xy 401.919448 -342.305921) (xy 401.942103 -342.256312) (xy 401.971587 -342.210432)
			(xy 402.0073 -342.169214) (xy 402.048516 -342.133499) (xy 402.094394 -342.104012) (xy 402.144002 -342.081355)
			(xy 402.19633 -342.065988) (xy 402.250311 -342.058224) (xy 402.27758 -342.057736) (xy 403.14118 -342.057736)
			(xy 403.168452 -342.058202) (xy 403.222441 -342.065962) (xy 403.274775 -342.081326) (xy 403.324391 -342.103983)
			(xy 403.370277 -342.13347) (xy 403.411499 -342.169187) (xy 403.447218 -342.210407) (xy 403.476708 -342.256292)
			(xy 403.499367 -342.305906) (xy 403.514734 -342.35824) (xy 403.522496 -342.412228) (xy 403.522496 -342.466769)
			(xy 408.913822 -342.466769) (xy 408.913822 -342.412231) (xy 408.921584 -342.358248) (xy 408.936949 -342.305918)
			(xy 408.959605 -342.256309) (xy 408.98909 -342.210428) (xy 409.024805 -342.16921) (xy 409.066021 -342.133495)
			(xy 409.111902 -342.104009) (xy 409.161511 -342.081352) (xy 409.21384 -342.065986) (xy 409.267823 -342.058223)
			(xy 409.295092 -342.057736) (xy 410.158692 -342.057736) (xy 410.185963 -342.058203) (xy 410.239951 -342.065964)
			(xy 410.292284 -342.08133) (xy 410.341898 -342.103987) (xy 410.387782 -342.133474) (xy 410.429003 -342.169191)
			(xy 410.464721 -342.210411) (xy 410.49421 -342.256295) (xy 410.516868 -342.305908) (xy 410.532234 -342.358241)
			(xy 410.539996 -342.412229) (xy 410.539996 -342.466767) (xy 412.022822 -342.466767) (xy 412.022822 -342.412233)
			(xy 412.030583 -342.358253) (xy 412.045946 -342.305927) (xy 412.068599 -342.25632) (xy 412.09808 -342.210441)
			(xy 412.13379 -342.169224) (xy 412.175002 -342.133509) (xy 412.220878 -342.104022) (xy 412.270482 -342.081363)
			(xy 412.322806 -342.065993) (xy 412.376785 -342.058226) (xy 412.404052 -342.057736) (xy 413.267652 -342.057736)
			(xy 413.294925 -342.0582) (xy 413.348917 -342.065957) (xy 413.401255 -342.081319) (xy 413.450874 -342.103974)
			(xy 413.496763 -342.13346) (xy 413.537989 -342.169177) (xy 413.573712 -342.210398) (xy 413.603203 -342.256284)
			(xy 413.625864 -342.3059) (xy 413.641233 -342.358236) (xy 413.648996 -342.412227) (xy 413.648996 -342.466772)
			(xy 415.1317 -342.466772) (xy 415.1317 -342.412228) (xy 415.139462 -342.35824) (xy 415.154829 -342.305906)
			(xy 415.177488 -342.256292) (xy 415.206976 -342.210407) (xy 415.242695 -342.169187) (xy 415.283917 -342.133469)
			(xy 415.329803 -342.103982) (xy 415.379417 -342.081325) (xy 415.431752 -342.065959) (xy 415.48574 -342.058199)
			(xy 415.513012 -342.057736) (xy 416.376612 -342.057736) (xy 416.403881 -342.058227) (xy 416.457863 -342.06599)
			(xy 416.510191 -342.081357) (xy 416.559799 -342.104013) (xy 416.605678 -342.133499) (xy 416.646894 -342.169214)
			(xy 416.682608 -342.210432) (xy 416.712092 -342.256312) (xy 416.734748 -342.305921) (xy 416.750112 -342.358249)
			(xy 416.757874 -342.412231) (xy 416.757874 -342.466768) (xy 418.240722 -342.466768) (xy 418.240722 -342.412232)
			(xy 418.248483 -342.35825) (xy 418.263847 -342.305923) (xy 418.286502 -342.256314) (xy 418.315985 -342.210434)
			(xy 418.351697 -342.169217) (xy 418.392912 -342.133502) (xy 418.43879 -342.104015) (xy 418.488396 -342.081357)
			(xy 418.540723 -342.065989) (xy 418.594704 -342.058224) (xy 418.621972 -342.057736) (xy 419.485572 -342.057736)
			(xy 419.512844 -342.058202) (xy 419.566834 -342.06596) (xy 419.61917 -342.081324) (xy 419.668786 -342.10398)
			(xy 419.714673 -342.133467) (xy 419.755896 -342.169184) (xy 419.791616 -342.210405) (xy 419.821107 -342.256289)
			(xy 419.843766 -342.305904) (xy 419.859134 -342.358239) (xy 419.866896 -342.412228) (xy 419.866896 -342.466772)
			(xy 419.866896 -342.466773) (xy 421.3496 -342.466773) (xy 421.3496 -342.412227) (xy 421.357363 -342.358237)
			(xy 421.372731 -342.305902) (xy 421.395391 -342.256286) (xy 421.424881 -342.210401) (xy 421.460602 -342.16918)
			(xy 421.501827 -342.133462) (xy 421.547715 -342.103975) (xy 421.597332 -342.081319) (xy 421.649669 -342.065956)
			(xy 421.703659 -342.058197) (xy 421.730932 -342.057736) (xy 422.594532 -342.057736) (xy 422.6218 -342.058229)
			(xy 422.67578 -342.065994) (xy 422.728105 -342.081362) (xy 422.777711 -342.10402) (xy 422.823588 -342.133506)
			(xy 422.864801 -342.169222) (xy 422.900513 -342.210438) (xy 422.929995 -342.256317) (xy 422.952649 -342.305925)
			(xy 422.968013 -342.358252) (xy 422.975774 -342.412232) (xy 422.975774 -342.466768) (xy 422.975774 -342.466769)
			(xy 424.458622 -342.466769) (xy 424.458622 -342.412231) (xy 424.466384 -342.358248) (xy 424.481749 -342.305918)
			(xy 424.504405 -342.256309) (xy 424.53389 -342.210428) (xy 424.569605 -342.16921) (xy 424.610821 -342.133495)
			(xy 424.656702 -342.104009) (xy 424.706311 -342.081352) (xy 424.75864 -342.065986) (xy 424.812623 -342.058223)
			(xy 424.839892 -342.057736) (xy 425.703492 -342.057736) (xy 425.730763 -342.058203) (xy 425.784751 -342.065964)
			(xy 425.837084 -342.08133) (xy 425.886698 -342.103987) (xy 425.932582 -342.133474) (xy 425.973803 -342.169191)
			(xy 426.009521 -342.210411) (xy 426.03901 -342.256295) (xy 426.061668 -342.305908) (xy 426.077034 -342.358241)
			(xy 426.084796 -342.412229) (xy 426.084796 -342.466767) (xy 427.567622 -342.466767) (xy 427.567622 -342.412233)
			(xy 427.575383 -342.358253) (xy 427.590746 -342.305927) (xy 427.613399 -342.25632) (xy 427.64288 -342.210441)
			(xy 427.67859 -342.169224) (xy 427.719802 -342.133509) (xy 427.765678 -342.104022) (xy 427.815282 -342.081363)
			(xy 427.867606 -342.065993) (xy 427.921585 -342.058226) (xy 427.948852 -342.057736) (xy 428.812452 -342.057736)
			(xy 428.839725 -342.0582) (xy 428.893717 -342.065957) (xy 428.946055 -342.081319) (xy 428.995674 -342.103974)
			(xy 429.041563 -342.13346) (xy 429.082789 -342.169177) (xy 429.118512 -342.210398) (xy 429.148003 -342.256284)
			(xy 429.170664 -342.3059) (xy 429.186033 -342.358236) (xy 429.193796 -342.412227) (xy 429.193796 -342.466772)
			(xy 430.6765 -342.466772) (xy 430.6765 -342.412228) (xy 430.684262 -342.35824) (xy 430.699629 -342.305906)
			(xy 430.722288 -342.256292) (xy 430.751776 -342.210407) (xy 430.787495 -342.169187) (xy 430.828717 -342.133469)
			(xy 430.874603 -342.103982) (xy 430.924217 -342.081325) (xy 430.976552 -342.065959) (xy 431.03054 -342.058199)
			(xy 431.057812 -342.057736) (xy 431.921412 -342.057736) (xy 431.948681 -342.058227) (xy 432.002663 -342.06599)
			(xy 432.054991 -342.081357) (xy 432.104599 -342.104013) (xy 432.150478 -342.133499) (xy 432.191694 -342.169214)
			(xy 432.227408 -342.210432) (xy 432.256892 -342.256312) (xy 432.279548 -342.305921) (xy 432.294912 -342.358249)
			(xy 432.302674 -342.412231) (xy 432.302674 -342.466768) (xy 433.785522 -342.466768) (xy 433.785522 -342.412232)
			(xy 433.793283 -342.35825) (xy 433.808647 -342.305923) (xy 433.831302 -342.256314) (xy 433.860785 -342.210434)
			(xy 433.896497 -342.169217) (xy 433.937712 -342.133502) (xy 433.98359 -342.104015) (xy 434.033196 -342.081357)
			(xy 434.085523 -342.065989) (xy 434.139504 -342.058224) (xy 434.166772 -342.057736) (xy 435.030372 -342.057736)
			(xy 435.057644 -342.058202) (xy 435.111634 -342.06596) (xy 435.16397 -342.081324) (xy 435.213586 -342.10398)
			(xy 435.259473 -342.133467) (xy 435.300696 -342.169184) (xy 435.336416 -342.210405) (xy 435.365907 -342.256289)
			(xy 435.388566 -342.305904) (xy 435.403934 -342.358239) (xy 435.411696 -342.412228) (xy 435.411696 -342.466772)
			(xy 435.411696 -342.466773) (xy 436.8944 -342.466773) (xy 436.8944 -342.412227) (xy 436.902163 -342.358237)
			(xy 436.917531 -342.305902) (xy 436.940191 -342.256286) (xy 436.969681 -342.210401) (xy 437.005402 -342.16918)
			(xy 437.046627 -342.133462) (xy 437.092515 -342.103975) (xy 437.142132 -342.081319) (xy 437.194469 -342.065956)
			(xy 437.248459 -342.058197) (xy 437.275732 -342.057736) (xy 438.139332 -342.057736) (xy 438.1666 -342.058229)
			(xy 438.22058 -342.065994) (xy 438.272905 -342.081362) (xy 438.322511 -342.10402) (xy 438.368388 -342.133506)
			(xy 438.409601 -342.169222) (xy 438.445313 -342.210438) (xy 438.474795 -342.256317) (xy 438.497449 -342.305925)
			(xy 438.512813 -342.358252) (xy 438.520574 -342.412232) (xy 438.520574 -342.466768) (xy 438.520574 -342.466769)
			(xy 440.003422 -342.466769) (xy 440.003422 -342.412231) (xy 440.011184 -342.358248) (xy 440.026549 -342.305918)
			(xy 440.049205 -342.256309) (xy 440.07869 -342.210428) (xy 440.114405 -342.16921) (xy 440.155621 -342.133495)
			(xy 440.201502 -342.104009) (xy 440.251111 -342.081352) (xy 440.30344 -342.065986) (xy 440.357423 -342.058223)
			(xy 440.384692 -342.057736) (xy 441.248292 -342.057736) (xy 441.275563 -342.058203) (xy 441.329551 -342.065964)
			(xy 441.381884 -342.08133) (xy 441.431498 -342.103987) (xy 441.477382 -342.133474) (xy 441.518603 -342.169191)
			(xy 441.554321 -342.210411) (xy 441.58381 -342.256295) (xy 441.606468 -342.305908) (xy 441.621834 -342.358241)
			(xy 441.629596 -342.412229) (xy 441.629596 -342.466771) (xy 441.621834 -342.520759) (xy 441.606468 -342.573092)
			(xy 441.58381 -342.622705) (xy 441.554321 -342.668589) (xy 441.518603 -342.709809) (xy 441.477382 -342.745526)
			(xy 441.431498 -342.775013) (xy 441.381884 -342.79767) (xy 441.329551 -342.813036) (xy 441.275563 -342.820797)
			(xy 441.248292 -342.82126) (xy 440.384692 -342.82126) (xy 440.357423 -342.820777) (xy 440.30344 -342.813014)
			(xy 440.251111 -342.797648) (xy 440.201502 -342.774991) (xy 440.155621 -342.745505) (xy 440.114405 -342.70979)
			(xy 440.07869 -342.668572) (xy 440.049205 -342.622691) (xy 440.026549 -342.573082) (xy 440.011184 -342.520752)
			(xy 440.003422 -342.466769) (xy 438.520574 -342.466769) (xy 438.512813 -342.520748) (xy 438.497449 -342.573075)
			(xy 438.474795 -342.622683) (xy 438.445313 -342.668562) (xy 438.409601 -342.709778) (xy 438.368388 -342.745494)
			(xy 438.322511 -342.77498) (xy 438.272905 -342.797638) (xy 438.22058 -342.813006) (xy 438.1666 -342.820771)
			(xy 438.139332 -342.82126) (xy 437.275732 -342.82126) (xy 437.248459 -342.820803) (xy 437.194469 -342.813044)
			(xy 437.142132 -342.797681) (xy 437.092515 -342.775025) (xy 437.046627 -342.745538) (xy 437.005402 -342.70982)
			(xy 436.969681 -342.668599) (xy 436.940191 -342.622714) (xy 436.917531 -342.573098) (xy 436.902163 -342.520763)
			(xy 436.8944 -342.466773) (xy 435.411696 -342.466773) (xy 435.403934 -342.520761) (xy 435.388566 -342.573096)
			(xy 435.365907 -342.622711) (xy 435.336416 -342.668595) (xy 435.300696 -342.709816) (xy 435.259473 -342.745533)
			(xy 435.213586 -342.77502) (xy 435.16397 -342.797676) (xy 435.111634 -342.81304) (xy 435.057644 -342.820798)
			(xy 435.030372 -342.82126) (xy 434.166772 -342.82126) (xy 434.139504 -342.820776) (xy 434.085523 -342.813011)
			(xy 434.033196 -342.797643) (xy 433.98359 -342.774985) (xy 433.937712 -342.745498) (xy 433.896497 -342.709783)
			(xy 433.860785 -342.668566) (xy 433.831302 -342.622686) (xy 433.808647 -342.573077) (xy 433.793283 -342.52075)
			(xy 433.785522 -342.466768) (xy 432.302674 -342.466768) (xy 432.302674 -342.466769) (xy 432.294912 -342.520751)
			(xy 432.279548 -342.573079) (xy 432.256892 -342.622688) (xy 432.227408 -342.668568) (xy 432.191694 -342.709786)
			(xy 432.150478 -342.745501) (xy 432.104599 -342.774987) (xy 432.054991 -342.797643) (xy 432.002663 -342.81301)
			(xy 431.948681 -342.820773) (xy 431.921412 -342.82126) (xy 431.057812 -342.82126) (xy 431.03054 -342.820801)
			(xy 430.976552 -342.813041) (xy 430.924217 -342.797675) (xy 430.874603 -342.775018) (xy 430.828717 -342.745531)
			(xy 430.787495 -342.709813) (xy 430.751776 -342.668593) (xy 430.722288 -342.622708) (xy 430.699629 -342.573094)
			(xy 430.684262 -342.52076) (xy 430.6765 -342.466772) (xy 429.193796 -342.466772) (xy 429.193796 -342.466773)
			(xy 429.186033 -342.520764) (xy 429.170664 -342.5731) (xy 429.148003 -342.622716) (xy 429.118512 -342.668602)
			(xy 429.082789 -342.709823) (xy 429.041563 -342.74554) (xy 428.995674 -342.775026) (xy 428.946055 -342.797681)
			(xy 428.893717 -342.813043) (xy 428.839725 -342.8208) (xy 428.812452 -342.82126) (xy 427.948852 -342.82126)
			(xy 427.921585 -342.820774) (xy 427.867606 -342.813007) (xy 427.815282 -342.797637) (xy 427.765678 -342.774978)
			(xy 427.719802 -342.745491) (xy 427.67859 -342.709776) (xy 427.64288 -342.668559) (xy 427.613399 -342.62268)
			(xy 427.590746 -342.573073) (xy 427.575383 -342.520747) (xy 427.567622 -342.466767) (xy 426.084796 -342.466767)
			(xy 426.084796 -342.466771) (xy 426.077034 -342.520759) (xy 426.061668 -342.573092) (xy 426.03901 -342.622705)
			(xy 426.009521 -342.668589) (xy 425.973803 -342.709809) (xy 425.932582 -342.745526) (xy 425.886698 -342.775013)
			(xy 425.837084 -342.79767) (xy 425.784751 -342.813036) (xy 425.730763 -342.820797) (xy 425.703492 -342.82126)
			(xy 424.839892 -342.82126) (xy 424.812623 -342.820777) (xy 424.75864 -342.813014) (xy 424.706311 -342.797648)
			(xy 424.656702 -342.774991) (xy 424.610821 -342.745505) (xy 424.569605 -342.70979) (xy 424.53389 -342.668572)
			(xy 424.504405 -342.622691) (xy 424.481749 -342.573082) (xy 424.466384 -342.520752) (xy 424.458622 -342.466769)
			(xy 422.975774 -342.466769) (xy 422.968013 -342.520748) (xy 422.952649 -342.573075) (xy 422.929995 -342.622683)
			(xy 422.900513 -342.668562) (xy 422.864801 -342.709778) (xy 422.823588 -342.745494) (xy 422.777711 -342.77498)
			(xy 422.728105 -342.797638) (xy 422.67578 -342.813006) (xy 422.6218 -342.820771) (xy 422.594532 -342.82126)
			(xy 421.730932 -342.82126) (xy 421.703659 -342.820803) (xy 421.649669 -342.813044) (xy 421.597332 -342.797681)
			(xy 421.547715 -342.775025) (xy 421.501827 -342.745538) (xy 421.460602 -342.70982) (xy 421.424881 -342.668599)
			(xy 421.395391 -342.622714) (xy 421.372731 -342.573098) (xy 421.357363 -342.520763) (xy 421.3496 -342.466773)
			(xy 419.866896 -342.466773) (xy 419.859134 -342.520761) (xy 419.843766 -342.573096) (xy 419.821107 -342.622711)
			(xy 419.791616 -342.668595) (xy 419.755896 -342.709816) (xy 419.714673 -342.745533) (xy 419.668786 -342.77502)
			(xy 419.61917 -342.797676) (xy 419.566834 -342.81304) (xy 419.512844 -342.820798) (xy 419.485572 -342.82126)
			(xy 418.621972 -342.82126) (xy 418.594704 -342.820776) (xy 418.540723 -342.813011) (xy 418.488396 -342.797643)
			(xy 418.43879 -342.774985) (xy 418.392912 -342.745498) (xy 418.351697 -342.709783) (xy 418.315985 -342.668566)
			(xy 418.286502 -342.622686) (xy 418.263847 -342.573077) (xy 418.248483 -342.52075) (xy 418.240722 -342.466768)
			(xy 416.757874 -342.466768) (xy 416.757874 -342.466769) (xy 416.750112 -342.520751) (xy 416.734748 -342.573079)
			(xy 416.712092 -342.622688) (xy 416.682608 -342.668568) (xy 416.646894 -342.709786) (xy 416.605678 -342.745501)
			(xy 416.559799 -342.774987) (xy 416.510191 -342.797643) (xy 416.457863 -342.81301) (xy 416.403881 -342.820773)
			(xy 416.376612 -342.82126) (xy 415.513012 -342.82126) (xy 415.48574 -342.820801) (xy 415.431752 -342.813041)
			(xy 415.379417 -342.797675) (xy 415.329803 -342.775018) (xy 415.283917 -342.745531) (xy 415.242695 -342.709813)
			(xy 415.206976 -342.668593) (xy 415.177488 -342.622708) (xy 415.154829 -342.573094) (xy 415.139462 -342.52076)
			(xy 415.1317 -342.466772) (xy 413.648996 -342.466772) (xy 413.648996 -342.466773) (xy 413.641233 -342.520764)
			(xy 413.625864 -342.5731) (xy 413.603203 -342.622716) (xy 413.573712 -342.668602) (xy 413.537989 -342.709823)
			(xy 413.496763 -342.74554) (xy 413.450874 -342.775026) (xy 413.401255 -342.797681) (xy 413.348917 -342.813043)
			(xy 413.294925 -342.8208) (xy 413.267652 -342.82126) (xy 412.404052 -342.82126) (xy 412.376785 -342.820774)
			(xy 412.322806 -342.813007) (xy 412.270482 -342.797637) (xy 412.220878 -342.774978) (xy 412.175002 -342.745491)
			(xy 412.13379 -342.709776) (xy 412.09808 -342.668559) (xy 412.068599 -342.62268) (xy 412.045946 -342.573073)
			(xy 412.030583 -342.520747) (xy 412.022822 -342.466767) (xy 410.539996 -342.466767) (xy 410.539996 -342.466771)
			(xy 410.532234 -342.520759) (xy 410.516868 -342.573092) (xy 410.49421 -342.622705) (xy 410.464721 -342.668589)
			(xy 410.429003 -342.709809) (xy 410.387782 -342.745526) (xy 410.341898 -342.775013) (xy 410.292284 -342.79767)
			(xy 410.239951 -342.813036) (xy 410.185963 -342.820797) (xy 410.158692 -342.82126) (xy 409.295092 -342.82126)
			(xy 409.267823 -342.820777) (xy 409.21384 -342.813014) (xy 409.161511 -342.797648) (xy 409.111902 -342.774991)
			(xy 409.066021 -342.745505) (xy 409.024805 -342.70979) (xy 408.98909 -342.668572) (xy 408.959605 -342.622691)
			(xy 408.936949 -342.573082) (xy 408.921584 -342.520752) (xy 408.913822 -342.466769) (xy 403.522496 -342.466769)
			(xy 403.522496 -342.466772) (xy 403.514734 -342.52076) (xy 403.499367 -342.573094) (xy 403.476708 -342.622708)
			(xy 403.447218 -342.668593) (xy 403.411499 -342.709813) (xy 403.370277 -342.74553) (xy 403.324391 -342.775017)
			(xy 403.274775 -342.797674) (xy 403.222441 -342.813038) (xy 403.168452 -342.820798) (xy 403.14118 -342.82126)
			(xy 402.27758 -342.82126) (xy 402.250311 -342.820776) (xy 402.19633 -342.813012) (xy 402.144002 -342.797645)
			(xy 402.094394 -342.774988) (xy 402.048516 -342.745501) (xy 402.0073 -342.709786) (xy 401.971587 -342.668568)
			(xy 401.942103 -342.622688) (xy 401.919448 -342.573079) (xy 401.904084 -342.520751) (xy 401.896322 -342.466769)
			(xy 400.413474 -342.466769) (xy 400.405713 -342.52075) (xy 400.390348 -342.573078) (xy 400.367694 -342.622686)
			(xy 400.33821 -342.668566) (xy 400.302497 -342.709783) (xy 400.261282 -342.745498) (xy 400.215404 -342.774984)
			(xy 400.165796 -342.797641) (xy 400.113469 -342.813008) (xy 400.059488 -342.820772) (xy 400.03222 -342.82126)
			(xy 399.16862 -342.82126) (xy 399.141348 -342.820802) (xy 399.087359 -342.813042) (xy 399.035023 -342.797677)
			(xy 398.985407 -342.775021) (xy 398.939521 -342.745534) (xy 398.898298 -342.709816) (xy 398.862578 -342.668595)
			(xy 398.833089 -342.62271) (xy 398.81043 -342.573096) (xy 398.795062 -342.520761) (xy 398.7873 -342.466772)
			(xy 397.304596 -342.466772) (xy 397.304596 -342.466773) (xy 397.296833 -342.520763) (xy 397.281465 -342.573098)
			(xy 397.258805 -342.622714) (xy 397.229313 -342.668599) (xy 397.193592 -342.70982) (xy 397.152367 -342.745537)
			(xy 397.106479 -342.775024) (xy 397.056861 -342.797679) (xy 397.004524 -342.813042) (xy 396.950533 -342.820799)
			(xy 396.92326 -342.82126) (xy 396.05966 -342.82126) (xy 396.032392 -342.820775) (xy 395.978413 -342.813009)
			(xy 395.926088 -342.79764) (xy 395.876482 -342.774981) (xy 395.830606 -342.745494) (xy 395.789393 -342.709778)
			(xy 395.753682 -342.668562) (xy 395.7242 -342.622682) (xy 395.701546 -342.573075) (xy 395.686183 -342.520748)
			(xy 395.678422 -342.466768) (xy 394.195574 -342.466768) (xy 394.195574 -342.466769) (xy 394.187812 -342.520753)
			(xy 394.172447 -342.573082) (xy 394.149791 -342.622692) (xy 394.120305 -342.668572) (xy 394.08459 -342.70979)
			(xy 394.043372 -342.745505) (xy 393.997492 -342.774991) (xy 393.947882 -342.797647) (xy 393.895553 -342.813012)
			(xy 393.841569 -342.820774) (xy 393.8143 -342.82126) (xy 392.9507 -342.82126) (xy 392.92343 -342.820778)
			(xy 392.869447 -342.813016) (xy 392.817117 -342.79765) (xy 392.767506 -342.774994) (xy 392.721625 -342.745508)
			(xy 392.680407 -342.709793) (xy 392.644692 -342.668575) (xy 392.615206 -342.622694) (xy 392.59255 -342.573083)
			(xy 392.577184 -342.520753) (xy 392.569422 -342.46677) (xy 391.086574 -342.46677) (xy 391.078813 -342.520747)
			(xy 391.06345 -342.573073) (xy 391.040797 -342.622681) (xy 391.011315 -342.668559) (xy 390.975604 -342.709776)
			(xy 390.934391 -342.745491) (xy 390.888516 -342.774978) (xy 390.838911 -342.797636) (xy 390.786586 -342.813005)
			(xy 390.732607 -342.820771) (xy 390.70534 -342.82126) (xy 389.84174 -342.82126) (xy 389.814467 -342.820803)
			(xy 389.760476 -342.813046) (xy 389.708138 -342.797683) (xy 389.658519 -342.775027) (xy 389.61263 -342.745541)
			(xy 389.571405 -342.709823) (xy 389.535683 -342.668602) (xy 389.506192 -342.622716) (xy 389.483531 -342.5731)
			(xy 389.468163 -342.520764) (xy 389.4604 -342.466773) (xy 387.977696 -342.466773) (xy 387.969934 -342.52076)
			(xy 387.954567 -342.573094) (xy 387.931908 -342.622708) (xy 387.902418 -342.668593) (xy 387.866699 -342.709813)
			(xy 387.825477 -342.74553) (xy 387.779591 -342.775017) (xy 387.729975 -342.797674) (xy 387.677641 -342.813038)
			(xy 387.623652 -342.820798) (xy 387.59638 -342.82126) (xy 386.73278 -342.82126) (xy 386.705511 -342.820776)
			(xy 386.65153 -342.813012) (xy 386.599202 -342.797645) (xy 386.549594 -342.774988) (xy 386.503716 -342.745501)
			(xy 386.4625 -342.709786) (xy 386.426787 -342.668568) (xy 386.397303 -342.622688) (xy 386.374648 -342.573079)
			(xy 386.359284 -342.520751) (xy 386.351522 -342.466769) (xy 384.868674 -342.466769) (xy 384.860913 -342.52075)
			(xy 384.845548 -342.573078) (xy 384.822894 -342.622686) (xy 384.79341 -342.668566) (xy 384.757697 -342.709783)
			(xy 384.716482 -342.745498) (xy 384.670604 -342.774984) (xy 384.620996 -342.797641) (xy 384.568669 -342.813008)
			(xy 384.514688 -342.820772) (xy 384.48742 -342.82126) (xy 383.62382 -342.82126) (xy 383.596548 -342.820802)
			(xy 383.542559 -342.813042) (xy 383.490223 -342.797677) (xy 383.440607 -342.775021) (xy 383.394721 -342.745534)
			(xy 383.353498 -342.709816) (xy 383.317778 -342.668595) (xy 383.288289 -342.62271) (xy 383.26563 -342.573096)
			(xy 383.250262 -342.520761) (xy 383.2425 -342.466772) (xy 381.759796 -342.466772) (xy 381.759796 -342.466773)
			(xy 381.752033 -342.520763) (xy 381.736665 -342.573098) (xy 381.714005 -342.622714) (xy 381.684513 -342.668599)
			(xy 381.648792 -342.70982) (xy 381.607567 -342.745537) (xy 381.561679 -342.775024) (xy 381.512061 -342.797679)
			(xy 381.459724 -342.813042) (xy 381.405733 -342.820799) (xy 381.37846 -342.82126) (xy 380.51486 -342.82126)
			(xy 380.487592 -342.820775) (xy 380.433613 -342.813009) (xy 380.381288 -342.79764) (xy 380.331682 -342.774981)
			(xy 380.285806 -342.745494) (xy 380.244593 -342.709778) (xy 380.208882 -342.668562) (xy 380.1794 -342.622682)
			(xy 380.156746 -342.573075) (xy 380.141383 -342.520748) (xy 380.133622 -342.466768) (xy 378.650774 -342.466768)
			(xy 378.650774 -342.466769) (xy 378.643012 -342.520753) (xy 378.627647 -342.573082) (xy 378.604991 -342.622692)
			(xy 378.575505 -342.668572) (xy 378.53979 -342.70979) (xy 378.498572 -342.745505) (xy 378.452692 -342.774991)
			(xy 378.403082 -342.797647) (xy 378.350753 -342.813012) (xy 378.296769 -342.820774) (xy 378.2695 -342.82126)
			(xy 377.4059 -342.82126) (xy 377.37863 -342.820778) (xy 377.324647 -342.813016) (xy 377.272317 -342.79765)
			(xy 377.222706 -342.774994) (xy 377.176825 -342.745508) (xy 377.135607 -342.709793) (xy 377.099892 -342.668575)
			(xy 377.070406 -342.622694) (xy 377.04775 -342.573083) (xy 377.032384 -342.520753) (xy 377.024622 -342.46677)
			(xy 375.541774 -342.46677) (xy 375.534013 -342.520747) (xy 375.51865 -342.573073) (xy 375.495997 -342.622681)
			(xy 375.466515 -342.668559) (xy 375.430804 -342.709776) (xy 375.389591 -342.745491) (xy 375.343716 -342.774978)
			(xy 375.294111 -342.797636) (xy 375.241786 -342.813005) (xy 375.187807 -342.820771) (xy 375.16054 -342.82126)
			(xy 374.29694 -342.82126) (xy 374.269667 -342.820803) (xy 374.215676 -342.813046) (xy 374.163338 -342.797683)
			(xy 374.113719 -342.775027) (xy 374.06783 -342.745541) (xy 374.026605 -342.709823) (xy 373.990883 -342.668602)
			(xy 373.961392 -342.622716) (xy 373.938731 -342.5731) (xy 373.923363 -342.520764) (xy 373.9156 -342.466773)
			(xy 372.432896 -342.466773) (xy 372.425134 -342.52076) (xy 372.409767 -342.573094) (xy 372.387108 -342.622708)
			(xy 372.357618 -342.668593) (xy 372.321899 -342.709813) (xy 372.280677 -342.74553) (xy 372.234791 -342.775017)
			(xy 372.185175 -342.797674) (xy 372.132841 -342.813038) (xy 372.078852 -342.820798) (xy 372.05158 -342.82126)
			(xy 371.18798 -342.82126) (xy 371.160711 -342.820776) (xy 371.10673 -342.813012) (xy 371.054402 -342.797645)
			(xy 371.004794 -342.774988) (xy 370.958916 -342.745501) (xy 370.9177 -342.709786) (xy 370.881987 -342.668568)
			(xy 370.852503 -342.622688) (xy 370.829848 -342.573079) (xy 370.814484 -342.520751) (xy 370.806722 -342.466769)
			(xy 344.837274 -342.466769) (xy 344.829512 -342.520752) (xy 344.814147 -342.573081) (xy 344.791491 -342.622691)
			(xy 344.762006 -342.668571) (xy 344.726291 -342.709788) (xy 344.685074 -342.745503) (xy 344.639194 -342.774989)
			(xy 344.589585 -342.797646) (xy 344.537256 -342.813011) (xy 344.483273 -342.820773) (xy 344.456004 -342.82126)
			(xy 343.592404 -342.82126) (xy 343.565133 -342.820801) (xy 343.511145 -342.813039) (xy 343.458812 -342.797673)
			(xy 343.409198 -342.775016) (xy 343.363313 -342.745528) (xy 343.322093 -342.70981) (xy 343.286374 -342.66859)
			(xy 343.256886 -342.622706) (xy 343.234228 -342.573092) (xy 343.218862 -342.520759) (xy 343.2111 -342.466771)
			(xy 341.728273 -342.466771) (xy 341.720513 -342.520747) (xy 341.70515 -342.573072) (xy 341.682497 -342.622679)
			(xy 341.653016 -342.668558) (xy 341.617305 -342.709774) (xy 341.576093 -342.745489) (xy 341.530218 -342.774976)
			(xy 341.480614 -342.797635) (xy 341.42829 -342.813004) (xy 341.374311 -342.820771) (xy 341.347044 -342.82126)
			(xy 340.483444 -342.82126) (xy 340.456171 -342.820804) (xy 340.402179 -342.813046) (xy 340.349841 -342.797684)
			(xy 340.300222 -342.775029) (xy 340.254332 -342.745542) (xy 340.213107 -342.709824) (xy 340.177384 -342.668603)
			(xy 340.147892 -342.622717) (xy 340.125232 -342.573101) (xy 340.109863 -342.520764) (xy 340.1021 -342.466773)
			(xy 338.619396 -342.466773) (xy 338.611634 -342.52076) (xy 338.596267 -342.573093) (xy 338.573608 -342.622707)
			(xy 338.544119 -342.668591) (xy 338.5084 -342.709812) (xy 338.467179 -342.745529) (xy 338.421293 -342.775016)
			(xy 338.371678 -342.797673) (xy 338.319344 -342.813037) (xy 338.265356 -342.820798) (xy 338.238084 -342.82126)
			(xy 337.374484 -342.82126) (xy 337.347215 -342.820776) (xy 337.293233 -342.813013) (xy 337.240905 -342.797646)
			(xy 337.191297 -342.774989) (xy 337.145418 -342.745502) (xy 337.104202 -342.709787) (xy 337.068488 -342.66857)
			(xy 337.039003 -342.622689) (xy 337.016348 -342.57308) (xy 337.000984 -342.520751) (xy 336.993222 -342.466769)
			(xy 335.510374 -342.466769) (xy 335.502613 -342.520749) (xy 335.487249 -342.573077) (xy 335.464594 -342.622685)
			(xy 335.435111 -342.668565) (xy 335.399398 -342.709781) (xy 335.358184 -342.745496) (xy 335.312306 -342.774983)
			(xy 335.262699 -342.79764) (xy 335.210373 -342.813008) (xy 335.156392 -342.820772) (xy 335.129124 -342.82126)
			(xy 334.265524 -342.82126) (xy 334.238252 -342.820802) (xy 334.184262 -342.813043) (xy 334.131926 -342.797678)
			(xy 334.08231 -342.775022) (xy 334.036423 -342.745535) (xy 333.9952 -342.709817) (xy 333.959479 -342.668596)
			(xy 333.929989 -342.622711) (xy 333.90733 -342.573096) (xy 333.891962 -342.520761) (xy 333.8842 -342.466772)
			(xy 332.401496 -342.466772) (xy 332.393733 -342.520762) (xy 332.378365 -342.573098) (xy 332.355705 -342.622713)
			(xy 332.326214 -342.668598) (xy 332.290493 -342.709819) (xy 332.249269 -342.745536) (xy 332.203381 -342.775023)
			(xy 332.153764 -342.797678) (xy 332.101427 -342.813041) (xy 332.047437 -342.820799) (xy 332.020164 -342.82126)
			(xy 331.156564 -342.82126) (xy 331.129296 -342.820775) (xy 331.075316 -342.813009) (xy 331.022991 -342.797641)
			(xy 330.973385 -342.774982) (xy 330.927508 -342.745495) (xy 330.886295 -342.70978) (xy 330.850583 -342.668563)
			(xy 330.8211 -342.622684) (xy 330.798447 -342.573076) (xy 330.783083 -342.520749) (xy 330.775322 -342.466768)
			(xy 329.292474 -342.466768) (xy 329.292474 -342.466769) (xy 329.284712 -342.520752) (xy 329.269347 -342.573081)
			(xy 329.246691 -342.622691) (xy 329.217206 -342.668571) (xy 329.181491 -342.709788) (xy 329.140274 -342.745503)
			(xy 329.094394 -342.774989) (xy 329.044785 -342.797646) (xy 328.992456 -342.813011) (xy 328.938473 -342.820773)
			(xy 328.911204 -342.82126) (xy 328.047604 -342.82126) (xy 328.020333 -342.820801) (xy 327.966345 -342.813039)
			(xy 327.914012 -342.797673) (xy 327.864398 -342.775016) (xy 327.818513 -342.745528) (xy 327.777293 -342.70981)
			(xy 327.741574 -342.66859) (xy 327.712086 -342.622706) (xy 327.689428 -342.573092) (xy 327.674062 -342.520759)
			(xy 327.6663 -342.466771) (xy 326.183473 -342.466771) (xy 326.175713 -342.520747) (xy 326.16035 -342.573072)
			(xy 326.137697 -342.622679) (xy 326.108216 -342.668558) (xy 326.072505 -342.709774) (xy 326.031293 -342.745489)
			(xy 325.985418 -342.774976) (xy 325.935814 -342.797635) (xy 325.88349 -342.813004) (xy 325.829511 -342.820771)
			(xy 325.802244 -342.82126) (xy 324.938644 -342.82126) (xy 324.911371 -342.820804) (xy 324.857379 -342.813046)
			(xy 324.805041 -342.797684) (xy 324.755422 -342.775029) (xy 324.709532 -342.745542) (xy 324.668307 -342.709824)
			(xy 324.632584 -342.668603) (xy 324.603092 -342.622717) (xy 324.580432 -342.573101) (xy 324.565063 -342.520764)
			(xy 324.5573 -342.466773) (xy 323.074596 -342.466773) (xy 323.066834 -342.52076) (xy 323.051467 -342.573093)
			(xy 323.028808 -342.622707) (xy 322.999319 -342.668591) (xy 322.9636 -342.709812) (xy 322.922379 -342.745529)
			(xy 322.876493 -342.775016) (xy 322.826878 -342.797673) (xy 322.774544 -342.813037) (xy 322.720556 -342.820798)
			(xy 322.693284 -342.82126) (xy 321.829684 -342.82126) (xy 321.802415 -342.820776) (xy 321.748433 -342.813013)
			(xy 321.696105 -342.797646) (xy 321.646497 -342.774989) (xy 321.600618 -342.745502) (xy 321.559402 -342.709787)
			(xy 321.523688 -342.66857) (xy 321.494203 -342.622689) (xy 321.471548 -342.57308) (xy 321.456184 -342.520751)
			(xy 321.448422 -342.466769) (xy 319.965574 -342.466769) (xy 319.957813 -342.520749) (xy 319.942449 -342.573077)
			(xy 319.919794 -342.622685) (xy 319.890311 -342.668565) (xy 319.854598 -342.709781) (xy 319.813384 -342.745496)
			(xy 319.767506 -342.774983) (xy 319.717899 -342.79764) (xy 319.665573 -342.813008) (xy 319.611592 -342.820772)
			(xy 319.584324 -342.82126) (xy 318.720724 -342.82126) (xy 318.693452 -342.820802) (xy 318.639462 -342.813043)
			(xy 318.587126 -342.797678) (xy 318.53751 -342.775022) (xy 318.491623 -342.745535) (xy 318.4504 -342.709817)
			(xy 318.414679 -342.668596) (xy 318.385189 -342.622711) (xy 318.36253 -342.573096) (xy 318.347162 -342.520761)
			(xy 318.3394 -342.466772) (xy 316.856696 -342.466772) (xy 316.848933 -342.520762) (xy 316.833565 -342.573098)
			(xy 316.810905 -342.622713) (xy 316.781414 -342.668598) (xy 316.745693 -342.709819) (xy 316.704469 -342.745536)
			(xy 316.658581 -342.775023) (xy 316.608964 -342.797678) (xy 316.556627 -342.813041) (xy 316.502637 -342.820799)
			(xy 316.475364 -342.82126) (xy 315.611764 -342.82126) (xy 315.584496 -342.820775) (xy 315.530516 -342.813009)
			(xy 315.478191 -342.797641) (xy 315.428585 -342.774982) (xy 315.382708 -342.745495) (xy 315.341495 -342.70978)
			(xy 315.305783 -342.668563) (xy 315.2763 -342.622684) (xy 315.253647 -342.573076) (xy 315.238283 -342.520749)
			(xy 315.230522 -342.466768) (xy 313.747674 -342.466768) (xy 313.747674 -342.466769) (xy 313.739912 -342.520752)
			(xy 313.724547 -342.573081) (xy 313.701891 -342.622691) (xy 313.672406 -342.668571) (xy 313.636691 -342.709788)
			(xy 313.595474 -342.745503) (xy 313.549594 -342.774989) (xy 313.499985 -342.797646) (xy 313.447656 -342.813011)
			(xy 313.393673 -342.820773) (xy 313.366404 -342.82126) (xy 312.502804 -342.82126) (xy 312.475533 -342.820801)
			(xy 312.421545 -342.813039) (xy 312.369212 -342.797673) (xy 312.319598 -342.775016) (xy 312.273713 -342.745528)
			(xy 312.232493 -342.70981) (xy 312.196774 -342.66859) (xy 312.167286 -342.622706) (xy 312.144628 -342.573092)
			(xy 312.129262 -342.520759) (xy 312.1215 -342.466771) (xy 300.231574 -342.466771) (xy 300.223812 -342.520752)
			(xy 300.208447 -342.573081) (xy 300.185791 -342.622691) (xy 300.156305 -342.668572) (xy 300.120591 -342.709789)
			(xy 300.079373 -342.745504) (xy 300.033493 -342.77499) (xy 299.983883 -342.797646) (xy 299.931554 -342.813012)
			(xy 299.877571 -342.820773) (xy 299.850302 -342.82126) (xy 298.986702 -342.82126) (xy 298.959431 -342.820801)
			(xy 298.905443 -342.813039) (xy 298.85311 -342.797673) (xy 298.803497 -342.775015) (xy 298.757612 -342.745527)
			(xy 298.716392 -342.70981) (xy 298.680674 -342.668589) (xy 298.651186 -342.622705) (xy 298.628528 -342.573092)
			(xy 298.613162 -342.520759) (xy 298.605399 -342.466771) (xy 297.122573 -342.466771) (xy 297.114813 -342.520747)
			(xy 297.09945 -342.573073) (xy 297.076797 -342.62268) (xy 297.047315 -342.668559) (xy 297.011605 -342.709775)
			(xy 296.970392 -342.74549) (xy 296.924517 -342.774977) (xy 296.874912 -342.797635) (xy 296.822588 -342.813004)
			(xy 296.768609 -342.820771) (xy 296.741342 -342.82126) (xy 295.877742 -342.82126) (xy 295.850469 -342.820803)
			(xy 295.796477 -342.813046) (xy 295.744139 -342.797683) (xy 295.694521 -342.775028) (xy 295.648631 -342.745541)
			(xy 295.607406 -342.709824) (xy 295.571684 -342.668602) (xy 295.542192 -342.622716) (xy 295.519531 -342.5731)
			(xy 295.504163 -342.520764) (xy 295.4964 -342.466773) (xy 294.013696 -342.466773) (xy 294.005934 -342.52076)
			(xy 293.990567 -342.573094) (xy 293.967908 -342.622708) (xy 293.938419 -342.668592) (xy 293.9027 -342.709812)
			(xy 293.861478 -342.74553) (xy 293.815592 -342.775017) (xy 293.765977 -342.797673) (xy 293.713642 -342.813038)
			(xy 293.659654 -342.820798) (xy 293.632382 -342.82126) (xy 292.768782 -342.82126) (xy 292.741513 -342.820776)
			(xy 292.687531 -342.813013) (xy 292.635204 -342.797646) (xy 292.585596 -342.774988) (xy 292.539717 -342.745502)
			(xy 292.498501 -342.709786) (xy 292.462787 -342.668569) (xy 292.433303 -342.622689) (xy 292.410648 -342.573079)
			(xy 292.395284 -342.520751) (xy 292.387522 -342.466769) (xy 290.904674 -342.466769) (xy 290.896913 -342.52075)
			(xy 290.881548 -342.573077) (xy 290.858894 -342.622686) (xy 290.82941 -342.668565) (xy 290.793698 -342.709782)
			(xy 290.752483 -342.745497) (xy 290.706605 -342.774983) (xy 290.656998 -342.797641) (xy 290.604671 -342.813008)
			(xy 290.55069 -342.820772) (xy 290.523422 -342.82126) (xy 289.659822 -342.82126) (xy 289.63255 -342.820802)
			(xy 289.57856 -342.813042) (xy 289.526225 -342.797678) (xy 289.476609 -342.775021) (xy 289.430722 -342.745534)
			(xy 289.389499 -342.709817) (xy 289.353779 -342.668596) (xy 289.324289 -342.622711) (xy 289.30163 -342.573096)
			(xy 289.286262 -342.520761) (xy 289.2785 -342.466772) (xy 287.795796 -342.466772) (xy 287.795796 -342.466773)
			(xy 287.788033 -342.520763) (xy 287.772665 -342.573098) (xy 287.750005 -342.622713) (xy 287.720514 -342.668599)
			(xy 287.684793 -342.70982) (xy 287.643568 -342.745537) (xy 287.59768 -342.775023) (xy 287.548062 -342.797679)
			(xy 287.495725 -342.813041) (xy 287.441735 -342.820799) (xy 287.414462 -342.82126) (xy 286.550862 -342.82126)
			(xy 286.523594 -342.820775) (xy 286.469614 -342.813009) (xy 286.417289 -342.79764) (xy 286.367684 -342.774982)
			(xy 286.321807 -342.745495) (xy 286.280594 -342.709779) (xy 286.244883 -342.668562) (xy 286.2154 -342.622683)
			(xy 286.192747 -342.573075) (xy 286.177383 -342.520748) (xy 286.169622 -342.466768) (xy 284.686774 -342.466768)
			(xy 284.686774 -342.466769) (xy 284.679012 -342.520752) (xy 284.663647 -342.573081) (xy 284.640991 -342.622691)
			(xy 284.611505 -342.668572) (xy 284.575791 -342.709789) (xy 284.534573 -342.745504) (xy 284.488693 -342.77499)
			(xy 284.439083 -342.797646) (xy 284.386754 -342.813012) (xy 284.332771 -342.820773) (xy 284.305502 -342.82126)
			(xy 283.441902 -342.82126) (xy 283.414631 -342.820801) (xy 283.360643 -342.813039) (xy 283.30831 -342.797673)
			(xy 283.258697 -342.775015) (xy 283.212812 -342.745527) (xy 283.171592 -342.70981) (xy 283.135874 -342.668589)
			(xy 283.106386 -342.622705) (xy 283.083728 -342.573092) (xy 283.068362 -342.520759) (xy 283.060599 -342.466771)
			(xy 281.577773 -342.466771) (xy 281.570013 -342.520747) (xy 281.55465 -342.573073) (xy 281.531997 -342.62268)
			(xy 281.502515 -342.668559) (xy 281.466805 -342.709775) (xy 281.425592 -342.74549) (xy 281.379717 -342.774977)
			(xy 281.330112 -342.797635) (xy 281.277788 -342.813004) (xy 281.223809 -342.820771) (xy 281.196542 -342.82126)
			(xy 280.332942 -342.82126) (xy 280.305669 -342.820803) (xy 280.251677 -342.813046) (xy 280.199339 -342.797683)
			(xy 280.149721 -342.775028) (xy 280.103831 -342.745541) (xy 280.062606 -342.709824) (xy 280.026884 -342.668602)
			(xy 279.997392 -342.622716) (xy 279.974731 -342.5731) (xy 279.959363 -342.520764) (xy 279.9516 -342.466773)
			(xy 278.468896 -342.466773) (xy 278.461134 -342.52076) (xy 278.445767 -342.573094) (xy 278.423108 -342.622708)
			(xy 278.393619 -342.668592) (xy 278.3579 -342.709812) (xy 278.316678 -342.74553) (xy 278.270792 -342.775017)
			(xy 278.221177 -342.797673) (xy 278.168842 -342.813038) (xy 278.114854 -342.820798) (xy 278.087582 -342.82126)
			(xy 277.223982 -342.82126) (xy 277.196713 -342.820776) (xy 277.142731 -342.813013) (xy 277.090404 -342.797646)
			(xy 277.040796 -342.774988) (xy 276.994917 -342.745502) (xy 276.953701 -342.709786) (xy 276.917987 -342.668569)
			(xy 276.888503 -342.622689) (xy 276.865848 -342.573079) (xy 276.850484 -342.520751) (xy 276.842722 -342.466769)
			(xy 275.359874 -342.466769) (xy 275.352113 -342.52075) (xy 275.336748 -342.573077) (xy 275.314094 -342.622686)
			(xy 275.28461 -342.668565) (xy 275.248898 -342.709782) (xy 275.207683 -342.745497) (xy 275.161805 -342.774983)
			(xy 275.112198 -342.797641) (xy 275.059871 -342.813008) (xy 275.00589 -342.820772) (xy 274.978622 -342.82126)
			(xy 274.115022 -342.82126) (xy 274.08775 -342.820802) (xy 274.03376 -342.813042) (xy 273.981425 -342.797678)
			(xy 273.931809 -342.775021) (xy 273.885922 -342.745534) (xy 273.844699 -342.709817) (xy 273.808979 -342.668596)
			(xy 273.779489 -342.622711) (xy 273.75683 -342.573096) (xy 273.741462 -342.520761) (xy 273.7337 -342.466772)
			(xy 272.250996 -342.466772) (xy 272.250996 -342.466773) (xy 272.243233 -342.520763) (xy 272.227865 -342.573098)
			(xy 272.205205 -342.622713) (xy 272.175714 -342.668599) (xy 272.139993 -342.70982) (xy 272.098768 -342.745537)
			(xy 272.05288 -342.775023) (xy 272.003262 -342.797679) (xy 271.950925 -342.813041) (xy 271.896935 -342.820799)
			(xy 271.869662 -342.82126) (xy 271.006062 -342.82126) (xy 270.978794 -342.820775) (xy 270.924814 -342.813009)
			(xy 270.872489 -342.79764) (xy 270.822884 -342.774982) (xy 270.777007 -342.745495) (xy 270.735794 -342.709779)
			(xy 270.700083 -342.668562) (xy 270.6706 -342.622683) (xy 270.647947 -342.573075) (xy 270.632583 -342.520748)
			(xy 270.624822 -342.466768) (xy 269.141974 -342.466768) (xy 269.141974 -342.466769) (xy 269.134212 -342.520752)
			(xy 269.118847 -342.573081) (xy 269.096191 -342.622691) (xy 269.066705 -342.668572) (xy 269.030991 -342.709789)
			(xy 268.989773 -342.745504) (xy 268.943893 -342.77499) (xy 268.894283 -342.797646) (xy 268.841954 -342.813012)
			(xy 268.787971 -342.820773) (xy 268.760702 -342.82126) (xy 267.897102 -342.82126) (xy 267.869831 -342.820801)
			(xy 267.815843 -342.813039) (xy 267.76351 -342.797673) (xy 267.713897 -342.775015) (xy 267.668012 -342.745527)
			(xy 267.626792 -342.70981) (xy 267.591074 -342.668589) (xy 267.561586 -342.622705) (xy 267.538928 -342.573092)
			(xy 267.523562 -342.520759) (xy 267.515799 -342.466771) (xy 256.581015 -342.466771) (xy 256.573351 -342.471196)
			(xy 256.517947 -342.494145) (xy 256.460022 -342.509666) (xy 256.400566 -342.517494) (xy 256.340598 -342.517494)
			(xy 256.281142 -342.509666) (xy 256.223217 -342.494145) (xy 256.167813 -342.471196) (xy 256.115879 -342.441212)
			(xy 256.068303 -342.404706) (xy 256.025898 -342.362301) (xy 255.989392 -342.314725) (xy 255.959408 -342.262791)
			(xy 255.936459 -342.207387) (xy 255.920938 -342.149462) (xy 255.91311 -342.090006) (xy 255.91262 -342.060022)
			(xy 197.28821 -342.060022) (xy 197.329534 -342.06596) (xy 197.38187 -342.081324) (xy 197.431486 -342.10398)
			(xy 197.477373 -342.133467) (xy 197.518596 -342.169184) (xy 197.554316 -342.210405) (xy 197.583807 -342.256289)
			(xy 197.606466 -342.305904) (xy 197.621834 -342.358239) (xy 197.629596 -342.412228) (xy 197.629596 -342.466772)
			(xy 197.621834 -342.520761) (xy 197.606466 -342.573096) (xy 197.583807 -342.622711) (xy 197.554316 -342.668595)
			(xy 197.518596 -342.709816) (xy 197.477373 -342.745533) (xy 197.431486 -342.77502) (xy 197.38187 -342.797676)
			(xy 197.329534 -342.81304) (xy 197.275544 -342.820798) (xy 197.248272 -342.82126) (xy 196.384672 -342.82126)
			(xy 196.357404 -342.820776) (xy 196.303423 -342.813011) (xy 196.251096 -342.797643) (xy 196.20149 -342.774985)
			(xy 196.155612 -342.745498) (xy 196.114397 -342.709783) (xy 196.078685 -342.668566) (xy 196.049202 -342.622686)
			(xy 196.026547 -342.573077) (xy 196.011183 -342.52075) (xy 196.003422 -342.466768) (xy 194.520574 -342.466768)
			(xy 194.520574 -342.466769) (xy 194.512812 -342.520751) (xy 194.497448 -342.573079) (xy 194.474792 -342.622688)
			(xy 194.445308 -342.668568) (xy 194.409594 -342.709786) (xy 194.368378 -342.745501) (xy 194.322499 -342.774987)
			(xy 194.272891 -342.797643) (xy 194.220563 -342.81301) (xy 194.166581 -342.820773) (xy 194.139312 -342.82126)
			(xy 193.275712 -342.82126) (xy 193.24844 -342.820801) (xy 193.194452 -342.813041) (xy 193.142117 -342.797675)
			(xy 193.092503 -342.775018) (xy 193.046617 -342.745531) (xy 193.005395 -342.709813) (xy 192.969676 -342.668593)
			(xy 192.940188 -342.622708) (xy 192.917529 -342.573094) (xy 192.902162 -342.52076) (xy 192.8944 -342.466772)
			(xy 191.411696 -342.466772) (xy 191.411696 -342.466773) (xy 191.403933 -342.520764) (xy 191.388564 -342.5731)
			(xy 191.365903 -342.622716) (xy 191.336412 -342.668602) (xy 191.300689 -342.709823) (xy 191.259463 -342.74554)
			(xy 191.213574 -342.775026) (xy 191.163955 -342.797681) (xy 191.111617 -342.813043) (xy 191.057625 -342.8208)
			(xy 191.030352 -342.82126) (xy 190.166752 -342.82126) (xy 190.139485 -342.820774) (xy 190.085506 -342.813007)
			(xy 190.033182 -342.797637) (xy 189.983578 -342.774978) (xy 189.937702 -342.745491) (xy 189.89649 -342.709776)
			(xy 189.86078 -342.668559) (xy 189.831299 -342.62268) (xy 189.808646 -342.573073) (xy 189.793283 -342.520747)
			(xy 189.785522 -342.466767) (xy 188.302696 -342.466767) (xy 188.302696 -342.466771) (xy 188.294934 -342.520759)
			(xy 188.279568 -342.573092) (xy 188.25691 -342.622705) (xy 188.227421 -342.668589) (xy 188.191703 -342.709809)
			(xy 188.150482 -342.745526) (xy 188.104598 -342.775013) (xy 188.054984 -342.79767) (xy 188.002651 -342.813036)
			(xy 187.948663 -342.820797) (xy 187.921392 -342.82126) (xy 187.057792 -342.82126) (xy 187.030523 -342.820777)
			(xy 186.97654 -342.813014) (xy 186.924211 -342.797648) (xy 186.874602 -342.774991) (xy 186.828721 -342.745505)
			(xy 186.787505 -342.70979) (xy 186.75179 -342.668572) (xy 186.722305 -342.622691) (xy 186.699649 -342.573082)
			(xy 186.684284 -342.520752) (xy 186.676522 -342.466769) (xy 185.193674 -342.466769) (xy 185.185913 -342.520748)
			(xy 185.170549 -342.573075) (xy 185.147895 -342.622683) (xy 185.118413 -342.668562) (xy 185.082701 -342.709778)
			(xy 185.041488 -342.745494) (xy 184.995611 -342.77498) (xy 184.946005 -342.797638) (xy 184.89368 -342.813006)
			(xy 184.8397 -342.820771) (xy 184.812432 -342.82126) (xy 183.948832 -342.82126) (xy 183.921559 -342.820803)
			(xy 183.867569 -342.813044) (xy 183.815232 -342.797681) (xy 183.765615 -342.775025) (xy 183.719727 -342.745538)
			(xy 183.678502 -342.70982) (xy 183.642781 -342.668599) (xy 183.613291 -342.622714) (xy 183.590631 -342.573098)
			(xy 183.575263 -342.520763) (xy 183.5675 -342.466773) (xy 182.084796 -342.466773) (xy 182.077034 -342.520761)
			(xy 182.061666 -342.573096) (xy 182.039007 -342.622711) (xy 182.009516 -342.668595) (xy 181.973796 -342.709816)
			(xy 181.932573 -342.745533) (xy 181.886686 -342.77502) (xy 181.83707 -342.797676) (xy 181.784734 -342.81304)
			(xy 181.730744 -342.820798) (xy 181.703472 -342.82126) (xy 180.839872 -342.82126) (xy 180.812604 -342.820776)
			(xy 180.758623 -342.813011) (xy 180.706296 -342.797643) (xy 180.65669 -342.774985) (xy 180.610812 -342.745498)
			(xy 180.569597 -342.709783) (xy 180.533885 -342.668566) (xy 180.504402 -342.622686) (xy 180.481747 -342.573077)
			(xy 180.466383 -342.52075) (xy 180.458622 -342.466768) (xy 178.975774 -342.466768) (xy 178.975774 -342.466769)
			(xy 178.968012 -342.520751) (xy 178.952648 -342.573079) (xy 178.929992 -342.622688) (xy 178.900508 -342.668568)
			(xy 178.864794 -342.709786) (xy 178.823578 -342.745501) (xy 178.777699 -342.774987) (xy 178.728091 -342.797643)
			(xy 178.675763 -342.81301) (xy 178.621781 -342.820773) (xy 178.594512 -342.82126) (xy 177.730912 -342.82126)
			(xy 177.70364 -342.820801) (xy 177.649652 -342.813041) (xy 177.597317 -342.797675) (xy 177.547703 -342.775018)
			(xy 177.501817 -342.745531) (xy 177.460595 -342.709813) (xy 177.424876 -342.668593) (xy 177.395388 -342.622708)
			(xy 177.372729 -342.573094) (xy 177.357362 -342.52076) (xy 177.3496 -342.466772) (xy 175.866896 -342.466772)
			(xy 175.866896 -342.466773) (xy 175.859133 -342.520764) (xy 175.843764 -342.5731) (xy 175.821103 -342.622716)
			(xy 175.791612 -342.668602) (xy 175.755889 -342.709823) (xy 175.714663 -342.74554) (xy 175.668774 -342.775026)
			(xy 175.619155 -342.797681) (xy 175.566817 -342.813043) (xy 175.512825 -342.8208) (xy 175.485552 -342.82126)
			(xy 174.621952 -342.82126) (xy 174.594685 -342.820774) (xy 174.540706 -342.813007) (xy 174.488382 -342.797637)
			(xy 174.438778 -342.774978) (xy 174.392902 -342.745491) (xy 174.35169 -342.709776) (xy 174.31598 -342.668559)
			(xy 174.286499 -342.62268) (xy 174.263846 -342.573073) (xy 174.248483 -342.520747) (xy 174.240722 -342.466767)
			(xy 172.757896 -342.466767) (xy 172.757896 -342.466771) (xy 172.750134 -342.520759) (xy 172.734768 -342.573092)
			(xy 172.71211 -342.622705) (xy 172.682621 -342.668589) (xy 172.646903 -342.709809) (xy 172.605682 -342.745526)
			(xy 172.559798 -342.775013) (xy 172.510184 -342.79767) (xy 172.457851 -342.813036) (xy 172.403863 -342.820797)
			(xy 172.376592 -342.82126) (xy 171.512992 -342.82126) (xy 171.485723 -342.820777) (xy 171.43174 -342.813014)
			(xy 171.379411 -342.797648) (xy 171.329802 -342.774991) (xy 171.283921 -342.745505) (xy 171.242705 -342.70979)
			(xy 171.20699 -342.668572) (xy 171.177505 -342.622691) (xy 171.154849 -342.573082) (xy 171.139484 -342.520752)
			(xy 171.131722 -342.466769) (xy 169.648874 -342.466769) (xy 169.641113 -342.520748) (xy 169.625749 -342.573075)
			(xy 169.603095 -342.622683) (xy 169.573613 -342.668562) (xy 169.537901 -342.709778) (xy 169.496688 -342.745494)
			(xy 169.450811 -342.77498) (xy 169.401205 -342.797638) (xy 169.34888 -342.813006) (xy 169.2949 -342.820771)
			(xy 169.267632 -342.82126) (xy 168.404032 -342.82126) (xy 168.376759 -342.820803) (xy 168.322769 -342.813044)
			(xy 168.270432 -342.797681) (xy 168.220815 -342.775025) (xy 168.174927 -342.745538) (xy 168.133702 -342.70982)
			(xy 168.097981 -342.668599) (xy 168.068491 -342.622714) (xy 168.045831 -342.573098) (xy 168.030463 -342.520763)
			(xy 168.0227 -342.466773) (xy 166.539996 -342.466773) (xy 166.532234 -342.520761) (xy 166.516866 -342.573096)
			(xy 166.494207 -342.622711) (xy 166.464716 -342.668595) (xy 166.428996 -342.709816) (xy 166.387773 -342.745533)
			(xy 166.341886 -342.77502) (xy 166.29227 -342.797676) (xy 166.239934 -342.81304) (xy 166.185944 -342.820798)
			(xy 166.158672 -342.82126) (xy 165.295072 -342.82126) (xy 165.267804 -342.820776) (xy 165.213823 -342.813011)
			(xy 165.161496 -342.797643) (xy 165.11189 -342.774985) (xy 165.066012 -342.745498) (xy 165.024797 -342.709783)
			(xy 164.989085 -342.668566) (xy 164.959602 -342.622686) (xy 164.936947 -342.573077) (xy 164.921583 -342.52075)
			(xy 164.913822 -342.466768) (xy 144.196574 -342.466768) (xy 144.196574 -342.466769) (xy 144.188812 -342.520751)
			(xy 144.173447 -342.57308) (xy 144.150792 -342.622689) (xy 144.121307 -342.66857) (xy 144.085593 -342.709787)
			(xy 144.044376 -342.745502) (xy 143.998497 -342.774988) (xy 143.948888 -342.797645) (xy 143.896559 -342.81301)
			(xy 143.842577 -342.820773) (xy 143.815308 -342.82126) (xy 142.951708 -342.82126) (xy 142.924436 -342.820801)
			(xy 142.870448 -342.81304) (xy 142.818115 -342.797674) (xy 142.7685 -342.775017) (xy 142.722615 -342.745529)
			(xy 142.681394 -342.709812) (xy 142.645675 -342.668591) (xy 142.616187 -342.622707) (xy 142.593529 -342.573093)
			(xy 142.578162 -342.520759) (xy 142.5704 -342.466772) (xy 141.087573 -342.466772) (xy 141.079813 -342.520746)
			(xy 141.064451 -342.573072) (xy 141.041798 -342.622678) (xy 141.012317 -342.668557) (xy 140.976607 -342.709773)
			(xy 140.935395 -342.745488) (xy 140.88952 -342.774975) (xy 140.839917 -342.797634) (xy 140.787593 -342.813003)
			(xy 140.733615 -342.82077) (xy 140.706348 -342.82126) (xy 139.842748 -342.82126) (xy 139.815475 -342.820804)
			(xy 139.761482 -342.813047) (xy 139.709144 -342.797685) (xy 139.659524 -342.77503) (xy 139.613634 -342.745544)
			(xy 139.572408 -342.709826) (xy 139.536685 -342.668604) (xy 139.507193 -342.622718) (xy 139.484532 -342.573101)
			(xy 139.469163 -342.520765) (xy 139.4614 -342.466773) (xy 137.978696 -342.466773) (xy 137.970934 -342.520759)
			(xy 137.955567 -342.573092) (xy 137.932909 -342.622706) (xy 137.90342 -342.66859) (xy 137.867702 -342.70981)
			(xy 137.82648 -342.745528) (xy 137.780596 -342.775015) (xy 137.730981 -342.797671) (xy 137.678647 -342.813037)
			(xy 137.624659 -342.820797) (xy 137.597388 -342.82126) (xy 136.733788 -342.82126) (xy 136.706519 -342.820777)
			(xy 136.652536 -342.813014) (xy 136.600208 -342.797647) (xy 136.550599 -342.77499) (xy 136.50472 -342.745504)
			(xy 136.463503 -342.709788) (xy 136.427789 -342.668571) (xy 136.398304 -342.62269) (xy 136.375649 -342.573081)
			(xy 136.360284 -342.520752) (xy 136.352522 -342.466769) (xy 134.869674 -342.466769) (xy 134.861913 -342.520749)
			(xy 134.846549 -342.573076) (xy 134.823895 -342.622684) (xy 134.794412 -342.668563) (xy 134.7587 -342.70978)
			(xy 134.717486 -342.745495) (xy 134.671609 -342.774981) (xy 134.622002 -342.797639) (xy 134.569676 -342.813007)
			(xy 134.515696 -342.820772) (xy 134.488428 -342.82126) (xy 133.624828 -342.82126) (xy 133.597556 -342.820802)
			(xy 133.543565 -342.813043) (xy 133.491229 -342.79768) (xy 133.441612 -342.775023) (xy 133.395725 -342.745536)
			(xy 133.354501 -342.709819) (xy 133.31878 -342.668598) (xy 133.28929 -342.622712) (xy 133.26663 -342.573097)
			(xy 133.251262 -342.520762) (xy 133.2435 -342.466772) (xy 131.760796 -342.466772) (xy 131.753033 -342.520762)
			(xy 131.737666 -342.573097) (xy 131.715006 -342.622712) (xy 131.685515 -342.668597) (xy 131.649795 -342.709817)
			(xy 131.608571 -342.745535) (xy 131.562684 -342.775021) (xy 131.513067 -342.797677) (xy 131.46073 -342.81304)
			(xy 131.40674 -342.820799) (xy 131.379468 -342.82126) (xy 130.515868 -342.82126) (xy 130.4886 -342.820775)
			(xy 130.43462 -342.81301) (xy 130.382294 -342.797642) (xy 130.332687 -342.774984) (xy 130.28681 -342.745497)
			(xy 130.245596 -342.709781) (xy 130.209884 -342.668564) (xy 130.180401 -342.622685) (xy 130.157747 -342.573076)
			(xy 130.142383 -342.520749) (xy 130.134622 -342.466768) (xy 128.651774 -342.466768) (xy 128.651774 -342.466769)
			(xy 128.644012 -342.520751) (xy 128.628647 -342.57308) (xy 128.605992 -342.622689) (xy 128.576507 -342.66857)
			(xy 128.540793 -342.709787) (xy 128.499576 -342.745502) (xy 128.453697 -342.774988) (xy 128.404088 -342.797645)
			(xy 128.351759 -342.81301) (xy 128.297777 -342.820773) (xy 128.270508 -342.82126) (xy 127.406908 -342.82126)
			(xy 127.379636 -342.820801) (xy 127.325648 -342.81304) (xy 127.273315 -342.797674) (xy 127.2237 -342.775017)
			(xy 127.177815 -342.745529) (xy 127.136594 -342.709812) (xy 127.100875 -342.668591) (xy 127.071387 -342.622707)
			(xy 127.048729 -342.573093) (xy 127.033362 -342.520759) (xy 127.0256 -342.466772) (xy 125.542773 -342.466772)
			(xy 125.535013 -342.520746) (xy 125.519651 -342.573072) (xy 125.496998 -342.622678) (xy 125.467517 -342.668557)
			(xy 125.431807 -342.709773) (xy 125.390595 -342.745488) (xy 125.34472 -342.774975) (xy 125.295117 -342.797634)
			(xy 125.242793 -342.813003) (xy 125.188815 -342.82077) (xy 125.161548 -342.82126) (xy 124.297948 -342.82126)
			(xy 124.270675 -342.820804) (xy 124.216682 -342.813047) (xy 124.164344 -342.797685) (xy 124.114724 -342.77503)
			(xy 124.068834 -342.745544) (xy 124.027608 -342.709826) (xy 123.991885 -342.668604) (xy 123.962393 -342.622718)
			(xy 123.939732 -342.573101) (xy 123.924363 -342.520765) (xy 123.9166 -342.466773) (xy 122.433896 -342.466773)
			(xy 122.426134 -342.520759) (xy 122.410767 -342.573092) (xy 122.388109 -342.622706) (xy 122.35862 -342.66859)
			(xy 122.322902 -342.70981) (xy 122.28168 -342.745528) (xy 122.235796 -342.775015) (xy 122.186181 -342.797671)
			(xy 122.133847 -342.813037) (xy 122.079859 -342.820797) (xy 122.052588 -342.82126) (xy 121.188988 -342.82126)
			(xy 121.161719 -342.820777) (xy 121.107736 -342.813014) (xy 121.055408 -342.797647) (xy 121.005799 -342.77499)
			(xy 120.95992 -342.745504) (xy 120.918703 -342.709788) (xy 120.882989 -342.668571) (xy 120.853504 -342.62269)
			(xy 120.830849 -342.573081) (xy 120.815484 -342.520752) (xy 120.807722 -342.466769) (xy 119.324874 -342.466769)
			(xy 119.317113 -342.520749) (xy 119.301749 -342.573076) (xy 119.279095 -342.622684) (xy 119.249612 -342.668563)
			(xy 119.2139 -342.70978) (xy 119.172686 -342.745495) (xy 119.126809 -342.774981) (xy 119.077202 -342.797639)
			(xy 119.024876 -342.813007) (xy 118.970896 -342.820772) (xy 118.943628 -342.82126) (xy 118.080028 -342.82126)
			(xy 118.052756 -342.820802) (xy 117.998765 -342.813043) (xy 117.946429 -342.79768) (xy 117.896812 -342.775023)
			(xy 117.850925 -342.745536) (xy 117.809701 -342.709819) (xy 117.77398 -342.668598) (xy 117.74449 -342.622712)
			(xy 117.72183 -342.573097) (xy 117.706462 -342.520762) (xy 117.6987 -342.466772) (xy 116.215996 -342.466772)
			(xy 116.208233 -342.520762) (xy 116.192866 -342.573097) (xy 116.170206 -342.622712) (xy 116.140715 -342.668597)
			(xy 116.104995 -342.709817) (xy 116.063771 -342.745535) (xy 116.017884 -342.775021) (xy 115.968267 -342.797677)
			(xy 115.91593 -342.81304) (xy 115.86194 -342.820799) (xy 115.834668 -342.82126) (xy 114.971068 -342.82126)
			(xy 114.9438 -342.820775) (xy 114.88982 -342.81301) (xy 114.837494 -342.797642) (xy 114.787887 -342.774984)
			(xy 114.74201 -342.745497) (xy 114.700796 -342.709781) (xy 114.665084 -342.668564) (xy 114.635601 -342.622685)
			(xy 114.612947 -342.573076) (xy 114.597583 -342.520749) (xy 114.589822 -342.466768) (xy 113.106974 -342.466768)
			(xy 113.106974 -342.466769) (xy 113.099212 -342.520751) (xy 113.083847 -342.57308) (xy 113.061192 -342.622689)
			(xy 113.031707 -342.66857) (xy 112.995993 -342.709787) (xy 112.954776 -342.745502) (xy 112.908897 -342.774988)
			(xy 112.859288 -342.797645) (xy 112.806959 -342.81301) (xy 112.752977 -342.820773) (xy 112.725708 -342.82126)
			(xy 111.862108 -342.82126) (xy 111.834836 -342.820801) (xy 111.780848 -342.81304) (xy 111.728515 -342.797674)
			(xy 111.6789 -342.775017) (xy 111.633015 -342.745529) (xy 111.591794 -342.709812) (xy 111.556075 -342.668591)
			(xy 111.526587 -342.622707) (xy 111.503929 -342.573093) (xy 111.488562 -342.520759) (xy 111.4808 -342.466772)
			(xy 104.085479 -342.466772) (xy 104.10629 -342.517011) (xy 104.121803 -342.574906) (xy 104.129627 -342.634331)
			(xy 104.129627 -342.694269) (xy 104.121803 -342.753694) (xy 104.10629 -342.811589) (xy 104.083352 -342.866964)
			(xy 104.053383 -342.918871) (xy 104.016895 -342.966422) (xy 103.974512 -343.008804) (xy 103.926959 -343.045291)
			(xy 103.875051 -343.075259) (xy 103.819676 -343.098195) (xy 103.76178 -343.113706) (xy 103.702355 -343.121528)
			(xy 103.672386 -343.121996) (xy 102.808786 -343.121996) (xy 102.778818 -343.121529) (xy 102.719395 -343.113704)
			(xy 102.661502 -343.09819) (xy 102.60613 -343.075253) (xy 102.554224 -343.045284) (xy 102.506675 -343.008796)
			(xy 102.464294 -342.966415) (xy 102.427809 -342.918864) (xy 102.397841 -342.866958) (xy 102.374905 -342.811584)
			(xy 102.359393 -342.753691) (xy 102.35157 -342.694268) (xy 93.60914 -342.694268) (xy 93.595705 -342.709775)
			(xy 93.554492 -342.74549) (xy 93.508617 -342.774977) (xy 93.459012 -342.797635) (xy 93.406688 -342.813004)
			(xy 93.352709 -342.820771) (xy 93.325442 -342.82126) (xy 92.461842 -342.82126) (xy 92.434569 -342.820803)
			(xy 92.380577 -342.813046) (xy 92.328239 -342.797683) (xy 92.278621 -342.775028) (xy 92.232731 -342.745541)
			(xy 92.191506 -342.709824) (xy 92.155784 -342.668602) (xy 92.126292 -342.622716) (xy 92.103631 -342.5731)
			(xy 92.088263 -342.520764) (xy 92.0805 -342.466773) (xy 90.597796 -342.466773) (xy 90.590034 -342.52076)
			(xy 90.574667 -342.573094) (xy 90.552008 -342.622708) (xy 90.522519 -342.668592) (xy 90.4868 -342.709812)
			(xy 90.445578 -342.74553) (xy 90.399692 -342.775017) (xy 90.350077 -342.797673) (xy 90.297742 -342.813038)
			(xy 90.243754 -342.820798) (xy 90.216482 -342.82126) (xy 89.352882 -342.82126) (xy 89.325613 -342.820776)
			(xy 89.271631 -342.813013) (xy 89.219304 -342.797646) (xy 89.169696 -342.774988) (xy 89.123817 -342.745502)
			(xy 89.082601 -342.709786) (xy 89.046887 -342.668569) (xy 89.017403 -342.622689) (xy 88.994748 -342.573079)
			(xy 88.979384 -342.520751) (xy 88.971622 -342.466769) (xy 87.488774 -342.466769) (xy 87.481013 -342.52075)
			(xy 87.465648 -342.573077) (xy 87.442994 -342.622686) (xy 87.41351 -342.668565) (xy 87.377798 -342.709782)
			(xy 87.336583 -342.745497) (xy 87.290705 -342.774983) (xy 87.241098 -342.797641) (xy 87.188771 -342.813008)
			(xy 87.13479 -342.820772) (xy 87.107522 -342.82126) (xy 86.243922 -342.82126) (xy 86.21665 -342.820802)
			(xy 86.16266 -342.813042) (xy 86.110325 -342.797678) (xy 86.060709 -342.775021) (xy 86.014822 -342.745534)
			(xy 85.973599 -342.709817) (xy 85.937879 -342.668596) (xy 85.908389 -342.622711) (xy 85.88573 -342.573096)
			(xy 85.870362 -342.520761) (xy 85.8626 -342.466772) (xy 84.379896 -342.466772) (xy 84.379896 -342.466773)
			(xy 84.372133 -342.520763) (xy 84.356765 -342.573098) (xy 84.334105 -342.622713) (xy 84.304614 -342.668599)
			(xy 84.268893 -342.70982) (xy 84.227668 -342.745537) (xy 84.18178 -342.775023) (xy 84.132162 -342.797679)
			(xy 84.079825 -342.813041) (xy 84.025835 -342.820799) (xy 83.998562 -342.82126) (xy 83.134962 -342.82126)
			(xy 83.107694 -342.820775) (xy 83.053714 -342.813009) (xy 83.001389 -342.79764) (xy 82.951784 -342.774982)
			(xy 82.905907 -342.745495) (xy 82.864694 -342.709779) (xy 82.828983 -342.668562) (xy 82.7995 -342.622683)
			(xy 82.776847 -342.573075) (xy 82.761483 -342.520748) (xy 82.753722 -342.466768) (xy 81.270874 -342.466768)
			(xy 81.270874 -342.466769) (xy 81.263112 -342.520752) (xy 81.247747 -342.573081) (xy 81.225091 -342.622691)
			(xy 81.195605 -342.668572) (xy 81.159891 -342.709789) (xy 81.118673 -342.745504) (xy 81.072793 -342.77499)
			(xy 81.023183 -342.797646) (xy 80.970854 -342.813012) (xy 80.916871 -342.820773) (xy 80.889602 -342.82126)
			(xy 80.026002 -342.82126) (xy 79.998731 -342.820801) (xy 79.944743 -342.813039) (xy 79.89241 -342.797673)
			(xy 79.842797 -342.775015) (xy 79.796912 -342.745527) (xy 79.755692 -342.70981) (xy 79.719974 -342.668589)
			(xy 79.690486 -342.622705) (xy 79.667828 -342.573092) (xy 79.652462 -342.520759) (xy 79.644699 -342.466771)
			(xy 78.161873 -342.466771) (xy 78.154113 -342.520747) (xy 78.13875 -342.573073) (xy 78.116097 -342.62268)
			(xy 78.086615 -342.668559) (xy 78.050905 -342.709775) (xy 78.009692 -342.74549) (xy 77.963817 -342.774977)
			(xy 77.914212 -342.797635) (xy 77.861888 -342.813004) (xy 77.807909 -342.820771) (xy 77.780642 -342.82126)
			(xy 76.917042 -342.82126) (xy 76.889769 -342.820803) (xy 76.835777 -342.813046) (xy 76.783439 -342.797683)
			(xy 76.733821 -342.775028) (xy 76.687931 -342.745541) (xy 76.646706 -342.709824) (xy 76.610984 -342.668602)
			(xy 76.581492 -342.622716) (xy 76.558831 -342.5731) (xy 76.543463 -342.520764) (xy 76.5357 -342.466773)
			(xy 75.052996 -342.466773) (xy 75.045234 -342.52076) (xy 75.029867 -342.573094) (xy 75.007208 -342.622708)
			(xy 74.977719 -342.668592) (xy 74.942 -342.709812) (xy 74.900778 -342.74553) (xy 74.854892 -342.775017)
			(xy 74.805277 -342.797673) (xy 74.752942 -342.813038) (xy 74.698954 -342.820798) (xy 74.671682 -342.82126)
			(xy 73.808082 -342.82126) (xy 73.780813 -342.820776) (xy 73.726831 -342.813013) (xy 73.674504 -342.797646)
			(xy 73.624896 -342.774988) (xy 73.579017 -342.745502) (xy 73.537801 -342.709786) (xy 73.502087 -342.668569)
			(xy 73.472603 -342.622689) (xy 73.449948 -342.573079) (xy 73.434584 -342.520751) (xy 73.426822 -342.466769)
			(xy 71.943974 -342.466769) (xy 71.936213 -342.52075) (xy 71.920848 -342.573077) (xy 71.898194 -342.622686)
			(xy 71.86871 -342.668565) (xy 71.832998 -342.709782) (xy 71.791783 -342.745497) (xy 71.745905 -342.774983)
			(xy 71.696298 -342.797641) (xy 71.643971 -342.813008) (xy 71.58999 -342.820772) (xy 71.562722 -342.82126)
			(xy 70.699122 -342.82126) (xy 70.67185 -342.820802) (xy 70.61786 -342.813042) (xy 70.565525 -342.797678)
			(xy 70.515909 -342.775021) (xy 70.470022 -342.745534) (xy 70.428799 -342.709817) (xy 70.393079 -342.668596)
			(xy 70.363589 -342.622711) (xy 70.34093 -342.573096) (xy 70.325562 -342.520761) (xy 70.3178 -342.466772)
			(xy 68.835096 -342.466772) (xy 68.835096 -342.466773) (xy 68.827333 -342.520763) (xy 68.811965 -342.573098)
			(xy 68.789305 -342.622713) (xy 68.759814 -342.668599) (xy 68.724093 -342.70982) (xy 68.682868 -342.745537)
			(xy 68.63698 -342.775023) (xy 68.587362 -342.797679) (xy 68.535025 -342.813041) (xy 68.481035 -342.820799)
			(xy 68.453762 -342.82126) (xy 67.590162 -342.82126) (xy 67.562894 -342.820775) (xy 67.508914 -342.813009)
			(xy 67.456589 -342.79764) (xy 67.406984 -342.774982) (xy 67.361107 -342.745495) (xy 67.319894 -342.709779)
			(xy 67.284183 -342.668562) (xy 67.2547 -342.622683) (xy 67.232047 -342.573075) (xy 67.216683 -342.520748)
			(xy 67.208922 -342.466768) (xy 65.726074 -342.466768) (xy 65.726074 -342.466769) (xy 65.718312 -342.520752)
			(xy 65.702947 -342.573081) (xy 65.680291 -342.622691) (xy 65.650805 -342.668572) (xy 65.615091 -342.709789)
			(xy 65.573873 -342.745504) (xy 65.527993 -342.77499) (xy 65.478383 -342.797646) (xy 65.426054 -342.813012)
			(xy 65.372071 -342.820773) (xy 65.344802 -342.82126) (xy 64.481202 -342.82126) (xy 64.453931 -342.820801)
			(xy 64.399943 -342.813039) (xy 64.34761 -342.797673) (xy 64.297997 -342.775015) (xy 64.252112 -342.745527)
			(xy 64.210892 -342.70981) (xy 64.175174 -342.668589) (xy 64.145686 -342.622705) (xy 64.123028 -342.573092)
			(xy 64.107662 -342.520759) (xy 64.099899 -342.466771) (xy 62.617073 -342.466771) (xy 62.609313 -342.520747)
			(xy 62.59395 -342.573073) (xy 62.571297 -342.62268) (xy 62.541815 -342.668559) (xy 62.506105 -342.709775)
			(xy 62.464892 -342.74549) (xy 62.419017 -342.774977) (xy 62.369412 -342.797635) (xy 62.317088 -342.813004)
			(xy 62.263109 -342.820771) (xy 62.235842 -342.82126) (xy 61.372242 -342.82126) (xy 61.344969 -342.820803)
			(xy 61.290977 -342.813046) (xy 61.238639 -342.797683) (xy 61.189021 -342.775028) (xy 61.143131 -342.745541)
			(xy 61.101906 -342.709824) (xy 61.066184 -342.668602) (xy 61.036692 -342.622716) (xy 61.014031 -342.5731)
			(xy 60.998663 -342.520764) (xy 60.9909 -342.466773) (xy 51.666873 -342.466773) (xy 51.659113 -342.520746)
			(xy 51.643751 -342.573072) (xy 51.621098 -342.622678) (xy 51.591617 -342.668557) (xy 51.555907 -342.709773)
			(xy 51.514695 -342.745488) (xy 51.46882 -342.774975) (xy 51.419217 -342.797634) (xy 51.366893 -342.813003)
			(xy 51.312915 -342.82077) (xy 51.285648 -342.82126) (xy 50.422048 -342.82126) (xy 50.394775 -342.820804)
			(xy 50.340782 -342.813047) (xy 50.288444 -342.797685) (xy 50.238824 -342.77503) (xy 50.192934 -342.745544)
			(xy 50.151708 -342.709826) (xy 50.115985 -342.668604) (xy 50.086493 -342.622718) (xy 50.063832 -342.573101)
			(xy 50.048463 -342.520765) (xy 50.0407 -342.466773) (xy 48.557996 -342.466773) (xy 48.550234 -342.520759)
			(xy 48.534867 -342.573092) (xy 48.512209 -342.622706) (xy 48.48272 -342.66859) (xy 48.447002 -342.70981)
			(xy 48.40578 -342.745528) (xy 48.359896 -342.775015) (xy 48.310281 -342.797671) (xy 48.257947 -342.813037)
			(xy 48.203959 -342.820797) (xy 48.176688 -342.82126) (xy 47.313088 -342.82126) (xy 47.285819 -342.820777)
			(xy 47.231836 -342.813014) (xy 47.179508 -342.797647) (xy 47.129899 -342.77499) (xy 47.08402 -342.745504)
			(xy 47.042803 -342.709788) (xy 47.007089 -342.668571) (xy 46.977604 -342.62269) (xy 46.954949 -342.573081)
			(xy 46.939584 -342.520752) (xy 46.931822 -342.466769) (xy 45.448974 -342.466769) (xy 45.441213 -342.520749)
			(xy 45.425849 -342.573076) (xy 45.403195 -342.622684) (xy 45.373712 -342.668563) (xy 45.338 -342.70978)
			(xy 45.296786 -342.745495) (xy 45.250909 -342.774981) (xy 45.201302 -342.797639) (xy 45.148976 -342.813007)
			(xy 45.094996 -342.820772) (xy 45.067728 -342.82126) (xy 44.204128 -342.82126) (xy 44.176856 -342.820802)
			(xy 44.122865 -342.813043) (xy 44.070529 -342.79768) (xy 44.020912 -342.775023) (xy 43.975025 -342.745536)
			(xy 43.933801 -342.709819) (xy 43.89808 -342.668598) (xy 43.86859 -342.622712) (xy 43.84593 -342.573097)
			(xy 43.830562 -342.520762) (xy 43.8228 -342.466772) (xy 42.340096 -342.466772) (xy 42.332333 -342.520762)
			(xy 42.316966 -342.573097) (xy 42.294306 -342.622712) (xy 42.264815 -342.668597) (xy 42.229095 -342.709817)
			(xy 42.187871 -342.745535) (xy 42.141984 -342.775021) (xy 42.092367 -342.797677) (xy 42.04003 -342.81304)
			(xy 41.98604 -342.820799) (xy 41.958768 -342.82126) (xy 41.095168 -342.82126) (xy 41.0679 -342.820775)
			(xy 41.01392 -342.81301) (xy 40.961594 -342.797642) (xy 40.911987 -342.774984) (xy 40.86611 -342.745497)
			(xy 40.824896 -342.709781) (xy 40.789184 -342.668564) (xy 40.759701 -342.622685) (xy 40.737047 -342.573076)
			(xy 40.721683 -342.520749) (xy 40.713922 -342.466768) (xy 39.231074 -342.466768) (xy 39.231074 -342.466769)
			(xy 39.223312 -342.520751) (xy 39.207947 -342.57308) (xy 39.185292 -342.622689) (xy 39.155807 -342.66857)
			(xy 39.120093 -342.709787) (xy 39.078876 -342.745502) (xy 39.032997 -342.774988) (xy 38.983388 -342.797645)
			(xy 38.931059 -342.81301) (xy 38.877077 -342.820773) (xy 38.849808 -342.82126) (xy 37.986208 -342.82126)
			(xy 37.958936 -342.820801) (xy 37.904948 -342.81304) (xy 37.852615 -342.797674) (xy 37.803 -342.775017)
			(xy 37.757115 -342.745529) (xy 37.715894 -342.709812) (xy 37.680175 -342.668591) (xy 37.650687 -342.622707)
			(xy 37.628029 -342.573093) (xy 37.612662 -342.520759) (xy 37.6049 -342.466772) (xy 36.122073 -342.466772)
			(xy 36.114313 -342.520746) (xy 36.098951 -342.573072) (xy 36.076298 -342.622678) (xy 36.046817 -342.668557)
			(xy 36.011107 -342.709773) (xy 35.969895 -342.745488) (xy 35.92402 -342.774975) (xy 35.874417 -342.797634)
			(xy 35.822093 -342.813003) (xy 35.768115 -342.82077) (xy 35.740848 -342.82126) (xy 34.877248 -342.82126)
			(xy 34.849975 -342.820804) (xy 34.795982 -342.813047) (xy 34.743644 -342.797685) (xy 34.694024 -342.77503)
			(xy 34.648134 -342.745544) (xy 34.606908 -342.709826) (xy 34.571185 -342.668604) (xy 34.541693 -342.622718)
			(xy 34.519032 -342.573101) (xy 34.503663 -342.520765) (xy 34.4959 -342.466773) (xy 33.013196 -342.466773)
			(xy 33.005434 -342.520759) (xy 32.990067 -342.573092) (xy 32.967409 -342.622706) (xy 32.93792 -342.66859)
			(xy 32.902202 -342.70981) (xy 32.86098 -342.745528) (xy 32.815096 -342.775015) (xy 32.765481 -342.797671)
			(xy 32.713147 -342.813037) (xy 32.659159 -342.820797) (xy 32.631888 -342.82126) (xy 31.768288 -342.82126)
			(xy 31.741019 -342.820777) (xy 31.687036 -342.813014) (xy 31.634708 -342.797647) (xy 31.585099 -342.77499)
			(xy 31.53922 -342.745504) (xy 31.498003 -342.709788) (xy 31.462289 -342.668571) (xy 31.432804 -342.62269)
			(xy 31.410149 -342.573081) (xy 31.394784 -342.520752) (xy 31.387022 -342.466769) (xy 29.904174 -342.466769)
			(xy 29.896413 -342.520749) (xy 29.881049 -342.573076) (xy 29.858395 -342.622684) (xy 29.828912 -342.668563)
			(xy 29.7932 -342.70978) (xy 29.751986 -342.745495) (xy 29.706109 -342.774981) (xy 29.656502 -342.797639)
			(xy 29.604176 -342.813007) (xy 29.550196 -342.820772) (xy 29.522928 -342.82126) (xy 28.659328 -342.82126)
			(xy 28.632056 -342.820802) (xy 28.578065 -342.813043) (xy 28.525729 -342.79768) (xy 28.476112 -342.775023)
			(xy 28.430225 -342.745536) (xy 28.389001 -342.709819) (xy 28.35328 -342.668598) (xy 28.32379 -342.622712)
			(xy 28.30113 -342.573097) (xy 28.285762 -342.520762) (xy 28.278 -342.466772) (xy 26.795296 -342.466772)
			(xy 26.787533 -342.520762) (xy 26.772166 -342.573097) (xy 26.749506 -342.622712) (xy 26.720015 -342.668597)
			(xy 26.684295 -342.709817) (xy 26.643071 -342.745535) (xy 26.597184 -342.775021) (xy 26.547567 -342.797677)
			(xy 26.49523 -342.81304) (xy 26.44124 -342.820799) (xy 26.413968 -342.82126) (xy 25.550368 -342.82126)
			(xy 25.5231 -342.820775) (xy 25.46912 -342.81301) (xy 25.416794 -342.797642) (xy 25.367187 -342.774984)
			(xy 25.32131 -342.745497) (xy 25.280096 -342.709781) (xy 25.244384 -342.668564) (xy 25.214901 -342.622685)
			(xy 25.192247 -342.573076) (xy 25.176883 -342.520749) (xy 25.169122 -342.466768) (xy 23.686274 -342.466768)
			(xy 23.686274 -342.466769) (xy 23.678512 -342.520751) (xy 23.663147 -342.57308) (xy 23.640492 -342.622689)
			(xy 23.611007 -342.66857) (xy 23.575293 -342.709787) (xy 23.534076 -342.745502) (xy 23.488197 -342.774988)
			(xy 23.438588 -342.797645) (xy 23.386259 -342.81301) (xy 23.332277 -342.820773) (xy 23.305008 -342.82126)
			(xy 22.441408 -342.82126) (xy 22.414136 -342.820801) (xy 22.360148 -342.81304) (xy 22.307815 -342.797674)
			(xy 22.2582 -342.775017) (xy 22.212315 -342.745529) (xy 22.171094 -342.709812) (xy 22.135375 -342.668591)
			(xy 22.105887 -342.622707) (xy 22.083229 -342.573093) (xy 22.067862 -342.520759) (xy 22.0601 -342.466772)
			(xy 20.577347 -342.466772) (xy 20.569584 -342.520758) (xy 20.554218 -342.57309) (xy 20.53156 -342.622703)
			(xy 20.502073 -342.668587) (xy 20.466355 -342.709807) (xy 20.425135 -342.745524) (xy 20.379252 -342.775011)
			(xy 20.329638 -342.797669) (xy 20.277306 -342.813035) (xy 20.223319 -342.820797) (xy 20.196048 -342.82126)
			(xy 19.332448 -342.82126) (xy 19.305179 -342.820777) (xy 19.251195 -342.813015) (xy 19.198865 -342.79765)
			(xy 19.149255 -342.774993) (xy 19.103374 -342.745507) (xy 19.062157 -342.709792) (xy 19.026441 -342.668574)
			(xy 18.996956 -342.622693) (xy 18.974299 -342.573083) (xy 18.958934 -342.520753) (xy 18.951172 -342.466769)
			(xy 1.524 -342.466769) (xy 1.524 -345.49242) (xy 18.95117 -345.49242) (xy 18.95117 -345.43788) (xy 18.958932 -345.383896)
			(xy 18.974298 -345.331567) (xy 18.996954 -345.281956) (xy 19.02644 -345.236075) (xy 19.062155 -345.194857)
			(xy 19.103373 -345.159141) (xy 19.149254 -345.129655) (xy 19.198865 -345.106998) (xy 19.251194 -345.091633)
			(xy 19.305178 -345.083871) (xy 19.332448 -345.083384) (xy 20.196048 -345.083384) (xy 20.223319 -345.083855)
			(xy 20.277305 -345.091617) (xy 20.329638 -345.106983) (xy 20.379251 -345.12964) (xy 20.425134 -345.159128)
			(xy 20.466354 -345.194845) (xy 20.502071 -345.236064) (xy 20.531559 -345.281948) (xy 20.554216 -345.33156)
			(xy 20.569582 -345.383893) (xy 20.577345 -345.437879) (xy 20.577345 -345.49242) (xy 22.06013 -345.49242)
			(xy 22.06013 -345.43788) (xy 22.067892 -345.383896) (xy 22.083258 -345.331567) (xy 22.105914 -345.281956)
			(xy 22.1354 -345.236075) (xy 22.171115 -345.194857) (xy 22.212333 -345.159141) (xy 22.258214 -345.129655)
			(xy 22.307825 -345.106998) (xy 22.360154 -345.091633) (xy 22.414138 -345.083871) (xy 22.441408 -345.083384)
			(xy 23.305008 -345.083384) (xy 23.332279 -345.083855) (xy 23.386265 -345.091617) (xy 23.438598 -345.106983)
			(xy 23.488211 -345.12964) (xy 23.534094 -345.159128) (xy 23.575314 -345.194845) (xy 23.611031 -345.236064)
			(xy 23.640519 -345.281948) (xy 23.663176 -345.33156) (xy 23.678542 -345.383893) (xy 23.686305 -345.437879)
			(xy 23.686305 -345.492365) (xy 25.16917 -345.492365) (xy 25.16917 -345.437835) (xy 25.17693 -345.383861)
			(xy 25.192292 -345.33154) (xy 25.214943 -345.281938) (xy 25.244422 -345.236064) (xy 25.28013 -345.194853)
			(xy 25.321339 -345.159142) (xy 25.36721 -345.129658) (xy 25.41681 -345.107003) (xy 25.46913 -345.091637)
			(xy 25.523103 -345.083872) (xy 25.550368 -345.083384) (xy 26.413968 -345.083384) (xy 26.441244 -345.083753)
			(xy 26.495241 -345.091513) (xy 26.547583 -345.106878) (xy 26.597207 -345.129537) (xy 26.6431 -345.159027)
			(xy 26.684329 -345.194749) (xy 26.720054 -345.235975) (xy 26.749548 -345.281865) (xy 26.772211 -345.331487)
			(xy 26.78758 -345.383828) (xy 26.795344 -345.437824) (xy 26.795344 -345.492369) (xy 28.278047 -345.492369)
			(xy 28.278047 -345.437831) (xy 28.285809 -345.383848) (xy 28.301175 -345.33152) (xy 28.323832 -345.281911)
			(xy 28.353319 -345.236031) (xy 28.389035 -345.194815) (xy 28.430253 -345.159102) (xy 28.476135 -345.129619)
			(xy 28.525746 -345.106965) (xy 28.578076 -345.091603) (xy 28.632059 -345.083845) (xy 28.659328 -345.083384)
			(xy 29.522928 -345.083384) (xy 29.550199 -345.08378) (xy 29.604186 -345.091546) (xy 29.656519 -345.106916)
			(xy 29.706132 -345.129576) (xy 29.752014 -345.159067) (xy 29.793234 -345.194786) (xy 29.82895 -345.236008)
			(xy 29.858437 -345.281893) (xy 29.881094 -345.331507) (xy 29.89646 -345.383841) (xy 29.904222 -345.437829)
			(xy 29.904222 -345.492366) (xy 31.38707 -345.492366) (xy 31.38707 -345.437834) (xy 31.394831 -345.383858)
			(xy 31.410194 -345.331536) (xy 31.432846 -345.281933) (xy 31.462327 -345.236058) (xy 31.498037 -345.194846)
			(xy 31.539248 -345.159135) (xy 31.585122 -345.129652) (xy 31.634725 -345.106998) (xy 31.687047 -345.091633)
			(xy 31.741022 -345.083871) (xy 31.768288 -345.083384) (xy 32.631888 -345.083384) (xy 32.659163 -345.083755)
			(xy 32.713157 -345.091516) (xy 32.765498 -345.106884) (xy 32.815119 -345.129543) (xy 32.861009 -345.159034)
			(xy 32.902236 -345.194756) (xy 32.937959 -345.235981) (xy 32.967451 -345.281871) (xy 32.990112 -345.331491)
			(xy 33.005481 -345.383831) (xy 33.013244 -345.437825) (xy 33.013244 -345.49237) (xy 34.495948 -345.49237)
			(xy 34.495948 -345.43783) (xy 34.50371 -345.383846) (xy 34.519077 -345.331515) (xy 34.541735 -345.281905)
			(xy 34.571224 -345.236024) (xy 34.606942 -345.194808) (xy 34.648163 -345.159095) (xy 34.694047 -345.129612)
			(xy 34.74366 -345.10696) (xy 34.795992 -345.0916) (xy 34.849978 -345.083844) (xy 34.877248 -345.083384)
			(xy 35.740848 -345.083384) (xy 35.768118 -345.083782) (xy 35.822103 -345.09155) (xy 35.874433 -345.106921)
			(xy 35.924044 -345.129583) (xy 35.969924 -345.159074) (xy 36.011141 -345.194793) (xy 36.046855 -345.236015)
			(xy 36.07634 -345.281899) (xy 36.098995 -345.331512) (xy 36.11436 -345.383844) (xy 36.122122 -345.43783)
			(xy 36.122122 -345.492368) (xy 37.604947 -345.492368) (xy 37.604947 -345.437832) (xy 37.612709 -345.383851)
			(xy 37.628074 -345.331524) (xy 37.650729 -345.281916) (xy 37.680214 -345.236038) (xy 37.715928 -345.194822)
			(xy 37.757144 -345.159109) (xy 37.803023 -345.129625) (xy 37.852631 -345.106971) (xy 37.904959 -345.091607)
			(xy 37.95894 -345.083847) (xy 37.986208 -345.083384) (xy 38.849808 -345.083384) (xy 38.87708 -345.083779)
			(xy 38.93107 -345.091543) (xy 38.983404 -345.106911) (xy 39.03302 -345.12957) (xy 39.078905 -345.15906)
			(xy 39.120127 -345.194779) (xy 39.155845 -345.236001) (xy 39.185334 -345.281888) (xy 39.207992 -345.331503)
			(xy 39.223359 -345.383838) (xy 39.231121 -345.437828) (xy 39.231121 -345.492365) (xy 40.71397 -345.492365)
			(xy 40.71397 -345.437835) (xy 40.72173 -345.383861) (xy 40.737092 -345.33154) (xy 40.759743 -345.281938)
			(xy 40.789222 -345.236064) (xy 40.82493 -345.194853) (xy 40.866139 -345.159142) (xy 40.91201 -345.129658)
			(xy 40.96161 -345.107003) (xy 41.01393 -345.091637) (xy 41.067903 -345.083872) (xy 41.095168 -345.083384)
			(xy 41.958768 -345.083384) (xy 41.986044 -345.083753) (xy 42.040041 -345.091513) (xy 42.092383 -345.106878)
			(xy 42.142007 -345.129537) (xy 42.1879 -345.159027) (xy 42.229129 -345.194749) (xy 42.264854 -345.235975)
			(xy 42.294348 -345.281865) (xy 42.317011 -345.331487) (xy 42.33238 -345.383828) (xy 42.340144 -345.437824)
			(xy 42.340144 -345.492369) (xy 43.822847 -345.492369) (xy 43.822847 -345.437831) (xy 43.830609 -345.383848)
			(xy 43.845975 -345.33152) (xy 43.868632 -345.281911) (xy 43.898119 -345.236031) (xy 43.933835 -345.194815)
			(xy 43.975053 -345.159102) (xy 44.020935 -345.129619) (xy 44.070546 -345.106965) (xy 44.122876 -345.091603)
			(xy 44.176859 -345.083845) (xy 44.204128 -345.083384) (xy 45.067728 -345.083384) (xy 45.094999 -345.08378)
			(xy 45.148986 -345.091546) (xy 45.201319 -345.106916) (xy 45.250932 -345.129576) (xy 45.296814 -345.159067)
			(xy 45.338034 -345.194786) (xy 45.37375 -345.236008) (xy 45.403237 -345.281893) (xy 45.425894 -345.331507)
			(xy 45.44126 -345.383841) (xy 45.449022 -345.437829) (xy 45.449022 -345.492366) (xy 46.93187 -345.492366)
			(xy 46.93187 -345.437834) (xy 46.939631 -345.383858) (xy 46.954994 -345.331536) (xy 46.977646 -345.281933)
			(xy 47.007127 -345.236058) (xy 47.042837 -345.194846) (xy 47.084048 -345.159135) (xy 47.129922 -345.129652)
			(xy 47.179525 -345.106998) (xy 47.231847 -345.091633) (xy 47.285822 -345.083871) (xy 47.313088 -345.083384)
			(xy 48.176688 -345.083384) (xy 48.203963 -345.083755) (xy 48.257957 -345.091516) (xy 48.310298 -345.106884)
			(xy 48.359919 -345.129543) (xy 48.405809 -345.159034) (xy 48.447036 -345.194756) (xy 48.482759 -345.235981)
			(xy 48.512251 -345.281871) (xy 48.534912 -345.331491) (xy 48.550281 -345.383831) (xy 48.558044 -345.437825)
			(xy 48.558044 -345.49237) (xy 50.040748 -345.49237) (xy 50.040748 -345.43783) (xy 50.04851 -345.383846)
			(xy 50.063877 -345.331515) (xy 50.086535 -345.281905) (xy 50.116024 -345.236024) (xy 50.151742 -345.194808)
			(xy 50.192963 -345.159095) (xy 50.238847 -345.129612) (xy 50.28846 -345.10696) (xy 50.340792 -345.0916)
			(xy 50.394778 -345.083844) (xy 50.422048 -345.083384) (xy 51.285648 -345.083384) (xy 51.312918 -345.083782)
			(xy 51.366903 -345.09155) (xy 51.419233 -345.106921) (xy 51.468844 -345.129583) (xy 51.514724 -345.159074)
			(xy 51.555941 -345.194793) (xy 51.591655 -345.236015) (xy 51.62114 -345.281899) (xy 51.643795 -345.331512)
			(xy 51.65916 -345.383844) (xy 51.666922 -345.43783) (xy 51.666922 -345.49237) (xy 60.990948 -345.49237)
			(xy 60.990948 -345.43783) (xy 60.99871 -345.383846) (xy 61.014076 -345.331517) (xy 61.036734 -345.281907)
			(xy 61.066222 -345.236026) (xy 61.10194 -345.19481) (xy 61.14316 -345.159097) (xy 61.189044 -345.129614)
			(xy 61.238656 -345.106962) (xy 61.290987 -345.091601) (xy 61.344972 -345.083845) (xy 61.372242 -345.083384)
			(xy 62.235842 -345.083384) (xy 62.263113 -345.083781) (xy 62.317098 -345.091549) (xy 62.369429 -345.10692)
			(xy 62.41904 -345.129581) (xy 62.464921 -345.159072) (xy 62.506139 -345.194791) (xy 62.541854 -345.236013)
			(xy 62.571339 -345.281897) (xy 62.593995 -345.33151) (xy 62.60936 -345.383843) (xy 62.617122 -345.437829)
			(xy 62.617122 -345.492368) (xy 64.099947 -345.492368) (xy 64.099947 -345.437832) (xy 64.107709 -345.383852)
			(xy 64.123073 -345.331525) (xy 64.145728 -345.281918) (xy 64.175212 -345.23604) (xy 64.210926 -345.194824)
			(xy 64.252141 -345.159111) (xy 64.29802 -345.129627) (xy 64.347627 -345.106972) (xy 64.399954 -345.091608)
			(xy 64.453934 -345.083847) (xy 64.481202 -345.083384) (xy 65.344802 -345.083384) (xy 65.372075 -345.083779)
			(xy 65.426064 -345.091542) (xy 65.4784 -345.106909) (xy 65.528016 -345.129568) (xy 65.573902 -345.159057)
			(xy 65.615124 -345.194777) (xy 65.650844 -345.236) (xy 65.680333 -345.281886) (xy 65.702992 -345.331502)
			(xy 65.718359 -345.383838) (xy 65.726121 -345.437827) (xy 65.726121 -345.492364) (xy 67.20897 -345.492364)
			(xy 67.20897 -345.437836) (xy 67.21673 -345.383862) (xy 67.232092 -345.331542) (xy 67.254742 -345.28194)
			(xy 67.284221 -345.236066) (xy 67.319928 -345.194855) (xy 67.361136 -345.159144) (xy 67.407007 -345.12966)
			(xy 67.456606 -345.107005) (xy 67.508925 -345.091638) (xy 67.562898 -345.083873) (xy 67.590162 -345.083384)
			(xy 68.453762 -345.083384) (xy 68.481038 -345.083753) (xy 68.535036 -345.091512) (xy 68.587379 -345.106877)
			(xy 68.637003 -345.129535) (xy 68.682897 -345.159025) (xy 68.724127 -345.194747) (xy 68.759852 -345.235973)
			(xy 68.789347 -345.281864) (xy 68.81201 -345.331485) (xy 68.82738 -345.383827) (xy 68.835144 -345.437824)
			(xy 68.835144 -345.492369) (xy 70.317847 -345.492369) (xy 70.317847 -345.437831) (xy 70.325609 -345.383849)
			(xy 70.340975 -345.331521) (xy 70.363631 -345.281912) (xy 70.393117 -345.236033) (xy 70.428833 -345.194817)
			(xy 70.470051 -345.159104) (xy 70.515932 -345.129621) (xy 70.565541 -345.106967) (xy 70.617871 -345.091605)
			(xy 70.671853 -345.083846) (xy 70.699122 -345.083384) (xy 71.562722 -345.083384) (xy 71.589994 -345.08378)
			(xy 71.643981 -345.091545) (xy 71.696315 -345.106914) (xy 71.745928 -345.129574) (xy 71.791812 -345.159064)
			(xy 71.833032 -345.194784) (xy 71.868749 -345.236006) (xy 71.898236 -345.281891) (xy 71.920893 -345.331506)
			(xy 71.936259 -345.38384) (xy 71.944022 -345.437828) (xy 71.944022 -345.492365) (xy 73.42687 -345.492365)
			(xy 73.42687 -345.437835) (xy 73.434631 -345.383859) (xy 73.449993 -345.331537) (xy 73.472645 -345.281934)
			(xy 73.502126 -345.23606) (xy 73.537835 -345.194848) (xy 73.579045 -345.159137) (xy 73.624919 -345.129654)
			(xy 73.674521 -345.106999) (xy 73.726842 -345.091634) (xy 73.780817 -345.083872) (xy 73.808082 -345.083384)
			(xy 74.671682 -345.083384) (xy 74.698957 -345.083754) (xy 74.752952 -345.091515) (xy 74.805294 -345.106882)
			(xy 74.854915 -345.129541) (xy 74.900806 -345.159032) (xy 74.942034 -345.194754) (xy 74.977757 -345.235979)
			(xy 75.00725 -345.281869) (xy 75.029912 -345.33149) (xy 75.045281 -345.38383) (xy 75.053044 -345.437825)
			(xy 75.053044 -345.49237) (xy 76.535748 -345.49237) (xy 76.535748 -345.43783) (xy 76.54351 -345.383846)
			(xy 76.558876 -345.331517) (xy 76.581534 -345.281907) (xy 76.611022 -345.236026) (xy 76.64674 -345.19481)
			(xy 76.68796 -345.159097) (xy 76.733844 -345.129614) (xy 76.783456 -345.106962) (xy 76.835787 -345.091601)
			(xy 76.889772 -345.083845) (xy 76.917042 -345.083384) (xy 77.780642 -345.083384) (xy 77.807913 -345.083781)
			(xy 77.861898 -345.091549) (xy 77.914229 -345.10692) (xy 77.96384 -345.129581) (xy 78.009721 -345.159072)
			(xy 78.050939 -345.194791) (xy 78.086654 -345.236013) (xy 78.116139 -345.281897) (xy 78.138795 -345.33151)
			(xy 78.15416 -345.383843) (xy 78.161922 -345.437829) (xy 78.161922 -345.492368) (xy 79.644747 -345.492368)
			(xy 79.644747 -345.437832) (xy 79.652509 -345.383852) (xy 79.667873 -345.331525) (xy 79.690528 -345.281918)
			(xy 79.720012 -345.23604) (xy 79.755726 -345.194824) (xy 79.796941 -345.159111) (xy 79.84282 -345.129627)
			(xy 79.892427 -345.106972) (xy 79.944754 -345.091608) (xy 79.998734 -345.083847) (xy 80.026002 -345.083384)
			(xy 80.889602 -345.083384) (xy 80.916875 -345.083779) (xy 80.970864 -345.091542) (xy 81.0232 -345.106909)
			(xy 81.072816 -345.129568) (xy 81.118702 -345.159057) (xy 81.159924 -345.194777) (xy 81.195644 -345.236)
			(xy 81.225133 -345.281886) (xy 81.247792 -345.331502) (xy 81.263159 -345.383838) (xy 81.270921 -345.437827)
			(xy 81.270921 -345.492364) (xy 82.75377 -345.492364) (xy 82.75377 -345.437836) (xy 82.76153 -345.383862)
			(xy 82.776892 -345.331542) (xy 82.799542 -345.28194) (xy 82.829021 -345.236066) (xy 82.864728 -345.194855)
			(xy 82.905936 -345.159144) (xy 82.951807 -345.12966) (xy 83.001406 -345.107005) (xy 83.053725 -345.091638)
			(xy 83.107698 -345.083873) (xy 83.134962 -345.083384) (xy 83.998562 -345.083384) (xy 84.025838 -345.083753)
			(xy 84.079836 -345.091512) (xy 84.132179 -345.106877) (xy 84.181803 -345.129535) (xy 84.227697 -345.159025)
			(xy 84.268927 -345.194747) (xy 84.304652 -345.235973) (xy 84.334147 -345.281864) (xy 84.35681 -345.331485)
			(xy 84.37218 -345.383827) (xy 84.379944 -345.437824) (xy 84.379944 -345.492369) (xy 85.862647 -345.492369)
			(xy 85.862647 -345.437831) (xy 85.870409 -345.383849) (xy 85.885775 -345.331521) (xy 85.908431 -345.281912)
			(xy 85.937917 -345.236033) (xy 85.973633 -345.194817) (xy 86.014851 -345.159104) (xy 86.060732 -345.129621)
			(xy 86.110341 -345.106967) (xy 86.162671 -345.091605) (xy 86.216653 -345.083846) (xy 86.243922 -345.083384)
			(xy 87.107522 -345.083384) (xy 87.134794 -345.08378) (xy 87.188781 -345.091545) (xy 87.241115 -345.106914)
			(xy 87.290728 -345.129574) (xy 87.336612 -345.159064) (xy 87.377832 -345.194784) (xy 87.413549 -345.236006)
			(xy 87.443036 -345.281891) (xy 87.465693 -345.331506) (xy 87.481059 -345.38384) (xy 87.488822 -345.437828)
			(xy 87.488822 -345.492365) (xy 88.97167 -345.492365) (xy 88.97167 -345.437835) (xy 88.979431 -345.383859)
			(xy 88.994793 -345.331537) (xy 89.017445 -345.281934) (xy 89.046926 -345.23606) (xy 89.082635 -345.194848)
			(xy 89.123845 -345.159137) (xy 89.169719 -345.129654) (xy 89.219321 -345.106999) (xy 89.271642 -345.091634)
			(xy 89.325617 -345.083872) (xy 89.352882 -345.083384) (xy 90.216482 -345.083384) (xy 90.243757 -345.083754)
			(xy 90.297752 -345.091515) (xy 90.350094 -345.106882) (xy 90.399715 -345.129541) (xy 90.445606 -345.159032)
			(xy 90.486834 -345.194754) (xy 90.522557 -345.235979) (xy 90.55205 -345.281869) (xy 90.574712 -345.33149)
			(xy 90.590081 -345.38383) (xy 90.597844 -345.437825) (xy 90.597844 -345.49237) (xy 92.080548 -345.49237)
			(xy 92.080548 -345.43783) (xy 92.08831 -345.383846) (xy 92.103676 -345.331517) (xy 92.126334 -345.281907)
			(xy 92.155822 -345.236026) (xy 92.19154 -345.19481) (xy 92.23276 -345.159097) (xy 92.278644 -345.129614)
			(xy 92.328256 -345.106962) (xy 92.380587 -345.091601) (xy 92.434572 -345.083845) (xy 92.461842 -345.083384)
			(xy 93.325442 -345.083384) (xy 93.352713 -345.083781) (xy 93.406698 -345.091549) (xy 93.459029 -345.10692)
			(xy 93.50864 -345.129581) (xy 93.554521 -345.159072) (xy 93.595739 -345.194791) (xy 93.631454 -345.236013)
			(xy 93.660939 -345.281897) (xy 93.683595 -345.33151) (xy 93.69896 -345.383843) (xy 93.706722 -345.437829)
			(xy 93.706722 -345.492368) (xy 111.480847 -345.492368) (xy 111.480847 -345.437832) (xy 111.488609 -345.383851)
			(xy 111.503974 -345.331524) (xy 111.526629 -345.281916) (xy 111.556114 -345.236038) (xy 111.591828 -345.194822)
			(xy 111.633044 -345.159109) (xy 111.678923 -345.129625) (xy 111.728531 -345.106971) (xy 111.780859 -345.091607)
			(xy 111.83484 -345.083847) (xy 111.862108 -345.083384) (xy 112.725708 -345.083384) (xy 112.75298 -345.083779)
			(xy 112.80697 -345.091543) (xy 112.859304 -345.106911) (xy 112.90892 -345.12957) (xy 112.954805 -345.15906)
			(xy 112.996027 -345.194779) (xy 113.031745 -345.236001) (xy 113.061234 -345.281888) (xy 113.083892 -345.331503)
			(xy 113.099259 -345.383838) (xy 113.107021 -345.437828) (xy 113.107021 -345.492365) (xy 114.58987 -345.492365)
			(xy 114.58987 -345.437835) (xy 114.59763 -345.383861) (xy 114.612992 -345.33154) (xy 114.635643 -345.281938)
			(xy 114.665122 -345.236064) (xy 114.70083 -345.194853) (xy 114.742039 -345.159142) (xy 114.78791 -345.129658)
			(xy 114.83751 -345.107003) (xy 114.88983 -345.091637) (xy 114.943803 -345.083872) (xy 114.971068 -345.083384)
			(xy 115.834668 -345.083384) (xy 115.861944 -345.083753) (xy 115.915941 -345.091513) (xy 115.968283 -345.106878)
			(xy 116.017907 -345.129537) (xy 116.0638 -345.159027) (xy 116.105029 -345.194749) (xy 116.140754 -345.235975)
			(xy 116.170248 -345.281865) (xy 116.192911 -345.331487) (xy 116.20828 -345.383828) (xy 116.216044 -345.437824)
			(xy 116.216044 -345.492369) (xy 117.698747 -345.492369) (xy 117.698747 -345.437831) (xy 117.706509 -345.383848)
			(xy 117.721875 -345.33152) (xy 117.744532 -345.281911) (xy 117.774019 -345.236031) (xy 117.809735 -345.194815)
			(xy 117.850953 -345.159102) (xy 117.896835 -345.129619) (xy 117.946446 -345.106965) (xy 117.998776 -345.091603)
			(xy 118.052759 -345.083845) (xy 118.080028 -345.083384) (xy 118.943628 -345.083384) (xy 118.970899 -345.08378)
			(xy 119.024886 -345.091546) (xy 119.077219 -345.106916) (xy 119.126832 -345.129576) (xy 119.172714 -345.159067)
			(xy 119.213934 -345.194786) (xy 119.24965 -345.236008) (xy 119.279137 -345.281893) (xy 119.301794 -345.331507)
			(xy 119.31716 -345.383841) (xy 119.324922 -345.437829) (xy 119.324922 -345.492366) (xy 120.80777 -345.492366)
			(xy 120.80777 -345.437834) (xy 120.815531 -345.383858) (xy 120.830894 -345.331536) (xy 120.853546 -345.281933)
			(xy 120.883027 -345.236058) (xy 120.918737 -345.194846) (xy 120.959948 -345.159135) (xy 121.005822 -345.129652)
			(xy 121.055425 -345.106998) (xy 121.107747 -345.091633) (xy 121.161722 -345.083871) (xy 121.188988 -345.083384)
			(xy 122.052588 -345.083384) (xy 122.079863 -345.083755) (xy 122.133857 -345.091516) (xy 122.186198 -345.106884)
			(xy 122.235819 -345.129543) (xy 122.281709 -345.159034) (xy 122.322936 -345.194756) (xy 122.358659 -345.235981)
			(xy 122.388151 -345.281871) (xy 122.410812 -345.331491) (xy 122.426181 -345.383831) (xy 122.433944 -345.437825)
			(xy 122.433944 -345.49237) (xy 123.916648 -345.49237) (xy 123.916648 -345.43783) (xy 123.92441 -345.383846)
			(xy 123.939777 -345.331515) (xy 123.962435 -345.281905) (xy 123.991924 -345.236024) (xy 124.027642 -345.194808)
			(xy 124.068863 -345.159095) (xy 124.114747 -345.129612) (xy 124.16436 -345.10696) (xy 124.216692 -345.0916)
			(xy 124.270678 -345.083844) (xy 124.297948 -345.083384) (xy 125.161548 -345.083384) (xy 125.188818 -345.083782)
			(xy 125.242803 -345.09155) (xy 125.295133 -345.106921) (xy 125.344744 -345.129583) (xy 125.390624 -345.159074)
			(xy 125.431841 -345.194793) (xy 125.467555 -345.236015) (xy 125.49704 -345.281899) (xy 125.519695 -345.331512)
			(xy 125.53506 -345.383844) (xy 125.542822 -345.43783) (xy 125.542822 -345.492368) (xy 127.025647 -345.492368)
			(xy 127.025647 -345.437832) (xy 127.033409 -345.383851) (xy 127.048774 -345.331524) (xy 127.071429 -345.281916)
			(xy 127.100914 -345.236038) (xy 127.136628 -345.194822) (xy 127.177844 -345.159109) (xy 127.223723 -345.129625)
			(xy 127.273331 -345.106971) (xy 127.325659 -345.091607) (xy 127.37964 -345.083847) (xy 127.406908 -345.083384)
			(xy 128.270508 -345.083384) (xy 128.29778 -345.083779) (xy 128.35177 -345.091543) (xy 128.404104 -345.106911)
			(xy 128.45372 -345.12957) (xy 128.499605 -345.15906) (xy 128.540827 -345.194779) (xy 128.576545 -345.236001)
			(xy 128.606034 -345.281888) (xy 128.628692 -345.331503) (xy 128.644059 -345.383838) (xy 128.651821 -345.437828)
			(xy 128.651821 -345.492365) (xy 130.13467 -345.492365) (xy 130.13467 -345.437835) (xy 130.14243 -345.383861)
			(xy 130.157792 -345.33154) (xy 130.180443 -345.281938) (xy 130.209922 -345.236064) (xy 130.24563 -345.194853)
			(xy 130.286839 -345.159142) (xy 130.33271 -345.129658) (xy 130.38231 -345.107003) (xy 130.43463 -345.091637)
			(xy 130.488603 -345.083872) (xy 130.515868 -345.083384) (xy 131.379468 -345.083384) (xy 131.406744 -345.083753)
			(xy 131.460741 -345.091513) (xy 131.513083 -345.106878) (xy 131.562707 -345.129537) (xy 131.6086 -345.159027)
			(xy 131.649829 -345.194749) (xy 131.685554 -345.235975) (xy 131.715048 -345.281865) (xy 131.737711 -345.331487)
			(xy 131.75308 -345.383828) (xy 131.760844 -345.437824) (xy 131.760844 -345.492369) (xy 133.243547 -345.492369)
			(xy 133.243547 -345.437831) (xy 133.251309 -345.383848) (xy 133.266675 -345.33152) (xy 133.289332 -345.281911)
			(xy 133.318819 -345.236031) (xy 133.354535 -345.194815) (xy 133.395753 -345.159102) (xy 133.441635 -345.129619)
			(xy 133.491246 -345.106965) (xy 133.543576 -345.091603) (xy 133.597559 -345.083845) (xy 133.624828 -345.083384)
			(xy 134.488428 -345.083384) (xy 134.515699 -345.08378) (xy 134.569686 -345.091546) (xy 134.622019 -345.106916)
			(xy 134.671632 -345.129576) (xy 134.717514 -345.159067) (xy 134.758734 -345.194786) (xy 134.79445 -345.236008)
			(xy 134.823937 -345.281893) (xy 134.846594 -345.331507) (xy 134.86196 -345.383841) (xy 134.869722 -345.437829)
			(xy 134.869722 -345.492366) (xy 136.35257 -345.492366) (xy 136.35257 -345.437834) (xy 136.360331 -345.383858)
			(xy 136.375694 -345.331536) (xy 136.398346 -345.281933) (xy 136.427827 -345.236058) (xy 136.463537 -345.194846)
			(xy 136.504748 -345.159135) (xy 136.550622 -345.129652) (xy 136.600225 -345.106998) (xy 136.652547 -345.091633)
			(xy 136.706522 -345.083871) (xy 136.733788 -345.083384) (xy 137.597388 -345.083384) (xy 137.624663 -345.083755)
			(xy 137.678657 -345.091516) (xy 137.730998 -345.106884) (xy 137.780619 -345.129543) (xy 137.826509 -345.159034)
			(xy 137.867736 -345.194756) (xy 137.903459 -345.235981) (xy 137.932951 -345.281871) (xy 137.955612 -345.331491)
			(xy 137.970981 -345.383831) (xy 137.978744 -345.437825) (xy 137.978744 -345.49237) (xy 139.461448 -345.49237)
			(xy 139.461448 -345.43783) (xy 139.46921 -345.383846) (xy 139.484577 -345.331515) (xy 139.507235 -345.281905)
			(xy 139.536724 -345.236024) (xy 139.572442 -345.194808) (xy 139.613663 -345.159095) (xy 139.659547 -345.129612)
			(xy 139.70916 -345.10696) (xy 139.761492 -345.0916) (xy 139.815478 -345.083844) (xy 139.842748 -345.083384)
			(xy 140.706348 -345.083384) (xy 140.733618 -345.083782) (xy 140.787603 -345.09155) (xy 140.839933 -345.106921)
			(xy 140.889544 -345.129583) (xy 140.935424 -345.159074) (xy 140.976641 -345.194793) (xy 141.012355 -345.236015)
			(xy 141.04184 -345.281899) (xy 141.064495 -345.331512) (xy 141.07986 -345.383844) (xy 141.087622 -345.43783)
			(xy 141.087622 -345.492368) (xy 142.570447 -345.492368) (xy 142.570447 -345.437832) (xy 142.578209 -345.383851)
			(xy 142.593574 -345.331524) (xy 142.616229 -345.281916) (xy 142.645714 -345.236038) (xy 142.681428 -345.194822)
			(xy 142.722644 -345.159109) (xy 142.768523 -345.129625) (xy 142.818131 -345.106971) (xy 142.870459 -345.091607)
			(xy 142.92444 -345.083847) (xy 142.951708 -345.083384) (xy 143.815308 -345.083384) (xy 143.84258 -345.083779)
			(xy 143.89657 -345.091543) (xy 143.948904 -345.106911) (xy 143.99852 -345.12957) (xy 144.044405 -345.15906)
			(xy 144.085627 -345.194779) (xy 144.121345 -345.236001) (xy 144.150834 -345.281888) (xy 144.173492 -345.331503)
			(xy 144.188859 -345.383838) (xy 144.196621 -345.437828) (xy 144.196621 -345.492365) (xy 164.91387 -345.492365)
			(xy 164.91387 -345.437835) (xy 164.92163 -345.383861) (xy 164.936992 -345.33154) (xy 164.959644 -345.281937)
			(xy 164.989123 -345.236063) (xy 165.024831 -345.194851) (xy 165.066041 -345.15914) (xy 165.111913 -345.129657)
			(xy 165.161513 -345.107002) (xy 165.213833 -345.091636) (xy 165.267807 -345.083872) (xy 165.295072 -345.083384)
			(xy 166.158672 -345.083384) (xy 166.185948 -345.083754) (xy 166.239944 -345.091514) (xy 166.292286 -345.106879)
			(xy 166.341909 -345.129538) (xy 166.387802 -345.159028) (xy 166.42903 -345.19475) (xy 166.464755 -345.235976)
			(xy 166.494249 -345.281866) (xy 166.516911 -345.331487) (xy 166.532281 -345.383829) (xy 166.540044 -345.437824)
			(xy 166.540044 -345.492369) (xy 168.022747 -345.492369) (xy 168.022747 -345.437831) (xy 168.03051 -345.383848)
			(xy 168.045876 -345.331519) (xy 168.068533 -345.281909) (xy 168.09802 -345.23603) (xy 168.133736 -345.194814)
			(xy 168.174955 -345.159101) (xy 168.220838 -345.129617) (xy 168.270449 -345.106964) (xy 168.322779 -345.091603)
			(xy 168.376763 -345.083845) (xy 168.404032 -345.083384) (xy 169.267632 -345.083384) (xy 169.294903 -345.083781)
			(xy 169.34889 -345.091547) (xy 169.401222 -345.106917) (xy 169.450834 -345.129578) (xy 169.496716 -345.159068)
			(xy 169.537935 -345.194788) (xy 169.573651 -345.236009) (xy 169.603138 -345.281894) (xy 169.625794 -345.331508)
			(xy 169.64116 -345.383842) (xy 169.648922 -345.437829) (xy 169.648922 -345.492366) (xy 171.13177 -345.492366)
			(xy 171.13177 -345.437834) (xy 171.139531 -345.383858) (xy 171.154894 -345.331535) (xy 171.177547 -345.281932)
			(xy 171.207028 -345.236057) (xy 171.242738 -345.194844) (xy 171.28395 -345.159133) (xy 171.329825 -345.129651)
			(xy 171.379428 -345.106997) (xy 171.43175 -345.091633) (xy 171.485726 -345.083871) (xy 171.512992 -345.083384)
			(xy 172.376592 -345.083384) (xy 172.403867 -345.083755) (xy 172.457861 -345.091517) (xy 172.510201 -345.106885)
			(xy 172.559821 -345.129544) (xy 172.605711 -345.159035) (xy 172.646937 -345.194757) (xy 172.68266 -345.235982)
			(xy 172.712152 -345.281872) (xy 172.734813 -345.331492) (xy 172.750181 -345.383831) (xy 172.757944 -345.437825)
			(xy 172.757944 -345.492364) (xy 174.24077 -345.492364) (xy 174.24077 -345.437836) (xy 174.24853 -345.383863)
			(xy 174.263891 -345.331544) (xy 174.286541 -345.281943) (xy 174.316019 -345.23607) (xy 174.351724 -345.194858)
			(xy 174.392931 -345.159147) (xy 174.438801 -345.129664) (xy 174.488399 -345.107008) (xy 174.540716 -345.09164)
			(xy 174.594688 -345.083874) (xy 174.621952 -345.083384) (xy 175.485552 -345.083384) (xy 175.512829 -345.083752)
			(xy 175.566827 -345.09151) (xy 175.619172 -345.106874) (xy 175.668797 -345.129531) (xy 175.714692 -345.159021)
			(xy 175.755923 -345.194743) (xy 175.79165 -345.235969) (xy 175.821146 -345.281861) (xy 175.843809 -345.331483)
			(xy 175.85918 -345.383826) (xy 175.866944 -345.437824) (xy 175.866944 -345.492368) (xy 177.349647 -345.492368)
			(xy 177.349647 -345.437832) (xy 177.357409 -345.38385) (xy 177.372774 -345.331523) (xy 177.39543 -345.281915)
			(xy 177.424915 -345.236036) (xy 177.460629 -345.194821) (xy 177.501846 -345.159108) (xy 177.547726 -345.129624)
			(xy 177.597334 -345.10697) (xy 177.649662 -345.091606) (xy 177.703644 -345.083847) (xy 177.730912 -345.083384)
			(xy 178.594512 -345.083384) (xy 178.621784 -345.083779) (xy 178.675773 -345.091543) (xy 178.728107 -345.106912)
			(xy 178.777722 -345.129571) (xy 178.823607 -345.159061) (xy 178.864828 -345.194781) (xy 178.900546 -345.236003)
			(xy 178.930035 -345.281889) (xy 178.952693 -345.331504) (xy 178.968059 -345.383839) (xy 178.975821 -345.437828)
			(xy 178.975821 -345.492365) (xy 180.45867 -345.492365) (xy 180.45867 -345.437835) (xy 180.46643 -345.383861)
			(xy 180.481792 -345.33154) (xy 180.504444 -345.281937) (xy 180.533923 -345.236063) (xy 180.569631 -345.194851)
			(xy 180.610841 -345.15914) (xy 180.656713 -345.129657) (xy 180.706313 -345.107002) (xy 180.758633 -345.091636)
			(xy 180.812607 -345.083872) (xy 180.839872 -345.083384) (xy 181.703472 -345.083384) (xy 181.730748 -345.083754)
			(xy 181.784744 -345.091514) (xy 181.837086 -345.106879) (xy 181.886709 -345.129538) (xy 181.932602 -345.159028)
			(xy 181.97383 -345.19475) (xy 182.009555 -345.235976) (xy 182.039049 -345.281866) (xy 182.061711 -345.331487)
			(xy 182.077081 -345.383829) (xy 182.084844 -345.437824) (xy 182.084844 -345.492369) (xy 183.567547 -345.492369)
			(xy 183.567547 -345.437831) (xy 183.57531 -345.383848) (xy 183.590676 -345.331519) (xy 183.613333 -345.281909)
			(xy 183.64282 -345.23603) (xy 183.678536 -345.194814) (xy 183.719755 -345.159101) (xy 183.765638 -345.129617)
			(xy 183.815249 -345.106964) (xy 183.867579 -345.091603) (xy 183.921563 -345.083845) (xy 183.948832 -345.083384)
			(xy 184.812432 -345.083384) (xy 184.839703 -345.083781) (xy 184.89369 -345.091547) (xy 184.946022 -345.106917)
			(xy 184.995634 -345.129578) (xy 185.041516 -345.159068) (xy 185.082735 -345.194788) (xy 185.118451 -345.236009)
			(xy 185.147938 -345.281894) (xy 185.170594 -345.331508) (xy 185.18596 -345.383842) (xy 185.193722 -345.437829)
			(xy 185.193722 -345.492366) (xy 186.67657 -345.492366) (xy 186.67657 -345.437834) (xy 186.684331 -345.383858)
			(xy 186.699694 -345.331535) (xy 186.722347 -345.281932) (xy 186.751828 -345.236057) (xy 186.787538 -345.194844)
			(xy 186.82875 -345.159133) (xy 186.874625 -345.129651) (xy 186.924228 -345.106997) (xy 186.97655 -345.091633)
			(xy 187.030526 -345.083871) (xy 187.057792 -345.083384) (xy 187.921392 -345.083384) (xy 187.948667 -345.083755)
			(xy 188.002661 -345.091517) (xy 188.055001 -345.106885) (xy 188.104621 -345.129544) (xy 188.150511 -345.159035)
			(xy 188.191737 -345.194757) (xy 188.22746 -345.235982) (xy 188.256952 -345.281872) (xy 188.279613 -345.331492)
			(xy 188.294981 -345.383831) (xy 188.302744 -345.437825) (xy 188.302744 -345.492364) (xy 189.78557 -345.492364)
			(xy 189.78557 -345.437836) (xy 189.79333 -345.383863) (xy 189.808691 -345.331544) (xy 189.831341 -345.281943)
			(xy 189.860819 -345.23607) (xy 189.896524 -345.194858) (xy 189.937731 -345.159147) (xy 189.983601 -345.129664)
			(xy 190.033199 -345.107008) (xy 190.085516 -345.09164) (xy 190.139488 -345.083874) (xy 190.166752 -345.083384)
			(xy 191.030352 -345.083384) (xy 191.057629 -345.083752) (xy 191.111627 -345.09151) (xy 191.163972 -345.106874)
			(xy 191.213597 -345.129531) (xy 191.259492 -345.159021) (xy 191.300723 -345.194743) (xy 191.33645 -345.235969)
			(xy 191.365946 -345.281861) (xy 191.388609 -345.331483) (xy 191.40398 -345.383826) (xy 191.411744 -345.437824)
			(xy 191.411744 -345.492368) (xy 192.894447 -345.492368) (xy 192.894447 -345.437832) (xy 192.902209 -345.38385)
			(xy 192.917574 -345.331523) (xy 192.94023 -345.281915) (xy 192.969715 -345.236036) (xy 193.005429 -345.194821)
			(xy 193.046646 -345.159108) (xy 193.092526 -345.129624) (xy 193.142134 -345.10697) (xy 193.194462 -345.091606)
			(xy 193.248444 -345.083847) (xy 193.275712 -345.083384) (xy 194.139312 -345.083384) (xy 194.166584 -345.083779)
			(xy 194.220573 -345.091543) (xy 194.272907 -345.106912) (xy 194.322522 -345.129571) (xy 194.368407 -345.159061)
			(xy 194.409628 -345.194781) (xy 194.445346 -345.236003) (xy 194.474835 -345.281889) (xy 194.497493 -345.331504)
			(xy 194.512859 -345.383839) (xy 194.520621 -345.437828) (xy 194.520621 -345.492365) (xy 196.00347 -345.492365)
			(xy 196.00347 -345.437835) (xy 196.01123 -345.383861) (xy 196.026592 -345.33154) (xy 196.049244 -345.281937)
			(xy 196.078723 -345.236063) (xy 196.114431 -345.194851) (xy 196.155641 -345.15914) (xy 196.201513 -345.129657)
			(xy 196.251113 -345.107002) (xy 196.303433 -345.091636) (xy 196.357407 -345.083872) (xy 196.384672 -345.083384)
			(xy 197.248272 -345.083384) (xy 197.275548 -345.083754) (xy 197.329544 -345.091514) (xy 197.381886 -345.106879)
			(xy 197.431509 -345.129538) (xy 197.477402 -345.159028) (xy 197.51863 -345.19475) (xy 197.554355 -345.235976)
			(xy 197.583849 -345.281866) (xy 197.606511 -345.331487) (xy 197.621881 -345.383829) (xy 197.629644 -345.437824)
			(xy 197.629644 -345.492376) (xy 197.621881 -345.546371) (xy 197.606511 -345.598713) (xy 197.583849 -345.648334)
			(xy 197.554355 -345.694224) (xy 197.51863 -345.73545) (xy 197.477402 -345.771172) (xy 197.431509 -345.800662)
			(xy 197.381886 -345.823321) (xy 197.329544 -345.838686) (xy 197.275548 -345.846446) (xy 197.248272 -345.846908)
			(xy 196.384672 -345.846908) (xy 196.357407 -345.846328) (xy 196.303433 -345.838564) (xy 196.251113 -345.823198)
			(xy 196.201513 -345.800543) (xy 196.155641 -345.77106) (xy 196.114431 -345.735349) (xy 196.078723 -345.694137)
			(xy 196.049244 -345.648263) (xy 196.026592 -345.59866) (xy 196.01123 -345.546339) (xy 196.00347 -345.492365)
			(xy 194.520621 -345.492365) (xy 194.520621 -345.492372) (xy 194.512859 -345.546361) (xy 194.497493 -345.598696)
			(xy 194.474835 -345.648311) (xy 194.445346 -345.694197) (xy 194.409628 -345.735419) (xy 194.368407 -345.771139)
			(xy 194.322522 -345.800629) (xy 194.272907 -345.823288) (xy 194.220573 -345.838657) (xy 194.166584 -345.846421)
			(xy 194.139312 -345.846908) (xy 193.275712 -345.846908) (xy 193.248444 -345.846353) (xy 193.194462 -345.838594)
			(xy 193.142134 -345.82323) (xy 193.092526 -345.800576) (xy 193.046646 -345.771092) (xy 193.005429 -345.735379)
			(xy 192.969715 -345.694164) (xy 192.94023 -345.648285) (xy 192.917574 -345.598677) (xy 192.902209 -345.54635)
			(xy 192.894447 -345.492368) (xy 191.411744 -345.492368) (xy 191.411744 -345.492376) (xy 191.40398 -345.546374)
			(xy 191.388609 -345.598717) (xy 191.365946 -345.648339) (xy 191.33645 -345.694231) (xy 191.300723 -345.735457)
			(xy 191.259492 -345.771179) (xy 191.213597 -345.800669) (xy 191.163972 -345.823326) (xy 191.111627 -345.83869)
			(xy 191.057629 -345.846448) (xy 191.030352 -345.846908) (xy 190.166752 -345.846908) (xy 190.139488 -345.846326)
			(xy 190.085516 -345.83856) (xy 190.033199 -345.823192) (xy 189.983601 -345.800536) (xy 189.937731 -345.771053)
			(xy 189.896524 -345.735342) (xy 189.860819 -345.69413) (xy 189.831341 -345.648257) (xy 189.808691 -345.598656)
			(xy 189.79333 -345.546337) (xy 189.78557 -345.492364) (xy 188.302744 -345.492364) (xy 188.302744 -345.492375)
			(xy 188.294981 -345.546369) (xy 188.279613 -345.598708) (xy 188.256952 -345.648328) (xy 188.22746 -345.694218)
			(xy 188.191737 -345.735443) (xy 188.150511 -345.771165) (xy 188.104621 -345.800656) (xy 188.055001 -345.823315)
			(xy 188.002661 -345.838683) (xy 187.948667 -345.846445) (xy 187.921392 -345.846908) (xy 187.057792 -345.846908)
			(xy 187.030526 -345.846329) (xy 186.97655 -345.838567) (xy 186.924228 -345.823203) (xy 186.874625 -345.800549)
			(xy 186.82875 -345.771067) (xy 186.787538 -345.735356) (xy 186.751828 -345.694143) (xy 186.722347 -345.648268)
			(xy 186.699694 -345.598665) (xy 186.684331 -345.546342) (xy 186.67657 -345.492366) (xy 185.193722 -345.492366)
			(xy 185.193722 -345.492371) (xy 185.18596 -345.546358) (xy 185.170594 -345.598692) (xy 185.147938 -345.648306)
			(xy 185.118451 -345.694191) (xy 185.082735 -345.735412) (xy 185.041516 -345.771132) (xy 184.995634 -345.800622)
			(xy 184.946022 -345.823283) (xy 184.89369 -345.838653) (xy 184.839703 -345.846419) (xy 184.812432 -345.846908)
			(xy 183.948832 -345.846908) (xy 183.921563 -345.846355) (xy 183.867579 -345.838597) (xy 183.815249 -345.823236)
			(xy 183.765638 -345.800583) (xy 183.719755 -345.771099) (xy 183.678536 -345.735386) (xy 183.64282 -345.69417)
			(xy 183.613333 -345.648291) (xy 183.590676 -345.598681) (xy 183.57531 -345.546352) (xy 183.567547 -345.492369)
			(xy 182.084844 -345.492369) (xy 182.084844 -345.492376) (xy 182.077081 -345.546371) (xy 182.061711 -345.598713)
			(xy 182.039049 -345.648334) (xy 182.009555 -345.694224) (xy 181.97383 -345.73545) (xy 181.932602 -345.771172)
			(xy 181.886709 -345.800662) (xy 181.837086 -345.823321) (xy 181.784744 -345.838686) (xy 181.730748 -345.846446)
			(xy 181.703472 -345.846908) (xy 180.839872 -345.846908) (xy 180.812607 -345.846328) (xy 180.758633 -345.838564)
			(xy 180.706313 -345.823198) (xy 180.656713 -345.800543) (xy 180.610841 -345.77106) (xy 180.569631 -345.735349)
			(xy 180.533923 -345.694137) (xy 180.504444 -345.648263) (xy 180.481792 -345.59866) (xy 180.46643 -345.546339)
			(xy 180.45867 -345.492365) (xy 178.975821 -345.492365) (xy 178.975821 -345.492372) (xy 178.968059 -345.546361)
			(xy 178.952693 -345.598696) (xy 178.930035 -345.648311) (xy 178.900546 -345.694197) (xy 178.864828 -345.735419)
			(xy 178.823607 -345.771139) (xy 178.777722 -345.800629) (xy 178.728107 -345.823288) (xy 178.675773 -345.838657)
			(xy 178.621784 -345.846421) (xy 178.594512 -345.846908) (xy 177.730912 -345.846908) (xy 177.703644 -345.846353)
			(xy 177.649662 -345.838594) (xy 177.597334 -345.82323) (xy 177.547726 -345.800576) (xy 177.501846 -345.771092)
			(xy 177.460629 -345.735379) (xy 177.424915 -345.694164) (xy 177.39543 -345.648285) (xy 177.372774 -345.598677)
			(xy 177.357409 -345.54635) (xy 177.349647 -345.492368) (xy 175.866944 -345.492368) (xy 175.866944 -345.492376)
			(xy 175.85918 -345.546374) (xy 175.843809 -345.598717) (xy 175.821146 -345.648339) (xy 175.79165 -345.694231)
			(xy 175.755923 -345.735457) (xy 175.714692 -345.771179) (xy 175.668797 -345.800669) (xy 175.619172 -345.823326)
			(xy 175.566827 -345.83869) (xy 175.512829 -345.846448) (xy 175.485552 -345.846908) (xy 174.621952 -345.846908)
			(xy 174.594688 -345.846326) (xy 174.540716 -345.83856) (xy 174.488399 -345.823192) (xy 174.438801 -345.800536)
			(xy 174.392931 -345.771053) (xy 174.351724 -345.735342) (xy 174.316019 -345.69413) (xy 174.286541 -345.648257)
			(xy 174.263891 -345.598656) (xy 174.24853 -345.546337) (xy 174.24077 -345.492364) (xy 172.757944 -345.492364)
			(xy 172.757944 -345.492375) (xy 172.750181 -345.546369) (xy 172.734813 -345.598708) (xy 172.712152 -345.648328)
			(xy 172.68266 -345.694218) (xy 172.646937 -345.735443) (xy 172.605711 -345.771165) (xy 172.559821 -345.800656)
			(xy 172.510201 -345.823315) (xy 172.457861 -345.838683) (xy 172.403867 -345.846445) (xy 172.376592 -345.846908)
			(xy 171.512992 -345.846908) (xy 171.485726 -345.846329) (xy 171.43175 -345.838567) (xy 171.379428 -345.823203)
			(xy 171.329825 -345.800549) (xy 171.28395 -345.771067) (xy 171.242738 -345.735356) (xy 171.207028 -345.694143)
			(xy 171.177547 -345.648268) (xy 171.154894 -345.598665) (xy 171.139531 -345.546342) (xy 171.13177 -345.492366)
			(xy 169.648922 -345.492366) (xy 169.648922 -345.492371) (xy 169.64116 -345.546358) (xy 169.625794 -345.598692)
			(xy 169.603138 -345.648306) (xy 169.573651 -345.694191) (xy 169.537935 -345.735412) (xy 169.496716 -345.771132)
			(xy 169.450834 -345.800622) (xy 169.401222 -345.823283) (xy 169.34889 -345.838653) (xy 169.294903 -345.846419)
			(xy 169.267632 -345.846908) (xy 168.404032 -345.846908) (xy 168.376763 -345.846355) (xy 168.322779 -345.838597)
			(xy 168.270449 -345.823236) (xy 168.220838 -345.800583) (xy 168.174955 -345.771099) (xy 168.133736 -345.735386)
			(xy 168.09802 -345.69417) (xy 168.068533 -345.648291) (xy 168.045876 -345.598681) (xy 168.03051 -345.546352)
			(xy 168.022747 -345.492369) (xy 166.540044 -345.492369) (xy 166.540044 -345.492376) (xy 166.532281 -345.546371)
			(xy 166.516911 -345.598713) (xy 166.494249 -345.648334) (xy 166.464755 -345.694224) (xy 166.42903 -345.73545)
			(xy 166.387802 -345.771172) (xy 166.341909 -345.800662) (xy 166.292286 -345.823321) (xy 166.239944 -345.838686)
			(xy 166.185948 -345.846446) (xy 166.158672 -345.846908) (xy 165.295072 -345.846908) (xy 165.267807 -345.846328)
			(xy 165.213833 -345.838564) (xy 165.161513 -345.823198) (xy 165.111913 -345.800543) (xy 165.066041 -345.77106)
			(xy 165.024831 -345.735349) (xy 164.989123 -345.694137) (xy 164.959644 -345.648263) (xy 164.936992 -345.59866)
			(xy 164.92163 -345.546339) (xy 164.91387 -345.492365) (xy 144.196621 -345.492365) (xy 144.196621 -345.492372)
			(xy 144.188859 -345.546362) (xy 144.173492 -345.598697) (xy 144.150834 -345.648312) (xy 144.121345 -345.694199)
			(xy 144.085627 -345.735421) (xy 144.044405 -345.77114) (xy 143.99852 -345.80063) (xy 143.948904 -345.82329)
			(xy 143.89657 -345.838657) (xy 143.84258 -345.846421) (xy 143.815308 -345.846908) (xy 142.951708 -345.846908)
			(xy 142.92444 -345.846353) (xy 142.870459 -345.838593) (xy 142.818131 -345.823229) (xy 142.768523 -345.800575)
			(xy 142.722644 -345.771091) (xy 142.681428 -345.735378) (xy 142.645714 -345.694162) (xy 142.616229 -345.648284)
			(xy 142.593574 -345.598676) (xy 142.578209 -345.546349) (xy 142.570447 -345.492368) (xy 141.087622 -345.492368)
			(xy 141.087622 -345.49237) (xy 141.07986 -345.546356) (xy 141.064495 -345.598688) (xy 141.04184 -345.648301)
			(xy 141.012355 -345.694185) (xy 140.976641 -345.735407) (xy 140.935424 -345.771126) (xy 140.889543 -345.800617)
			(xy 140.839933 -345.823279) (xy 140.787603 -345.83865) (xy 140.733618 -345.846418) (xy 140.706348 -345.846908)
			(xy 139.842748 -345.846908) (xy 139.815478 -345.846356) (xy 139.761492 -345.8386) (xy 139.70916 -345.82324)
			(xy 139.659547 -345.800588) (xy 139.613663 -345.771105) (xy 139.572442 -345.735392) (xy 139.536724 -345.694176)
			(xy 139.507235 -345.648295) (xy 139.484577 -345.598685) (xy 139.46921 -345.546354) (xy 139.461448 -345.49237)
			(xy 137.978744 -345.49237) (xy 137.978744 -345.492375) (xy 137.970981 -345.546369) (xy 137.955612 -345.598709)
			(xy 137.932951 -345.648329) (xy 137.903459 -345.694219) (xy 137.867736 -345.735444) (xy 137.826509 -345.771166)
			(xy 137.780619 -345.800657) (xy 137.730998 -345.823316) (xy 137.678658 -345.838684) (xy 137.624663 -345.846445)
			(xy 137.597388 -345.846908) (xy 136.733788 -345.846908) (xy 136.706522 -345.846329) (xy 136.652547 -345.838567)
			(xy 136.600225 -345.823202) (xy 136.550622 -345.800548) (xy 136.504748 -345.771065) (xy 136.463537 -345.735354)
			(xy 136.427827 -345.694142) (xy 136.398346 -345.648267) (xy 136.375694 -345.598664) (xy 136.360331 -345.546342)
			(xy 136.35257 -345.492366) (xy 134.869722 -345.492366) (xy 134.869722 -345.492371) (xy 134.86196 -345.546359)
			(xy 134.846594 -345.598693) (xy 134.823937 -345.648307) (xy 134.79445 -345.694192) (xy 134.758734 -345.735414)
			(xy 134.717514 -345.771133) (xy 134.671632 -345.800624) (xy 134.622019 -345.823284) (xy 134.569686 -345.838654)
			(xy 134.515699 -345.84642) (xy 134.488428 -345.846908) (xy 133.624828 -345.846908) (xy 133.597559 -345.846355)
			(xy 133.543576 -345.838597) (xy 133.491246 -345.823235) (xy 133.441635 -345.800581) (xy 133.395753 -345.771098)
			(xy 133.354535 -345.735385) (xy 133.318819 -345.694169) (xy 133.289332 -345.648289) (xy 133.266675 -345.59868)
			(xy 133.251309 -345.546352) (xy 133.243547 -345.492369) (xy 131.760844 -345.492369) (xy 131.760844 -345.492376)
			(xy 131.75308 -345.546372) (xy 131.737711 -345.598713) (xy 131.715048 -345.648335) (xy 131.685554 -345.694225)
			(xy 131.649829 -345.735451) (xy 131.6086 -345.771173) (xy 131.562707 -345.800663) (xy 131.513083 -345.823322)
			(xy 131.460741 -345.838687) (xy 131.406744 -345.846447) (xy 131.379468 -345.846908) (xy 130.515868 -345.846908)
			(xy 130.488603 -345.846328) (xy 130.43463 -345.838563) (xy 130.38231 -345.823197) (xy 130.33271 -345.800542)
			(xy 130.286839 -345.771058) (xy 130.24563 -345.735347) (xy 130.209922 -345.694136) (xy 130.180443 -345.648262)
			(xy 130.157792 -345.59866) (xy 130.14243 -345.546339) (xy 130.13467 -345.492365) (xy 128.651821 -345.492365)
			(xy 128.651821 -345.492372) (xy 128.644059 -345.546362) (xy 128.628692 -345.598697) (xy 128.606034 -345.648312)
			(xy 128.576545 -345.694199) (xy 128.540827 -345.735421) (xy 128.499605 -345.77114) (xy 128.45372 -345.80063)
			(xy 128.404104 -345.82329) (xy 128.35177 -345.838657) (xy 128.29778 -345.846421) (xy 128.270508 -345.846908)
			(xy 127.406908 -345.846908) (xy 127.37964 -345.846353) (xy 127.325659 -345.838593) (xy 127.273331 -345.823229)
			(xy 127.223723 -345.800575) (xy 127.177844 -345.771091) (xy 127.136628 -345.735378) (xy 127.100914 -345.694162)
			(xy 127.071429 -345.648284) (xy 127.048774 -345.598676) (xy 127.033409 -345.546349) (xy 127.025647 -345.492368)
			(xy 125.542822 -345.492368) (xy 125.542822 -345.49237) (xy 125.53506 -345.546356) (xy 125.519695 -345.598688)
			(xy 125.49704 -345.648301) (xy 125.467555 -345.694185) (xy 125.431841 -345.735407) (xy 125.390624 -345.771126)
			(xy 125.344743 -345.800617) (xy 125.295133 -345.823279) (xy 125.242803 -345.83865) (xy 125.188818 -345.846418)
			(xy 125.161548 -345.846908) (xy 124.297948 -345.846908) (xy 124.270678 -345.846356) (xy 124.216692 -345.8386)
			(xy 124.16436 -345.82324) (xy 124.114747 -345.800588) (xy 124.068863 -345.771105) (xy 124.027642 -345.735392)
			(xy 123.991924 -345.694176) (xy 123.962435 -345.648295) (xy 123.939777 -345.598685) (xy 123.92441 -345.546354)
			(xy 123.916648 -345.49237) (xy 122.433944 -345.49237) (xy 122.433944 -345.492375) (xy 122.426181 -345.546369)
			(xy 122.410812 -345.598709) (xy 122.388151 -345.648329) (xy 122.358659 -345.694219) (xy 122.322936 -345.735444)
			(xy 122.281709 -345.771166) (xy 122.235819 -345.800657) (xy 122.186198 -345.823316) (xy 122.133858 -345.838684)
			(xy 122.079863 -345.846445) (xy 122.052588 -345.846908) (xy 121.188988 -345.846908) (xy 121.161722 -345.846329)
			(xy 121.107747 -345.838567) (xy 121.055425 -345.823202) (xy 121.005822 -345.800548) (xy 120.959948 -345.771065)
			(xy 120.918737 -345.735354) (xy 120.883027 -345.694142) (xy 120.853546 -345.648267) (xy 120.830894 -345.598664)
			(xy 120.815531 -345.546342) (xy 120.80777 -345.492366) (xy 119.324922 -345.492366) (xy 119.324922 -345.492371)
			(xy 119.31716 -345.546359) (xy 119.301794 -345.598693) (xy 119.279137 -345.648307) (xy 119.24965 -345.694192)
			(xy 119.213934 -345.735414) (xy 119.172714 -345.771133) (xy 119.126832 -345.800624) (xy 119.077219 -345.823284)
			(xy 119.024886 -345.838654) (xy 118.970899 -345.84642) (xy 118.943628 -345.846908) (xy 118.080028 -345.846908)
			(xy 118.052759 -345.846355) (xy 117.998776 -345.838597) (xy 117.946446 -345.823235) (xy 117.896835 -345.800581)
			(xy 117.850953 -345.771098) (xy 117.809735 -345.735385) (xy 117.774019 -345.694169) (xy 117.744532 -345.648289)
			(xy 117.721875 -345.59868) (xy 117.706509 -345.546352) (xy 117.698747 -345.492369) (xy 116.216044 -345.492369)
			(xy 116.216044 -345.492376) (xy 116.20828 -345.546372) (xy 116.192911 -345.598713) (xy 116.170248 -345.648335)
			(xy 116.140754 -345.694225) (xy 116.105029 -345.735451) (xy 116.0638 -345.771173) (xy 116.017907 -345.800663)
			(xy 115.968283 -345.823322) (xy 115.915941 -345.838687) (xy 115.861944 -345.846447) (xy 115.834668 -345.846908)
			(xy 114.971068 -345.846908) (xy 114.943803 -345.846328) (xy 114.88983 -345.838563) (xy 114.83751 -345.823197)
			(xy 114.78791 -345.800542) (xy 114.742039 -345.771058) (xy 114.70083 -345.735347) (xy 114.665122 -345.694136)
			(xy 114.635643 -345.648262) (xy 114.612992 -345.59866) (xy 114.59763 -345.546339) (xy 114.58987 -345.492365)
			(xy 113.107021 -345.492365) (xy 113.107021 -345.492372) (xy 113.099259 -345.546362) (xy 113.083892 -345.598697)
			(xy 113.061234 -345.648312) (xy 113.031745 -345.694199) (xy 112.996027 -345.735421) (xy 112.954805 -345.77114)
			(xy 112.90892 -345.80063) (xy 112.859304 -345.82329) (xy 112.80697 -345.838657) (xy 112.75298 -345.846421)
			(xy 112.725708 -345.846908) (xy 111.862108 -345.846908) (xy 111.83484 -345.846353) (xy 111.780859 -345.838593)
			(xy 111.728531 -345.823229) (xy 111.678923 -345.800575) (xy 111.633044 -345.771091) (xy 111.591828 -345.735378)
			(xy 111.556114 -345.694162) (xy 111.526629 -345.648284) (xy 111.503974 -345.598676) (xy 111.488609 -345.546349)
			(xy 111.480847 -345.492368) (xy 93.706722 -345.492368) (xy 93.706722 -345.492371) (xy 93.69896 -345.546357)
			(xy 93.683595 -345.59869) (xy 93.660939 -345.648303) (xy 93.631454 -345.694187) (xy 93.595739 -345.735409)
			(xy 93.554521 -345.771128) (xy 93.50864 -345.800619) (xy 93.459029 -345.82328) (xy 93.406698 -345.838651)
			(xy 93.352713 -345.846419) (xy 93.325442 -345.846908) (xy 92.461842 -345.846908) (xy 92.434572 -345.846355)
			(xy 92.380587 -345.838599) (xy 92.328256 -345.823238) (xy 92.278643 -345.800586) (xy 92.23276 -345.771103)
			(xy 92.19154 -345.73539) (xy 92.155822 -345.694174) (xy 92.126334 -345.648293) (xy 92.103676 -345.598683)
			(xy 92.08831 -345.546354) (xy 92.080548 -345.49237) (xy 90.597844 -345.49237) (xy 90.597844 -345.492375)
			(xy 90.590081 -345.54637) (xy 90.574712 -345.59871) (xy 90.55205 -345.648331) (xy 90.522557 -345.694221)
			(xy 90.486834 -345.735446) (xy 90.445606 -345.771168) (xy 90.399715 -345.800659) (xy 90.350094 -345.823318)
			(xy 90.297752 -345.838685) (xy 90.243757 -345.846446) (xy 90.216482 -345.846908) (xy 89.352882 -345.846908)
			(xy 89.325617 -345.846328) (xy 89.271642 -345.838566) (xy 89.219321 -345.823201) (xy 89.169719 -345.800546)
			(xy 89.123845 -345.771063) (xy 89.082635 -345.735352) (xy 89.046926 -345.69414) (xy 89.017445 -345.648266)
			(xy 88.994793 -345.598663) (xy 88.979431 -345.546341) (xy 88.97167 -345.492365) (xy 87.488822 -345.492365)
			(xy 87.488822 -345.492372) (xy 87.481059 -345.54636) (xy 87.465693 -345.598694) (xy 87.443036 -345.648309)
			(xy 87.413549 -345.694194) (xy 87.377832 -345.735416) (xy 87.336612 -345.771136) (xy 87.290728 -345.800626)
			(xy 87.241115 -345.823286) (xy 87.188781 -345.838655) (xy 87.134794 -345.84642) (xy 87.107522 -345.846908)
			(xy 86.243922 -345.846908) (xy 86.216653 -345.846354) (xy 86.16267 -345.838595) (xy 86.110341 -345.823233)
			(xy 86.060732 -345.800579) (xy 86.014851 -345.771096) (xy 85.973633 -345.735383) (xy 85.937917 -345.694167)
			(xy 85.908431 -345.648288) (xy 85.885775 -345.598679) (xy 85.870409 -345.546351) (xy 85.862647 -345.492369)
			(xy 84.379944 -345.492369) (xy 84.379944 -345.492376) (xy 84.37218 -345.546373) (xy 84.35681 -345.598715)
			(xy 84.334147 -345.648336) (xy 84.304652 -345.694227) (xy 84.268927 -345.735453) (xy 84.227697 -345.771175)
			(xy 84.181803 -345.800665) (xy 84.132179 -345.823323) (xy 84.079836 -345.838688) (xy 84.025838 -345.846447)
			(xy 83.998562 -345.846908) (xy 83.134962 -345.846908) (xy 83.107698 -345.846327) (xy 83.053725 -345.838562)
			(xy 83.001406 -345.823195) (xy 82.951807 -345.80054) (xy 82.905936 -345.771056) (xy 82.864728 -345.735345)
			(xy 82.829021 -345.694134) (xy 82.799542 -345.64826) (xy 82.776892 -345.598658) (xy 82.76153 -345.546338)
			(xy 82.75377 -345.492364) (xy 81.270921 -345.492364) (xy 81.270921 -345.492373) (xy 81.263159 -345.546362)
			(xy 81.247792 -345.598698) (xy 81.225133 -345.648314) (xy 81.195644 -345.6942) (xy 81.159924 -345.735423)
			(xy 81.118702 -345.771143) (xy 81.072816 -345.800632) (xy 81.0232 -345.823291) (xy 80.970864 -345.838658)
			(xy 80.916875 -345.846421) (xy 80.889602 -345.846908) (xy 80.026002 -345.846908) (xy 79.998734 -345.846353)
			(xy 79.944754 -345.838592) (xy 79.892427 -345.823228) (xy 79.84282 -345.800573) (xy 79.796941 -345.771089)
			(xy 79.755726 -345.735376) (xy 79.720012 -345.69416) (xy 79.690528 -345.648282) (xy 79.667873 -345.598675)
			(xy 79.652509 -345.546348) (xy 79.644747 -345.492368) (xy 78.161922 -345.492368) (xy 78.161922 -345.492371)
			(xy 78.15416 -345.546357) (xy 78.138795 -345.59869) (xy 78.116139 -345.648303) (xy 78.086654 -345.694187)
			(xy 78.050939 -345.735409) (xy 78.009721 -345.771128) (xy 77.96384 -345.800619) (xy 77.914229 -345.82328)
			(xy 77.861898 -345.838651) (xy 77.807913 -345.846419) (xy 77.780642 -345.846908) (xy 76.917042 -345.846908)
			(xy 76.889772 -345.846355) (xy 76.835787 -345.838599) (xy 76.783456 -345.823238) (xy 76.733843 -345.800586)
			(xy 76.68796 -345.771103) (xy 76.64674 -345.73539) (xy 76.611022 -345.694174) (xy 76.581534 -345.648293)
			(xy 76.558876 -345.598683) (xy 76.54351 -345.546354) (xy 76.535748 -345.49237) (xy 75.053044 -345.49237)
			(xy 75.053044 -345.492375) (xy 75.045281 -345.54637) (xy 75.029912 -345.59871) (xy 75.00725 -345.648331)
			(xy 74.977757 -345.694221) (xy 74.942034 -345.735446) (xy 74.900806 -345.771168) (xy 74.854915 -345.800659)
			(xy 74.805294 -345.823318) (xy 74.752952 -345.838685) (xy 74.698957 -345.846446) (xy 74.671682 -345.846908)
			(xy 73.808082 -345.846908) (xy 73.780817 -345.846328) (xy 73.726842 -345.838566) (xy 73.674521 -345.823201)
			(xy 73.624919 -345.800546) (xy 73.579045 -345.771063) (xy 73.537835 -345.735352) (xy 73.502126 -345.69414)
			(xy 73.472645 -345.648266) (xy 73.449993 -345.598663) (xy 73.434631 -345.546341) (xy 73.42687 -345.492365)
			(xy 71.944022 -345.492365) (xy 71.944022 -345.492372) (xy 71.936259 -345.54636) (xy 71.920893 -345.598694)
			(xy 71.898236 -345.648309) (xy 71.868749 -345.694194) (xy 71.833032 -345.735416) (xy 71.791812 -345.771136)
			(xy 71.745928 -345.800626) (xy 71.696315 -345.823286) (xy 71.643981 -345.838655) (xy 71.589994 -345.84642)
			(xy 71.562722 -345.846908) (xy 70.699122 -345.846908) (xy 70.671853 -345.846354) (xy 70.61787 -345.838595)
			(xy 70.565541 -345.823233) (xy 70.515932 -345.800579) (xy 70.470051 -345.771096) (xy 70.428833 -345.735383)
			(xy 70.393117 -345.694167) (xy 70.363631 -345.648288) (xy 70.340975 -345.598679) (xy 70.325609 -345.546351)
			(xy 70.317847 -345.492369) (xy 68.835144 -345.492369) (xy 68.835144 -345.492376) (xy 68.82738 -345.546373)
			(xy 68.81201 -345.598715) (xy 68.789347 -345.648336) (xy 68.759852 -345.694227) (xy 68.724127 -345.735453)
			(xy 68.682897 -345.771175) (xy 68.637003 -345.800665) (xy 68.587379 -345.823323) (xy 68.535036 -345.838688)
			(xy 68.481038 -345.846447) (xy 68.453762 -345.846908) (xy 67.590162 -345.846908) (xy 67.562898 -345.846327)
			(xy 67.508925 -345.838562) (xy 67.456606 -345.823195) (xy 67.407007 -345.80054) (xy 67.361136 -345.771056)
			(xy 67.319928 -345.735345) (xy 67.284221 -345.694134) (xy 67.254742 -345.64826) (xy 67.232092 -345.598658)
			(xy 67.21673 -345.546338) (xy 67.20897 -345.492364) (xy 65.726121 -345.492364) (xy 65.726121 -345.492373)
			(xy 65.718359 -345.546362) (xy 65.702992 -345.598698) (xy 65.680333 -345.648314) (xy 65.650844 -345.6942)
			(xy 65.615124 -345.735423) (xy 65.573902 -345.771143) (xy 65.528016 -345.800632) (xy 65.4784 -345.823291)
			(xy 65.426064 -345.838658) (xy 65.372075 -345.846421) (xy 65.344802 -345.846908) (xy 64.481202 -345.846908)
			(xy 64.453934 -345.846353) (xy 64.399954 -345.838592) (xy 64.347627 -345.823228) (xy 64.29802 -345.800573)
			(xy 64.252141 -345.771089) (xy 64.210926 -345.735376) (xy 64.175212 -345.69416) (xy 64.145728 -345.648282)
			(xy 64.123073 -345.598675) (xy 64.107709 -345.546348) (xy 64.099947 -345.492368) (xy 62.617122 -345.492368)
			(xy 62.617122 -345.492371) (xy 62.60936 -345.546357) (xy 62.593995 -345.59869) (xy 62.571339 -345.648303)
			(xy 62.541854 -345.694187) (xy 62.506139 -345.735409) (xy 62.464921 -345.771128) (xy 62.41904 -345.800619)
			(xy 62.369429 -345.82328) (xy 62.317098 -345.838651) (xy 62.263113 -345.846419) (xy 62.235842 -345.846908)
			(xy 61.372242 -345.846908) (xy 61.344972 -345.846355) (xy 61.290987 -345.838599) (xy 61.238656 -345.823238)
			(xy 61.189043 -345.800586) (xy 61.14316 -345.771103) (xy 61.10194 -345.73539) (xy 61.066222 -345.694174)
			(xy 61.036734 -345.648293) (xy 61.014076 -345.598683) (xy 60.99871 -345.546354) (xy 60.990948 -345.49237)
			(xy 51.666922 -345.49237) (xy 51.65916 -345.546356) (xy 51.643795 -345.598688) (xy 51.62114 -345.648301)
			(xy 51.591655 -345.694185) (xy 51.555941 -345.735407) (xy 51.514724 -345.771126) (xy 51.468843 -345.800617)
			(xy 51.419233 -345.823279) (xy 51.366903 -345.83865) (xy 51.312918 -345.846418) (xy 51.285648 -345.846908)
			(xy 50.422048 -345.846908) (xy 50.394778 -345.846356) (xy 50.340792 -345.8386) (xy 50.28846 -345.82324)
			(xy 50.238847 -345.800588) (xy 50.192963 -345.771105) (xy 50.151742 -345.735392) (xy 50.116024 -345.694176)
			(xy 50.086535 -345.648295) (xy 50.063877 -345.598685) (xy 50.04851 -345.546354) (xy 50.040748 -345.49237)
			(xy 48.558044 -345.49237) (xy 48.558044 -345.492375) (xy 48.550281 -345.546369) (xy 48.534912 -345.598709)
			(xy 48.512251 -345.648329) (xy 48.482759 -345.694219) (xy 48.447036 -345.735444) (xy 48.405809 -345.771166)
			(xy 48.359919 -345.800657) (xy 48.310298 -345.823316) (xy 48.257958 -345.838684) (xy 48.203963 -345.846445)
			(xy 48.176688 -345.846908) (xy 47.313088 -345.846908) (xy 47.285822 -345.846329) (xy 47.231847 -345.838567)
			(xy 47.179525 -345.823202) (xy 47.129922 -345.800548) (xy 47.084048 -345.771065) (xy 47.042837 -345.735354)
			(xy 47.007127 -345.694142) (xy 46.977646 -345.648267) (xy 46.954994 -345.598664) (xy 46.939631 -345.546342)
			(xy 46.93187 -345.492366) (xy 45.449022 -345.492366) (xy 45.449022 -345.492371) (xy 45.44126 -345.546359)
			(xy 45.425894 -345.598693) (xy 45.403237 -345.648307) (xy 45.37375 -345.694192) (xy 45.338034 -345.735414)
			(xy 45.296814 -345.771133) (xy 45.250932 -345.800624) (xy 45.201319 -345.823284) (xy 45.148986 -345.838654)
			(xy 45.094999 -345.84642) (xy 45.067728 -345.846908) (xy 44.204128 -345.846908) (xy 44.176859 -345.846355)
			(xy 44.122876 -345.838597) (xy 44.070546 -345.823235) (xy 44.020935 -345.800581) (xy 43.975053 -345.771098)
			(xy 43.933835 -345.735385) (xy 43.898119 -345.694169) (xy 43.868632 -345.648289) (xy 43.845975 -345.59868)
			(xy 43.830609 -345.546352) (xy 43.822847 -345.492369) (xy 42.340144 -345.492369) (xy 42.340144 -345.492376)
			(xy 42.33238 -345.546372) (xy 42.317011 -345.598713) (xy 42.294348 -345.648335) (xy 42.264854 -345.694225)
			(xy 42.229129 -345.735451) (xy 42.1879 -345.771173) (xy 42.142007 -345.800663) (xy 42.092383 -345.823322)
			(xy 42.040041 -345.838687) (xy 41.986044 -345.846447) (xy 41.958768 -345.846908) (xy 41.095168 -345.846908)
			(xy 41.067903 -345.846328) (xy 41.01393 -345.838563) (xy 40.96161 -345.823197) (xy 40.91201 -345.800542)
			(xy 40.866139 -345.771058) (xy 40.82493 -345.735347) (xy 40.789222 -345.694136) (xy 40.759743 -345.648262)
			(xy 40.737092 -345.59866) (xy 40.72173 -345.546339) (xy 40.71397 -345.492365) (xy 39.231121 -345.492365)
			(xy 39.231121 -345.492372) (xy 39.223359 -345.546362) (xy 39.207992 -345.598697) (xy 39.185334 -345.648312)
			(xy 39.155845 -345.694199) (xy 39.120127 -345.735421) (xy 39.078905 -345.77114) (xy 39.03302 -345.80063)
			(xy 38.983404 -345.82329) (xy 38.93107 -345.838657) (xy 38.87708 -345.846421) (xy 38.849808 -345.846908)
			(xy 37.986208 -345.846908) (xy 37.95894 -345.846353) (xy 37.904959 -345.838593) (xy 37.852631 -345.823229)
			(xy 37.803023 -345.800575) (xy 37.757144 -345.771091) (xy 37.715928 -345.735378) (xy 37.680214 -345.694162)
			(xy 37.650729 -345.648284) (xy 37.628074 -345.598676) (xy 37.612709 -345.546349) (xy 37.604947 -345.492368)
			(xy 36.122122 -345.492368) (xy 36.122122 -345.49237) (xy 36.11436 -345.546356) (xy 36.098995 -345.598688)
			(xy 36.07634 -345.648301) (xy 36.046855 -345.694185) (xy 36.011141 -345.735407) (xy 35.969924 -345.771126)
			(xy 35.924043 -345.800617) (xy 35.874433 -345.823279) (xy 35.822103 -345.83865) (xy 35.768118 -345.846418)
			(xy 35.740848 -345.846908) (xy 34.877248 -345.846908) (xy 34.849978 -345.846356) (xy 34.795992 -345.8386)
			(xy 34.74366 -345.82324) (xy 34.694047 -345.800588) (xy 34.648163 -345.771105) (xy 34.606942 -345.735392)
			(xy 34.571224 -345.694176) (xy 34.541735 -345.648295) (xy 34.519077 -345.598685) (xy 34.50371 -345.546354)
			(xy 34.495948 -345.49237) (xy 33.013244 -345.49237) (xy 33.013244 -345.492375) (xy 33.005481 -345.546369)
			(xy 32.990112 -345.598709) (xy 32.967451 -345.648329) (xy 32.937959 -345.694219) (xy 32.902236 -345.735444)
			(xy 32.861009 -345.771166) (xy 32.815119 -345.800657) (xy 32.765498 -345.823316) (xy 32.713158 -345.838684)
			(xy 32.659163 -345.846445) (xy 32.631888 -345.846908) (xy 31.768288 -345.846908) (xy 31.741022 -345.846329)
			(xy 31.687047 -345.838567) (xy 31.634725 -345.823202) (xy 31.585122 -345.800548) (xy 31.539248 -345.771065)
			(xy 31.498037 -345.735354) (xy 31.462327 -345.694142) (xy 31.432846 -345.648267) (xy 31.410194 -345.598664)
			(xy 31.394831 -345.546342) (xy 31.38707 -345.492366) (xy 29.904222 -345.492366) (xy 29.904222 -345.492371)
			(xy 29.89646 -345.546359) (xy 29.881094 -345.598693) (xy 29.858437 -345.648307) (xy 29.82895 -345.694192)
			(xy 29.793234 -345.735414) (xy 29.752014 -345.771133) (xy 29.706132 -345.800624) (xy 29.656519 -345.823284)
			(xy 29.604186 -345.838654) (xy 29.550199 -345.84642) (xy 29.522928 -345.846908) (xy 28.659328 -345.846908)
			(xy 28.632059 -345.846355) (xy 28.578076 -345.838597) (xy 28.525746 -345.823235) (xy 28.476135 -345.800581)
			(xy 28.430253 -345.771098) (xy 28.389035 -345.735385) (xy 28.353319 -345.694169) (xy 28.323832 -345.648289)
			(xy 28.301175 -345.59868) (xy 28.285809 -345.546352) (xy 28.278047 -345.492369) (xy 26.795344 -345.492369)
			(xy 26.795344 -345.492376) (xy 26.78758 -345.546372) (xy 26.772211 -345.598713) (xy 26.749548 -345.648335)
			(xy 26.720054 -345.694225) (xy 26.684329 -345.735451) (xy 26.6431 -345.771173) (xy 26.597207 -345.800663)
			(xy 26.547583 -345.823322) (xy 26.495241 -345.838687) (xy 26.441244 -345.846447) (xy 26.413968 -345.846908)
			(xy 25.550368 -345.846908) (xy 25.523103 -345.846328) (xy 25.46913 -345.838563) (xy 25.41681 -345.823197)
			(xy 25.36721 -345.800542) (xy 25.321339 -345.771058) (xy 25.28013 -345.735347) (xy 25.244422 -345.694136)
			(xy 25.214943 -345.648262) (xy 25.192292 -345.59866) (xy 25.17693 -345.546339) (xy 25.16917 -345.492365)
			(xy 23.686305 -345.492365) (xy 23.686305 -345.492421) (xy 23.678542 -345.546407) (xy 23.663176 -345.59874)
			(xy 23.640519 -345.648352) (xy 23.611031 -345.694236) (xy 23.575314 -345.735455) (xy 23.534094 -345.771172)
			(xy 23.488211 -345.80066) (xy 23.438598 -345.823317) (xy 23.386265 -345.838683) (xy 23.332279 -345.846445)
			(xy 23.305008 -345.846908) (xy 22.441408 -345.846908) (xy 22.414138 -345.846429) (xy 22.360154 -345.838667)
			(xy 22.307825 -345.823302) (xy 22.258214 -345.800645) (xy 22.212333 -345.771159) (xy 22.171115 -345.735443)
			(xy 22.1354 -345.694225) (xy 22.105914 -345.648344) (xy 22.083258 -345.598733) (xy 22.067892 -345.546404)
			(xy 22.06013 -345.49242) (xy 20.577345 -345.49242) (xy 20.577345 -345.492421) (xy 20.569582 -345.546407)
			(xy 20.554216 -345.59874) (xy 20.531559 -345.648352) (xy 20.502071 -345.694236) (xy 20.466354 -345.735455)
			(xy 20.425134 -345.771172) (xy 20.379251 -345.80066) (xy 20.329638 -345.823317) (xy 20.277305 -345.838683)
			(xy 20.223319 -345.846445) (xy 20.196048 -345.846908) (xy 19.332448 -345.846908) (xy 19.305178 -345.846429)
			(xy 19.251194 -345.838667) (xy 19.198865 -345.823302) (xy 19.149254 -345.800645) (xy 19.103373 -345.771159)
			(xy 19.062155 -345.735443) (xy 19.02644 -345.694225) (xy 18.996954 -345.648344) (xy 18.974298 -345.598733)
			(xy 18.958932 -345.546404) (xy 18.95117 -345.49242) (xy 1.524 -345.49242) (xy 1.524 -348.976496)
			(xy 4.708641 -348.976496) (xy 4.708641 -348.847356) (xy 4.716591 -348.718461) (xy 4.732461 -348.590301)
			(xy 4.75619 -348.46336) (xy 4.787689 -348.338121) (xy 4.826838 -348.215058) (xy 4.873489 -348.094639)
			(xy 4.927464 -347.97732) (xy 4.988559 -347.863546) (xy 5.056542 -347.753749) (xy 5.131156 -347.648346)
			(xy 5.212117 -347.547736) (xy 5.299117 -347.452301) (xy 5.391828 -347.362402) (xy 5.489898 -347.278381)
			(xy 5.592953 -347.200557) (xy 5.700604 -347.129225) (xy 5.812443 -347.064655) (xy 5.928044 -347.007093)
			(xy 6.046969 -346.956756) (xy 6.168768 -346.913836) (xy 6.292978 -346.878495) (xy 6.419127 -346.850868)
			(xy 6.546739 -346.831059) (xy 6.675328 -346.819143) (xy 6.804406 -346.815167) (xy 6.933484 -346.819143)
			(xy 7.062073 -346.831059) (xy 7.189685 -346.850868) (xy 7.315834 -346.878495) (xy 7.440044 -346.913836)
			(xy 7.561843 -346.956756) (xy 7.680768 -347.007093) (xy 7.796369 -347.064655) (xy 7.908208 -347.129225)
			(xy 8.015859 -347.200557) (xy 8.118914 -347.278381) (xy 8.216984 -347.362402) (xy 8.25588 -347.400118)
			(xy 211.503015 -347.400118) (xy 211.507009 -347.215797) (xy 211.518984 -347.031821) (xy 211.538917 -346.848538)
			(xy 211.566771 -346.666289) (xy 211.602494 -346.485419) (xy 211.646018 -346.306266) (xy 211.697263 -346.129166)
			(xy 211.756131 -345.954452) (xy 211.822512 -345.782453) (xy 211.896281 -345.61349) (xy 211.977301 -345.447882)
			(xy 212.065418 -345.285938) (xy 212.160468 -345.127964) (xy 212.262272 -344.974256) (xy 212.370638 -344.825102)
			(xy 212.485365 -344.680782) (xy 212.606235 -344.541568) (xy 212.733022 -344.40772) (xy 212.865489 -344.27949)
			(xy 213.003386 -344.157119) (xy 213.146454 -344.040836) (xy 213.294425 -343.93086) (xy 213.447022 -343.827397)
			(xy 213.603957 -343.730641) (xy 213.764936 -343.640775) (xy 213.929657 -343.557966) (xy 214.097811 -343.48237)
			(xy 214.269081 -343.41413) (xy 214.443147 -343.353373) (xy 214.619681 -343.300213) (xy 214.798352 -343.254751)
			(xy 214.978825 -343.217071) (xy 215.160761 -343.187244) (xy 215.343818 -343.165326) (xy 215.527653 -343.151359)
			(xy 215.71192 -343.145368) (xy 215.896274 -343.147365) (xy 216.080368 -343.157347) (xy 216.263857 -343.175293)
			(xy 216.446396 -343.201172) (xy 216.627643 -343.234933) (xy 216.807258 -343.276514) (xy 216.984902 -343.325837)
			(xy 217.160243 -343.382809) (xy 217.332952 -343.447323) (xy 217.502703 -343.519257) (xy 217.66918 -343.598478)
			(xy 217.832068 -343.684836) (xy 217.991063 -343.778169) (xy 218.145865 -343.878302) (xy 218.296184 -343.985046)
			(xy 218.441738 -344.098202) (xy 218.582254 -344.217558) (xy 218.717467 -344.342888) (xy 218.847124 -344.473957)
			(xy 218.970982 -344.61052) (xy 219.088808 -344.752321) (xy 219.200381 -344.899092) (xy 219.305491 -345.050559)
			(xy 219.403941 -345.206437) (xy 219.495546 -345.366433) (xy 219.560575 -345.492368) (xy 267.515847 -345.492368)
			(xy 267.515847 -345.437832) (xy 267.523609 -345.383852) (xy 267.538973 -345.331525) (xy 267.561628 -345.281918)
			(xy 267.591112 -345.23604) (xy 267.626826 -345.194824) (xy 267.668041 -345.159111) (xy 267.71392 -345.129627)
			(xy 267.763527 -345.106972) (xy 267.815854 -345.091608) (xy 267.869834 -345.083847) (xy 267.897102 -345.083384)
			(xy 268.760702 -345.083384) (xy 268.787975 -345.083779) (xy 268.841964 -345.091542) (xy 268.8943 -345.106909)
			(xy 268.943916 -345.129568) (xy 268.989802 -345.159057) (xy 269.031024 -345.194777) (xy 269.066744 -345.236)
			(xy 269.096233 -345.281886) (xy 269.118892 -345.331502) (xy 269.134259 -345.383838) (xy 269.142021 -345.437827)
			(xy 269.142021 -345.492364) (xy 270.62487 -345.492364) (xy 270.62487 -345.437836) (xy 270.63263 -345.383862)
			(xy 270.647992 -345.331542) (xy 270.670642 -345.28194) (xy 270.700121 -345.236066) (xy 270.735828 -345.194855)
			(xy 270.777036 -345.159144) (xy 270.822907 -345.12966) (xy 270.872506 -345.107005) (xy 270.924825 -345.091638)
			(xy 270.978798 -345.083873) (xy 271.006062 -345.083384) (xy 271.869662 -345.083384) (xy 271.896938 -345.083753)
			(xy 271.950936 -345.091512) (xy 272.003279 -345.106877) (xy 272.052903 -345.129535) (xy 272.098797 -345.159025)
			(xy 272.140027 -345.194747) (xy 272.175752 -345.235973) (xy 272.205247 -345.281864) (xy 272.22791 -345.331485)
			(xy 272.24328 -345.383827) (xy 272.251044 -345.437824) (xy 272.251044 -345.492369) (xy 273.733747 -345.492369)
			(xy 273.733747 -345.437831) (xy 273.741509 -345.383849) (xy 273.756875 -345.331521) (xy 273.779531 -345.281912)
			(xy 273.809017 -345.236033) (xy 273.844733 -345.194817) (xy 273.885951 -345.159104) (xy 273.931832 -345.129621)
			(xy 273.981441 -345.106967) (xy 274.033771 -345.091605) (xy 274.087753 -345.083846) (xy 274.115022 -345.083384)
			(xy 274.978622 -345.083384) (xy 275.005894 -345.08378) (xy 275.059881 -345.091545) (xy 275.112215 -345.106914)
			(xy 275.161828 -345.129574) (xy 275.207712 -345.159064) (xy 275.248932 -345.194784) (xy 275.284649 -345.236006)
			(xy 275.314136 -345.281891) (xy 275.336793 -345.331506) (xy 275.352159 -345.38384) (xy 275.359922 -345.437828)
			(xy 275.359922 -345.492365) (xy 276.84277 -345.492365) (xy 276.84277 -345.437835) (xy 276.850531 -345.383859)
			(xy 276.865893 -345.331537) (xy 276.888545 -345.281934) (xy 276.918026 -345.23606) (xy 276.953735 -345.194848)
			(xy 276.994945 -345.159137) (xy 277.040819 -345.129654) (xy 277.090421 -345.106999) (xy 277.142742 -345.091634)
			(xy 277.196717 -345.083872) (xy 277.223982 -345.083384) (xy 278.087582 -345.083384) (xy 278.114857 -345.083754)
			(xy 278.168852 -345.091515) (xy 278.221194 -345.106882) (xy 278.270815 -345.129541) (xy 278.316706 -345.159032)
			(xy 278.357934 -345.194754) (xy 278.393657 -345.235979) (xy 278.42315 -345.281869) (xy 278.445812 -345.33149)
			(xy 278.461181 -345.38383) (xy 278.468944 -345.437825) (xy 278.468944 -345.49237) (xy 279.951648 -345.49237)
			(xy 279.951648 -345.43783) (xy 279.95941 -345.383846) (xy 279.974776 -345.331517) (xy 279.997434 -345.281907)
			(xy 280.026922 -345.236026) (xy 280.06264 -345.19481) (xy 280.10386 -345.159097) (xy 280.149744 -345.129614)
			(xy 280.199356 -345.106962) (xy 280.251687 -345.091601) (xy 280.305672 -345.083845) (xy 280.332942 -345.083384)
			(xy 281.196542 -345.083384) (xy 281.223813 -345.083781) (xy 281.277798 -345.091549) (xy 281.330129 -345.10692)
			(xy 281.37974 -345.129581) (xy 281.425621 -345.159072) (xy 281.466839 -345.194791) (xy 281.502554 -345.236013)
			(xy 281.532039 -345.281897) (xy 281.554695 -345.33151) (xy 281.57006 -345.383843) (xy 281.577822 -345.437829)
			(xy 281.577822 -345.492368) (xy 283.060647 -345.492368) (xy 283.060647 -345.437832) (xy 283.068409 -345.383852)
			(xy 283.083773 -345.331525) (xy 283.106428 -345.281918) (xy 283.135912 -345.23604) (xy 283.171626 -345.194824)
			(xy 283.212841 -345.159111) (xy 283.25872 -345.129627) (xy 283.308327 -345.106972) (xy 283.360654 -345.091608)
			(xy 283.414634 -345.083847) (xy 283.441902 -345.083384) (xy 284.305502 -345.083384) (xy 284.332775 -345.083779)
			(xy 284.386764 -345.091542) (xy 284.4391 -345.106909) (xy 284.488716 -345.129568) (xy 284.534602 -345.159057)
			(xy 284.575824 -345.194777) (xy 284.611544 -345.236) (xy 284.641033 -345.281886) (xy 284.663692 -345.331502)
			(xy 284.679059 -345.383838) (xy 284.686821 -345.437827) (xy 284.686821 -345.492364) (xy 286.16967 -345.492364)
			(xy 286.16967 -345.437836) (xy 286.17743 -345.383862) (xy 286.192792 -345.331542) (xy 286.215442 -345.28194)
			(xy 286.244921 -345.236066) (xy 286.280628 -345.194855) (xy 286.321836 -345.159144) (xy 286.367707 -345.12966)
			(xy 286.417306 -345.107005) (xy 286.469625 -345.091638) (xy 286.523598 -345.083873) (xy 286.550862 -345.083384)
			(xy 287.414462 -345.083384) (xy 287.441738 -345.083753) (xy 287.495736 -345.091512) (xy 287.548079 -345.106877)
			(xy 287.597703 -345.129535) (xy 287.643597 -345.159025) (xy 287.684827 -345.194747) (xy 287.720552 -345.235973)
			(xy 287.750047 -345.281864) (xy 287.77271 -345.331485) (xy 287.78808 -345.383827) (xy 287.795844 -345.437824)
			(xy 287.795844 -345.492369) (xy 289.278547 -345.492369) (xy 289.278547 -345.437831) (xy 289.286309 -345.383849)
			(xy 289.301675 -345.331521) (xy 289.324331 -345.281912) (xy 289.353817 -345.236033) (xy 289.389533 -345.194817)
			(xy 289.430751 -345.159104) (xy 289.476632 -345.129621) (xy 289.526241 -345.106967) (xy 289.578571 -345.091605)
			(xy 289.632553 -345.083846) (xy 289.659822 -345.083384) (xy 290.523422 -345.083384) (xy 290.550694 -345.08378)
			(xy 290.604681 -345.091545) (xy 290.657015 -345.106914) (xy 290.706628 -345.129574) (xy 290.752512 -345.159064)
			(xy 290.793732 -345.194784) (xy 290.829449 -345.236006) (xy 290.858936 -345.281891) (xy 290.881593 -345.331506)
			(xy 290.896959 -345.38384) (xy 290.904722 -345.437828) (xy 290.904722 -345.492365) (xy 292.38757 -345.492365)
			(xy 292.38757 -345.437835) (xy 292.395331 -345.383859) (xy 292.410693 -345.331537) (xy 292.433345 -345.281934)
			(xy 292.462826 -345.23606) (xy 292.498535 -345.194848) (xy 292.539745 -345.159137) (xy 292.585619 -345.129654)
			(xy 292.635221 -345.106999) (xy 292.687542 -345.091634) (xy 292.741517 -345.083872) (xy 292.768782 -345.083384)
			(xy 293.632382 -345.083384) (xy 293.659657 -345.083754) (xy 293.713652 -345.091515) (xy 293.765994 -345.106882)
			(xy 293.815615 -345.129541) (xy 293.861506 -345.159032) (xy 293.902734 -345.194754) (xy 293.938457 -345.235979)
			(xy 293.96795 -345.281869) (xy 293.990612 -345.33149) (xy 294.005981 -345.38383) (xy 294.013744 -345.437825)
			(xy 294.013744 -345.49237) (xy 295.496448 -345.49237) (xy 295.496448 -345.43783) (xy 295.50421 -345.383846)
			(xy 295.519576 -345.331517) (xy 295.542234 -345.281907) (xy 295.571722 -345.236026) (xy 295.60744 -345.19481)
			(xy 295.64866 -345.159097) (xy 295.694544 -345.129614) (xy 295.744156 -345.106962) (xy 295.796487 -345.091601)
			(xy 295.850472 -345.083845) (xy 295.877742 -345.083384) (xy 296.741342 -345.083384) (xy 296.768613 -345.083781)
			(xy 296.822598 -345.091549) (xy 296.874929 -345.10692) (xy 296.92454 -345.129581) (xy 296.970421 -345.159072)
			(xy 297.011639 -345.194791) (xy 297.047354 -345.236013) (xy 297.076839 -345.281897) (xy 297.099495 -345.33151)
			(xy 297.11486 -345.383843) (xy 297.122622 -345.437829) (xy 297.122622 -345.492368) (xy 298.605447 -345.492368)
			(xy 298.605447 -345.437832) (xy 298.613209 -345.383852) (xy 298.628573 -345.331525) (xy 298.651228 -345.281918)
			(xy 298.680712 -345.23604) (xy 298.716426 -345.194824) (xy 298.757641 -345.159111) (xy 298.80352 -345.129627)
			(xy 298.853127 -345.106972) (xy 298.905454 -345.091608) (xy 298.959434 -345.083847) (xy 298.986702 -345.083384)
			(xy 299.850302 -345.083384) (xy 299.877575 -345.083779) (xy 299.931564 -345.091542) (xy 299.9839 -345.106909)
			(xy 300.033516 -345.129568) (xy 300.079402 -345.159057) (xy 300.120624 -345.194777) (xy 300.156344 -345.236)
			(xy 300.185833 -345.281886) (xy 300.208492 -345.331502) (xy 300.223859 -345.383838) (xy 300.231621 -345.437827)
			(xy 300.231621 -345.492368) (xy 312.121547 -345.492368) (xy 312.121547 -345.437832) (xy 312.129309 -345.383851)
			(xy 312.144673 -345.331525) (xy 312.167328 -345.281917) (xy 312.196813 -345.236039) (xy 312.232526 -345.194824)
			(xy 312.273742 -345.159111) (xy 312.319621 -345.129627) (xy 312.369228 -345.106972) (xy 312.421555 -345.091608)
			(xy 312.475536 -345.083847) (xy 312.502804 -345.083384) (xy 313.366404 -345.083384) (xy 313.393676 -345.083779)
			(xy 313.447666 -345.091542) (xy 313.500001 -345.106909) (xy 313.549617 -345.129569) (xy 313.595503 -345.159058)
			(xy 313.636725 -345.194778) (xy 313.672444 -345.236) (xy 313.701933 -345.281886) (xy 313.724592 -345.331502)
			(xy 313.739959 -345.383838) (xy 313.747721 -345.437828) (xy 313.747721 -345.492364) (xy 315.23057 -345.492364)
			(xy 315.23057 -345.437836) (xy 315.23833 -345.383862) (xy 315.253692 -345.331541) (xy 315.276343 -345.281939)
			(xy 315.305821 -345.236066) (xy 315.341529 -345.194854) (xy 315.382737 -345.159143) (xy 315.428608 -345.12966)
			(xy 315.478207 -345.107004) (xy 315.530526 -345.091638) (xy 315.5845 -345.083873) (xy 315.611764 -345.083384)
			(xy 316.475364 -345.083384) (xy 316.50264 -345.083753) (xy 316.556637 -345.091512) (xy 316.608981 -345.106877)
			(xy 316.658604 -345.129535) (xy 316.704498 -345.159026) (xy 316.745727 -345.194747) (xy 316.781453 -345.235973)
			(xy 316.810947 -345.281864) (xy 316.83361 -345.331486) (xy 316.84898 -345.383828) (xy 316.856744 -345.437824)
			(xy 316.856744 -345.492369) (xy 318.339447 -345.492369) (xy 318.339447 -345.437831) (xy 318.347209 -345.383849)
			(xy 318.362575 -345.33152) (xy 318.385231 -345.281912) (xy 318.414718 -345.236032) (xy 318.450434 -345.194817)
			(xy 318.491652 -345.159103) (xy 318.537533 -345.12962) (xy 318.587143 -345.106966) (xy 318.639472 -345.091604)
			(xy 318.693455 -345.083846) (xy 318.720724 -345.083384) (xy 319.584324 -345.083384) (xy 319.611596 -345.08378)
			(xy 319.665583 -345.091546) (xy 319.717916 -345.106915) (xy 319.767529 -345.129575) (xy 319.813413 -345.159065)
			(xy 319.854632 -345.194785) (xy 319.890349 -345.236007) (xy 319.919836 -345.281892) (xy 319.942494 -345.331507)
			(xy 319.95786 -345.38384) (xy 319.965622 -345.437828) (xy 319.965622 -345.492365) (xy 321.44847 -345.492365)
			(xy 321.44847 -345.437835) (xy 321.456231 -345.383859) (xy 321.471593 -345.331537) (xy 321.494246 -345.281934)
			(xy 321.523726 -345.236059) (xy 321.559436 -345.194847) (xy 321.600646 -345.159136) (xy 321.64652 -345.129653)
			(xy 321.696122 -345.106999) (xy 321.748443 -345.091634) (xy 321.802419 -345.083871) (xy 321.829684 -345.083384)
			(xy 322.693284 -345.083384) (xy 322.720559 -345.083755) (xy 322.774554 -345.091516) (xy 322.826895 -345.106882)
			(xy 322.876516 -345.129542) (xy 322.922407 -345.159033) (xy 322.963634 -345.194754) (xy 322.999358 -345.23598)
			(xy 323.02885 -345.28187) (xy 323.051512 -345.33149) (xy 323.066881 -345.38383) (xy 323.074644 -345.437825)
			(xy 323.074644 -345.49237) (xy 324.557348 -345.49237) (xy 324.557348 -345.43783) (xy 324.56511 -345.383846)
			(xy 324.580476 -345.331516) (xy 324.603135 -345.281906) (xy 324.632623 -345.236026) (xy 324.668341 -345.194809)
			(xy 324.709561 -345.159096) (xy 324.755445 -345.129613) (xy 324.805057 -345.106961) (xy 324.857389 -345.0916)
			(xy 324.911374 -345.083844) (xy 324.938644 -345.083384) (xy 325.802244 -345.083384) (xy 325.829515 -345.083782)
			(xy 325.8835 -345.091549) (xy 325.93583 -345.10692) (xy 325.985441 -345.129582) (xy 326.031322 -345.159072)
			(xy 326.072539 -345.194792) (xy 326.108254 -345.236013) (xy 326.137739 -345.281898) (xy 326.160395 -345.331511)
			(xy 326.17576 -345.383843) (xy 326.183522 -345.437829) (xy 326.183522 -345.492368) (xy 327.666347 -345.492368)
			(xy 327.666347 -345.437832) (xy 327.674109 -345.383851) (xy 327.689473 -345.331525) (xy 327.712128 -345.281917)
			(xy 327.741613 -345.236039) (xy 327.777326 -345.194824) (xy 327.818542 -345.159111) (xy 327.864421 -345.129627)
			(xy 327.914028 -345.106972) (xy 327.966355 -345.091608) (xy 328.020336 -345.083847) (xy 328.047604 -345.083384)
			(xy 328.911204 -345.083384) (xy 328.938476 -345.083779) (xy 328.992466 -345.091542) (xy 329.044801 -345.106909)
			(xy 329.094417 -345.129569) (xy 329.140303 -345.159058) (xy 329.181525 -345.194778) (xy 329.217244 -345.236)
			(xy 329.246733 -345.281886) (xy 329.269392 -345.331502) (xy 329.284759 -345.383838) (xy 329.292521 -345.437828)
			(xy 329.292521 -345.492364) (xy 330.77537 -345.492364) (xy 330.77537 -345.437836) (xy 330.78313 -345.383862)
			(xy 330.798492 -345.331541) (xy 330.821143 -345.281939) (xy 330.850621 -345.236066) (xy 330.886329 -345.194854)
			(xy 330.927537 -345.159143) (xy 330.973408 -345.12966) (xy 331.023007 -345.107004) (xy 331.075326 -345.091638)
			(xy 331.1293 -345.083873) (xy 331.156564 -345.083384) (xy 332.020164 -345.083384) (xy 332.04744 -345.083753)
			(xy 332.101437 -345.091512) (xy 332.153781 -345.106877) (xy 332.203404 -345.129535) (xy 332.249298 -345.159026)
			(xy 332.290527 -345.194747) (xy 332.326253 -345.235973) (xy 332.355747 -345.281864) (xy 332.37841 -345.331486)
			(xy 332.39378 -345.383828) (xy 332.401544 -345.437824) (xy 332.401544 -345.492369) (xy 333.884247 -345.492369)
			(xy 333.884247 -345.437831) (xy 333.892009 -345.383849) (xy 333.907375 -345.33152) (xy 333.930031 -345.281912)
			(xy 333.959518 -345.236032) (xy 333.995234 -345.194817) (xy 334.036452 -345.159103) (xy 334.082333 -345.12962)
			(xy 334.131943 -345.106966) (xy 334.184272 -345.091604) (xy 334.238255 -345.083846) (xy 334.265524 -345.083384)
			(xy 335.129124 -345.083384) (xy 335.156396 -345.08378) (xy 335.210383 -345.091546) (xy 335.262716 -345.106915)
			(xy 335.312329 -345.129575) (xy 335.358213 -345.159065) (xy 335.399432 -345.194785) (xy 335.435149 -345.236007)
			(xy 335.464636 -345.281892) (xy 335.487294 -345.331507) (xy 335.50266 -345.38384) (xy 335.510422 -345.437828)
			(xy 335.510422 -345.492365) (xy 336.99327 -345.492365) (xy 336.99327 -345.437835) (xy 337.001031 -345.383859)
			(xy 337.016393 -345.331537) (xy 337.039046 -345.281934) (xy 337.068526 -345.236059) (xy 337.104236 -345.194847)
			(xy 337.145446 -345.159136) (xy 337.19132 -345.129653) (xy 337.240922 -345.106999) (xy 337.293243 -345.091634)
			(xy 337.347219 -345.083871) (xy 337.374484 -345.083384) (xy 338.238084 -345.083384) (xy 338.265359 -345.083755)
			(xy 338.319354 -345.091516) (xy 338.371695 -345.106882) (xy 338.421316 -345.129542) (xy 338.467207 -345.159033)
			(xy 338.508434 -345.194754) (xy 338.544158 -345.23598) (xy 338.57365 -345.28187) (xy 338.596312 -345.33149)
			(xy 338.611681 -345.38383) (xy 338.619444 -345.437825) (xy 338.619444 -345.49237) (xy 340.102148 -345.49237)
			(xy 340.102148 -345.43783) (xy 340.10991 -345.383846) (xy 340.125276 -345.331516) (xy 340.147935 -345.281906)
			(xy 340.177423 -345.236026) (xy 340.213141 -345.194809) (xy 340.254361 -345.159096) (xy 340.300245 -345.129613)
			(xy 340.349857 -345.106961) (xy 340.402189 -345.0916) (xy 340.456174 -345.083844) (xy 340.483444 -345.083384)
			(xy 341.347044 -345.083384) (xy 341.374315 -345.083782) (xy 341.4283 -345.091549) (xy 341.48063 -345.10692)
			(xy 341.530241 -345.129582) (xy 341.576122 -345.159072) (xy 341.617339 -345.194792) (xy 341.653054 -345.236013)
			(xy 341.682539 -345.281898) (xy 341.705195 -345.331511) (xy 341.72056 -345.383843) (xy 341.728322 -345.437829)
			(xy 341.728322 -345.492368) (xy 343.211147 -345.492368) (xy 343.211147 -345.437832) (xy 343.218909 -345.383851)
			(xy 343.234273 -345.331525) (xy 343.256928 -345.281917) (xy 343.286413 -345.236039) (xy 343.322126 -345.194824)
			(xy 343.363342 -345.159111) (xy 343.409221 -345.129627) (xy 343.458828 -345.106972) (xy 343.511155 -345.091608)
			(xy 343.565136 -345.083847) (xy 343.592404 -345.083384) (xy 344.456004 -345.083384) (xy 344.483276 -345.083779)
			(xy 344.537266 -345.091542) (xy 344.589601 -345.106909) (xy 344.639217 -345.129569) (xy 344.685103 -345.159058)
			(xy 344.726325 -345.194778) (xy 344.762044 -345.236) (xy 344.791533 -345.281886) (xy 344.814192 -345.331502)
			(xy 344.829559 -345.383838) (xy 344.837321 -345.437828) (xy 344.837321 -345.492365) (xy 370.80677 -345.492365)
			(xy 370.80677 -345.437835) (xy 370.81453 -345.383859) (xy 370.829893 -345.331538) (xy 370.852545 -345.281935)
			(xy 370.882025 -345.236061) (xy 370.917734 -345.194848) (xy 370.958945 -345.159137) (xy 371.004817 -345.129655)
			(xy 371.054419 -345.107) (xy 371.10674 -345.091635) (xy 371.160715 -345.083872) (xy 371.18798 -345.083384)
			(xy 372.05158 -345.083384) (xy 372.078855 -345.083754) (xy 372.132851 -345.091515) (xy 372.185192 -345.106881)
			(xy 372.234814 -345.129541) (xy 372.280705 -345.159031) (xy 372.321933 -345.194753) (xy 372.357657 -345.235978)
			(xy 372.38715 -345.281869) (xy 372.409812 -345.331489) (xy 372.425181 -345.38383) (xy 372.432944 -345.437825)
			(xy 372.432944 -345.49237) (xy 373.915647 -345.49237) (xy 373.915647 -345.43783) (xy 373.92341 -345.383847)
			(xy 373.938776 -345.331517) (xy 373.961434 -345.281907) (xy 373.990922 -345.236027) (xy 374.026639 -345.194811)
			(xy 374.067859 -345.159098) (xy 374.113742 -345.129615) (xy 374.163355 -345.106962) (xy 374.215686 -345.091601)
			(xy 374.26967 -345.083845) (xy 374.29694 -345.083384) (xy 375.16054 -345.083384) (xy 375.187811 -345.083781)
			(xy 375.241797 -345.091549) (xy 375.294128 -345.106919) (xy 375.343739 -345.12958) (xy 375.38962 -345.159071)
			(xy 375.430838 -345.19479) (xy 375.466553 -345.236012) (xy 375.496039 -345.281896) (xy 375.518695 -345.33151)
			(xy 375.53406 -345.383843) (xy 375.541822 -345.437829) (xy 375.541822 -345.492366) (xy 377.02467 -345.492366)
			(xy 377.02467 -345.437834) (xy 377.032431 -345.383857) (xy 377.047795 -345.331534) (xy 377.070448 -345.281929)
			(xy 377.09993 -345.236054) (xy 377.135641 -345.194841) (xy 377.176854 -345.15913) (xy 377.222729 -345.129648)
			(xy 377.272334 -345.106995) (xy 377.324657 -345.091631) (xy 377.378634 -345.08387) (xy 377.4059 -345.083384)
			(xy 378.2695 -345.083384) (xy 378.296773 -345.083779) (xy 378.350763 -345.091541) (xy 378.403099 -345.106908)
			(xy 378.452715 -345.129567) (xy 378.498601 -345.159057) (xy 378.539824 -345.194776) (xy 378.575543 -345.235999)
			(xy 378.605033 -345.281885) (xy 378.627692 -345.331501) (xy 378.643059 -345.383837) (xy 378.650821 -345.437827)
			(xy 378.650821 -345.492364) (xy 380.13367 -345.492364) (xy 380.13367 -345.437836) (xy 380.14143 -345.383862)
			(xy 380.156791 -345.331542) (xy 380.179442 -345.281941) (xy 380.208921 -345.236067) (xy 380.244627 -345.194855)
			(xy 380.285835 -345.159145) (xy 380.331705 -345.129661) (xy 380.381305 -345.107005) (xy 380.433623 -345.091638)
			(xy 380.487596 -345.083873) (xy 380.51486 -345.083384) (xy 381.37846 -345.083384) (xy 381.405736 -345.083753)
			(xy 381.459734 -345.091511) (xy 381.512078 -345.106876) (xy 381.561702 -345.129534) (xy 381.607596 -345.159024)
			(xy 381.648826 -345.194746) (xy 381.684552 -345.235972) (xy 381.714047 -345.281863) (xy 381.73671 -345.331485)
			(xy 381.75208 -345.383827) (xy 381.759844 -345.437824) (xy 381.759844 -345.492369) (xy 383.242547 -345.492369)
			(xy 383.242547 -345.437831) (xy 383.250309 -345.383849) (xy 383.265675 -345.331521) (xy 383.288331 -345.281913)
			(xy 383.317817 -345.236034) (xy 383.353532 -345.194818) (xy 383.39475 -345.159105) (xy 383.44063 -345.129621)
			(xy 383.49024 -345.106968) (xy 383.542569 -345.091605) (xy 383.596551 -345.083846) (xy 383.62382 -345.083384)
			(xy 384.48742 -345.083384) (xy 384.514692 -345.08378) (xy 384.56868 -345.091545) (xy 384.621013 -345.106914)
			(xy 384.670627 -345.129574) (xy 384.716511 -345.159064) (xy 384.757731 -345.194783) (xy 384.793448 -345.236005)
			(xy 384.822936 -345.281891) (xy 384.845593 -345.331506) (xy 384.860959 -345.38384) (xy 384.868722 -345.437828)
			(xy 384.868722 -345.492365) (xy 386.35157 -345.492365) (xy 386.35157 -345.437835) (xy 386.35933 -345.383859)
			(xy 386.374693 -345.331538) (xy 386.397345 -345.281935) (xy 386.426825 -345.236061) (xy 386.462534 -345.194848)
			(xy 386.503745 -345.159137) (xy 386.549617 -345.129655) (xy 386.599219 -345.107) (xy 386.65154 -345.091635)
			(xy 386.705515 -345.083872) (xy 386.73278 -345.083384) (xy 387.59638 -345.083384) (xy 387.623655 -345.083754)
			(xy 387.677651 -345.091515) (xy 387.729992 -345.106881) (xy 387.779614 -345.129541) (xy 387.825505 -345.159031)
			(xy 387.866733 -345.194753) (xy 387.902457 -345.235978) (xy 387.93195 -345.281869) (xy 387.954612 -345.331489)
			(xy 387.969981 -345.38383) (xy 387.977744 -345.437825) (xy 387.977744 -345.49237) (xy 389.460447 -345.49237)
			(xy 389.460447 -345.43783) (xy 389.46821 -345.383847) (xy 389.483576 -345.331517) (xy 389.506234 -345.281907)
			(xy 389.535722 -345.236027) (xy 389.571439 -345.194811) (xy 389.612659 -345.159098) (xy 389.658542 -345.129615)
			(xy 389.708155 -345.106962) (xy 389.760486 -345.091601) (xy 389.81447 -345.083845) (xy 389.84174 -345.083384)
			(xy 390.70534 -345.083384) (xy 390.732611 -345.083781) (xy 390.786597 -345.091549) (xy 390.838928 -345.106919)
			(xy 390.888539 -345.12958) (xy 390.93442 -345.159071) (xy 390.975638 -345.19479) (xy 391.011353 -345.236012)
			(xy 391.040839 -345.281896) (xy 391.063495 -345.33151) (xy 391.07886 -345.383843) (xy 391.086622 -345.437829)
			(xy 391.086622 -345.492366) (xy 392.56947 -345.492366) (xy 392.56947 -345.437834) (xy 392.577231 -345.383857)
			(xy 392.592595 -345.331534) (xy 392.615248 -345.281929) (xy 392.64473 -345.236054) (xy 392.680441 -345.194841)
			(xy 392.721654 -345.15913) (xy 392.767529 -345.129648) (xy 392.817134 -345.106995) (xy 392.869457 -345.091631)
			(xy 392.923434 -345.08387) (xy 392.9507 -345.083384) (xy 393.8143 -345.083384) (xy 393.841573 -345.083779)
			(xy 393.895563 -345.091541) (xy 393.947899 -345.106908) (xy 393.997515 -345.129567) (xy 394.043401 -345.159057)
			(xy 394.084624 -345.194776) (xy 394.120343 -345.235999) (xy 394.149833 -345.281885) (xy 394.172492 -345.331501)
			(xy 394.187859 -345.383837) (xy 394.195621 -345.437827) (xy 394.195621 -345.492364) (xy 395.67847 -345.492364)
			(xy 395.67847 -345.437836) (xy 395.68623 -345.383862) (xy 395.701591 -345.331542) (xy 395.724242 -345.281941)
			(xy 395.753721 -345.236067) (xy 395.789427 -345.194855) (xy 395.830635 -345.159145) (xy 395.876505 -345.129661)
			(xy 395.926105 -345.107005) (xy 395.978423 -345.091638) (xy 396.032396 -345.083873) (xy 396.05966 -345.083384)
			(xy 396.92326 -345.083384) (xy 396.950536 -345.083753) (xy 397.004534 -345.091511) (xy 397.056878 -345.106876)
			(xy 397.106502 -345.129534) (xy 397.152396 -345.159024) (xy 397.193626 -345.194746) (xy 397.229352 -345.235972)
			(xy 397.258847 -345.281863) (xy 397.28151 -345.331485) (xy 397.29688 -345.383827) (xy 397.304644 -345.437824)
			(xy 397.304644 -345.492369) (xy 398.787347 -345.492369) (xy 398.787347 -345.437831) (xy 398.795109 -345.383849)
			(xy 398.810475 -345.331521) (xy 398.833131 -345.281913) (xy 398.862617 -345.236034) (xy 398.898332 -345.194818)
			(xy 398.93955 -345.159105) (xy 398.98543 -345.129621) (xy 399.03504 -345.106968) (xy 399.087369 -345.091605)
			(xy 399.141351 -345.083846) (xy 399.16862 -345.083384) (xy 400.03222 -345.083384) (xy 400.059492 -345.08378)
			(xy 400.11348 -345.091545) (xy 400.165813 -345.106914) (xy 400.215427 -345.129574) (xy 400.261311 -345.159064)
			(xy 400.302531 -345.194783) (xy 400.338248 -345.236005) (xy 400.367736 -345.281891) (xy 400.390393 -345.331506)
			(xy 400.405759 -345.38384) (xy 400.413522 -345.437828) (xy 400.413522 -345.492365) (xy 401.89637 -345.492365)
			(xy 401.89637 -345.437835) (xy 401.90413 -345.383859) (xy 401.919493 -345.331538) (xy 401.942145 -345.281935)
			(xy 401.971625 -345.236061) (xy 402.007334 -345.194848) (xy 402.048545 -345.159137) (xy 402.094417 -345.129655)
			(xy 402.144019 -345.107) (xy 402.19634 -345.091635) (xy 402.250315 -345.083872) (xy 402.27758 -345.083384)
			(xy 403.14118 -345.083384) (xy 403.168455 -345.083754) (xy 403.222451 -345.091515) (xy 403.274792 -345.106881)
			(xy 403.324414 -345.129541) (xy 403.370305 -345.159031) (xy 403.411533 -345.194753) (xy 403.447257 -345.235978)
			(xy 403.47675 -345.281869) (xy 403.499412 -345.331489) (xy 403.514781 -345.38383) (xy 403.522544 -345.437825)
			(xy 403.522544 -345.492366) (xy 408.91387 -345.492366) (xy 408.91387 -345.437834) (xy 408.921631 -345.383858)
			(xy 408.936994 -345.331535) (xy 408.959647 -345.281932) (xy 408.989128 -345.236057) (xy 409.024838 -345.194844)
			(xy 409.06605 -345.159133) (xy 409.111925 -345.129651) (xy 409.161528 -345.106997) (xy 409.21385 -345.091633)
			(xy 409.267826 -345.083871) (xy 409.295092 -345.083384) (xy 410.158692 -345.083384) (xy 410.185967 -345.083755)
			(xy 410.239961 -345.091517) (xy 410.292301 -345.106885) (xy 410.341921 -345.129544) (xy 410.387811 -345.159035)
			(xy 410.429037 -345.194757) (xy 410.46476 -345.235982) (xy 410.494252 -345.281872) (xy 410.516913 -345.331492)
			(xy 410.532281 -345.383831) (xy 410.540044 -345.437825) (xy 410.540044 -345.492364) (xy 412.02287 -345.492364)
			(xy 412.02287 -345.437836) (xy 412.03063 -345.383863) (xy 412.045991 -345.331544) (xy 412.068641 -345.281943)
			(xy 412.098119 -345.23607) (xy 412.133824 -345.194858) (xy 412.175031 -345.159147) (xy 412.220901 -345.129664)
			(xy 412.270499 -345.107008) (xy 412.322816 -345.09164) (xy 412.376788 -345.083874) (xy 412.404052 -345.083384)
			(xy 413.267652 -345.083384) (xy 413.294929 -345.083752) (xy 413.348927 -345.09151) (xy 413.401272 -345.106874)
			(xy 413.450897 -345.129531) (xy 413.496792 -345.159021) (xy 413.538023 -345.194743) (xy 413.57375 -345.235969)
			(xy 413.603246 -345.281861) (xy 413.625909 -345.331483) (xy 413.64128 -345.383826) (xy 413.649044 -345.437824)
			(xy 413.649044 -345.492368) (xy 415.131747 -345.492368) (xy 415.131747 -345.437832) (xy 415.139509 -345.38385)
			(xy 415.154874 -345.331523) (xy 415.17753 -345.281915) (xy 415.207015 -345.236036) (xy 415.242729 -345.194821)
			(xy 415.283946 -345.159108) (xy 415.329826 -345.129624) (xy 415.379434 -345.10697) (xy 415.431762 -345.091606)
			(xy 415.485744 -345.083847) (xy 415.513012 -345.083384) (xy 416.376612 -345.083384) (xy 416.403884 -345.083779)
			(xy 416.457873 -345.091543) (xy 416.510207 -345.106912) (xy 416.559822 -345.129571) (xy 416.605707 -345.159061)
			(xy 416.646928 -345.194781) (xy 416.682646 -345.236003) (xy 416.712135 -345.281889) (xy 416.734793 -345.331504)
			(xy 416.750159 -345.383839) (xy 416.757921 -345.437828) (xy 416.757921 -345.492365) (xy 418.24077 -345.492365)
			(xy 418.24077 -345.437835) (xy 418.24853 -345.383861) (xy 418.263892 -345.33154) (xy 418.286544 -345.281937)
			(xy 418.316023 -345.236063) (xy 418.351731 -345.194851) (xy 418.392941 -345.15914) (xy 418.438813 -345.129657)
			(xy 418.488413 -345.107002) (xy 418.540733 -345.091636) (xy 418.594707 -345.083872) (xy 418.621972 -345.083384)
			(xy 419.485572 -345.083384) (xy 419.512848 -345.083754) (xy 419.566844 -345.091514) (xy 419.619186 -345.106879)
			(xy 419.668809 -345.129538) (xy 419.714702 -345.159028) (xy 419.75593 -345.19475) (xy 419.791655 -345.235976)
			(xy 419.821149 -345.281866) (xy 419.843811 -345.331487) (xy 419.859181 -345.383829) (xy 419.866944 -345.437824)
			(xy 419.866944 -345.492369) (xy 421.349647 -345.492369) (xy 421.349647 -345.437831) (xy 421.35741 -345.383848)
			(xy 421.372776 -345.331519) (xy 421.395433 -345.281909) (xy 421.42492 -345.23603) (xy 421.460636 -345.194814)
			(xy 421.501855 -345.159101) (xy 421.547738 -345.129617) (xy 421.597349 -345.106964) (xy 421.649679 -345.091603)
			(xy 421.703663 -345.083845) (xy 421.730932 -345.083384) (xy 422.594532 -345.083384) (xy 422.621803 -345.083781)
			(xy 422.67579 -345.091547) (xy 422.728122 -345.106917) (xy 422.777734 -345.129578) (xy 422.823616 -345.159068)
			(xy 422.864835 -345.194788) (xy 422.900551 -345.236009) (xy 422.930038 -345.281894) (xy 422.952694 -345.331508)
			(xy 422.96806 -345.383842) (xy 422.975822 -345.437829) (xy 422.975822 -345.492366) (xy 424.45867 -345.492366)
			(xy 424.45867 -345.437834) (xy 424.466431 -345.383858) (xy 424.481794 -345.331535) (xy 424.504447 -345.281932)
			(xy 424.533928 -345.236057) (xy 424.569638 -345.194844) (xy 424.61085 -345.159133) (xy 424.656725 -345.129651)
			(xy 424.706328 -345.106997) (xy 424.75865 -345.091633) (xy 424.812626 -345.083871) (xy 424.839892 -345.083384)
			(xy 425.703492 -345.083384) (xy 425.730767 -345.083755) (xy 425.784761 -345.091517) (xy 425.837101 -345.106885)
			(xy 425.886721 -345.129544) (xy 425.932611 -345.159035) (xy 425.973837 -345.194757) (xy 426.00956 -345.235982)
			(xy 426.039052 -345.281872) (xy 426.061713 -345.331492) (xy 426.077081 -345.383831) (xy 426.084844 -345.437825)
			(xy 426.084844 -345.492364) (xy 427.56767 -345.492364) (xy 427.56767 -345.437836) (xy 427.57543 -345.383863)
			(xy 427.590791 -345.331544) (xy 427.613441 -345.281943) (xy 427.642919 -345.23607) (xy 427.678624 -345.194858)
			(xy 427.719831 -345.159147) (xy 427.765701 -345.129664) (xy 427.815299 -345.107008) (xy 427.867616 -345.09164)
			(xy 427.921588 -345.083874) (xy 427.948852 -345.083384) (xy 428.812452 -345.083384) (xy 428.839729 -345.083752)
			(xy 428.893727 -345.09151) (xy 428.946072 -345.106874) (xy 428.995697 -345.129531) (xy 429.041592 -345.159021)
			(xy 429.082823 -345.194743) (xy 429.11855 -345.235969) (xy 429.148046 -345.281861) (xy 429.170709 -345.331483)
			(xy 429.18608 -345.383826) (xy 429.193844 -345.437824) (xy 429.193844 -345.492368) (xy 430.676547 -345.492368)
			(xy 430.676547 -345.437832) (xy 430.684309 -345.38385) (xy 430.699674 -345.331523) (xy 430.72233 -345.281915)
			(xy 430.751815 -345.236036) (xy 430.787529 -345.194821) (xy 430.828746 -345.159108) (xy 430.874626 -345.129624)
			(xy 430.924234 -345.10697) (xy 430.976562 -345.091606) (xy 431.030544 -345.083847) (xy 431.057812 -345.083384)
			(xy 431.921412 -345.083384) (xy 431.948684 -345.083779) (xy 432.002673 -345.091543) (xy 432.055007 -345.106912)
			(xy 432.104622 -345.129571) (xy 432.150507 -345.159061) (xy 432.191728 -345.194781) (xy 432.227446 -345.236003)
			(xy 432.256935 -345.281889) (xy 432.279593 -345.331504) (xy 432.294959 -345.383839) (xy 432.302721 -345.437828)
			(xy 432.302721 -345.492365) (xy 433.78557 -345.492365) (xy 433.78557 -345.437835) (xy 433.79333 -345.383861)
			(xy 433.808692 -345.33154) (xy 433.831344 -345.281937) (xy 433.860823 -345.236063) (xy 433.896531 -345.194851)
			(xy 433.937741 -345.15914) (xy 433.983613 -345.129657) (xy 434.033213 -345.107002) (xy 434.085533 -345.091636)
			(xy 434.139507 -345.083872) (xy 434.166772 -345.083384) (xy 435.030372 -345.083384) (xy 435.057648 -345.083754)
			(xy 435.111644 -345.091514) (xy 435.163986 -345.106879) (xy 435.213609 -345.129538) (xy 435.259502 -345.159028)
			(xy 435.30073 -345.19475) (xy 435.336455 -345.235976) (xy 435.365949 -345.281866) (xy 435.388611 -345.331487)
			(xy 435.403981 -345.383829) (xy 435.411744 -345.437824) (xy 435.411744 -345.492369) (xy 436.894447 -345.492369)
			(xy 436.894447 -345.437831) (xy 436.90221 -345.383848) (xy 436.917576 -345.331519) (xy 436.940233 -345.281909)
			(xy 436.96972 -345.23603) (xy 437.005436 -345.194814) (xy 437.046655 -345.159101) (xy 437.092538 -345.129617)
			(xy 437.142149 -345.106964) (xy 437.194479 -345.091603) (xy 437.248463 -345.083845) (xy 437.275732 -345.083384)
			(xy 438.139332 -345.083384) (xy 438.166603 -345.083781) (xy 438.22059 -345.091547) (xy 438.272922 -345.106917)
			(xy 438.322534 -345.129578) (xy 438.368416 -345.159068) (xy 438.409635 -345.194788) (xy 438.445351 -345.236009)
			(xy 438.474838 -345.281894) (xy 438.497494 -345.331508) (xy 438.51286 -345.383842) (xy 438.520622 -345.437829)
			(xy 438.520622 -345.492366) (xy 440.00347 -345.492366) (xy 440.00347 -345.437834) (xy 440.011231 -345.383858)
			(xy 440.026594 -345.331535) (xy 440.049247 -345.281932) (xy 440.078728 -345.236057) (xy 440.114438 -345.194844)
			(xy 440.15565 -345.159133) (xy 440.201525 -345.129651) (xy 440.251128 -345.106997) (xy 440.30345 -345.091633)
			(xy 440.357426 -345.083871) (xy 440.384692 -345.083384) (xy 441.248292 -345.083384) (xy 441.275567 -345.083755)
			(xy 441.329561 -345.091517) (xy 441.381901 -345.106885) (xy 441.431521 -345.129544) (xy 441.477411 -345.159035)
			(xy 441.518637 -345.194757) (xy 441.55436 -345.235982) (xy 441.583852 -345.281872) (xy 441.606513 -345.331492)
			(xy 441.621881 -345.383831) (xy 441.629644 -345.437825) (xy 441.629644 -345.492375) (xy 441.621881 -345.546369)
			(xy 441.606513 -345.598708) (xy 441.583852 -345.648328) (xy 441.55436 -345.694218) (xy 441.518637 -345.735443)
			(xy 441.477411 -345.771165) (xy 441.431521 -345.800656) (xy 441.381901 -345.823315) (xy 441.329561 -345.838683)
			(xy 441.275567 -345.846445) (xy 441.248292 -345.846908) (xy 440.384692 -345.846908) (xy 440.357426 -345.846329)
			(xy 440.30345 -345.838567) (xy 440.251128 -345.823203) (xy 440.201525 -345.800549) (xy 440.15565 -345.771067)
			(xy 440.114438 -345.735356) (xy 440.078728 -345.694143) (xy 440.049247 -345.648268) (xy 440.026594 -345.598665)
			(xy 440.011231 -345.546342) (xy 440.00347 -345.492366) (xy 438.520622 -345.492366) (xy 438.520622 -345.492371)
			(xy 438.51286 -345.546358) (xy 438.497494 -345.598692) (xy 438.474838 -345.648306) (xy 438.445351 -345.694191)
			(xy 438.409635 -345.735412) (xy 438.368416 -345.771132) (xy 438.322534 -345.800622) (xy 438.272922 -345.823283)
			(xy 438.22059 -345.838653) (xy 438.166603 -345.846419) (xy 438.139332 -345.846908) (xy 437.275732 -345.846908)
			(xy 437.248463 -345.846355) (xy 437.194479 -345.838597) (xy 437.142149 -345.823236) (xy 437.092538 -345.800583)
			(xy 437.046655 -345.771099) (xy 437.005436 -345.735386) (xy 436.96972 -345.69417) (xy 436.940233 -345.648291)
			(xy 436.917576 -345.598681) (xy 436.90221 -345.546352) (xy 436.894447 -345.492369) (xy 435.411744 -345.492369)
			(xy 435.411744 -345.492376) (xy 435.403981 -345.546371) (xy 435.388611 -345.598713) (xy 435.365949 -345.648334)
			(xy 435.336455 -345.694224) (xy 435.30073 -345.73545) (xy 435.259502 -345.771172) (xy 435.213609 -345.800662)
			(xy 435.163986 -345.823321) (xy 435.111644 -345.838686) (xy 435.057648 -345.846446) (xy 435.030372 -345.846908)
			(xy 434.166772 -345.846908) (xy 434.139507 -345.846328) (xy 434.085533 -345.838564) (xy 434.033213 -345.823198)
			(xy 433.983613 -345.800543) (xy 433.937741 -345.77106) (xy 433.896531 -345.735349) (xy 433.860823 -345.694137)
			(xy 433.831344 -345.648263) (xy 433.808692 -345.59866) (xy 433.79333 -345.546339) (xy 433.78557 -345.492365)
			(xy 432.302721 -345.492365) (xy 432.302721 -345.492372) (xy 432.294959 -345.546361) (xy 432.279593 -345.598696)
			(xy 432.256935 -345.648311) (xy 432.227446 -345.694197) (xy 432.191728 -345.735419) (xy 432.150507 -345.771139)
			(xy 432.104622 -345.800629) (xy 432.055007 -345.823288) (xy 432.002673 -345.838657) (xy 431.948684 -345.846421)
			(xy 431.921412 -345.846908) (xy 431.057812 -345.846908) (xy 431.030544 -345.846353) (xy 430.976562 -345.838594)
			(xy 430.924234 -345.82323) (xy 430.874626 -345.800576) (xy 430.828746 -345.771092) (xy 430.787529 -345.735379)
			(xy 430.751815 -345.694164) (xy 430.72233 -345.648285) (xy 430.699674 -345.598677) (xy 430.684309 -345.54635)
			(xy 430.676547 -345.492368) (xy 429.193844 -345.492368) (xy 429.193844 -345.492376) (xy 429.18608 -345.546374)
			(xy 429.170709 -345.598717) (xy 429.148046 -345.648339) (xy 429.11855 -345.694231) (xy 429.082823 -345.735457)
			(xy 429.041592 -345.771179) (xy 428.995697 -345.800669) (xy 428.946072 -345.823326) (xy 428.893727 -345.83869)
			(xy 428.839729 -345.846448) (xy 428.812452 -345.846908) (xy 427.948852 -345.846908) (xy 427.921588 -345.846326)
			(xy 427.867616 -345.83856) (xy 427.815299 -345.823192) (xy 427.765701 -345.800536) (xy 427.719831 -345.771053)
			(xy 427.678624 -345.735342) (xy 427.642919 -345.69413) (xy 427.613441 -345.648257) (xy 427.590791 -345.598656)
			(xy 427.57543 -345.546337) (xy 427.56767 -345.492364) (xy 426.084844 -345.492364) (xy 426.084844 -345.492375)
			(xy 426.077081 -345.546369) (xy 426.061713 -345.598708) (xy 426.039052 -345.648328) (xy 426.00956 -345.694218)
			(xy 425.973837 -345.735443) (xy 425.932611 -345.771165) (xy 425.886721 -345.800656) (xy 425.837101 -345.823315)
			(xy 425.784761 -345.838683) (xy 425.730767 -345.846445) (xy 425.703492 -345.846908) (xy 424.839892 -345.846908)
			(xy 424.812626 -345.846329) (xy 424.75865 -345.838567) (xy 424.706328 -345.823203) (xy 424.656725 -345.800549)
			(xy 424.61085 -345.771067) (xy 424.569638 -345.735356) (xy 424.533928 -345.694143) (xy 424.504447 -345.648268)
			(xy 424.481794 -345.598665) (xy 424.466431 -345.546342) (xy 424.45867 -345.492366) (xy 422.975822 -345.492366)
			(xy 422.975822 -345.492371) (xy 422.96806 -345.546358) (xy 422.952694 -345.598692) (xy 422.930038 -345.648306)
			(xy 422.900551 -345.694191) (xy 422.864835 -345.735412) (xy 422.823616 -345.771132) (xy 422.777734 -345.800622)
			(xy 422.728122 -345.823283) (xy 422.67579 -345.838653) (xy 422.621803 -345.846419) (xy 422.594532 -345.846908)
			(xy 421.730932 -345.846908) (xy 421.703663 -345.846355) (xy 421.649679 -345.838597) (xy 421.597349 -345.823236)
			(xy 421.547738 -345.800583) (xy 421.501855 -345.771099) (xy 421.460636 -345.735386) (xy 421.42492 -345.69417)
			(xy 421.395433 -345.648291) (xy 421.372776 -345.598681) (xy 421.35741 -345.546352) (xy 421.349647 -345.492369)
			(xy 419.866944 -345.492369) (xy 419.866944 -345.492376) (xy 419.859181 -345.546371) (xy 419.843811 -345.598713)
			(xy 419.821149 -345.648334) (xy 419.791655 -345.694224) (xy 419.75593 -345.73545) (xy 419.714702 -345.771172)
			(xy 419.668809 -345.800662) (xy 419.619186 -345.823321) (xy 419.566844 -345.838686) (xy 419.512848 -345.846446)
			(xy 419.485572 -345.846908) (xy 418.621972 -345.846908) (xy 418.594707 -345.846328) (xy 418.540733 -345.838564)
			(xy 418.488413 -345.823198) (xy 418.438813 -345.800543) (xy 418.392941 -345.77106) (xy 418.351731 -345.735349)
			(xy 418.316023 -345.694137) (xy 418.286544 -345.648263) (xy 418.263892 -345.59866) (xy 418.24853 -345.546339)
			(xy 418.24077 -345.492365) (xy 416.757921 -345.492365) (xy 416.757921 -345.492372) (xy 416.750159 -345.546361)
			(xy 416.734793 -345.598696) (xy 416.712135 -345.648311) (xy 416.682646 -345.694197) (xy 416.646928 -345.735419)
			(xy 416.605707 -345.771139) (xy 416.559822 -345.800629) (xy 416.510207 -345.823288) (xy 416.457873 -345.838657)
			(xy 416.403884 -345.846421) (xy 416.376612 -345.846908) (xy 415.513012 -345.846908) (xy 415.485744 -345.846353)
			(xy 415.431762 -345.838594) (xy 415.379434 -345.82323) (xy 415.329826 -345.800576) (xy 415.283946 -345.771092)
			(xy 415.242729 -345.735379) (xy 415.207015 -345.694164) (xy 415.17753 -345.648285) (xy 415.154874 -345.598677)
			(xy 415.139509 -345.54635) (xy 415.131747 -345.492368) (xy 413.649044 -345.492368) (xy 413.649044 -345.492376)
			(xy 413.64128 -345.546374) (xy 413.625909 -345.598717) (xy 413.603246 -345.648339) (xy 413.57375 -345.694231)
			(xy 413.538023 -345.735457) (xy 413.496792 -345.771179) (xy 413.450897 -345.800669) (xy 413.401272 -345.823326)
			(xy 413.348927 -345.83869) (xy 413.294929 -345.846448) (xy 413.267652 -345.846908) (xy 412.404052 -345.846908)
			(xy 412.376788 -345.846326) (xy 412.322816 -345.83856) (xy 412.270499 -345.823192) (xy 412.220901 -345.800536)
			(xy 412.175031 -345.771053) (xy 412.133824 -345.735342) (xy 412.098119 -345.69413) (xy 412.068641 -345.648257)
			(xy 412.045991 -345.598656) (xy 412.03063 -345.546337) (xy 412.02287 -345.492364) (xy 410.540044 -345.492364)
			(xy 410.540044 -345.492375) (xy 410.532281 -345.546369) (xy 410.516913 -345.598708) (xy 410.494252 -345.648328)
			(xy 410.46476 -345.694218) (xy 410.429037 -345.735443) (xy 410.387811 -345.771165) (xy 410.341921 -345.800656)
			(xy 410.292301 -345.823315) (xy 410.239961 -345.838683) (xy 410.185967 -345.846445) (xy 410.158692 -345.846908)
			(xy 409.295092 -345.846908) (xy 409.267826 -345.846329) (xy 409.21385 -345.838567) (xy 409.161528 -345.823203)
			(xy 409.111925 -345.800549) (xy 409.06605 -345.771067) (xy 409.024838 -345.735356) (xy 408.989128 -345.694143)
			(xy 408.959647 -345.648268) (xy 408.936994 -345.598665) (xy 408.921631 -345.546342) (xy 408.91387 -345.492366)
			(xy 403.522544 -345.492366) (xy 403.522544 -345.492375) (xy 403.514781 -345.54637) (xy 403.499412 -345.598711)
			(xy 403.47675 -345.648331) (xy 403.447257 -345.694221) (xy 403.411533 -345.735447) (xy 403.370305 -345.771169)
			(xy 403.324414 -345.800659) (xy 403.274792 -345.823319) (xy 403.222451 -345.838685) (xy 403.168455 -345.846446)
			(xy 403.14118 -345.846908) (xy 402.27758 -345.846908) (xy 402.250315 -345.846328) (xy 402.19634 -345.838565)
			(xy 402.144019 -345.8232) (xy 402.094417 -345.800545) (xy 402.048545 -345.771063) (xy 402.007334 -345.735352)
			(xy 401.971625 -345.694139) (xy 401.942145 -345.648265) (xy 401.919493 -345.598662) (xy 401.90413 -345.546341)
			(xy 401.89637 -345.492365) (xy 400.413522 -345.492365) (xy 400.413522 -345.492372) (xy 400.405759 -345.54636)
			(xy 400.390393 -345.598694) (xy 400.367736 -345.648309) (xy 400.338248 -345.694195) (xy 400.302531 -345.735417)
			(xy 400.261311 -345.771136) (xy 400.215427 -345.800626) (xy 400.165813 -345.823286) (xy 400.11348 -345.838655)
			(xy 400.059492 -345.84642) (xy 400.03222 -345.846908) (xy 399.16862 -345.846908) (xy 399.141351 -345.846354)
			(xy 399.087369 -345.838595) (xy 399.03504 -345.823232) (xy 398.98543 -345.800579) (xy 398.93955 -345.771095)
			(xy 398.898332 -345.735382) (xy 398.862617 -345.694166) (xy 398.833131 -345.648287) (xy 398.810475 -345.598679)
			(xy 398.795109 -345.546351) (xy 398.787347 -345.492369) (xy 397.304644 -345.492369) (xy 397.304644 -345.492376)
			(xy 397.29688 -345.546373) (xy 397.28151 -345.598715) (xy 397.258847 -345.648337) (xy 397.229352 -345.694228)
			(xy 397.193626 -345.735454) (xy 397.152396 -345.771176) (xy 397.106502 -345.800666) (xy 397.056878 -345.823324)
			(xy 397.004534 -345.838689) (xy 396.950536 -345.846447) (xy 396.92326 -345.846908) (xy 396.05966 -345.846908)
			(xy 396.032396 -345.846327) (xy 395.978423 -345.838562) (xy 395.926105 -345.823195) (xy 395.876505 -345.800539)
			(xy 395.830635 -345.771055) (xy 395.789427 -345.735345) (xy 395.753721 -345.694133) (xy 395.724242 -345.648259)
			(xy 395.701591 -345.598658) (xy 395.68623 -345.546338) (xy 395.67847 -345.492364) (xy 394.195621 -345.492364)
			(xy 394.195621 -345.492373) (xy 394.187859 -345.546363) (xy 394.172492 -345.598699) (xy 394.149833 -345.648315)
			(xy 394.120343 -345.694201) (xy 394.084624 -345.735424) (xy 394.043401 -345.771143) (xy 393.997515 -345.800633)
			(xy 393.947899 -345.823292) (xy 393.895563 -345.838659) (xy 393.841573 -345.846421) (xy 393.8143 -345.846908)
			(xy 392.9507 -345.846908) (xy 392.923434 -345.84633) (xy 392.869457 -345.838569) (xy 392.817134 -345.823205)
			(xy 392.767529 -345.800552) (xy 392.721654 -345.77107) (xy 392.680441 -345.735359) (xy 392.64473 -345.694146)
			(xy 392.615248 -345.648271) (xy 392.592595 -345.598666) (xy 392.577231 -345.546343) (xy 392.56947 -345.492366)
			(xy 391.086622 -345.492366) (xy 391.086622 -345.492371) (xy 391.07886 -345.546357) (xy 391.063495 -345.59869)
			(xy 391.040839 -345.648304) (xy 391.011353 -345.694188) (xy 390.975638 -345.73541) (xy 390.93442 -345.771129)
			(xy 390.888539 -345.80062) (xy 390.838928 -345.823281) (xy 390.786597 -345.838651) (xy 390.732611 -345.846419)
			(xy 390.70534 -345.846908) (xy 389.84174 -345.846908) (xy 389.81447 -345.846355) (xy 389.760486 -345.838599)
			(xy 389.708155 -345.823238) (xy 389.658542 -345.800585) (xy 389.612659 -345.771102) (xy 389.571439 -345.735389)
			(xy 389.535722 -345.694173) (xy 389.506234 -345.648293) (xy 389.483576 -345.598683) (xy 389.46821 -345.546353)
			(xy 389.460447 -345.49237) (xy 387.977744 -345.49237) (xy 387.977744 -345.492375) (xy 387.969981 -345.54637)
			(xy 387.954612 -345.598711) (xy 387.93195 -345.648331) (xy 387.902457 -345.694221) (xy 387.866733 -345.735447)
			(xy 387.825505 -345.771169) (xy 387.779614 -345.800659) (xy 387.729992 -345.823319) (xy 387.677651 -345.838685)
			(xy 387.623655 -345.846446) (xy 387.59638 -345.846908) (xy 386.73278 -345.846908) (xy 386.705515 -345.846328)
			(xy 386.65154 -345.838565) (xy 386.599219 -345.8232) (xy 386.549617 -345.800545) (xy 386.503745 -345.771063)
			(xy 386.462534 -345.735352) (xy 386.426825 -345.694139) (xy 386.397345 -345.648265) (xy 386.374693 -345.598662)
			(xy 386.35933 -345.546341) (xy 386.35157 -345.492365) (xy 384.868722 -345.492365) (xy 384.868722 -345.492372)
			(xy 384.860959 -345.54636) (xy 384.845593 -345.598694) (xy 384.822936 -345.648309) (xy 384.793448 -345.694195)
			(xy 384.757731 -345.735417) (xy 384.716511 -345.771136) (xy 384.670627 -345.800626) (xy 384.621013 -345.823286)
			(xy 384.56868 -345.838655) (xy 384.514692 -345.84642) (xy 384.48742 -345.846908) (xy 383.62382 -345.846908)
			(xy 383.596551 -345.846354) (xy 383.542569 -345.838595) (xy 383.49024 -345.823232) (xy 383.44063 -345.800579)
			(xy 383.39475 -345.771095) (xy 383.353532 -345.735382) (xy 383.317817 -345.694166) (xy 383.288331 -345.648287)
			(xy 383.265675 -345.598679) (xy 383.250309 -345.546351) (xy 383.242547 -345.492369) (xy 381.759844 -345.492369)
			(xy 381.759844 -345.492376) (xy 381.75208 -345.546373) (xy 381.73671 -345.598715) (xy 381.714047 -345.648337)
			(xy 381.684552 -345.694228) (xy 381.648826 -345.735454) (xy 381.607596 -345.771176) (xy 381.561702 -345.800666)
			(xy 381.512078 -345.823324) (xy 381.459734 -345.838689) (xy 381.405736 -345.846447) (xy 381.37846 -345.846908)
			(xy 380.51486 -345.846908) (xy 380.487596 -345.846327) (xy 380.433623 -345.838562) (xy 380.381305 -345.823195)
			(xy 380.331705 -345.800539) (xy 380.285835 -345.771055) (xy 380.244627 -345.735345) (xy 380.208921 -345.694133)
			(xy 380.179442 -345.648259) (xy 380.156791 -345.598658) (xy 380.14143 -345.546338) (xy 380.13367 -345.492364)
			(xy 378.650821 -345.492364) (xy 378.650821 -345.492373) (xy 378.643059 -345.546363) (xy 378.627692 -345.598699)
			(xy 378.605033 -345.648315) (xy 378.575543 -345.694201) (xy 378.539824 -345.735424) (xy 378.498601 -345.771143)
			(xy 378.452715 -345.800633) (xy 378.403099 -345.823292) (xy 378.350763 -345.838659) (xy 378.296773 -345.846421)
			(xy 378.2695 -345.846908) (xy 377.4059 -345.846908) (xy 377.378634 -345.84633) (xy 377.324657 -345.838569)
			(xy 377.272334 -345.823205) (xy 377.222729 -345.800552) (xy 377.176854 -345.77107) (xy 377.135641 -345.735359)
			(xy 377.09993 -345.694146) (xy 377.070448 -345.648271) (xy 377.047795 -345.598666) (xy 377.032431 -345.546343)
			(xy 377.02467 -345.492366) (xy 375.541822 -345.492366) (xy 375.541822 -345.492371) (xy 375.53406 -345.546357)
			(xy 375.518695 -345.59869) (xy 375.496039 -345.648304) (xy 375.466553 -345.694188) (xy 375.430838 -345.73541)
			(xy 375.38962 -345.771129) (xy 375.343739 -345.80062) (xy 375.294128 -345.823281) (xy 375.241797 -345.838651)
			(xy 375.187811 -345.846419) (xy 375.16054 -345.846908) (xy 374.29694 -345.846908) (xy 374.26967 -345.846355)
			(xy 374.215686 -345.838599) (xy 374.163355 -345.823238) (xy 374.113742 -345.800585) (xy 374.067859 -345.771102)
			(xy 374.026639 -345.735389) (xy 373.990922 -345.694173) (xy 373.961434 -345.648293) (xy 373.938776 -345.598683)
			(xy 373.92341 -345.546353) (xy 373.915647 -345.49237) (xy 372.432944 -345.49237) (xy 372.432944 -345.492375)
			(xy 372.425181 -345.54637) (xy 372.409812 -345.598711) (xy 372.38715 -345.648331) (xy 372.357657 -345.694221)
			(xy 372.321933 -345.735447) (xy 372.280705 -345.771169) (xy 372.234814 -345.800659) (xy 372.185192 -345.823319)
			(xy 372.132851 -345.838685) (xy 372.078855 -345.846446) (xy 372.05158 -345.846908) (xy 371.18798 -345.846908)
			(xy 371.160715 -345.846328) (xy 371.10674 -345.838565) (xy 371.054419 -345.8232) (xy 371.004817 -345.800545)
			(xy 370.958945 -345.771063) (xy 370.917734 -345.735352) (xy 370.882025 -345.694139) (xy 370.852545 -345.648265)
			(xy 370.829893 -345.598662) (xy 370.81453 -345.546341) (xy 370.80677 -345.492365) (xy 344.837321 -345.492365)
			(xy 344.837321 -345.492372) (xy 344.829559 -345.546362) (xy 344.814192 -345.598698) (xy 344.791533 -345.648314)
			(xy 344.762044 -345.6942) (xy 344.726325 -345.735422) (xy 344.685103 -345.771142) (xy 344.639217 -345.800631)
			(xy 344.589601 -345.823291) (xy 344.537266 -345.838658) (xy 344.483276 -345.846421) (xy 344.456004 -345.846908)
			(xy 343.592404 -345.846908) (xy 343.565136 -345.846353) (xy 343.511155 -345.838592) (xy 343.458828 -345.823228)
			(xy 343.409221 -345.800573) (xy 343.363342 -345.771089) (xy 343.322126 -345.735376) (xy 343.286413 -345.694161)
			(xy 343.256928 -345.648283) (xy 343.234273 -345.598675) (xy 343.218909 -345.546349) (xy 343.211147 -345.492368)
			(xy 341.728322 -345.492368) (xy 341.728322 -345.492371) (xy 341.72056 -345.546357) (xy 341.705195 -345.598689)
			(xy 341.682539 -345.648302) (xy 341.653054 -345.694187) (xy 341.617339 -345.735408) (xy 341.576122 -345.771128)
			(xy 341.530241 -345.800618) (xy 341.48063 -345.82328) (xy 341.4283 -345.838651) (xy 341.374315 -345.846418)
			(xy 341.347044 -345.846908) (xy 340.483444 -345.846908) (xy 340.456174 -345.846356) (xy 340.402189 -345.8386)
			(xy 340.349857 -345.823239) (xy 340.300245 -345.800587) (xy 340.254361 -345.771104) (xy 340.213141 -345.735391)
			(xy 340.177423 -345.694174) (xy 340.147935 -345.648294) (xy 340.125276 -345.598684) (xy 340.10991 -345.546354)
			(xy 340.102148 -345.49237) (xy 338.619444 -345.49237) (xy 338.619444 -345.492375) (xy 338.611681 -345.54637)
			(xy 338.596312 -345.59871) (xy 338.57365 -345.64833) (xy 338.544158 -345.69422) (xy 338.508434 -345.735446)
			(xy 338.467207 -345.771167) (xy 338.421316 -345.800658) (xy 338.371695 -345.823318) (xy 338.319354 -345.838684)
			(xy 338.265359 -345.846445) (xy 338.238084 -345.846908) (xy 337.374484 -345.846908) (xy 337.347219 -345.846329)
			(xy 337.293243 -345.838566) (xy 337.240922 -345.823201) (xy 337.19132 -345.800547) (xy 337.145446 -345.771064)
			(xy 337.104236 -345.735353) (xy 337.068526 -345.694141) (xy 337.039046 -345.648266) (xy 337.016393 -345.598663)
			(xy 337.001031 -345.546341) (xy 336.99327 -345.492365) (xy 335.510422 -345.492365) (xy 335.510422 -345.492372)
			(xy 335.50266 -345.54636) (xy 335.487294 -345.598693) (xy 335.464636 -345.648308) (xy 335.435149 -345.694193)
			(xy 335.399432 -345.735415) (xy 335.358213 -345.771135) (xy 335.312329 -345.800625) (xy 335.262716 -345.823285)
			(xy 335.210383 -345.838654) (xy 335.156396 -345.84642) (xy 335.129124 -345.846908) (xy 334.265524 -345.846908)
			(xy 334.238255 -345.846354) (xy 334.184272 -345.838596) (xy 334.131943 -345.823234) (xy 334.082333 -345.80058)
			(xy 334.036452 -345.771097) (xy 333.995234 -345.735383) (xy 333.959518 -345.694168) (xy 333.930031 -345.648288)
			(xy 333.907375 -345.59868) (xy 333.892009 -345.546351) (xy 333.884247 -345.492369) (xy 332.401544 -345.492369)
			(xy 332.401544 -345.492376) (xy 332.39378 -345.546372) (xy 332.37841 -345.598714) (xy 332.355747 -345.648336)
			(xy 332.326253 -345.694227) (xy 332.290527 -345.735453) (xy 332.249298 -345.771174) (xy 332.203404 -345.800665)
			(xy 332.153781 -345.823323) (xy 332.101437 -345.838688) (xy 332.04744 -345.846447) (xy 332.020164 -345.846908)
			(xy 331.156564 -345.846908) (xy 331.1293 -345.846327) (xy 331.075326 -345.838562) (xy 331.023007 -345.823196)
			(xy 330.973408 -345.80054) (xy 330.927537 -345.771057) (xy 330.886329 -345.735346) (xy 330.850622 -345.694134)
			(xy 330.821143 -345.648261) (xy 330.798492 -345.598659) (xy 330.78313 -345.546338) (xy 330.77537 -345.492364)
			(xy 329.292521 -345.492364) (xy 329.292521 -345.492372) (xy 329.284759 -345.546362) (xy 329.269392 -345.598698)
			(xy 329.246733 -345.648314) (xy 329.217244 -345.6942) (xy 329.181525 -345.735422) (xy 329.140303 -345.771142)
			(xy 329.094417 -345.800631) (xy 329.044801 -345.823291) (xy 328.992466 -345.838658) (xy 328.938476 -345.846421)
			(xy 328.911204 -345.846908) (xy 328.047604 -345.846908) (xy 328.020336 -345.846353) (xy 327.966355 -345.838592)
			(xy 327.914028 -345.823228) (xy 327.864421 -345.800573) (xy 327.818542 -345.771089) (xy 327.777326 -345.735376)
			(xy 327.741613 -345.694161) (xy 327.712128 -345.648283) (xy 327.689473 -345.598675) (xy 327.674109 -345.546349)
			(xy 327.666347 -345.492368) (xy 326.183522 -345.492368) (xy 326.183522 -345.492371) (xy 326.17576 -345.546357)
			(xy 326.160395 -345.598689) (xy 326.137739 -345.648302) (xy 326.108254 -345.694187) (xy 326.072539 -345.735408)
			(xy 326.031322 -345.771128) (xy 325.985441 -345.800618) (xy 325.93583 -345.82328) (xy 325.8835 -345.838651)
			(xy 325.829515 -345.846418) (xy 325.802244 -345.846908) (xy 324.938644 -345.846908) (xy 324.911374 -345.846356)
			(xy 324.857389 -345.8386) (xy 324.805057 -345.823239) (xy 324.755445 -345.800587) (xy 324.709561 -345.771104)
			(xy 324.668341 -345.735391) (xy 324.632623 -345.694174) (xy 324.603135 -345.648294) (xy 324.580476 -345.598684)
			(xy 324.56511 -345.546354) (xy 324.557348 -345.49237) (xy 323.074644 -345.49237) (xy 323.074644 -345.492375)
			(xy 323.066881 -345.54637) (xy 323.051512 -345.59871) (xy 323.02885 -345.64833) (xy 322.999358 -345.69422)
			(xy 322.963634 -345.735446) (xy 322.922407 -345.771167) (xy 322.876516 -345.800658) (xy 322.826895 -345.823318)
			(xy 322.774554 -345.838684) (xy 322.720559 -345.846445) (xy 322.693284 -345.846908) (xy 321.829684 -345.846908)
			(xy 321.802419 -345.846329) (xy 321.748443 -345.838566) (xy 321.696122 -345.823201) (xy 321.64652 -345.800547)
			(xy 321.600646 -345.771064) (xy 321.559436 -345.735353) (xy 321.523726 -345.694141) (xy 321.494246 -345.648266)
			(xy 321.471593 -345.598663) (xy 321.456231 -345.546341) (xy 321.44847 -345.492365) (xy 319.965622 -345.492365)
			(xy 319.965622 -345.492372) (xy 319.95786 -345.54636) (xy 319.942494 -345.598693) (xy 319.919836 -345.648308)
			(xy 319.890349 -345.694193) (xy 319.854632 -345.735415) (xy 319.813413 -345.771135) (xy 319.767529 -345.800625)
			(xy 319.717916 -345.823285) (xy 319.665583 -345.838654) (xy 319.611596 -345.84642) (xy 319.584324 -345.846908)
			(xy 318.720724 -345.846908) (xy 318.693455 -345.846354) (xy 318.639472 -345.838596) (xy 318.587143 -345.823234)
			(xy 318.537533 -345.80058) (xy 318.491652 -345.771097) (xy 318.450434 -345.735383) (xy 318.414718 -345.694168)
			(xy 318.385231 -345.648288) (xy 318.362575 -345.59868) (xy 318.347209 -345.546351) (xy 318.339447 -345.492369)
			(xy 316.856744 -345.492369) (xy 316.856744 -345.492376) (xy 316.84898 -345.546372) (xy 316.83361 -345.598714)
			(xy 316.810947 -345.648336) (xy 316.781453 -345.694227) (xy 316.745727 -345.735453) (xy 316.704498 -345.771174)
			(xy 316.658604 -345.800665) (xy 316.608981 -345.823323) (xy 316.556637 -345.838688) (xy 316.50264 -345.846447)
			(xy 316.475364 -345.846908) (xy 315.611764 -345.846908) (xy 315.5845 -345.846327) (xy 315.530526 -345.838562)
			(xy 315.478207 -345.823196) (xy 315.428608 -345.80054) (xy 315.382737 -345.771057) (xy 315.341529 -345.735346)
			(xy 315.305822 -345.694134) (xy 315.276343 -345.648261) (xy 315.253692 -345.598659) (xy 315.23833 -345.546338)
			(xy 315.23057 -345.492364) (xy 313.747721 -345.492364) (xy 313.747721 -345.492372) (xy 313.739959 -345.546362)
			(xy 313.724592 -345.598698) (xy 313.701933 -345.648314) (xy 313.672444 -345.6942) (xy 313.636725 -345.735422)
			(xy 313.595503 -345.771142) (xy 313.549617 -345.800631) (xy 313.500001 -345.823291) (xy 313.447666 -345.838658)
			(xy 313.393676 -345.846421) (xy 313.366404 -345.846908) (xy 312.502804 -345.846908) (xy 312.475536 -345.846353)
			(xy 312.421555 -345.838592) (xy 312.369228 -345.823228) (xy 312.319621 -345.800573) (xy 312.273742 -345.771089)
			(xy 312.232526 -345.735376) (xy 312.196813 -345.694161) (xy 312.167328 -345.648283) (xy 312.144673 -345.598675)
			(xy 312.129309 -345.546349) (xy 312.121547 -345.492368) (xy 300.231621 -345.492368) (xy 300.231621 -345.492373)
			(xy 300.223859 -345.546362) (xy 300.208492 -345.598698) (xy 300.185833 -345.648314) (xy 300.156344 -345.6942)
			(xy 300.120624 -345.735423) (xy 300.079402 -345.771143) (xy 300.033516 -345.800632) (xy 299.9839 -345.823291)
			(xy 299.931564 -345.838658) (xy 299.877575 -345.846421) (xy 299.850302 -345.846908) (xy 298.986702 -345.846908)
			(xy 298.959434 -345.846353) (xy 298.905454 -345.838592) (xy 298.853127 -345.823228) (xy 298.80352 -345.800573)
			(xy 298.757641 -345.771089) (xy 298.716426 -345.735376) (xy 298.680712 -345.69416) (xy 298.651228 -345.648282)
			(xy 298.628573 -345.598675) (xy 298.613209 -345.546348) (xy 298.605447 -345.492368) (xy 297.122622 -345.492368)
			(xy 297.122622 -345.492371) (xy 297.11486 -345.546357) (xy 297.099495 -345.59869) (xy 297.076839 -345.648303)
			(xy 297.047354 -345.694187) (xy 297.011639 -345.735409) (xy 296.970421 -345.771128) (xy 296.92454 -345.800619)
			(xy 296.874929 -345.82328) (xy 296.822598 -345.838651) (xy 296.768613 -345.846419) (xy 296.741342 -345.846908)
			(xy 295.877742 -345.846908) (xy 295.850472 -345.846355) (xy 295.796487 -345.838599) (xy 295.744156 -345.823238)
			(xy 295.694543 -345.800586) (xy 295.64866 -345.771103) (xy 295.60744 -345.73539) (xy 295.571722 -345.694174)
			(xy 295.542234 -345.648293) (xy 295.519576 -345.598683) (xy 295.50421 -345.546354) (xy 295.496448 -345.49237)
			(xy 294.013744 -345.49237) (xy 294.013744 -345.492375) (xy 294.005981 -345.54637) (xy 293.990612 -345.59871)
			(xy 293.96795 -345.648331) (xy 293.938457 -345.694221) (xy 293.902734 -345.735446) (xy 293.861506 -345.771168)
			(xy 293.815615 -345.800659) (xy 293.765994 -345.823318) (xy 293.713652 -345.838685) (xy 293.659657 -345.846446)
			(xy 293.632382 -345.846908) (xy 292.768782 -345.846908) (xy 292.741517 -345.846328) (xy 292.687542 -345.838566)
			(xy 292.635221 -345.823201) (xy 292.585619 -345.800546) (xy 292.539745 -345.771063) (xy 292.498535 -345.735352)
			(xy 292.462826 -345.69414) (xy 292.433345 -345.648266) (xy 292.410693 -345.598663) (xy 292.395331 -345.546341)
			(xy 292.38757 -345.492365) (xy 290.904722 -345.492365) (xy 290.904722 -345.492372) (xy 290.896959 -345.54636)
			(xy 290.881593 -345.598694) (xy 290.858936 -345.648309) (xy 290.829449 -345.694194) (xy 290.793732 -345.735416)
			(xy 290.752512 -345.771136) (xy 290.706628 -345.800626) (xy 290.657015 -345.823286) (xy 290.604681 -345.838655)
			(xy 290.550694 -345.84642) (xy 290.523422 -345.846908) (xy 289.659822 -345.846908) (xy 289.632553 -345.846354)
			(xy 289.57857 -345.838595) (xy 289.526241 -345.823233) (xy 289.476632 -345.800579) (xy 289.430751 -345.771096)
			(xy 289.389533 -345.735383) (xy 289.353817 -345.694167) (xy 289.324331 -345.648288) (xy 289.301675 -345.598679)
			(xy 289.286309 -345.546351) (xy 289.278547 -345.492369) (xy 287.795844 -345.492369) (xy 287.795844 -345.492376)
			(xy 287.78808 -345.546373) (xy 287.77271 -345.598715) (xy 287.750047 -345.648336) (xy 287.720552 -345.694227)
			(xy 287.684827 -345.735453) (xy 287.643597 -345.771175) (xy 287.597703 -345.800665) (xy 287.548079 -345.823323)
			(xy 287.495736 -345.838688) (xy 287.441738 -345.846447) (xy 287.414462 -345.846908) (xy 286.550862 -345.846908)
			(xy 286.523598 -345.846327) (xy 286.469625 -345.838562) (xy 286.417306 -345.823195) (xy 286.367707 -345.80054)
			(xy 286.321836 -345.771056) (xy 286.280628 -345.735345) (xy 286.244921 -345.694134) (xy 286.215442 -345.64826)
			(xy 286.192792 -345.598658) (xy 286.17743 -345.546338) (xy 286.16967 -345.492364) (xy 284.686821 -345.492364)
			(xy 284.686821 -345.492373) (xy 284.679059 -345.546362) (xy 284.663692 -345.598698) (xy 284.641033 -345.648314)
			(xy 284.611544 -345.6942) (xy 284.575824 -345.735423) (xy 284.534602 -345.771143) (xy 284.488716 -345.800632)
			(xy 284.4391 -345.823291) (xy 284.386764 -345.838658) (xy 284.332775 -345.846421) (xy 284.305502 -345.846908)
			(xy 283.441902 -345.846908) (xy 283.414634 -345.846353) (xy 283.360654 -345.838592) (xy 283.308327 -345.823228)
			(xy 283.25872 -345.800573) (xy 283.212841 -345.771089) (xy 283.171626 -345.735376) (xy 283.135912 -345.69416)
			(xy 283.106428 -345.648282) (xy 283.083773 -345.598675) (xy 283.068409 -345.546348) (xy 283.060647 -345.492368)
			(xy 281.577822 -345.492368) (xy 281.577822 -345.492371) (xy 281.57006 -345.546357) (xy 281.554695 -345.59869)
			(xy 281.532039 -345.648303) (xy 281.502554 -345.694187) (xy 281.466839 -345.735409) (xy 281.425621 -345.771128)
			(xy 281.37974 -345.800619) (xy 281.330129 -345.82328) (xy 281.277798 -345.838651) (xy 281.223813 -345.846419)
			(xy 281.196542 -345.846908) (xy 280.332942 -345.846908) (xy 280.305672 -345.846355) (xy 280.251687 -345.838599)
			(xy 280.199356 -345.823238) (xy 280.149743 -345.800586) (xy 280.10386 -345.771103) (xy 280.06264 -345.73539)
			(xy 280.026922 -345.694174) (xy 279.997434 -345.648293) (xy 279.974776 -345.598683) (xy 279.95941 -345.546354)
			(xy 279.951648 -345.49237) (xy 278.468944 -345.49237) (xy 278.468944 -345.492375) (xy 278.461181 -345.54637)
			(xy 278.445812 -345.59871) (xy 278.42315 -345.648331) (xy 278.393657 -345.694221) (xy 278.357934 -345.735446)
			(xy 278.316706 -345.771168) (xy 278.270815 -345.800659) (xy 278.221194 -345.823318) (xy 278.168852 -345.838685)
			(xy 278.114857 -345.846446) (xy 278.087582 -345.846908) (xy 277.223982 -345.846908) (xy 277.196717 -345.846328)
			(xy 277.142742 -345.838566) (xy 277.090421 -345.823201) (xy 277.040819 -345.800546) (xy 276.994945 -345.771063)
			(xy 276.953735 -345.735352) (xy 276.918026 -345.69414) (xy 276.888545 -345.648266) (xy 276.865893 -345.598663)
			(xy 276.850531 -345.546341) (xy 276.84277 -345.492365) (xy 275.359922 -345.492365) (xy 275.359922 -345.492372)
			(xy 275.352159 -345.54636) (xy 275.336793 -345.598694) (xy 275.314136 -345.648309) (xy 275.284649 -345.694194)
			(xy 275.248932 -345.735416) (xy 275.207712 -345.771136) (xy 275.161828 -345.800626) (xy 275.112215 -345.823286)
			(xy 275.059881 -345.838655) (xy 275.005894 -345.84642) (xy 274.978622 -345.846908) (xy 274.115022 -345.846908)
			(xy 274.087753 -345.846354) (xy 274.03377 -345.838595) (xy 273.981441 -345.823233) (xy 273.931832 -345.800579)
			(xy 273.885951 -345.771096) (xy 273.844733 -345.735383) (xy 273.809017 -345.694167) (xy 273.779531 -345.648288)
			(xy 273.756875 -345.598679) (xy 273.741509 -345.546351) (xy 273.733747 -345.492369) (xy 272.251044 -345.492369)
			(xy 272.251044 -345.492376) (xy 272.24328 -345.546373) (xy 272.22791 -345.598715) (xy 272.205247 -345.648336)
			(xy 272.175752 -345.694227) (xy 272.140027 -345.735453) (xy 272.098797 -345.771175) (xy 272.052903 -345.800665)
			(xy 272.003279 -345.823323) (xy 271.950936 -345.838688) (xy 271.896938 -345.846447) (xy 271.869662 -345.846908)
			(xy 271.006062 -345.846908) (xy 270.978798 -345.846327) (xy 270.924825 -345.838562) (xy 270.872506 -345.823195)
			(xy 270.822907 -345.80054) (xy 270.777036 -345.771056) (xy 270.735828 -345.735345) (xy 270.700121 -345.694134)
			(xy 270.670642 -345.64826) (xy 270.647992 -345.598658) (xy 270.63263 -345.546338) (xy 270.62487 -345.492364)
			(xy 269.142021 -345.492364) (xy 269.142021 -345.492373) (xy 269.134259 -345.546362) (xy 269.118892 -345.598698)
			(xy 269.096233 -345.648314) (xy 269.066744 -345.6942) (xy 269.031024 -345.735423) (xy 268.989802 -345.771143)
			(xy 268.943916 -345.800632) (xy 268.8943 -345.823291) (xy 268.841964 -345.838658) (xy 268.787975 -345.846421)
			(xy 268.760702 -345.846908) (xy 267.897102 -345.846908) (xy 267.869834 -345.846353) (xy 267.815854 -345.838592)
			(xy 267.763527 -345.823228) (xy 267.71392 -345.800573) (xy 267.668041 -345.771089) (xy 267.626826 -345.735376)
			(xy 267.591112 -345.69416) (xy 267.561628 -345.648282) (xy 267.538973 -345.598675) (xy 267.523609 -345.546348)
			(xy 267.515847 -345.492368) (xy 219.560575 -345.492368) (xy 219.580134 -345.530247) (xy 219.657547 -345.697572)
			(xy 219.727639 -345.868093) (xy 219.790278 -346.04149) (xy 219.845347 -346.217438) (xy 219.892742 -346.395606)
			(xy 219.932375 -346.575661) (xy 219.964171 -346.757263) (xy 219.98518 -346.917956) (xy 245.50903 -346.917956)
			(xy 245.50903 -346.83326) (xy 245.517081 -346.748946) (xy 245.53311 -346.66578) (xy 245.556971 -346.584513)
			(xy 245.58845 -346.505883) (xy 245.627261 -346.430602) (xy 245.673051 -346.35935) (xy 245.725407 -346.292774)
			(xy 245.783855 -346.231476) (xy 245.847865 -346.176011) (xy 245.916857 -346.126882) (xy 245.990207 -346.084533)
			(xy 246.06725 -346.049349) (xy 246.147289 -346.021647) (xy 246.229598 -346.001679) (xy 246.313433 -345.989626)
			(xy 246.398034 -345.985596) (xy 246.482635 -345.989626) (xy 246.56647 -346.001679) (xy 246.648779 -346.021647)
			(xy 246.728818 -346.049349) (xy 246.805861 -346.084533) (xy 246.879211 -346.126882) (xy 246.948203 -346.176011)
			(xy 247.012213 -346.231476) (xy 247.070661 -346.292774) (xy 247.123017 -346.35935) (xy 247.168807 -346.430602)
			(xy 247.207618 -346.505883) (xy 247.239097 -346.584513) (xy 247.262958 -346.66578) (xy 247.278987 -346.748946)
			(xy 247.287038 -346.83326) (xy 247.287542 -346.875608) (xy 247.287038 -346.917956) (xy 247.278987 -347.00227)
			(xy 247.262958 -347.085436) (xy 247.239097 -347.166703) (xy 247.207618 -347.245333) (xy 247.168807 -347.320614)
			(xy 247.123017 -347.391866) (xy 247.070661 -347.458442) (xy 247.012213 -347.51974) (xy 246.948203 -347.575205)
			(xy 246.879211 -347.624334) (xy 246.805861 -347.666683) (xy 246.728818 -347.701867) (xy 246.648779 -347.729569)
			(xy 246.56647 -347.749537) (xy 246.482635 -347.76159) (xy 246.398034 -347.765621) (xy 246.313433 -347.76159)
			(xy 246.229598 -347.749537) (xy 246.147289 -347.729569) (xy 246.06725 -347.701867) (xy 245.990207 -347.666683)
			(xy 245.916857 -347.624334) (xy 245.847865 -347.575205) (xy 245.783855 -347.51974) (xy 245.725407 -347.458442)
			(xy 245.673051 -347.391866) (xy 245.627261 -347.320614) (xy 245.58845 -347.245333) (xy 245.556971 -347.166703)
			(xy 245.53311 -347.085436) (xy 245.517081 -347.00227) (xy 245.50903 -346.917956) (xy 219.98518 -346.917956)
			(xy 219.988071 -346.940072) (xy 220.004028 -347.123744) (xy 220.012015 -347.307936) (xy 220.012514 -347.400118)
			(xy 220.012015 -347.4923) (xy 220.004028 -347.676492) (xy 219.988071 -347.860164) (xy 219.964171 -348.042973)
			(xy 219.932375 -348.224575) (xy 219.892742 -348.40463) (xy 219.845347 -348.582798) (xy 219.835872 -348.613072)
			(xy 267.515792 -348.613072) (xy 267.515792 -348.558528) (xy 267.523554 -348.50454) (xy 267.538921 -348.452206)
			(xy 267.561579 -348.402591) (xy 267.591068 -348.356706) (xy 267.626786 -348.315485) (xy 267.668008 -348.279766)
			(xy 267.713893 -348.250278) (xy 267.763507 -348.22762) (xy 267.815842 -348.212253) (xy 267.86983 -348.204491)
			(xy 267.897102 -348.204028) (xy 268.760702 -348.204028) (xy 268.787971 -348.204535) (xy 268.841953 -348.212296)
			(xy 268.89428 -348.227661) (xy 268.943889 -348.250317) (xy 268.989769 -348.279802) (xy 269.030985 -348.315517)
			(xy 269.066699 -348.356733) (xy 269.096184 -348.402613) (xy 269.118839 -348.452221) (xy 269.134204 -348.504549)
			(xy 269.141966 -348.558531) (xy 269.141966 -348.613068) (xy 270.624814 -348.613068) (xy 270.624814 -348.558532)
			(xy 270.632575 -348.50455) (xy 270.647939 -348.452222) (xy 270.670593 -348.402613) (xy 270.700076 -348.356733)
			(xy 270.735788 -348.315515) (xy 270.777002 -348.279799) (xy 270.82288 -348.250311) (xy 270.872486 -348.227652)
			(xy 270.924813 -348.212283) (xy 270.978794 -348.204517) (xy 271.006062 -348.204028) (xy 271.869662 -348.204028)
			(xy 271.896934 -348.204509) (xy 271.950924 -348.212266) (xy 272.00326 -348.227629) (xy 272.052876 -348.250284)
			(xy 272.098763 -348.27977) (xy 272.139987 -348.315486) (xy 272.175708 -348.356706) (xy 272.205198 -348.40259)
			(xy 272.227858 -348.452205) (xy 272.243226 -348.504539) (xy 272.250988 -348.558528) (xy 272.250988 -348.613072)
			(xy 272.250988 -348.613073) (xy 273.733692 -348.613073) (xy 273.733692 -348.558527) (xy 273.741454 -348.504537)
			(xy 273.756822 -348.452201) (xy 273.779482 -348.402585) (xy 273.808972 -348.356699) (xy 273.844693 -348.315478)
			(xy 273.885917 -348.279759) (xy 273.931805 -348.250271) (xy 273.981422 -348.227615) (xy 274.033759 -348.21225)
			(xy 274.087749 -348.20449) (xy 274.115022 -348.204028) (xy 274.978622 -348.204028) (xy 275.00589 -348.204536)
			(xy 275.059869 -348.2123) (xy 275.112195 -348.227667) (xy 275.161801 -348.250324) (xy 275.207678 -348.279809)
			(xy 275.248892 -348.315524) (xy 275.284604 -348.35674) (xy 275.314087 -348.402618) (xy 275.336741 -348.452226)
			(xy 275.352105 -348.504552) (xy 275.359866 -348.558532) (xy 275.359866 -348.613068) (xy 275.359866 -348.613069)
			(xy 276.842714 -348.613069) (xy 276.842714 -348.558531) (xy 276.850476 -348.504547) (xy 276.865841 -348.452218)
			(xy 276.888496 -348.402608) (xy 276.917981 -348.356726) (xy 276.953695 -348.315508) (xy 276.994912 -348.279792)
			(xy 277.040792 -348.250305) (xy 277.090401 -348.227647) (xy 277.14273 -348.21228) (xy 277.196713 -348.204516)
			(xy 277.223982 -348.204028) (xy 278.087582 -348.204028) (xy 278.114853 -348.20451) (xy 278.168841 -348.21227)
			(xy 278.221174 -348.227634) (xy 278.270788 -348.25029) (xy 278.316673 -348.279777) (xy 278.357894 -348.315493)
			(xy 278.393612 -348.356713) (xy 278.423101 -348.402596) (xy 278.445759 -348.452209) (xy 278.461126 -348.504542)
			(xy 278.468888 -348.558529) (xy 278.468888 -348.613071) (xy 278.468888 -348.613074) (xy 279.951592 -348.613074)
			(xy 279.951592 -348.558526) (xy 279.959355 -348.504534) (xy 279.974724 -348.452197) (xy 279.997385 -348.40258)
			(xy 280.026877 -348.356693) (xy 280.0626 -348.315471) (xy 280.103827 -348.279752) (xy 280.149717 -348.250265)
			(xy 280.199336 -348.227609) (xy 280.251676 -348.212246) (xy 280.305668 -348.204489) (xy 280.332942 -348.204028)
			(xy 281.196542 -348.204028) (xy 281.223809 -348.204537) (xy 281.277786 -348.212304) (xy 281.330109 -348.227672)
			(xy 281.379713 -348.25033) (xy 281.425587 -348.279816) (xy 281.466799 -348.315531) (xy 281.502509 -348.356746)
			(xy 281.53199 -348.402624) (xy 281.554643 -348.45223) (xy 281.570005 -348.504555) (xy 281.577766 -348.558533)
			(xy 281.577766 -348.613067) (xy 281.577765 -348.613072) (xy 283.060592 -348.613072) (xy 283.060592 -348.558528)
			(xy 283.068354 -348.50454) (xy 283.083721 -348.452206) (xy 283.106379 -348.402591) (xy 283.135868 -348.356706)
			(xy 283.171586 -348.315485) (xy 283.212808 -348.279766) (xy 283.258693 -348.250278) (xy 283.308307 -348.22762)
			(xy 283.360642 -348.212253) (xy 283.41463 -348.204491) (xy 283.441902 -348.204028) (xy 284.305502 -348.204028)
			(xy 284.332771 -348.204535) (xy 284.386753 -348.212296) (xy 284.43908 -348.227661) (xy 284.488689 -348.250317)
			(xy 284.534569 -348.279802) (xy 284.575785 -348.315517) (xy 284.611499 -348.356733) (xy 284.640984 -348.402613)
			(xy 284.663639 -348.452221) (xy 284.679004 -348.504549) (xy 284.686766 -348.558531) (xy 284.686766 -348.613068)
			(xy 286.169614 -348.613068) (xy 286.169614 -348.558532) (xy 286.177375 -348.50455) (xy 286.192739 -348.452222)
			(xy 286.215393 -348.402613) (xy 286.244876 -348.356733) (xy 286.280588 -348.315515) (xy 286.321802 -348.279799)
			(xy 286.36768 -348.250311) (xy 286.417286 -348.227652) (xy 286.469613 -348.212283) (xy 286.523594 -348.204517)
			(xy 286.550862 -348.204028) (xy 287.414462 -348.204028) (xy 287.441734 -348.204509) (xy 287.495724 -348.212266)
			(xy 287.54806 -348.227629) (xy 287.597676 -348.250284) (xy 287.643563 -348.27977) (xy 287.684787 -348.315486)
			(xy 287.720508 -348.356706) (xy 287.749998 -348.40259) (xy 287.772658 -348.452205) (xy 287.788026 -348.504539)
			(xy 287.795788 -348.558528) (xy 287.795788 -348.613072) (xy 287.795788 -348.613073) (xy 289.278492 -348.613073)
			(xy 289.278492 -348.558527) (xy 289.286254 -348.504537) (xy 289.301622 -348.452201) (xy 289.324282 -348.402585)
			(xy 289.353772 -348.356699) (xy 289.389493 -348.315478) (xy 289.430717 -348.279759) (xy 289.476605 -348.250271)
			(xy 289.526222 -348.227615) (xy 289.578559 -348.21225) (xy 289.632549 -348.20449) (xy 289.659822 -348.204028)
			(xy 290.523422 -348.204028) (xy 290.55069 -348.204536) (xy 290.604669 -348.2123) (xy 290.656995 -348.227667)
			(xy 290.706601 -348.250324) (xy 290.752478 -348.279809) (xy 290.793692 -348.315524) (xy 290.829404 -348.35674)
			(xy 290.858887 -348.402618) (xy 290.881541 -348.452226) (xy 290.896905 -348.504552) (xy 290.904666 -348.558532)
			(xy 290.904666 -348.613068) (xy 290.904666 -348.613069) (xy 292.387514 -348.613069) (xy 292.387514 -348.558531)
			(xy 292.395276 -348.504547) (xy 292.410641 -348.452218) (xy 292.433296 -348.402608) (xy 292.462781 -348.356726)
			(xy 292.498495 -348.315508) (xy 292.539712 -348.279792) (xy 292.585592 -348.250305) (xy 292.635201 -348.227647)
			(xy 292.68753 -348.21228) (xy 292.741513 -348.204516) (xy 292.768782 -348.204028) (xy 293.632382 -348.204028)
			(xy 293.659653 -348.20451) (xy 293.713641 -348.21227) (xy 293.765974 -348.227634) (xy 293.815588 -348.25029)
			(xy 293.861473 -348.279777) (xy 293.902694 -348.315493) (xy 293.938412 -348.356713) (xy 293.967901 -348.402596)
			(xy 293.990559 -348.452209) (xy 294.005926 -348.504542) (xy 294.013688 -348.558529) (xy 294.013688 -348.613071)
			(xy 294.013688 -348.613074) (xy 295.496392 -348.613074) (xy 295.496392 -348.558526) (xy 295.504155 -348.504534)
			(xy 295.519524 -348.452197) (xy 295.542185 -348.40258) (xy 295.571677 -348.356693) (xy 295.6074 -348.315471)
			(xy 295.648627 -348.279752) (xy 295.694517 -348.250265) (xy 295.744136 -348.227609) (xy 295.796476 -348.212246)
			(xy 295.850468 -348.204489) (xy 295.877742 -348.204028) (xy 296.741342 -348.204028) (xy 296.768609 -348.204537)
			(xy 296.822586 -348.212304) (xy 296.874909 -348.227672) (xy 296.924513 -348.25033) (xy 296.970387 -348.279816)
			(xy 297.011599 -348.315531) (xy 297.047309 -348.356746) (xy 297.07679 -348.402624) (xy 297.099443 -348.45223)
			(xy 297.114805 -348.504555) (xy 297.122566 -348.558533) (xy 297.122566 -348.613067) (xy 297.122565 -348.613072)
			(xy 298.605392 -348.613072) (xy 298.605392 -348.558528) (xy 298.613154 -348.50454) (xy 298.628521 -348.452206)
			(xy 298.651179 -348.402591) (xy 298.680668 -348.356706) (xy 298.716386 -348.315485) (xy 298.757608 -348.279766)
			(xy 298.803493 -348.250278) (xy 298.853107 -348.22762) (xy 298.905442 -348.212253) (xy 298.95943 -348.204491)
			(xy 298.986702 -348.204028) (xy 299.850302 -348.204028) (xy 299.877571 -348.204535) (xy 299.931553 -348.212296)
			(xy 299.98388 -348.227661) (xy 300.033489 -348.250317) (xy 300.079369 -348.279802) (xy 300.120585 -348.315517)
			(xy 300.156299 -348.356733) (xy 300.185784 -348.402613) (xy 300.208439 -348.452221) (xy 300.223804 -348.504549)
			(xy 300.231566 -348.558531) (xy 300.231566 -348.613069) (xy 300.231566 -348.613072) (xy 312.121492 -348.613072)
			(xy 312.121492 -348.558528) (xy 312.129254 -348.504539) (xy 312.144621 -348.452205) (xy 312.167279 -348.40259)
			(xy 312.196768 -348.356705) (xy 312.232487 -348.315484) (xy 312.273709 -348.279766) (xy 312.319594 -348.250277)
			(xy 312.369209 -348.227619) (xy 312.421543 -348.212253) (xy 312.475532 -348.204491) (xy 312.502804 -348.204028)
			(xy 313.366404 -348.204028) (xy 313.393672 -348.204535) (xy 313.447654 -348.212297) (xy 313.499982 -348.227662)
			(xy 313.54959 -348.250318) (xy 313.595469 -348.279803) (xy 313.636686 -348.315517) (xy 313.672399 -348.356734)
			(xy 313.701884 -348.402613) (xy 313.72454 -348.452222) (xy 313.739904 -348.50455) (xy 313.747666 -348.558532)
			(xy 313.747666 -348.613068) (xy 315.230514 -348.613068) (xy 315.230514 -348.558532) (xy 315.238275 -348.50455)
			(xy 315.253639 -348.452222) (xy 315.276293 -348.402613) (xy 315.305777 -348.356732) (xy 315.341489 -348.315514)
			(xy 315.382703 -348.279798) (xy 315.428581 -348.250311) (xy 315.478188 -348.227652) (xy 315.530514 -348.212283)
			(xy 315.584496 -348.204517) (xy 315.611764 -348.204028) (xy 316.475364 -348.204028) (xy 316.502636 -348.204509)
			(xy 316.556625 -348.212267) (xy 316.608961 -348.22763) (xy 316.658577 -348.250284) (xy 316.704464 -348.27977)
			(xy 316.745688 -348.315487) (xy 316.781408 -348.356707) (xy 316.810898 -348.402591) (xy 316.833558 -348.452205)
			(xy 316.848926 -348.504539) (xy 316.856688 -348.558528) (xy 316.856688 -348.613072) (xy 316.856688 -348.613073)
			(xy 318.339392 -348.613073) (xy 318.339392 -348.558527) (xy 318.347155 -348.504537) (xy 318.362522 -348.452201)
			(xy 318.385182 -348.402585) (xy 318.414673 -348.356699) (xy 318.450394 -348.315477) (xy 318.491618 -348.279759)
			(xy 318.537506 -348.250271) (xy 318.587123 -348.227614) (xy 318.63946 -348.212249) (xy 318.693451 -348.20449)
			(xy 318.720724 -348.204028) (xy 319.584324 -348.204028) (xy 319.611592 -348.204536) (xy 319.665571 -348.2123)
			(xy 319.717896 -348.227667) (xy 319.767502 -348.250324) (xy 319.813379 -348.27981) (xy 319.854593 -348.315524)
			(xy 319.890304 -348.35674) (xy 319.919787 -348.402619) (xy 319.942441 -348.452226) (xy 319.957805 -348.504552)
			(xy 319.965566 -348.558532) (xy 319.965566 -348.613068) (xy 319.965566 -348.613069) (xy 321.448414 -348.613069)
			(xy 321.448414 -348.558531) (xy 321.456176 -348.504547) (xy 321.471541 -348.452217) (xy 321.494196 -348.402607)
			(xy 321.523682 -348.356726) (xy 321.559396 -348.315507) (xy 321.600613 -348.279791) (xy 321.646493 -348.250304)
			(xy 321.696102 -348.227646) (xy 321.748431 -348.212279) (xy 321.802415 -348.204516) (xy 321.829684 -348.204028)
			(xy 322.693284 -348.204028) (xy 322.720555 -348.20451) (xy 322.774542 -348.21227) (xy 322.826875 -348.227635)
			(xy 322.876489 -348.250291) (xy 322.922374 -348.279777) (xy 322.963595 -348.315494) (xy 322.999313 -348.356713)
			(xy 323.028801 -348.402597) (xy 323.051459 -348.45221) (xy 323.066826 -348.504542) (xy 323.074588 -348.558529)
			(xy 323.074588 -348.613071) (xy 323.074588 -348.613074) (xy 324.557292 -348.613074) (xy 324.557292 -348.558526)
			(xy 324.565055 -348.504534) (xy 324.580424 -348.452197) (xy 324.603085 -348.402579) (xy 324.632578 -348.356692)
			(xy 324.668301 -348.31547) (xy 324.709527 -348.279751) (xy 324.755418 -348.250264) (xy 324.805038 -348.227609)
			(xy 324.857377 -348.212246) (xy 324.91137 -348.204489) (xy 324.938644 -348.204028) (xy 325.802244 -348.204028)
			(xy 325.829511 -348.204537) (xy 325.883488 -348.212304) (xy 325.935811 -348.227673) (xy 325.985414 -348.250331)
			(xy 326.031288 -348.279817) (xy 326.0725 -348.315531) (xy 326.108209 -348.356747) (xy 326.13769 -348.402624)
			(xy 326.160343 -348.45223) (xy 326.175705 -348.504555) (xy 326.183466 -348.558533) (xy 326.183466 -348.613067)
			(xy 326.183465 -348.613072) (xy 327.666292 -348.613072) (xy 327.666292 -348.558528) (xy 327.674054 -348.504539)
			(xy 327.689421 -348.452205) (xy 327.712079 -348.40259) (xy 327.741568 -348.356705) (xy 327.777287 -348.315484)
			(xy 327.818509 -348.279766) (xy 327.864394 -348.250277) (xy 327.914009 -348.227619) (xy 327.966343 -348.212253)
			(xy 328.020332 -348.204491) (xy 328.047604 -348.204028) (xy 328.911204 -348.204028) (xy 328.938472 -348.204535)
			(xy 328.992454 -348.212297) (xy 329.044782 -348.227662) (xy 329.09439 -348.250318) (xy 329.140269 -348.279803)
			(xy 329.181486 -348.315517) (xy 329.217199 -348.356734) (xy 329.246684 -348.402613) (xy 329.26934 -348.452222)
			(xy 329.284704 -348.50455) (xy 329.292466 -348.558532) (xy 329.292466 -348.613068) (xy 330.775314 -348.613068)
			(xy 330.775314 -348.558532) (xy 330.783075 -348.50455) (xy 330.798439 -348.452222) (xy 330.821093 -348.402613)
			(xy 330.850577 -348.356732) (xy 330.886289 -348.315514) (xy 330.927503 -348.279798) (xy 330.973381 -348.250311)
			(xy 331.022988 -348.227652) (xy 331.075314 -348.212283) (xy 331.129296 -348.204517) (xy 331.156564 -348.204028)
			(xy 332.020164 -348.204028) (xy 332.047436 -348.204509) (xy 332.101425 -348.212267) (xy 332.153761 -348.22763)
			(xy 332.203377 -348.250284) (xy 332.249264 -348.27977) (xy 332.290488 -348.315487) (xy 332.326208 -348.356707)
			(xy 332.355698 -348.402591) (xy 332.378358 -348.452205) (xy 332.393726 -348.504539) (xy 332.401488 -348.558528)
			(xy 332.401488 -348.613072) (xy 332.401488 -348.613073) (xy 333.884192 -348.613073) (xy 333.884192 -348.558527)
			(xy 333.891955 -348.504537) (xy 333.907322 -348.452201) (xy 333.929982 -348.402585) (xy 333.959473 -348.356699)
			(xy 333.995194 -348.315477) (xy 334.036418 -348.279759) (xy 334.082306 -348.250271) (xy 334.131923 -348.227614)
			(xy 334.18426 -348.212249) (xy 334.238251 -348.20449) (xy 334.265524 -348.204028) (xy 335.129124 -348.204028)
			(xy 335.156392 -348.204536) (xy 335.210371 -348.2123) (xy 335.262696 -348.227667) (xy 335.312302 -348.250324)
			(xy 335.358179 -348.27981) (xy 335.399393 -348.315524) (xy 335.435104 -348.35674) (xy 335.464587 -348.402619)
			(xy 335.487241 -348.452226) (xy 335.502605 -348.504552) (xy 335.510366 -348.558532) (xy 335.510366 -348.613068)
			(xy 335.510366 -348.613069) (xy 336.993214 -348.613069) (xy 336.993214 -348.558531) (xy 337.000976 -348.504547)
			(xy 337.016341 -348.452217) (xy 337.038996 -348.402607) (xy 337.068482 -348.356726) (xy 337.104196 -348.315507)
			(xy 337.145413 -348.279791) (xy 337.191293 -348.250304) (xy 337.240902 -348.227646) (xy 337.293231 -348.212279)
			(xy 337.347215 -348.204516) (xy 337.374484 -348.204028) (xy 338.238084 -348.204028) (xy 338.265355 -348.20451)
			(xy 338.319342 -348.21227) (xy 338.371675 -348.227635) (xy 338.421289 -348.250291) (xy 338.467174 -348.279777)
			(xy 338.508395 -348.315494) (xy 338.544113 -348.356713) (xy 338.573601 -348.402597) (xy 338.596259 -348.45221)
			(xy 338.611626 -348.504542) (xy 338.619388 -348.558529) (xy 338.619388 -348.613071) (xy 338.619388 -348.613074)
			(xy 340.102092 -348.613074) (xy 340.102092 -348.558526) (xy 340.109855 -348.504534) (xy 340.125224 -348.452197)
			(xy 340.147885 -348.402579) (xy 340.177378 -348.356692) (xy 340.213101 -348.31547) (xy 340.254327 -348.279751)
			(xy 340.300218 -348.250264) (xy 340.349838 -348.227609) (xy 340.402177 -348.212246) (xy 340.45617 -348.204489)
			(xy 340.483444 -348.204028) (xy 341.347044 -348.204028) (xy 341.374311 -348.204537) (xy 341.428288 -348.212304)
			(xy 341.480611 -348.227673) (xy 341.530214 -348.250331) (xy 341.576088 -348.279817) (xy 341.6173 -348.315531)
			(xy 341.653009 -348.356747) (xy 341.68249 -348.402624) (xy 341.705143 -348.45223) (xy 341.720505 -348.504555)
			(xy 341.728266 -348.558533) (xy 341.728266 -348.613067) (xy 341.728265 -348.613072) (xy 343.211092 -348.613072)
			(xy 343.211092 -348.558528) (xy 343.218854 -348.504539) (xy 343.234221 -348.452205) (xy 343.256879 -348.40259)
			(xy 343.286368 -348.356705) (xy 343.322087 -348.315484) (xy 343.363309 -348.279766) (xy 343.409194 -348.250277)
			(xy 343.458809 -348.227619) (xy 343.511143 -348.212253) (xy 343.565132 -348.204491) (xy 343.592404 -348.204028)
			(xy 344.456004 -348.204028) (xy 344.483272 -348.204535) (xy 344.537254 -348.212297) (xy 344.589582 -348.227662)
			(xy 344.63919 -348.250318) (xy 344.685069 -348.279803) (xy 344.726286 -348.315517) (xy 344.761999 -348.356734)
			(xy 344.791484 -348.402613) (xy 344.81414 -348.452222) (xy 344.829504 -348.50455) (xy 344.837266 -348.558532)
			(xy 344.837266 -348.613068) (xy 344.837266 -348.613069) (xy 370.806714 -348.613069) (xy 370.806714 -348.558531)
			(xy 370.814476 -348.504548) (xy 370.82984 -348.452218) (xy 370.852496 -348.402608) (xy 370.881981 -348.356727)
			(xy 370.917695 -348.315509) (xy 370.958911 -348.279793) (xy 371.004791 -348.250305) (xy 371.054399 -348.227647)
			(xy 371.106728 -348.21228) (xy 371.160711 -348.204516) (xy 371.18798 -348.204028) (xy 372.05158 -348.204028)
			(xy 372.078851 -348.20451) (xy 372.132839 -348.21227) (xy 372.185173 -348.227634) (xy 372.234787 -348.25029)
			(xy 372.280672 -348.279776) (xy 372.321893 -348.315493) (xy 372.357612 -348.356712) (xy 372.387101 -348.402595)
			(xy 372.409759 -348.452209) (xy 372.425126 -348.504542) (xy 372.432888 -348.558529) (xy 372.432888 -348.613071)
			(xy 372.432888 -348.613074) (xy 373.915592 -348.613074) (xy 373.915592 -348.558526) (xy 373.923355 -348.504535)
			(xy 373.938724 -348.452197) (xy 373.961385 -348.40258) (xy 373.990877 -348.356694) (xy 374.0266 -348.315471)
			(xy 374.067826 -348.279753) (xy 374.113715 -348.250266) (xy 374.163335 -348.22761) (xy 374.215674 -348.212246)
			(xy 374.269666 -348.204489) (xy 374.29694 -348.204028) (xy 375.16054 -348.204028) (xy 375.187807 -348.204537)
			(xy 375.241785 -348.212303) (xy 375.294108 -348.227672) (xy 375.343712 -348.25033) (xy 375.389587 -348.279816)
			(xy 375.430798 -348.31553) (xy 375.466508 -348.356746) (xy 375.49599 -348.402623) (xy 375.518642 -348.45223)
			(xy 375.534005 -348.504554) (xy 375.541766 -348.558533) (xy 375.541766 -348.613067) (xy 375.541766 -348.61307)
			(xy 377.024614 -348.61307) (xy 377.024614 -348.55853) (xy 377.032376 -348.504545) (xy 377.047742 -348.452214)
			(xy 377.070399 -348.402603) (xy 377.099886 -348.35672) (xy 377.135602 -348.315502) (xy 377.17682 -348.279786)
			(xy 377.222703 -348.250299) (xy 377.272314 -348.227642) (xy 377.324645 -348.212276) (xy 377.37863 -348.204514)
			(xy 377.4059 -348.204028) (xy 378.2695 -348.204028) (xy 378.296769 -348.204534) (xy 378.350751 -348.212296)
			(xy 378.403079 -348.227661) (xy 378.452688 -348.250316) (xy 378.498568 -348.279802) (xy 378.539784 -348.315516)
			(xy 378.575498 -348.356732) (xy 378.604984 -348.402612) (xy 378.627639 -348.452221) (xy 378.643004 -348.504549)
			(xy 378.650766 -348.558531) (xy 378.650766 -348.613068) (xy 380.133614 -348.613068) (xy 380.133614 -348.558532)
			(xy 380.141375 -348.50455) (xy 380.156739 -348.452223) (xy 380.179393 -348.402614) (xy 380.208876 -348.356734)
			(xy 380.244588 -348.315516) (xy 380.285801 -348.2798) (xy 380.331679 -348.250312) (xy 380.381285 -348.227653)
			(xy 380.433611 -348.212284) (xy 380.487592 -348.204517) (xy 380.51486 -348.204028) (xy 381.37846 -348.204028)
			(xy 381.405732 -348.204509) (xy 381.459722 -348.212266) (xy 381.512058 -348.227628) (xy 381.561675 -348.250283)
			(xy 381.607562 -348.279769) (xy 381.648786 -348.315485) (xy 381.684507 -348.356706) (xy 381.713998 -348.40259)
			(xy 381.736658 -348.452204) (xy 381.752025 -348.504539) (xy 381.759788 -348.558528) (xy 381.759788 -348.613072)
			(xy 381.759788 -348.613073) (xy 383.242492 -348.613073) (xy 383.242492 -348.558527) (xy 383.250254 -348.504537)
			(xy 383.265622 -348.452202) (xy 383.288282 -348.402586) (xy 383.317772 -348.3567) (xy 383.353493 -348.315478)
			(xy 383.394716 -348.27976) (xy 383.440603 -348.250272) (xy 383.49022 -348.227615) (xy 383.542557 -348.21225)
			(xy 383.596547 -348.20449) (xy 383.62382 -348.204028) (xy 384.48742 -348.204028) (xy 384.514688 -348.204536)
			(xy 384.568668 -348.2123) (xy 384.620994 -348.227666) (xy 384.6706 -348.250323) (xy 384.716477 -348.279809)
			(xy 384.757691 -348.315523) (xy 384.793403 -348.356739) (xy 384.822887 -348.402618) (xy 384.845541 -348.452225)
			(xy 384.860905 -348.504552) (xy 384.868666 -348.558532) (xy 384.868666 -348.613068) (xy 384.868666 -348.613069)
			(xy 386.351514 -348.613069) (xy 386.351514 -348.558531) (xy 386.359276 -348.504548) (xy 386.37464 -348.452218)
			(xy 386.397296 -348.402608) (xy 386.426781 -348.356727) (xy 386.462495 -348.315509) (xy 386.503711 -348.279793)
			(xy 386.549591 -348.250305) (xy 386.599199 -348.227647) (xy 386.651528 -348.21228) (xy 386.705511 -348.204516)
			(xy 386.73278 -348.204028) (xy 387.59638 -348.204028) (xy 387.623651 -348.20451) (xy 387.677639 -348.21227)
			(xy 387.729973 -348.227634) (xy 387.779587 -348.25029) (xy 387.825472 -348.279776) (xy 387.866693 -348.315493)
			(xy 387.902412 -348.356712) (xy 387.931901 -348.402595) (xy 387.954559 -348.452209) (xy 387.969926 -348.504542)
			(xy 387.977688 -348.558529) (xy 387.977688 -348.613071) (xy 387.977688 -348.613074) (xy 389.460392 -348.613074)
			(xy 389.460392 -348.558526) (xy 389.468155 -348.504535) (xy 389.483524 -348.452197) (xy 389.506185 -348.40258)
			(xy 389.535677 -348.356694) (xy 389.5714 -348.315471) (xy 389.612626 -348.279753) (xy 389.658515 -348.250266)
			(xy 389.708135 -348.22761) (xy 389.760474 -348.212246) (xy 389.814466 -348.204489) (xy 389.84174 -348.204028)
			(xy 390.70534 -348.204028) (xy 390.732607 -348.204537) (xy 390.786585 -348.212303) (xy 390.838908 -348.227672)
			(xy 390.888512 -348.25033) (xy 390.934387 -348.279816) (xy 390.975598 -348.31553) (xy 391.011308 -348.356746)
			(xy 391.04079 -348.402623) (xy 391.063442 -348.45223) (xy 391.078805 -348.504554) (xy 391.086566 -348.558533)
			(xy 391.086566 -348.613067) (xy 391.086566 -348.61307) (xy 392.569414 -348.61307) (xy 392.569414 -348.55853)
			(xy 392.577176 -348.504545) (xy 392.592542 -348.452214) (xy 392.615199 -348.402603) (xy 392.644686 -348.35672)
			(xy 392.680402 -348.315502) (xy 392.72162 -348.279786) (xy 392.767503 -348.250299) (xy 392.817114 -348.227642)
			(xy 392.869445 -348.212276) (xy 392.92343 -348.204514) (xy 392.9507 -348.204028) (xy 393.8143 -348.204028)
			(xy 393.841569 -348.204534) (xy 393.895551 -348.212296) (xy 393.947879 -348.227661) (xy 393.997488 -348.250316)
			(xy 394.043368 -348.279802) (xy 394.084584 -348.315516) (xy 394.120298 -348.356732) (xy 394.149784 -348.402612)
			(xy 394.172439 -348.452221) (xy 394.187804 -348.504549) (xy 394.195566 -348.558531) (xy 394.195566 -348.613068)
			(xy 395.678414 -348.613068) (xy 395.678414 -348.558532) (xy 395.686175 -348.50455) (xy 395.701539 -348.452223)
			(xy 395.724193 -348.402614) (xy 395.753676 -348.356734) (xy 395.789388 -348.315516) (xy 395.830601 -348.2798)
			(xy 395.876479 -348.250312) (xy 395.926085 -348.227653) (xy 395.978411 -348.212284) (xy 396.032392 -348.204517)
			(xy 396.05966 -348.204028) (xy 396.92326 -348.204028) (xy 396.950532 -348.204509) (xy 397.004522 -348.212266)
			(xy 397.056858 -348.227628) (xy 397.106475 -348.250283) (xy 397.152362 -348.279769) (xy 397.193586 -348.315485)
			(xy 397.229307 -348.356706) (xy 397.258798 -348.40259) (xy 397.281458 -348.452204) (xy 397.296825 -348.504539)
			(xy 397.304588 -348.558528) (xy 397.304588 -348.613072) (xy 397.304588 -348.613073) (xy 398.787292 -348.613073)
			(xy 398.787292 -348.558527) (xy 398.795054 -348.504537) (xy 398.810422 -348.452202) (xy 398.833082 -348.402586)
			(xy 398.862572 -348.3567) (xy 398.898293 -348.315478) (xy 398.939516 -348.27976) (xy 398.985403 -348.250272)
			(xy 399.03502 -348.227615) (xy 399.087357 -348.21225) (xy 399.141347 -348.20449) (xy 399.16862 -348.204028)
			(xy 400.03222 -348.204028) (xy 400.059488 -348.204536) (xy 400.113468 -348.2123) (xy 400.165794 -348.227666)
			(xy 400.2154 -348.250323) (xy 400.261277 -348.279809) (xy 400.302491 -348.315523) (xy 400.338203 -348.356739)
			(xy 400.367687 -348.402618) (xy 400.390341 -348.452225) (xy 400.405705 -348.504552) (xy 400.413466 -348.558532)
			(xy 400.413466 -348.613068) (xy 400.413466 -348.613069) (xy 401.896314 -348.613069) (xy 401.896314 -348.558531)
			(xy 401.904076 -348.504548) (xy 401.91944 -348.452218) (xy 401.942096 -348.402608) (xy 401.971581 -348.356727)
			(xy 402.007295 -348.315509) (xy 402.048511 -348.279793) (xy 402.094391 -348.250305) (xy 402.143999 -348.227647)
			(xy 402.196328 -348.21228) (xy 402.250311 -348.204516) (xy 402.27758 -348.204028) (xy 403.14118 -348.204028)
			(xy 403.168451 -348.20451) (xy 403.222439 -348.21227) (xy 403.274773 -348.227634) (xy 403.324387 -348.25029)
			(xy 403.370272 -348.279776) (xy 403.411493 -348.315493) (xy 403.447212 -348.356712) (xy 403.476701 -348.402595)
			(xy 403.499359 -348.452209) (xy 403.514726 -348.504542) (xy 403.522488 -348.558529) (xy 403.522488 -348.61307)
			(xy 408.913814 -348.61307) (xy 408.913814 -348.55853) (xy 408.921576 -348.504546) (xy 408.936941 -348.452216)
			(xy 408.959598 -348.402605) (xy 408.989084 -348.356723) (xy 409.024799 -348.315505) (xy 409.066017 -348.279788)
			(xy 409.111898 -348.250301) (xy 409.161508 -348.227644) (xy 409.213838 -348.212278) (xy 409.267822 -348.204515)
			(xy 409.295092 -348.204028) (xy 410.158692 -348.204028) (xy 410.185963 -348.204511) (xy 410.239949 -348.212272)
			(xy 410.292281 -348.227637) (xy 410.341894 -348.250294) (xy 410.387778 -348.27978) (xy 410.428998 -348.315497)
			(xy 410.464715 -348.356716) (xy 410.494203 -348.402599) (xy 410.51686 -348.452211) (xy 410.532226 -348.504543)
			(xy 410.539989 -348.558529) (xy 410.539989 -348.613068) (xy 412.022814 -348.613068) (xy 412.022814 -348.558532)
			(xy 412.030575 -348.504551) (xy 412.045938 -348.452224) (xy 412.068592 -348.402616) (xy 412.098074 -348.356736)
			(xy 412.133785 -348.315519) (xy 412.174998 -348.279803) (xy 412.220874 -348.250315) (xy 412.270479 -348.227655)
			(xy 412.322804 -348.212285) (xy 412.376784 -348.204518) (xy 412.404052 -348.204028) (xy 413.267652 -348.204028)
			(xy 413.294925 -348.204508) (xy 413.348915 -348.212265) (xy 413.401252 -348.227626) (xy 413.45087 -348.250281)
			(xy 413.496759 -348.279766) (xy 413.537983 -348.315483) (xy 413.573705 -348.356703) (xy 413.603196 -348.402588)
			(xy 413.625857 -348.452203) (xy 413.641225 -348.504538) (xy 413.648988 -348.558528) (xy 413.648988 -348.613072)
			(xy 415.131692 -348.613072) (xy 415.131692 -348.558528) (xy 415.139454 -348.504538) (xy 415.154821 -348.452203)
			(xy 415.177481 -348.402588) (xy 415.20697 -348.356703) (xy 415.24269 -348.315481) (xy 415.283912 -348.279763)
			(xy 415.329799 -348.250275) (xy 415.379415 -348.227617) (xy 415.43175 -348.212252) (xy 415.48574 -348.204491)
			(xy 415.513012 -348.204028) (xy 416.376612 -348.204028) (xy 416.40388 -348.204535) (xy 416.457861 -348.212298)
			(xy 416.510188 -348.227664) (xy 416.559795 -348.25032) (xy 416.605673 -348.279806) (xy 416.646888 -348.31552)
			(xy 416.682601 -348.356736) (xy 416.712085 -348.402615) (xy 416.73474 -348.452224) (xy 416.750104 -348.504551)
			(xy 416.757866 -348.558532) (xy 416.757866 -348.613068) (xy 416.757866 -348.613069) (xy 418.240714 -348.613069)
			(xy 418.240714 -348.558531) (xy 418.248476 -348.504549) (xy 418.26384 -348.45222) (xy 418.286495 -348.40261)
			(xy 418.315979 -348.35673) (xy 418.351692 -348.315512) (xy 418.392907 -348.279795) (xy 418.438786 -348.250308)
			(xy 418.488394 -348.22765) (xy 418.540721 -348.212281) (xy 418.594703 -348.204516) (xy 418.621972 -348.204028)
			(xy 419.485572 -348.204028) (xy 419.512844 -348.20451) (xy 419.566832 -348.212268) (xy 419.619167 -348.227632)
			(xy 419.668782 -348.250287) (xy 419.714668 -348.279773) (xy 419.75589 -348.31549) (xy 419.79161 -348.356709)
			(xy 419.821099 -348.402593) (xy 419.843759 -348.452207) (xy 419.859126 -348.504541) (xy 419.866888 -348.558528)
			(xy 419.866888 -348.613072) (xy 419.866888 -348.613073) (xy 421.349592 -348.613073) (xy 421.349592 -348.558527)
			(xy 421.357355 -348.504536) (xy 421.372723 -348.452199) (xy 421.395384 -348.402583) (xy 421.424875 -348.356696)
			(xy 421.460597 -348.315474) (xy 421.501822 -348.279756) (xy 421.547711 -348.250268) (xy 421.597329 -348.227612)
			(xy 421.649667 -348.212248) (xy 421.703659 -348.204489) (xy 421.730932 -348.204028) (xy 422.594532 -348.204028)
			(xy 422.621799 -348.204537) (xy 422.675778 -348.212302) (xy 422.728102 -348.227669) (xy 422.777707 -348.250327)
			(xy 422.823583 -348.279813) (xy 422.864795 -348.315527) (xy 422.900506 -348.356743) (xy 422.929988 -348.402621)
			(xy 422.952642 -348.452228) (xy 422.968005 -348.504553) (xy 422.975766 -348.558533) (xy 422.975766 -348.613067)
			(xy 422.975766 -348.61307) (xy 424.458614 -348.61307) (xy 424.458614 -348.55853) (xy 424.466376 -348.504546)
			(xy 424.481741 -348.452216) (xy 424.504398 -348.402605) (xy 424.533884 -348.356723) (xy 424.569599 -348.315505)
			(xy 424.610817 -348.279788) (xy 424.656698 -348.250301) (xy 424.706308 -348.227644) (xy 424.758638 -348.212278)
			(xy 424.812622 -348.204515) (xy 424.839892 -348.204028) (xy 425.703492 -348.204028) (xy 425.730763 -348.204511)
			(xy 425.784749 -348.212272) (xy 425.837081 -348.227637) (xy 425.886694 -348.250294) (xy 425.932578 -348.27978)
			(xy 425.973798 -348.315497) (xy 426.009515 -348.356716) (xy 426.039003 -348.402599) (xy 426.06166 -348.452211)
			(xy 426.077026 -348.504543) (xy 426.084789 -348.558529) (xy 426.084789 -348.613068) (xy 427.567614 -348.613068)
			(xy 427.567614 -348.558532) (xy 427.575375 -348.504551) (xy 427.590738 -348.452224) (xy 427.613392 -348.402616)
			(xy 427.642874 -348.356736) (xy 427.678585 -348.315519) (xy 427.719798 -348.279803) (xy 427.765674 -348.250315)
			(xy 427.815279 -348.227655) (xy 427.867604 -348.212285) (xy 427.921584 -348.204518) (xy 427.948852 -348.204028)
			(xy 428.812452 -348.204028) (xy 428.839725 -348.204508) (xy 428.893715 -348.212265) (xy 428.946052 -348.227626)
			(xy 428.99567 -348.250281) (xy 429.041559 -348.279766) (xy 429.082783 -348.315483) (xy 429.118505 -348.356703)
			(xy 429.147996 -348.402588) (xy 429.170657 -348.452203) (xy 429.186025 -348.504538) (xy 429.193788 -348.558528)
			(xy 429.193788 -348.613072) (xy 430.676492 -348.613072) (xy 430.676492 -348.558528) (xy 430.684254 -348.504538)
			(xy 430.699621 -348.452203) (xy 430.722281 -348.402588) (xy 430.75177 -348.356703) (xy 430.78749 -348.315481)
			(xy 430.828712 -348.279763) (xy 430.874599 -348.250275) (xy 430.924215 -348.227617) (xy 430.97655 -348.212252)
			(xy 431.03054 -348.204491) (xy 431.057812 -348.204028) (xy 431.921412 -348.204028) (xy 431.94868 -348.204535)
			(xy 432.002661 -348.212298) (xy 432.054988 -348.227664) (xy 432.104595 -348.25032) (xy 432.150473 -348.279806)
			(xy 432.191688 -348.31552) (xy 432.227401 -348.356736) (xy 432.256885 -348.402615) (xy 432.27954 -348.452224)
			(xy 432.294904 -348.504551) (xy 432.302666 -348.558532) (xy 432.302666 -348.613068) (xy 432.302666 -348.613069)
			(xy 433.785514 -348.613069) (xy 433.785514 -348.558531) (xy 433.793276 -348.504549) (xy 433.80864 -348.45222)
			(xy 433.831295 -348.40261) (xy 433.860779 -348.35673) (xy 433.896492 -348.315512) (xy 433.937707 -348.279795)
			(xy 433.983586 -348.250308) (xy 434.033194 -348.22765) (xy 434.085521 -348.212281) (xy 434.139503 -348.204516)
			(xy 434.166772 -348.204028) (xy 435.030372 -348.204028) (xy 435.057644 -348.20451) (xy 435.111632 -348.212268)
			(xy 435.163967 -348.227632) (xy 435.213582 -348.250287) (xy 435.259468 -348.279773) (xy 435.30069 -348.31549)
			(xy 435.33641 -348.356709) (xy 435.365899 -348.402593) (xy 435.388559 -348.452207) (xy 435.403926 -348.504541)
			(xy 435.411688 -348.558528) (xy 435.411688 -348.613072) (xy 435.411688 -348.613073) (xy 436.894392 -348.613073)
			(xy 436.894392 -348.558527) (xy 436.902155 -348.504536) (xy 436.917523 -348.452199) (xy 436.940184 -348.402583)
			(xy 436.969675 -348.356696) (xy 437.005397 -348.315474) (xy 437.046622 -348.279756) (xy 437.092511 -348.250268)
			(xy 437.142129 -348.227612) (xy 437.194467 -348.212248) (xy 437.248459 -348.204489) (xy 437.275732 -348.204028)
			(xy 438.139332 -348.204028) (xy 438.166599 -348.204537) (xy 438.220578 -348.212302) (xy 438.272902 -348.227669)
			(xy 438.322507 -348.250327) (xy 438.368383 -348.279813) (xy 438.409595 -348.315527) (xy 438.445306 -348.356743)
			(xy 438.474788 -348.402621) (xy 438.497442 -348.452228) (xy 438.512805 -348.504553) (xy 438.520566 -348.558533)
			(xy 438.520566 -348.613067) (xy 438.520566 -348.61307) (xy 440.003414 -348.61307) (xy 440.003414 -348.55853)
			(xy 440.011176 -348.504546) (xy 440.026541 -348.452216) (xy 440.049198 -348.402605) (xy 440.078684 -348.356723)
			(xy 440.114399 -348.315505) (xy 440.155617 -348.279788) (xy 440.201498 -348.250301) (xy 440.251108 -348.227644)
			(xy 440.303438 -348.212278) (xy 440.357422 -348.204515) (xy 440.384692 -348.204028) (xy 441.248292 -348.204028)
			(xy 441.275563 -348.204511) (xy 441.329549 -348.212272) (xy 441.381881 -348.227637) (xy 441.431494 -348.250294)
			(xy 441.477378 -348.27978) (xy 441.518598 -348.315497) (xy 441.554315 -348.356716) (xy 441.583803 -348.402599)
			(xy 441.60646 -348.452211) (xy 441.621826 -348.504543) (xy 441.629589 -348.558529) (xy 441.629589 -348.613071)
			(xy 441.621826 -348.667057) (xy 441.60646 -348.719389) (xy 441.583803 -348.769001) (xy 441.554315 -348.814884)
			(xy 441.518598 -348.856103) (xy 441.477378 -348.89182) (xy 441.431494 -348.921306) (xy 441.381881 -348.943963)
			(xy 441.329549 -348.959328) (xy 441.275563 -348.967089) (xy 441.248292 -348.967552) (xy 440.384692 -348.967552)
			(xy 440.357422 -348.967085) (xy 440.303438 -348.959322) (xy 440.251108 -348.943956) (xy 440.201498 -348.921299)
			(xy 440.155617 -348.891812) (xy 440.114399 -348.856095) (xy 440.078684 -348.814877) (xy 440.049198 -348.768995)
			(xy 440.026541 -348.719384) (xy 440.011176 -348.667054) (xy 440.003414 -348.61307) (xy 438.520566 -348.61307)
			(xy 438.512805 -348.667047) (xy 438.497442 -348.719372) (xy 438.474788 -348.768979) (xy 438.445306 -348.814857)
			(xy 438.409595 -348.856073) (xy 438.368383 -348.891787) (xy 438.322507 -348.921273) (xy 438.272902 -348.943931)
			(xy 438.220578 -348.959298) (xy 438.166599 -348.967063) (xy 438.139332 -348.967552) (xy 437.275732 -348.967552)
			(xy 437.248459 -348.967111) (xy 437.194467 -348.959352) (xy 437.142129 -348.943988) (xy 437.092511 -348.921332)
			(xy 437.046622 -348.891844) (xy 437.005397 -348.856126) (xy 436.969675 -348.814904) (xy 436.940184 -348.769017)
			(xy 436.917523 -348.719401) (xy 436.902155 -348.667064) (xy 436.894392 -348.613073) (xy 435.411688 -348.613073)
			(xy 435.403926 -348.667059) (xy 435.388559 -348.719393) (xy 435.365899 -348.769007) (xy 435.33641 -348.814891)
			(xy 435.30069 -348.85611) (xy 435.259468 -348.891827) (xy 435.213582 -348.921313) (xy 435.163967 -348.943968)
			(xy 435.111632 -348.959332) (xy 435.057644 -348.96709) (xy 435.030372 -348.967552) (xy 434.166772 -348.967552)
			(xy 434.139503 -348.967084) (xy 434.085521 -348.959319) (xy 434.033194 -348.94395) (xy 433.983586 -348.921292)
			(xy 433.937707 -348.891805) (xy 433.896492 -348.856088) (xy 433.860779 -348.81487) (xy 433.831295 -348.76899)
			(xy 433.80864 -348.71938) (xy 433.793276 -348.667051) (xy 433.785514 -348.613069) (xy 432.302666 -348.613069)
			(xy 432.294904 -348.667049) (xy 432.27954 -348.719376) (xy 432.256885 -348.768985) (xy 432.227401 -348.814864)
			(xy 432.191688 -348.85608) (xy 432.150473 -348.891794) (xy 432.104595 -348.92128) (xy 432.054988 -348.943936)
			(xy 432.002661 -348.959302) (xy 431.94868 -348.967065) (xy 431.921412 -348.967552) (xy 431.057812 -348.967552)
			(xy 431.03054 -348.967109) (xy 430.97655 -348.959348) (xy 430.924215 -348.943983) (xy 430.874599 -348.921325)
			(xy 430.828712 -348.891837) (xy 430.78749 -348.856119) (xy 430.75177 -348.814897) (xy 430.722281 -348.769012)
			(xy 430.699621 -348.719397) (xy 430.684254 -348.667062) (xy 430.676492 -348.613072) (xy 429.193788 -348.613072)
			(xy 429.186025 -348.667062) (xy 429.170657 -348.719397) (xy 429.147996 -348.769012) (xy 429.118505 -348.814897)
			(xy 429.082783 -348.856117) (xy 429.041559 -348.891834) (xy 428.99567 -348.921319) (xy 428.946052 -348.943974)
			(xy 428.893715 -348.959335) (xy 428.839725 -348.967092) (xy 428.812452 -348.967552) (xy 427.948852 -348.967552)
			(xy 427.921584 -348.967082) (xy 427.867604 -348.959315) (xy 427.815279 -348.943945) (xy 427.765674 -348.921285)
			(xy 427.719798 -348.891797) (xy 427.678585 -348.856081) (xy 427.642874 -348.814864) (xy 427.613392 -348.768984)
			(xy 427.590738 -348.719376) (xy 427.575375 -348.667049) (xy 427.567614 -348.613068) (xy 426.084789 -348.613068)
			(xy 426.084789 -348.613071) (xy 426.077026 -348.667057) (xy 426.06166 -348.719389) (xy 426.039003 -348.769001)
			(xy 426.009515 -348.814884) (xy 425.973798 -348.856103) (xy 425.932578 -348.89182) (xy 425.886694 -348.921306)
			(xy 425.837081 -348.943963) (xy 425.784749 -348.959328) (xy 425.730763 -348.967089) (xy 425.703492 -348.967552)
			(xy 424.839892 -348.967552) (xy 424.812622 -348.967085) (xy 424.758638 -348.959322) (xy 424.706308 -348.943956)
			(xy 424.656698 -348.921299) (xy 424.610817 -348.891812) (xy 424.569599 -348.856095) (xy 424.533884 -348.814877)
			(xy 424.504398 -348.768995) (xy 424.481741 -348.719384) (xy 424.466376 -348.667054) (xy 424.458614 -348.61307)
			(xy 422.975766 -348.61307) (xy 422.968005 -348.667047) (xy 422.952642 -348.719372) (xy 422.929988 -348.768979)
			(xy 422.900506 -348.814857) (xy 422.864795 -348.856073) (xy 422.823583 -348.891787) (xy 422.777707 -348.921273)
			(xy 422.728102 -348.943931) (xy 422.675778 -348.959298) (xy 422.621799 -348.967063) (xy 422.594532 -348.967552)
			(xy 421.730932 -348.967552) (xy 421.703659 -348.967111) (xy 421.649667 -348.959352) (xy 421.597329 -348.943988)
			(xy 421.547711 -348.921332) (xy 421.501822 -348.891844) (xy 421.460597 -348.856126) (xy 421.424875 -348.814904)
			(xy 421.395384 -348.769017) (xy 421.372723 -348.719401) (xy 421.357355 -348.667064) (xy 421.349592 -348.613073)
			(xy 419.866888 -348.613073) (xy 419.859126 -348.667059) (xy 419.843759 -348.719393) (xy 419.821099 -348.769007)
			(xy 419.79161 -348.814891) (xy 419.75589 -348.85611) (xy 419.714668 -348.891827) (xy 419.668782 -348.921313)
			(xy 419.619167 -348.943968) (xy 419.566832 -348.959332) (xy 419.512844 -348.96709) (xy 419.485572 -348.967552)
			(xy 418.621972 -348.967552) (xy 418.594703 -348.967084) (xy 418.540721 -348.959319) (xy 418.488394 -348.94395)
			(xy 418.438786 -348.921292) (xy 418.392907 -348.891805) (xy 418.351692 -348.856088) (xy 418.315979 -348.81487)
			(xy 418.286495 -348.76899) (xy 418.26384 -348.71938) (xy 418.248476 -348.667051) (xy 418.240714 -348.613069)
			(xy 416.757866 -348.613069) (xy 416.750104 -348.667049) (xy 416.73474 -348.719376) (xy 416.712085 -348.768985)
			(xy 416.682601 -348.814864) (xy 416.646888 -348.85608) (xy 416.605673 -348.891794) (xy 416.559795 -348.92128)
			(xy 416.510188 -348.943936) (xy 416.457861 -348.959302) (xy 416.40388 -348.967065) (xy 416.376612 -348.967552)
			(xy 415.513012 -348.967552) (xy 415.48574 -348.967109) (xy 415.43175 -348.959348) (xy 415.379415 -348.943983)
			(xy 415.329799 -348.921325) (xy 415.283912 -348.891837) (xy 415.24269 -348.856119) (xy 415.20697 -348.814897)
			(xy 415.177481 -348.769012) (xy 415.154821 -348.719397) (xy 415.139454 -348.667062) (xy 415.131692 -348.613072)
			(xy 413.648988 -348.613072) (xy 413.641225 -348.667062) (xy 413.625857 -348.719397) (xy 413.603196 -348.769012)
			(xy 413.573705 -348.814897) (xy 413.537983 -348.856117) (xy 413.496759 -348.891834) (xy 413.45087 -348.921319)
			(xy 413.401252 -348.943974) (xy 413.348915 -348.959335) (xy 413.294925 -348.967092) (xy 413.267652 -348.967552)
			(xy 412.404052 -348.967552) (xy 412.376784 -348.967082) (xy 412.322804 -348.959315) (xy 412.270479 -348.943945)
			(xy 412.220874 -348.921285) (xy 412.174998 -348.891797) (xy 412.133785 -348.856081) (xy 412.098074 -348.814864)
			(xy 412.068592 -348.768984) (xy 412.045938 -348.719376) (xy 412.030575 -348.667049) (xy 412.022814 -348.613068)
			(xy 410.539989 -348.613068) (xy 410.539989 -348.613071) (xy 410.532226 -348.667057) (xy 410.51686 -348.719389)
			(xy 410.494203 -348.769001) (xy 410.464715 -348.814884) (xy 410.428998 -348.856103) (xy 410.387778 -348.89182)
			(xy 410.341894 -348.921306) (xy 410.292281 -348.943963) (xy 410.239949 -348.959328) (xy 410.185963 -348.967089)
			(xy 410.158692 -348.967552) (xy 409.295092 -348.967552) (xy 409.267822 -348.967085) (xy 409.213838 -348.959322)
			(xy 409.161508 -348.943956) (xy 409.111898 -348.921299) (xy 409.066017 -348.891812) (xy 409.024799 -348.856095)
			(xy 408.989084 -348.814877) (xy 408.959598 -348.768995) (xy 408.936941 -348.719384) (xy 408.921576 -348.667054)
			(xy 408.913814 -348.61307) (xy 403.522488 -348.61307) (xy 403.522488 -348.613071) (xy 403.514726 -348.667058)
			(xy 403.499359 -348.719391) (xy 403.476701 -348.769005) (xy 403.447212 -348.814888) (xy 403.411493 -348.856107)
			(xy 403.370272 -348.891824) (xy 403.324387 -348.92131) (xy 403.274773 -348.943966) (xy 403.222439 -348.95933)
			(xy 403.168451 -348.96709) (xy 403.14118 -348.967552) (xy 402.27758 -348.967552) (xy 402.250311 -348.967084)
			(xy 402.196328 -348.95932) (xy 402.143999 -348.943953) (xy 402.094391 -348.921295) (xy 402.048511 -348.891807)
			(xy 402.007295 -348.856091) (xy 401.971581 -348.814873) (xy 401.942096 -348.768992) (xy 401.91944 -348.719382)
			(xy 401.904076 -348.667052) (xy 401.896314 -348.613069) (xy 400.413466 -348.613069) (xy 400.405705 -348.667048)
			(xy 400.390341 -348.719375) (xy 400.367687 -348.768982) (xy 400.338203 -348.814861) (xy 400.302491 -348.856077)
			(xy 400.261277 -348.891791) (xy 400.2154 -348.921277) (xy 400.165794 -348.943934) (xy 400.113468 -348.9593)
			(xy 400.059488 -348.967064) (xy 400.03222 -348.967552) (xy 399.16862 -348.967552) (xy 399.141347 -348.96711)
			(xy 399.087357 -348.95935) (xy 399.03502 -348.943985) (xy 398.985403 -348.921328) (xy 398.939516 -348.89184)
			(xy 398.898293 -348.856122) (xy 398.862572 -348.8149) (xy 398.833082 -348.769014) (xy 398.810422 -348.719398)
			(xy 398.795054 -348.667063) (xy 398.787292 -348.613073) (xy 397.304588 -348.613073) (xy 397.296825 -348.667061)
			(xy 397.281458 -348.719396) (xy 397.258798 -348.76901) (xy 397.229307 -348.814894) (xy 397.193586 -348.856115)
			(xy 397.152362 -348.891831) (xy 397.106475 -348.921317) (xy 397.056858 -348.943972) (xy 397.004522 -348.959334)
			(xy 396.950532 -348.967091) (xy 396.92326 -348.967552) (xy 396.05966 -348.967552) (xy 396.032392 -348.967083)
			(xy 395.978411 -348.959316) (xy 395.926085 -348.943947) (xy 395.876479 -348.921288) (xy 395.830601 -348.8918)
			(xy 395.789388 -348.856084) (xy 395.753676 -348.814866) (xy 395.724193 -348.768986) (xy 395.701539 -348.719377)
			(xy 395.686175 -348.66705) (xy 395.678414 -348.613068) (xy 394.195566 -348.613068) (xy 394.195566 -348.613069)
			(xy 394.187804 -348.667051) (xy 394.172439 -348.719379) (xy 394.149784 -348.768988) (xy 394.120298 -348.814868)
			(xy 394.084584 -348.856084) (xy 394.043368 -348.891798) (xy 393.997488 -348.921284) (xy 393.947879 -348.943939)
			(xy 393.895551 -348.959304) (xy 393.841569 -348.967066) (xy 393.8143 -348.967552) (xy 392.9507 -348.967552)
			(xy 392.92343 -348.967086) (xy 392.869445 -348.959324) (xy 392.817114 -348.943958) (xy 392.767503 -348.921301)
			(xy 392.72162 -348.891814) (xy 392.680402 -348.856098) (xy 392.644686 -348.81488) (xy 392.615199 -348.768997)
			(xy 392.592542 -348.719386) (xy 392.577176 -348.667055) (xy 392.569414 -348.61307) (xy 391.086566 -348.61307)
			(xy 391.078805 -348.667046) (xy 391.063442 -348.71937) (xy 391.04079 -348.768977) (xy 391.011308 -348.814854)
			(xy 390.975598 -348.85607) (xy 390.934387 -348.891784) (xy 390.888512 -348.92127) (xy 390.838908 -348.943928)
			(xy 390.786585 -348.959297) (xy 390.732607 -348.967063) (xy 390.70534 -348.967552) (xy 389.84174 -348.967552)
			(xy 389.814466 -348.967111) (xy 389.760474 -348.959354) (xy 389.708135 -348.94399) (xy 389.658515 -348.921334)
			(xy 389.612626 -348.891847) (xy 389.5714 -348.856129) (xy 389.535677 -348.814906) (xy 389.506185 -348.76902)
			(xy 389.483524 -348.719403) (xy 389.468155 -348.667065) (xy 389.460392 -348.613074) (xy 387.977688 -348.613074)
			(xy 387.969926 -348.667058) (xy 387.954559 -348.719391) (xy 387.931901 -348.769005) (xy 387.902412 -348.814888)
			(xy 387.866693 -348.856107) (xy 387.825472 -348.891824) (xy 387.779587 -348.92131) (xy 387.729973 -348.943966)
			(xy 387.677639 -348.95933) (xy 387.623651 -348.96709) (xy 387.59638 -348.967552) (xy 386.73278 -348.967552)
			(xy 386.705511 -348.967084) (xy 386.651528 -348.95932) (xy 386.599199 -348.943953) (xy 386.549591 -348.921295)
			(xy 386.503711 -348.891807) (xy 386.462495 -348.856091) (xy 386.426781 -348.814873) (xy 386.397296 -348.768992)
			(xy 386.37464 -348.719382) (xy 386.359276 -348.667052) (xy 386.351514 -348.613069) (xy 384.868666 -348.613069)
			(xy 384.860905 -348.667048) (xy 384.845541 -348.719375) (xy 384.822887 -348.768982) (xy 384.793403 -348.814861)
			(xy 384.757691 -348.856077) (xy 384.716477 -348.891791) (xy 384.6706 -348.921277) (xy 384.620994 -348.943934)
			(xy 384.568668 -348.9593) (xy 384.514688 -348.967064) (xy 384.48742 -348.967552) (xy 383.62382 -348.967552)
			(xy 383.596547 -348.96711) (xy 383.542557 -348.95935) (xy 383.49022 -348.943985) (xy 383.440603 -348.921328)
			(xy 383.394716 -348.89184) (xy 383.353493 -348.856122) (xy 383.317772 -348.8149) (xy 383.288282 -348.769014)
			(xy 383.265622 -348.719398) (xy 383.250254 -348.667063) (xy 383.242492 -348.613073) (xy 381.759788 -348.613073)
			(xy 381.752025 -348.667061) (xy 381.736658 -348.719396) (xy 381.713998 -348.76901) (xy 381.684507 -348.814894)
			(xy 381.648786 -348.856115) (xy 381.607562 -348.891831) (xy 381.561675 -348.921317) (xy 381.512058 -348.943972)
			(xy 381.459722 -348.959334) (xy 381.405732 -348.967091) (xy 381.37846 -348.967552) (xy 380.51486 -348.967552)
			(xy 380.487592 -348.967083) (xy 380.433611 -348.959316) (xy 380.381285 -348.943947) (xy 380.331679 -348.921288)
			(xy 380.285801 -348.8918) (xy 380.244588 -348.856084) (xy 380.208876 -348.814866) (xy 380.179393 -348.768986)
			(xy 380.156739 -348.719377) (xy 380.141375 -348.66705) (xy 380.133614 -348.613068) (xy 378.650766 -348.613068)
			(xy 378.650766 -348.613069) (xy 378.643004 -348.667051) (xy 378.627639 -348.719379) (xy 378.604984 -348.768988)
			(xy 378.575498 -348.814868) (xy 378.539784 -348.856084) (xy 378.498568 -348.891798) (xy 378.452688 -348.921284)
			(xy 378.403079 -348.943939) (xy 378.350751 -348.959304) (xy 378.296769 -348.967066) (xy 378.2695 -348.967552)
			(xy 377.4059 -348.967552) (xy 377.37863 -348.967086) (xy 377.324645 -348.959324) (xy 377.272314 -348.943958)
			(xy 377.222703 -348.921301) (xy 377.17682 -348.891814) (xy 377.135602 -348.856098) (xy 377.099886 -348.81488)
			(xy 377.070399 -348.768997) (xy 377.047742 -348.719386) (xy 377.032376 -348.667055) (xy 377.024614 -348.61307)
			(xy 375.541766 -348.61307) (xy 375.534005 -348.667046) (xy 375.518642 -348.71937) (xy 375.49599 -348.768977)
			(xy 375.466508 -348.814854) (xy 375.430798 -348.85607) (xy 375.389587 -348.891784) (xy 375.343712 -348.92127)
			(xy 375.294108 -348.943928) (xy 375.241785 -348.959297) (xy 375.187807 -348.967063) (xy 375.16054 -348.967552)
			(xy 374.29694 -348.967552) (xy 374.269666 -348.967111) (xy 374.215674 -348.959354) (xy 374.163335 -348.94399)
			(xy 374.113715 -348.921334) (xy 374.067826 -348.891847) (xy 374.0266 -348.856129) (xy 373.990877 -348.814906)
			(xy 373.961385 -348.76902) (xy 373.938724 -348.719403) (xy 373.923355 -348.667065) (xy 373.915592 -348.613074)
			(xy 372.432888 -348.613074) (xy 372.425126 -348.667058) (xy 372.409759 -348.719391) (xy 372.387101 -348.769005)
			(xy 372.357612 -348.814888) (xy 372.321893 -348.856107) (xy 372.280672 -348.891824) (xy 372.234787 -348.92131)
			(xy 372.185173 -348.943966) (xy 372.132839 -348.95933) (xy 372.078851 -348.96709) (xy 372.05158 -348.967552)
			(xy 371.18798 -348.967552) (xy 371.160711 -348.967084) (xy 371.106728 -348.95932) (xy 371.054399 -348.943953)
			(xy 371.004791 -348.921295) (xy 370.958911 -348.891807) (xy 370.917695 -348.856091) (xy 370.881981 -348.814873)
			(xy 370.852496 -348.768992) (xy 370.82984 -348.719382) (xy 370.814476 -348.667052) (xy 370.806714 -348.613069)
			(xy 344.837266 -348.613069) (xy 344.829504 -348.66705) (xy 344.81414 -348.719378) (xy 344.791484 -348.768987)
			(xy 344.761999 -348.814866) (xy 344.726286 -348.856083) (xy 344.685069 -348.891797) (xy 344.63919 -348.921282)
			(xy 344.589582 -348.943938) (xy 344.537254 -348.959303) (xy 344.483272 -348.967065) (xy 344.456004 -348.967552)
			(xy 343.592404 -348.967552) (xy 343.565132 -348.967109) (xy 343.511143 -348.959347) (xy 343.458809 -348.943981)
			(xy 343.409194 -348.921323) (xy 343.363309 -348.891834) (xy 343.322087 -348.856116) (xy 343.286368 -348.814895)
			(xy 343.256879 -348.76901) (xy 343.234221 -348.719395) (xy 343.218854 -348.667061) (xy 343.211092 -348.613072)
			(xy 341.728265 -348.613072) (xy 341.720505 -348.667045) (xy 341.705143 -348.71937) (xy 341.68249 -348.768976)
			(xy 341.653009 -348.814853) (xy 341.6173 -348.856069) (xy 341.576088 -348.891783) (xy 341.530214 -348.921269)
			(xy 341.480611 -348.943927) (xy 341.428288 -348.959296) (xy 341.374311 -348.967063) (xy 341.347044 -348.967552)
			(xy 340.483444 -348.967552) (xy 340.45617 -348.967111) (xy 340.402177 -348.959354) (xy 340.349838 -348.943991)
			(xy 340.300218 -348.921336) (xy 340.254327 -348.891849) (xy 340.213101 -348.85613) (xy 340.177378 -348.814908)
			(xy 340.147885 -348.769021) (xy 340.125224 -348.719403) (xy 340.109855 -348.667066) (xy 340.102092 -348.613074)
			(xy 338.619388 -348.613074) (xy 338.611626 -348.667058) (xy 338.596259 -348.71939) (xy 338.573601 -348.769003)
			(xy 338.544113 -348.814887) (xy 338.508395 -348.856106) (xy 338.467174 -348.891823) (xy 338.421289 -348.921309)
			(xy 338.371675 -348.943965) (xy 338.319342 -348.95933) (xy 338.265355 -348.96709) (xy 338.238084 -348.967552)
			(xy 337.374484 -348.967552) (xy 337.347215 -348.967084) (xy 337.293231 -348.959321) (xy 337.240902 -348.943954)
			(xy 337.191293 -348.921296) (xy 337.145413 -348.891809) (xy 337.104196 -348.856093) (xy 337.068482 -348.814874)
			(xy 337.038996 -348.768993) (xy 337.016341 -348.719383) (xy 337.000976 -348.667053) (xy 336.993214 -348.613069)
			(xy 335.510366 -348.613069) (xy 335.502605 -348.667048) (xy 335.487241 -348.719374) (xy 335.464587 -348.768981)
			(xy 335.435104 -348.81486) (xy 335.399393 -348.856076) (xy 335.358179 -348.89179) (xy 335.312302 -348.921276)
			(xy 335.262696 -348.943933) (xy 335.210371 -348.9593) (xy 335.156392 -348.967064) (xy 335.129124 -348.967552)
			(xy 334.265524 -348.967552) (xy 334.238251 -348.96711) (xy 334.18426 -348.959351) (xy 334.131923 -348.943986)
			(xy 334.082306 -348.921329) (xy 334.036418 -348.891841) (xy 333.995194 -348.856123) (xy 333.959473 -348.814901)
			(xy 333.929982 -348.769015) (xy 333.907322 -348.719399) (xy 333.891955 -348.667063) (xy 333.884192 -348.613073)
			(xy 332.401488 -348.613073) (xy 332.393726 -348.667061) (xy 332.378358 -348.719395) (xy 332.355698 -348.769009)
			(xy 332.326208 -348.814893) (xy 332.290488 -348.856113) (xy 332.249264 -348.89183) (xy 332.203377 -348.921316)
			(xy 332.153761 -348.94397) (xy 332.101425 -348.959333) (xy 332.047436 -348.967091) (xy 332.020164 -348.967552)
			(xy 331.156564 -348.967552) (xy 331.129296 -348.967083) (xy 331.075314 -348.959317) (xy 331.022988 -348.943948)
			(xy 330.973381 -348.921289) (xy 330.927503 -348.891802) (xy 330.886289 -348.856086) (xy 330.850577 -348.814868)
			(xy 330.821093 -348.768987) (xy 330.798439 -348.719378) (xy 330.783075 -348.66705) (xy 330.775314 -348.613068)
			(xy 329.292466 -348.613068) (xy 329.284704 -348.66705) (xy 329.26934 -348.719378) (xy 329.246684 -348.768987)
			(xy 329.217199 -348.814866) (xy 329.181486 -348.856083) (xy 329.140269 -348.891797) (xy 329.09439 -348.921282)
			(xy 329.044782 -348.943938) (xy 328.992454 -348.959303) (xy 328.938472 -348.967065) (xy 328.911204 -348.967552)
			(xy 328.047604 -348.967552) (xy 328.020332 -348.967109) (xy 327.966343 -348.959347) (xy 327.914009 -348.943981)
			(xy 327.864394 -348.921323) (xy 327.818509 -348.891834) (xy 327.777287 -348.856116) (xy 327.741568 -348.814895)
			(xy 327.712079 -348.76901) (xy 327.689421 -348.719395) (xy 327.674054 -348.667061) (xy 327.666292 -348.613072)
			(xy 326.183465 -348.613072) (xy 326.175705 -348.667045) (xy 326.160343 -348.71937) (xy 326.13769 -348.768976)
			(xy 326.108209 -348.814853) (xy 326.0725 -348.856069) (xy 326.031288 -348.891783) (xy 325.985414 -348.921269)
			(xy 325.935811 -348.943927) (xy 325.883488 -348.959296) (xy 325.829511 -348.967063) (xy 325.802244 -348.967552)
			(xy 324.938644 -348.967552) (xy 324.91137 -348.967111) (xy 324.857377 -348.959354) (xy 324.805038 -348.943991)
			(xy 324.755418 -348.921336) (xy 324.709527 -348.891849) (xy 324.668301 -348.85613) (xy 324.632578 -348.814908)
			(xy 324.603085 -348.769021) (xy 324.580424 -348.719403) (xy 324.565055 -348.667066) (xy 324.557292 -348.613074)
			(xy 323.074588 -348.613074) (xy 323.066826 -348.667058) (xy 323.051459 -348.71939) (xy 323.028801 -348.769003)
			(xy 322.999313 -348.814887) (xy 322.963595 -348.856106) (xy 322.922374 -348.891823) (xy 322.876489 -348.921309)
			(xy 322.826875 -348.943965) (xy 322.774542 -348.95933) (xy 322.720555 -348.96709) (xy 322.693284 -348.967552)
			(xy 321.829684 -348.967552) (xy 321.802415 -348.967084) (xy 321.748431 -348.959321) (xy 321.696102 -348.943954)
			(xy 321.646493 -348.921296) (xy 321.600613 -348.891809) (xy 321.559396 -348.856093) (xy 321.523682 -348.814874)
			(xy 321.494196 -348.768993) (xy 321.471541 -348.719383) (xy 321.456176 -348.667053) (xy 321.448414 -348.613069)
			(xy 319.965566 -348.613069) (xy 319.957805 -348.667048) (xy 319.942441 -348.719374) (xy 319.919787 -348.768981)
			(xy 319.890304 -348.81486) (xy 319.854593 -348.856076) (xy 319.813379 -348.89179) (xy 319.767502 -348.921276)
			(xy 319.717896 -348.943933) (xy 319.665571 -348.9593) (xy 319.611592 -348.967064) (xy 319.584324 -348.967552)
			(xy 318.720724 -348.967552) (xy 318.693451 -348.96711) (xy 318.63946 -348.959351) (xy 318.587123 -348.943986)
			(xy 318.537506 -348.921329) (xy 318.491618 -348.891841) (xy 318.450394 -348.856123) (xy 318.414673 -348.814901)
			(xy 318.385182 -348.769015) (xy 318.362522 -348.719399) (xy 318.347155 -348.667063) (xy 318.339392 -348.613073)
			(xy 316.856688 -348.613073) (xy 316.848926 -348.667061) (xy 316.833558 -348.719395) (xy 316.810898 -348.769009)
			(xy 316.781408 -348.814893) (xy 316.745688 -348.856113) (xy 316.704464 -348.89183) (xy 316.658577 -348.921316)
			(xy 316.608961 -348.94397) (xy 316.556625 -348.959333) (xy 316.502636 -348.967091) (xy 316.475364 -348.967552)
			(xy 315.611764 -348.967552) (xy 315.584496 -348.967083) (xy 315.530514 -348.959317) (xy 315.478188 -348.943948)
			(xy 315.428581 -348.921289) (xy 315.382703 -348.891802) (xy 315.341489 -348.856086) (xy 315.305777 -348.814868)
			(xy 315.276293 -348.768987) (xy 315.253639 -348.719378) (xy 315.238275 -348.66705) (xy 315.230514 -348.613068)
			(xy 313.747666 -348.613068) (xy 313.739904 -348.66705) (xy 313.72454 -348.719378) (xy 313.701884 -348.768987)
			(xy 313.672399 -348.814866) (xy 313.636686 -348.856083) (xy 313.595469 -348.891797) (xy 313.54959 -348.921282)
			(xy 313.499982 -348.943938) (xy 313.447654 -348.959303) (xy 313.393672 -348.967065) (xy 313.366404 -348.967552)
			(xy 312.502804 -348.967552) (xy 312.475532 -348.967109) (xy 312.421543 -348.959347) (xy 312.369209 -348.943981)
			(xy 312.319594 -348.921323) (xy 312.273709 -348.891834) (xy 312.232487 -348.856116) (xy 312.196768 -348.814895)
			(xy 312.167279 -348.76901) (xy 312.144621 -348.719395) (xy 312.129254 -348.667061) (xy 312.121492 -348.613072)
			(xy 300.231566 -348.613072) (xy 300.223804 -348.667051) (xy 300.208439 -348.719379) (xy 300.185784 -348.768987)
			(xy 300.156299 -348.814867) (xy 300.120585 -348.856083) (xy 300.079369 -348.891798) (xy 300.033489 -348.921283)
			(xy 299.98388 -348.943939) (xy 299.931553 -348.959304) (xy 299.877571 -348.967065) (xy 299.850302 -348.967552)
			(xy 298.986702 -348.967552) (xy 298.95943 -348.967109) (xy 298.905442 -348.959347) (xy 298.853107 -348.94398)
			(xy 298.803493 -348.921322) (xy 298.757608 -348.891834) (xy 298.716386 -348.856115) (xy 298.680668 -348.814894)
			(xy 298.651179 -348.769009) (xy 298.628521 -348.719394) (xy 298.613154 -348.66706) (xy 298.605392 -348.613072)
			(xy 297.122565 -348.613072) (xy 297.114805 -348.667045) (xy 297.099443 -348.71937) (xy 297.07679 -348.768976)
			(xy 297.047309 -348.814854) (xy 297.011599 -348.856069) (xy 296.970387 -348.891784) (xy 296.924513 -348.92127)
			(xy 296.874909 -348.943928) (xy 296.822586 -348.959296) (xy 296.768609 -348.967063) (xy 296.741342 -348.967552)
			(xy 295.877742 -348.967552) (xy 295.850468 -348.967111) (xy 295.796476 -348.959354) (xy 295.744136 -348.943991)
			(xy 295.694517 -348.921335) (xy 295.648627 -348.891848) (xy 295.6074 -348.856129) (xy 295.571677 -348.814907)
			(xy 295.542185 -348.76902) (xy 295.519524 -348.719403) (xy 295.504155 -348.667066) (xy 295.496392 -348.613074)
			(xy 294.013688 -348.613074) (xy 294.005926 -348.667058) (xy 293.990559 -348.719391) (xy 293.967901 -348.769004)
			(xy 293.938412 -348.814887) (xy 293.902694 -348.856107) (xy 293.861473 -348.891823) (xy 293.815588 -348.92131)
			(xy 293.765974 -348.943966) (xy 293.713641 -348.95933) (xy 293.659653 -348.96709) (xy 293.632382 -348.967552)
			(xy 292.768782 -348.967552) (xy 292.741513 -348.967084) (xy 292.68753 -348.95932) (xy 292.635201 -348.943953)
			(xy 292.585592 -348.921295) (xy 292.539712 -348.891808) (xy 292.498495 -348.856092) (xy 292.462781 -348.814874)
			(xy 292.433296 -348.768992) (xy 292.410641 -348.719382) (xy 292.395276 -348.667053) (xy 292.387514 -348.613069)
			(xy 290.904666 -348.613069) (xy 290.896905 -348.667048) (xy 290.881541 -348.719374) (xy 290.858887 -348.768982)
			(xy 290.829404 -348.81486) (xy 290.793692 -348.856076) (xy 290.752478 -348.891791) (xy 290.706601 -348.921276)
			(xy 290.656995 -348.943933) (xy 290.604669 -348.9593) (xy 290.55069 -348.967064) (xy 290.523422 -348.967552)
			(xy 289.659822 -348.967552) (xy 289.632549 -348.96711) (xy 289.578559 -348.95935) (xy 289.526222 -348.943985)
			(xy 289.476605 -348.921329) (xy 289.430717 -348.891841) (xy 289.389493 -348.856122) (xy 289.353772 -348.814901)
			(xy 289.324282 -348.769015) (xy 289.301622 -348.719399) (xy 289.286254 -348.667063) (xy 289.278492 -348.613073)
			(xy 287.795788 -348.613073) (xy 287.788026 -348.667061) (xy 287.772658 -348.719395) (xy 287.749998 -348.76901)
			(xy 287.720508 -348.814894) (xy 287.684787 -348.856114) (xy 287.643563 -348.89183) (xy 287.597676 -348.921316)
			(xy 287.54806 -348.943971) (xy 287.495724 -348.959334) (xy 287.441734 -348.967091) (xy 287.414462 -348.967552)
			(xy 286.550862 -348.967552) (xy 286.523594 -348.967083) (xy 286.469613 -348.959317) (xy 286.417286 -348.943948)
			(xy 286.36768 -348.921289) (xy 286.321802 -348.891801) (xy 286.280588 -348.856085) (xy 286.244876 -348.814867)
			(xy 286.215393 -348.768987) (xy 286.192739 -348.719378) (xy 286.177375 -348.66705) (xy 286.169614 -348.613068)
			(xy 284.686766 -348.613068) (xy 284.686766 -348.613069) (xy 284.679004 -348.667051) (xy 284.663639 -348.719379)
			(xy 284.640984 -348.768987) (xy 284.611499 -348.814867) (xy 284.575785 -348.856083) (xy 284.534569 -348.891798)
			(xy 284.488689 -348.921283) (xy 284.43908 -348.943939) (xy 284.386753 -348.959304) (xy 284.332771 -348.967065)
			(xy 284.305502 -348.967552) (xy 283.441902 -348.967552) (xy 283.41463 -348.967109) (xy 283.360642 -348.959347)
			(xy 283.308307 -348.94398) (xy 283.258693 -348.921322) (xy 283.212808 -348.891834) (xy 283.171586 -348.856115)
			(xy 283.135868 -348.814894) (xy 283.106379 -348.769009) (xy 283.083721 -348.719394) (xy 283.068354 -348.66706)
			(xy 283.060592 -348.613072) (xy 281.577765 -348.613072) (xy 281.570005 -348.667045) (xy 281.554643 -348.71937)
			(xy 281.53199 -348.768976) (xy 281.502509 -348.814854) (xy 281.466799 -348.856069) (xy 281.425587 -348.891784)
			(xy 281.379713 -348.92127) (xy 281.330109 -348.943928) (xy 281.277786 -348.959296) (xy 281.223809 -348.967063)
			(xy 281.196542 -348.967552) (xy 280.332942 -348.967552) (xy 280.305668 -348.967111) (xy 280.251676 -348.959354)
			(xy 280.199336 -348.943991) (xy 280.149717 -348.921335) (xy 280.103827 -348.891848) (xy 280.0626 -348.856129)
			(xy 280.026877 -348.814907) (xy 279.997385 -348.76902) (xy 279.974724 -348.719403) (xy 279.959355 -348.667066)
			(xy 279.951592 -348.613074) (xy 278.468888 -348.613074) (xy 278.461126 -348.667058) (xy 278.445759 -348.719391)
			(xy 278.423101 -348.769004) (xy 278.393612 -348.814887) (xy 278.357894 -348.856107) (xy 278.316673 -348.891823)
			(xy 278.270788 -348.92131) (xy 278.221174 -348.943966) (xy 278.168841 -348.95933) (xy 278.114853 -348.96709)
			(xy 278.087582 -348.967552) (xy 277.223982 -348.967552) (xy 277.196713 -348.967084) (xy 277.14273 -348.95932)
			(xy 277.090401 -348.943953) (xy 277.040792 -348.921295) (xy 276.994912 -348.891808) (xy 276.953695 -348.856092)
			(xy 276.917981 -348.814874) (xy 276.888496 -348.768992) (xy 276.865841 -348.719382) (xy 276.850476 -348.667053)
			(xy 276.842714 -348.613069) (xy 275.359866 -348.613069) (xy 275.352105 -348.667048) (xy 275.336741 -348.719374)
			(xy 275.314087 -348.768982) (xy 275.284604 -348.81486) (xy 275.248892 -348.856076) (xy 275.207678 -348.891791)
			(xy 275.161801 -348.921276) (xy 275.112195 -348.943933) (xy 275.059869 -348.9593) (xy 275.00589 -348.967064)
			(xy 274.978622 -348.967552) (xy 274.115022 -348.967552) (xy 274.087749 -348.96711) (xy 274.033759 -348.95935)
			(xy 273.981422 -348.943985) (xy 273.931805 -348.921329) (xy 273.885917 -348.891841) (xy 273.844693 -348.856122)
			(xy 273.808972 -348.814901) (xy 273.779482 -348.769015) (xy 273.756822 -348.719399) (xy 273.741454 -348.667063)
			(xy 273.733692 -348.613073) (xy 272.250988 -348.613073) (xy 272.243226 -348.667061) (xy 272.227858 -348.719395)
			(xy 272.205198 -348.76901) (xy 272.175708 -348.814894) (xy 272.139987 -348.856114) (xy 272.098763 -348.89183)
			(xy 272.052876 -348.921316) (xy 272.00326 -348.943971) (xy 271.950924 -348.959334) (xy 271.896934 -348.967091)
			(xy 271.869662 -348.967552) (xy 271.006062 -348.967552) (xy 270.978794 -348.967083) (xy 270.924813 -348.959317)
			(xy 270.872486 -348.943948) (xy 270.82288 -348.921289) (xy 270.777002 -348.891801) (xy 270.735788 -348.856085)
			(xy 270.700076 -348.814867) (xy 270.670593 -348.768987) (xy 270.647939 -348.719378) (xy 270.632575 -348.66705)
			(xy 270.624814 -348.613068) (xy 269.141966 -348.613068) (xy 269.141966 -348.613069) (xy 269.134204 -348.667051)
			(xy 269.118839 -348.719379) (xy 269.096184 -348.768987) (xy 269.066699 -348.814867) (xy 269.030985 -348.856083)
			(xy 268.989769 -348.891798) (xy 268.943889 -348.921283) (xy 268.89428 -348.943939) (xy 268.841953 -348.959304)
			(xy 268.787971 -348.967065) (xy 268.760702 -348.967552) (xy 267.897102 -348.967552) (xy 267.86983 -348.967109)
			(xy 267.815842 -348.959347) (xy 267.763507 -348.94398) (xy 267.713893 -348.921322) (xy 267.668008 -348.891834)
			(xy 267.626786 -348.856115) (xy 267.591068 -348.814894) (xy 267.561579 -348.769009) (xy 267.538921 -348.719394)
			(xy 267.523554 -348.66706) (xy 267.515792 -348.613072) (xy 219.835872 -348.613072) (xy 219.790278 -348.758746)
			(xy 219.727639 -348.932143) (xy 219.657547 -349.102664) (xy 219.580134 -349.269989) (xy 219.495546 -349.433803)
			(xy 219.403941 -349.593799) (xy 219.305491 -349.749677) (xy 219.200381 -349.901144) (xy 219.088808 -350.047915)
			(xy 218.970982 -350.189716) (xy 218.847124 -350.326279) (xy 218.717467 -350.457348) (xy 218.582254 -350.582678)
			(xy 218.441738 -350.702034) (xy 218.296184 -350.81519) (xy 218.145865 -350.921934) (xy 217.991063 -351.022067)
			(xy 217.832068 -351.1154) (xy 217.66918 -351.201758) (xy 217.502703 -351.280979) (xy 217.332952 -351.352913)
			(xy 217.160243 -351.417427) (xy 216.984902 -351.474399) (xy 216.807258 -351.523722) (xy 216.627643 -351.565303)
			(xy 216.446396 -351.599064) (xy 216.263857 -351.624943) (xy 216.123526 -351.638668) (xy 267.515839 -351.638668)
			(xy 267.515839 -351.584132) (xy 267.523601 -351.53015) (xy 267.538966 -351.477822) (xy 267.561621 -351.428214)
			(xy 267.591106 -351.382335) (xy 267.62682 -351.341119) (xy 267.668036 -351.305405) (xy 267.713916 -351.27592)
			(xy 267.763524 -351.253265) (xy 267.815852 -351.2379) (xy 267.869834 -351.230139) (xy 267.897102 -351.229676)
			(xy 268.760702 -351.229676) (xy 268.787974 -351.230087) (xy 268.841963 -351.237849) (xy 268.894297 -351.253216)
			(xy 268.943912 -351.275875) (xy 268.989797 -351.305364) (xy 269.031019 -351.341083) (xy 269.066737 -351.382304)
			(xy 269.096226 -351.42819) (xy 269.118884 -351.477805) (xy 269.134251 -351.530139) (xy 269.142013 -351.584128)
			(xy 269.142013 -351.638665) (xy 270.624862 -351.638665) (xy 270.624862 -351.584135) (xy 270.632622 -351.53016)
			(xy 270.647984 -351.477839) (xy 270.670635 -351.428236) (xy 270.700115 -351.382362) (xy 270.735822 -351.341149)
			(xy 270.777031 -351.305437) (xy 270.822903 -351.275953) (xy 270.872503 -351.253297) (xy 270.924823 -351.23793)
			(xy 270.978797 -351.230165) (xy 271.006062 -351.229676) (xy 271.869662 -351.229676) (xy 271.896937 -351.230061)
			(xy 271.950934 -351.23782) (xy 272.003276 -351.253184) (xy 272.052899 -351.275842) (xy 272.098792 -351.305331)
			(xy 272.140021 -351.341052) (xy 272.175746 -351.382277) (xy 272.20524 -351.428167) (xy 272.227903 -351.477788)
			(xy 272.243272 -351.530129) (xy 272.251036 -351.584125) (xy 272.251036 -351.638669) (xy 273.733739 -351.638669)
			(xy 273.733739 -351.584131) (xy 273.741501 -351.530147) (xy 273.756867 -351.477818) (xy 273.779524 -351.428208)
			(xy 273.809011 -351.382328) (xy 273.844727 -351.341112) (xy 273.885946 -351.305398) (xy 273.931828 -351.275914)
			(xy 273.981439 -351.25326) (xy 274.033769 -351.237897) (xy 274.087753 -351.230138) (xy 274.115022 -351.229676)
			(xy 274.978622 -351.229676) (xy 275.005893 -351.230088) (xy 275.05988 -351.237853) (xy 275.112212 -351.253222)
			(xy 275.161824 -351.275881) (xy 275.207707 -351.305371) (xy 275.248926 -351.34109) (xy 275.284642 -351.382311)
			(xy 275.314129 -351.428195) (xy 275.336786 -351.477809) (xy 275.352152 -351.530142) (xy 275.359914 -351.584129)
			(xy 275.359914 -351.638666) (xy 276.842762 -351.638666) (xy 276.842762 -351.584134) (xy 276.850523 -351.530158)
			(xy 276.865886 -351.477835) (xy 276.888538 -351.428231) (xy 276.91802 -351.382355) (xy 276.953729 -351.341142)
			(xy 276.994941 -351.30543) (xy 277.040815 -351.275947) (xy 277.090418 -351.253292) (xy 277.14274 -351.237927)
			(xy 277.196716 -351.230164) (xy 277.223982 -351.229676) (xy 278.087582 -351.229676) (xy 278.114857 -351.230062)
			(xy 278.168851 -351.237823) (xy 278.221191 -351.253189) (xy 278.270811 -351.275848) (xy 278.316702 -351.305338)
			(xy 278.357928 -351.341059) (xy 278.393651 -351.382284) (xy 278.423143 -351.428173) (xy 278.445804 -351.477792)
			(xy 278.461173 -351.530132) (xy 278.468936 -351.584125) (xy 278.468936 -351.63867) (xy 279.95164 -351.63867)
			(xy 279.95164 -351.58413) (xy 279.959402 -351.530145) (xy 279.974769 -351.477814) (xy 279.997427 -351.428203)
			(xy 280.026916 -351.382322) (xy 280.062634 -351.341105) (xy 280.103855 -351.305391) (xy 280.14974 -351.275907)
			(xy 280.199353 -351.253254) (xy 280.251686 -351.237893) (xy 280.305672 -351.230137) (xy 280.332942 -351.229676)
			(xy 281.196542 -351.229676) (xy 281.223812 -351.230089) (xy 281.277797 -351.237857) (xy 281.330126 -351.253227)
			(xy 281.379736 -351.275888) (xy 281.425616 -351.305378) (xy 281.466833 -351.341097) (xy 281.502547 -351.382317)
			(xy 281.532032 -351.428201) (xy 281.554688 -351.477813) (xy 281.570052 -351.530145) (xy 281.577814 -351.58413)
			(xy 281.577814 -351.638668) (xy 283.060639 -351.638668) (xy 283.060639 -351.584132) (xy 283.068401 -351.53015)
			(xy 283.083766 -351.477822) (xy 283.106421 -351.428214) (xy 283.135906 -351.382335) (xy 283.17162 -351.341119)
			(xy 283.212836 -351.305405) (xy 283.258716 -351.27592) (xy 283.308324 -351.253265) (xy 283.360652 -351.2379)
			(xy 283.414634 -351.230139) (xy 283.441902 -351.229676) (xy 284.305502 -351.229676) (xy 284.332774 -351.230087)
			(xy 284.386763 -351.237849) (xy 284.439097 -351.253216) (xy 284.488712 -351.275875) (xy 284.534597 -351.305364)
			(xy 284.575819 -351.341083) (xy 284.611537 -351.382304) (xy 284.641026 -351.42819) (xy 284.663684 -351.477805)
			(xy 284.679051 -351.530139) (xy 284.686813 -351.584128) (xy 284.686813 -351.638665) (xy 286.169662 -351.638665)
			(xy 286.169662 -351.584135) (xy 286.177422 -351.53016) (xy 286.192784 -351.477839) (xy 286.215435 -351.428236)
			(xy 286.244915 -351.382362) (xy 286.280622 -351.341149) (xy 286.321831 -351.305437) (xy 286.367703 -351.275953)
			(xy 286.417303 -351.253297) (xy 286.469623 -351.23793) (xy 286.523597 -351.230165) (xy 286.550862 -351.229676)
			(xy 287.414462 -351.229676) (xy 287.441737 -351.230061) (xy 287.495734 -351.23782) (xy 287.548076 -351.253184)
			(xy 287.597699 -351.275842) (xy 287.643592 -351.305331) (xy 287.684821 -351.341052) (xy 287.720546 -351.382277)
			(xy 287.75004 -351.428167) (xy 287.772703 -351.477788) (xy 287.788072 -351.530129) (xy 287.795836 -351.584125)
			(xy 287.795836 -351.638669) (xy 289.278539 -351.638669) (xy 289.278539 -351.584131) (xy 289.286301 -351.530147)
			(xy 289.301667 -351.477818) (xy 289.324324 -351.428208) (xy 289.353811 -351.382328) (xy 289.389527 -351.341112)
			(xy 289.430746 -351.305398) (xy 289.476628 -351.275914) (xy 289.526239 -351.25326) (xy 289.578569 -351.237897)
			(xy 289.632553 -351.230138) (xy 289.659822 -351.229676) (xy 290.523422 -351.229676) (xy 290.550693 -351.230088)
			(xy 290.60468 -351.237853) (xy 290.657012 -351.253222) (xy 290.706624 -351.275881) (xy 290.752507 -351.305371)
			(xy 290.793726 -351.34109) (xy 290.829442 -351.382311) (xy 290.858929 -351.428195) (xy 290.881586 -351.477809)
			(xy 290.896952 -351.530142) (xy 290.904714 -351.584129) (xy 290.904714 -351.638666) (xy 292.387562 -351.638666)
			(xy 292.387562 -351.584134) (xy 292.395323 -351.530158) (xy 292.410686 -351.477835) (xy 292.433338 -351.428231)
			(xy 292.46282 -351.382355) (xy 292.498529 -351.341142) (xy 292.539741 -351.30543) (xy 292.585615 -351.275947)
			(xy 292.635218 -351.253292) (xy 292.68754 -351.237927) (xy 292.741516 -351.230164) (xy 292.768782 -351.229676)
			(xy 293.632382 -351.229676) (xy 293.659657 -351.230062) (xy 293.713651 -351.237823) (xy 293.765991 -351.253189)
			(xy 293.815611 -351.275848) (xy 293.861502 -351.305338) (xy 293.902728 -351.341059) (xy 293.938451 -351.382284)
			(xy 293.967943 -351.428173) (xy 293.990604 -351.477792) (xy 294.005973 -351.530132) (xy 294.013736 -351.584125)
			(xy 294.013736 -351.63867) (xy 295.49644 -351.63867) (xy 295.49644 -351.58413) (xy 295.504202 -351.530145)
			(xy 295.519569 -351.477814) (xy 295.542227 -351.428203) (xy 295.571716 -351.382322) (xy 295.607434 -351.341105)
			(xy 295.648655 -351.305391) (xy 295.69454 -351.275907) (xy 295.744153 -351.253254) (xy 295.796486 -351.237893)
			(xy 295.850472 -351.230137) (xy 295.877742 -351.229676) (xy 296.741342 -351.229676) (xy 296.768612 -351.230089)
			(xy 296.822597 -351.237857) (xy 296.874926 -351.253227) (xy 296.924536 -351.275888) (xy 296.970416 -351.305378)
			(xy 297.011633 -351.341097) (xy 297.047347 -351.382317) (xy 297.076832 -351.428201) (xy 297.099488 -351.477813)
			(xy 297.114852 -351.530145) (xy 297.122614 -351.58413) (xy 297.122614 -351.638668) (xy 298.605439 -351.638668)
			(xy 298.605439 -351.584132) (xy 298.613201 -351.53015) (xy 298.628566 -351.477822) (xy 298.651221 -351.428214)
			(xy 298.680706 -351.382335) (xy 298.71642 -351.341119) (xy 298.757636 -351.305405) (xy 298.803516 -351.27592)
			(xy 298.853124 -351.253265) (xy 298.905452 -351.2379) (xy 298.959434 -351.230139) (xy 298.986702 -351.229676)
			(xy 299.850302 -351.229676) (xy 299.877574 -351.230087) (xy 299.931563 -351.237849) (xy 299.983897 -351.253216)
			(xy 300.033512 -351.275875) (xy 300.079397 -351.305364) (xy 300.120619 -351.341083) (xy 300.156337 -351.382304)
			(xy 300.185826 -351.42819) (xy 300.208484 -351.477805) (xy 300.223851 -351.530139) (xy 300.231613 -351.584128)
			(xy 300.231613 -351.638668) (xy 312.121539 -351.638668) (xy 312.121539 -351.584132) (xy 312.129301 -351.53015)
			(xy 312.144666 -351.477822) (xy 312.167321 -351.428213) (xy 312.196807 -351.382334) (xy 312.232521 -351.341118)
			(xy 312.273737 -351.305404) (xy 312.319617 -351.27592) (xy 312.369226 -351.253264) (xy 312.421554 -351.2379)
			(xy 312.475536 -351.230139) (xy 312.502804 -351.229676) (xy 313.366404 -351.229676) (xy 313.393676 -351.230087)
			(xy 313.447664 -351.23785) (xy 313.499999 -351.253217) (xy 313.549613 -351.275876) (xy 313.595498 -351.305365)
			(xy 313.63672 -351.341083) (xy 313.672438 -351.382305) (xy 313.701926 -351.42819) (xy 313.724584 -351.477805)
			(xy 313.739951 -351.530139) (xy 313.747713 -351.584128) (xy 313.747713 -351.638665) (xy 315.230562 -351.638665)
			(xy 315.230562 -351.584135) (xy 315.238322 -351.53016) (xy 315.253684 -351.477838) (xy 315.276335 -351.428236)
			(xy 315.305815 -351.382361) (xy 315.341523 -351.341148) (xy 315.382732 -351.305437) (xy 315.428604 -351.275953)
			(xy 315.478205 -351.253297) (xy 315.530525 -351.23793) (xy 315.584499 -351.230165) (xy 315.611764 -351.229676)
			(xy 316.475364 -351.229676) (xy 316.502639 -351.230061) (xy 316.556636 -351.23782) (xy 316.608978 -351.253185)
			(xy 316.6586 -351.275842) (xy 316.704493 -351.305332) (xy 316.745722 -351.341053) (xy 316.781446 -351.382278)
			(xy 316.81094 -351.428168) (xy 316.833603 -351.477788) (xy 316.848972 -351.530129) (xy 316.856736 -351.584125)
			(xy 316.856736 -351.638669) (xy 318.339439 -351.638669) (xy 318.339439 -351.584131) (xy 318.347201 -351.530147)
			(xy 318.362567 -351.477818) (xy 318.385224 -351.428208) (xy 318.414711 -351.382328) (xy 318.450428 -351.341111)
			(xy 318.491647 -351.305397) (xy 318.537529 -351.275913) (xy 318.58714 -351.253259) (xy 318.63947 -351.237896)
			(xy 318.693455 -351.230138) (xy 318.720724 -351.229676) (xy 319.584324 -351.229676) (xy 319.611595 -351.230088)
			(xy 319.665581 -351.237853) (xy 319.717913 -351.253222) (xy 319.767525 -351.275882) (xy 319.813408 -351.305372)
			(xy 319.854627 -351.34109) (xy 319.890343 -351.382312) (xy 319.919829 -351.428196) (xy 319.942486 -351.477809)
			(xy 319.957852 -351.530142) (xy 319.965614 -351.584129) (xy 319.965614 -351.638666) (xy 321.448462 -351.638666)
			(xy 321.448462 -351.584134) (xy 321.456223 -351.530157) (xy 321.471586 -351.477834) (xy 321.494239 -351.42823)
			(xy 321.52372 -351.382354) (xy 321.55943 -351.341141) (xy 321.600642 -351.30543) (xy 321.646516 -351.275946)
			(xy 321.696119 -351.253291) (xy 321.748442 -351.237926) (xy 321.802418 -351.230163) (xy 321.829684 -351.229676)
			(xy 322.693284 -351.229676) (xy 322.720558 -351.230062) (xy 322.774552 -351.237824) (xy 322.826892 -351.25319)
			(xy 322.876512 -351.275849) (xy 322.922403 -351.305339) (xy 322.963629 -351.34106) (xy 322.999351 -351.382285)
			(xy 323.028843 -351.428174) (xy 323.051504 -351.477793) (xy 323.066873 -351.530132) (xy 323.074636 -351.584126)
			(xy 323.074636 -351.63867) (xy 324.55734 -351.63867) (xy 324.55734 -351.58413) (xy 324.565102 -351.530144)
			(xy 324.580469 -351.477813) (xy 324.603128 -351.428202) (xy 324.632616 -351.382321) (xy 324.668335 -351.341104)
			(xy 324.709556 -351.30539) (xy 324.755441 -351.275906) (xy 324.805055 -351.253254) (xy 324.857387 -351.237893)
			(xy 324.911374 -351.230136) (xy 324.938644 -351.229676) (xy 325.802244 -351.229676) (xy 325.829514 -351.23009)
			(xy 325.883498 -351.237857) (xy 325.935828 -351.253228) (xy 325.985437 -351.275889) (xy 326.031317 -351.305379)
			(xy 326.072534 -351.341097) (xy 326.108248 -351.382318) (xy 326.137732 -351.428201) (xy 326.160388 -351.477814)
			(xy 326.175752 -351.530145) (xy 326.183514 -351.58413) (xy 326.183514 -351.638668) (xy 327.666339 -351.638668)
			(xy 327.666339 -351.584132) (xy 327.674101 -351.53015) (xy 327.689466 -351.477822) (xy 327.712121 -351.428213)
			(xy 327.741607 -351.382334) (xy 327.777321 -351.341118) (xy 327.818537 -351.305404) (xy 327.864417 -351.27592)
			(xy 327.914026 -351.253264) (xy 327.966354 -351.2379) (xy 328.020336 -351.230139) (xy 328.047604 -351.229676)
			(xy 328.911204 -351.229676) (xy 328.938476 -351.230087) (xy 328.992464 -351.23785) (xy 329.044799 -351.253217)
			(xy 329.094413 -351.275876) (xy 329.140298 -351.305365) (xy 329.18152 -351.341083) (xy 329.217238 -351.382305)
			(xy 329.246726 -351.42819) (xy 329.269384 -351.477805) (xy 329.284751 -351.530139) (xy 329.292513 -351.584128)
			(xy 329.292513 -351.638665) (xy 330.775362 -351.638665) (xy 330.775362 -351.584135) (xy 330.783122 -351.53016)
			(xy 330.798484 -351.477838) (xy 330.821135 -351.428236) (xy 330.850615 -351.382361) (xy 330.886323 -351.341148)
			(xy 330.927532 -351.305437) (xy 330.973404 -351.275953) (xy 331.023005 -351.253297) (xy 331.075325 -351.23793)
			(xy 331.129299 -351.230165) (xy 331.156564 -351.229676) (xy 332.020164 -351.229676) (xy 332.047439 -351.230061)
			(xy 332.101436 -351.23782) (xy 332.153778 -351.253185) (xy 332.2034 -351.275842) (xy 332.249293 -351.305332)
			(xy 332.290522 -351.341053) (xy 332.326246 -351.382278) (xy 332.35574 -351.428168) (xy 332.378403 -351.477788)
			(xy 332.393772 -351.530129) (xy 332.401536 -351.584125) (xy 332.401536 -351.638669) (xy 333.884239 -351.638669)
			(xy 333.884239 -351.584131) (xy 333.892001 -351.530147) (xy 333.907367 -351.477818) (xy 333.930024 -351.428208)
			(xy 333.959511 -351.382328) (xy 333.995228 -351.341111) (xy 334.036447 -351.305397) (xy 334.082329 -351.275913)
			(xy 334.13194 -351.253259) (xy 334.18427 -351.237896) (xy 334.238255 -351.230138) (xy 334.265524 -351.229676)
			(xy 335.129124 -351.229676) (xy 335.156395 -351.230088) (xy 335.210381 -351.237853) (xy 335.262713 -351.253222)
			(xy 335.312325 -351.275882) (xy 335.358208 -351.305372) (xy 335.399427 -351.34109) (xy 335.435143 -351.382312)
			(xy 335.464629 -351.428196) (xy 335.487286 -351.477809) (xy 335.502652 -351.530142) (xy 335.510414 -351.584129)
			(xy 335.510414 -351.638666) (xy 336.993262 -351.638666) (xy 336.993262 -351.584134) (xy 337.001023 -351.530157)
			(xy 337.016386 -351.477834) (xy 337.039039 -351.42823) (xy 337.06852 -351.382354) (xy 337.10423 -351.341141)
			(xy 337.145442 -351.30543) (xy 337.191316 -351.275946) (xy 337.240919 -351.253291) (xy 337.293242 -351.237926)
			(xy 337.347218 -351.230163) (xy 337.374484 -351.229676) (xy 338.238084 -351.229676) (xy 338.265358 -351.230062)
			(xy 338.319352 -351.237824) (xy 338.371692 -351.25319) (xy 338.421312 -351.275849) (xy 338.467203 -351.305339)
			(xy 338.508429 -351.34106) (xy 338.544151 -351.382285) (xy 338.573643 -351.428174) (xy 338.596304 -351.477793)
			(xy 338.611673 -351.530132) (xy 338.619436 -351.584126) (xy 338.619436 -351.63867) (xy 340.10214 -351.63867)
			(xy 340.10214 -351.58413) (xy 340.109902 -351.530144) (xy 340.125269 -351.477813) (xy 340.147928 -351.428202)
			(xy 340.177416 -351.382321) (xy 340.213135 -351.341104) (xy 340.254356 -351.30539) (xy 340.300241 -351.275906)
			(xy 340.349855 -351.253254) (xy 340.402187 -351.237893) (xy 340.456174 -351.230136) (xy 340.483444 -351.229676)
			(xy 341.347044 -351.229676) (xy 341.374314 -351.23009) (xy 341.428298 -351.237857) (xy 341.480628 -351.253228)
			(xy 341.530237 -351.275889) (xy 341.576117 -351.305379) (xy 341.617334 -351.341097) (xy 341.653048 -351.382318)
			(xy 341.682532 -351.428201) (xy 341.705188 -351.477814) (xy 341.720552 -351.530145) (xy 341.728314 -351.58413)
			(xy 341.728314 -351.638668) (xy 343.211139 -351.638668) (xy 343.211139 -351.584132) (xy 343.218901 -351.53015)
			(xy 343.234266 -351.477822) (xy 343.256921 -351.428213) (xy 343.286407 -351.382334) (xy 343.322121 -351.341118)
			(xy 343.363337 -351.305404) (xy 343.409217 -351.27592) (xy 343.458826 -351.253264) (xy 343.511154 -351.2379)
			(xy 343.565136 -351.230139) (xy 343.592404 -351.229676) (xy 344.456004 -351.229676) (xy 344.483276 -351.230087)
			(xy 344.537264 -351.23785) (xy 344.589599 -351.253217) (xy 344.639213 -351.275876) (xy 344.685098 -351.305365)
			(xy 344.72632 -351.341083) (xy 344.762038 -351.382305) (xy 344.791526 -351.42819) (xy 344.814184 -351.477805)
			(xy 344.829551 -351.530139) (xy 344.837313 -351.584128) (xy 344.837313 -351.638666) (xy 370.806762 -351.638666)
			(xy 370.806762 -351.584134) (xy 370.814523 -351.530158) (xy 370.829885 -351.477835) (xy 370.852538 -351.428231)
			(xy 370.882019 -351.382356) (xy 370.917729 -351.341143) (xy 370.95894 -351.305431) (xy 371.004814 -351.275948)
			(xy 371.054416 -351.253292) (xy 371.106738 -351.237927) (xy 371.160714 -351.230164) (xy 371.18798 -351.229676)
			(xy 372.05158 -351.229676) (xy 372.078855 -351.230062) (xy 372.132849 -351.237823) (xy 372.185189 -351.253189)
			(xy 372.23481 -351.275848) (xy 372.280701 -351.305338) (xy 372.321927 -351.341059) (xy 372.35765 -351.382283)
			(xy 372.387143 -351.428172) (xy 372.409804 -351.477792) (xy 372.425173 -351.530131) (xy 372.432936 -351.584125)
			(xy 372.432936 -351.63867) (xy 373.91564 -351.63867) (xy 373.91564 -351.58413) (xy 373.923402 -351.530145)
			(xy 373.938769 -351.477814) (xy 373.961427 -351.428203) (xy 373.990915 -351.382322) (xy 374.026634 -351.341105)
			(xy 374.067854 -351.305391) (xy 374.113738 -351.275908) (xy 374.163352 -351.253255) (xy 374.215684 -351.237893)
			(xy 374.26967 -351.230137) (xy 374.29694 -351.229676) (xy 375.16054 -351.229676) (xy 375.18781 -351.230089)
			(xy 375.241795 -351.237856) (xy 375.294125 -351.253227) (xy 375.343735 -351.275887) (xy 375.389615 -351.305377)
			(xy 375.430832 -351.341096) (xy 375.466547 -351.382317) (xy 375.496032 -351.4282) (xy 375.518687 -351.477813)
			(xy 375.534052 -351.530144) (xy 375.541814 -351.58413) (xy 375.541814 -351.638667) (xy 377.024662 -351.638667)
			(xy 377.024662 -351.584133) (xy 377.032423 -351.530155) (xy 377.047787 -351.477831) (xy 377.070441 -351.428226)
			(xy 377.099924 -351.382349) (xy 377.135636 -351.341136) (xy 377.176849 -351.305424) (xy 377.222726 -351.275941)
			(xy 377.272331 -351.253287) (xy 377.324655 -351.237923) (xy 377.378633 -351.230162) (xy 377.4059 -351.229676)
			(xy 378.2695 -351.229676) (xy 378.296772 -351.230087) (xy 378.350761 -351.237849) (xy 378.403096 -351.253216)
			(xy 378.452711 -351.275874) (xy 378.498596 -351.305363) (xy 378.539818 -351.341082) (xy 378.575537 -351.382304)
			(xy 378.605026 -351.428189) (xy 378.627684 -351.477804) (xy 378.643051 -351.530139) (xy 378.650813 -351.584128)
			(xy 378.650813 -351.638665) (xy 380.133662 -351.638665) (xy 380.133662 -351.584135) (xy 380.141422 -351.53016)
			(xy 380.156784 -351.477839) (xy 380.179435 -351.428237) (xy 380.208914 -351.382362) (xy 380.244621 -351.34115)
			(xy 380.28583 -351.305438) (xy 380.331702 -351.275954) (xy 380.381302 -351.253298) (xy 380.433621 -351.237931)
			(xy 380.487595 -351.230165) (xy 380.51486 -351.229676) (xy 381.37846 -351.229676) (xy 381.405736 -351.230061)
			(xy 381.459732 -351.237819) (xy 381.512075 -351.253183) (xy 381.561698 -351.275841) (xy 381.607591 -351.30533)
			(xy 381.64882 -351.341051) (xy 381.684546 -351.382277) (xy 381.71404 -351.428167) (xy 381.736703 -351.477788)
			(xy 381.752072 -351.530129) (xy 381.759836 -351.584124) (xy 381.759836 -351.638669) (xy 383.242539 -351.638669)
			(xy 383.242539 -351.584131) (xy 383.250301 -351.530148) (xy 383.265667 -351.477818) (xy 383.288324 -351.428209)
			(xy 383.31781 -351.382329) (xy 383.353526 -351.341112) (xy 383.394745 -351.305398) (xy 383.440626 -351.275914)
			(xy 383.490237 -351.25326) (xy 383.542567 -351.237897) (xy 383.596551 -351.230138) (xy 383.62382 -351.229676)
			(xy 384.48742 -351.229676) (xy 384.514691 -351.230088) (xy 384.568678 -351.237853) (xy 384.62101 -351.253221)
			(xy 384.670623 -351.275881) (xy 384.716506 -351.30537) (xy 384.757725 -351.341089) (xy 384.793442 -351.38231)
			(xy 384.822929 -351.428195) (xy 384.845586 -351.477808) (xy 384.860952 -351.530142) (xy 384.868714 -351.584129)
			(xy 384.868714 -351.638666) (xy 386.351562 -351.638666) (xy 386.351562 -351.584134) (xy 386.359323 -351.530158)
			(xy 386.374685 -351.477835) (xy 386.397338 -351.428231) (xy 386.426819 -351.382356) (xy 386.462529 -351.341143)
			(xy 386.50374 -351.305431) (xy 386.549614 -351.275948) (xy 386.599216 -351.253292) (xy 386.651538 -351.237927)
			(xy 386.705514 -351.230164) (xy 386.73278 -351.229676) (xy 387.59638 -351.229676) (xy 387.623655 -351.230062)
			(xy 387.677649 -351.237823) (xy 387.729989 -351.253189) (xy 387.77961 -351.275848) (xy 387.825501 -351.305338)
			(xy 387.866727 -351.341059) (xy 387.90245 -351.382283) (xy 387.931943 -351.428172) (xy 387.954604 -351.477792)
			(xy 387.969973 -351.530131) (xy 387.977736 -351.584125) (xy 387.977736 -351.63867) (xy 389.46044 -351.63867)
			(xy 389.46044 -351.58413) (xy 389.468202 -351.530145) (xy 389.483569 -351.477814) (xy 389.506227 -351.428203)
			(xy 389.535715 -351.382322) (xy 389.571434 -351.341105) (xy 389.612654 -351.305391) (xy 389.658538 -351.275908)
			(xy 389.708152 -351.253255) (xy 389.760484 -351.237893) (xy 389.81447 -351.230137) (xy 389.84174 -351.229676)
			(xy 390.70534 -351.229676) (xy 390.73261 -351.230089) (xy 390.786595 -351.237856) (xy 390.838925 -351.253227)
			(xy 390.888535 -351.275887) (xy 390.934415 -351.305377) (xy 390.975632 -351.341096) (xy 391.011347 -351.382317)
			(xy 391.040832 -351.4282) (xy 391.063487 -351.477813) (xy 391.078852 -351.530144) (xy 391.086614 -351.58413)
			(xy 391.086614 -351.638667) (xy 392.569462 -351.638667) (xy 392.569462 -351.584133) (xy 392.577223 -351.530155)
			(xy 392.592587 -351.477831) (xy 392.615241 -351.428226) (xy 392.644724 -351.382349) (xy 392.680436 -351.341136)
			(xy 392.721649 -351.305424) (xy 392.767526 -351.275941) (xy 392.817131 -351.253287) (xy 392.869455 -351.237923)
			(xy 392.923433 -351.230162) (xy 392.9507 -351.229676) (xy 393.8143 -351.229676) (xy 393.841572 -351.230087)
			(xy 393.895561 -351.237849) (xy 393.947896 -351.253216) (xy 393.997511 -351.275874) (xy 394.043396 -351.305363)
			(xy 394.084618 -351.341082) (xy 394.120337 -351.382304) (xy 394.149826 -351.428189) (xy 394.172484 -351.477804)
			(xy 394.187851 -351.530139) (xy 394.195613 -351.584128) (xy 394.195613 -351.638665) (xy 395.678462 -351.638665)
			(xy 395.678462 -351.584135) (xy 395.686222 -351.53016) (xy 395.701584 -351.477839) (xy 395.724235 -351.428237)
			(xy 395.753714 -351.382362) (xy 395.789421 -351.34115) (xy 395.83063 -351.305438) (xy 395.876502 -351.275954)
			(xy 395.926102 -351.253298) (xy 395.978421 -351.237931) (xy 396.032395 -351.230165) (xy 396.05966 -351.229676)
			(xy 396.92326 -351.229676) (xy 396.950536 -351.230061) (xy 397.004532 -351.237819) (xy 397.056875 -351.253183)
			(xy 397.106498 -351.275841) (xy 397.152391 -351.30533) (xy 397.19362 -351.341051) (xy 397.229346 -351.382277)
			(xy 397.25884 -351.428167) (xy 397.281503 -351.477788) (xy 397.296872 -351.530129) (xy 397.304636 -351.584124)
			(xy 397.304636 -351.638669) (xy 398.787339 -351.638669) (xy 398.787339 -351.584131) (xy 398.795101 -351.530148)
			(xy 398.810467 -351.477818) (xy 398.833124 -351.428209) (xy 398.86261 -351.382329) (xy 398.898326 -351.341112)
			(xy 398.939545 -351.305398) (xy 398.985426 -351.275914) (xy 399.035037 -351.25326) (xy 399.087367 -351.237897)
			(xy 399.141351 -351.230138) (xy 399.16862 -351.229676) (xy 400.03222 -351.229676) (xy 400.059491 -351.230088)
			(xy 400.113478 -351.237853) (xy 400.16581 -351.253221) (xy 400.215423 -351.275881) (xy 400.261306 -351.30537)
			(xy 400.302525 -351.341089) (xy 400.338242 -351.38231) (xy 400.367729 -351.428195) (xy 400.390386 -351.477808)
			(xy 400.405752 -351.530142) (xy 400.413514 -351.584129) (xy 400.413514 -351.638666) (xy 401.896362 -351.638666)
			(xy 401.896362 -351.584134) (xy 401.904123 -351.530158) (xy 401.919485 -351.477835) (xy 401.942138 -351.428231)
			(xy 401.971619 -351.382356) (xy 402.007329 -351.341143) (xy 402.04854 -351.305431) (xy 402.094414 -351.275948)
			(xy 402.144016 -351.253292) (xy 402.196338 -351.237927) (xy 402.250314 -351.230164) (xy 402.27758 -351.229676)
			(xy 403.14118 -351.229676) (xy 403.168455 -351.230062) (xy 403.222449 -351.237823) (xy 403.274789 -351.253189)
			(xy 403.32441 -351.275848) (xy 403.370301 -351.305338) (xy 403.411527 -351.341059) (xy 403.44725 -351.382283)
			(xy 403.476743 -351.428172) (xy 403.499404 -351.477792) (xy 403.514773 -351.530131) (xy 403.522536 -351.584125)
			(xy 403.522536 -351.638666) (xy 408.913862 -351.638666) (xy 408.913862 -351.584134) (xy 408.921623 -351.530156)
			(xy 408.936986 -351.477832) (xy 408.95964 -351.428228) (xy 408.989122 -351.382352) (xy 409.024833 -351.341138)
			(xy 409.066045 -351.305427) (xy 409.111921 -351.275944) (xy 409.161525 -351.253289) (xy 409.213848 -351.237925)
			(xy 409.267826 -351.230163) (xy 409.295092 -351.229676) (xy 410.158692 -351.229676) (xy 410.185966 -351.230063)
			(xy 410.239959 -351.237825) (xy 410.292298 -351.253192) (xy 410.341917 -351.275851) (xy 410.387806 -351.305342)
			(xy 410.429032 -351.341063) (xy 410.464753 -351.382287) (xy 410.494245 -351.428176) (xy 410.516905 -351.477794)
			(xy 410.532273 -351.530133) (xy 410.540036 -351.584126) (xy 410.540036 -351.638664) (xy 412.022862 -351.638664)
			(xy 412.022862 -351.584136) (xy 412.030622 -351.530162) (xy 412.045983 -351.477841) (xy 412.068634 -351.428239)
			(xy 412.098112 -351.382365) (xy 412.133819 -351.341153) (xy 412.175026 -351.305441) (xy 412.220897 -351.275957)
			(xy 412.270496 -351.2533) (xy 412.322815 -351.237932) (xy 412.376788 -351.230166) (xy 412.404052 -351.229676)
			(xy 413.267652 -351.229676) (xy 413.294928 -351.23006) (xy 413.348925 -351.237818) (xy 413.401269 -351.253181)
			(xy 413.450893 -351.275838) (xy 413.496787 -351.305328) (xy 413.538017 -351.341049) (xy 413.573744 -351.382274)
			(xy 413.603239 -351.428165) (xy 413.625902 -351.477786) (xy 413.641272 -351.530128) (xy 413.649036 -351.584124)
			(xy 413.649036 -351.638669) (xy 415.131739 -351.638669) (xy 415.131739 -351.584131) (xy 415.139501 -351.530149)
			(xy 415.154866 -351.47782) (xy 415.177523 -351.428211) (xy 415.207008 -351.382331) (xy 415.242724 -351.341115)
			(xy 415.283941 -351.305401) (xy 415.329822 -351.275917) (xy 415.379431 -351.253262) (xy 415.43176 -351.237899)
			(xy 415.485743 -351.230139) (xy 415.513012 -351.229676) (xy 416.376612 -351.229676) (xy 416.403884 -351.230087)
			(xy 416.457871 -351.237851) (xy 416.510204 -351.253219) (xy 416.559818 -351.275878) (xy 416.605702 -351.305367)
			(xy 416.646922 -351.341086) (xy 416.68264 -351.382308) (xy 416.712128 -351.428192) (xy 416.734785 -351.477807)
			(xy 416.750151 -351.530141) (xy 416.757914 -351.584128) (xy 416.757914 -351.638665) (xy 418.240762 -351.638665)
			(xy 418.240762 -351.584135) (xy 418.248522 -351.530159) (xy 418.263885 -351.477837) (xy 418.286537 -351.428233)
			(xy 418.316017 -351.382358) (xy 418.351726 -351.341146) (xy 418.392936 -351.305434) (xy 418.438809 -351.27595)
			(xy 418.48841 -351.253295) (xy 418.540731 -351.237928) (xy 418.594707 -351.230164) (xy 418.621972 -351.229676)
			(xy 419.485572 -351.229676) (xy 419.512847 -351.230062) (xy 419.566842 -351.237821) (xy 419.619184 -351.253187)
			(xy 419.668805 -351.275845) (xy 419.714697 -351.305335) (xy 419.755924 -351.341056) (xy 419.791648 -351.382281)
			(xy 419.821142 -351.42817) (xy 419.843803 -351.47779) (xy 419.859173 -351.53013) (xy 419.866936 -351.584125)
			(xy 419.866936 -351.63867) (xy 421.349639 -351.63867) (xy 421.349639 -351.58413) (xy 421.357402 -351.530146)
			(xy 421.372768 -351.477816) (xy 421.395426 -351.428206) (xy 421.424913 -351.382325) (xy 421.460631 -351.341108)
			(xy 421.501851 -351.305394) (xy 421.547734 -351.27591) (xy 421.597346 -351.253257) (xy 421.649677 -351.237895)
			(xy 421.703662 -351.230137) (xy 421.730932 -351.229676) (xy 422.594532 -351.229676) (xy 422.621803 -351.230089)
			(xy 422.675788 -351.237855) (xy 422.728119 -351.253224) (xy 422.77773 -351.275885) (xy 422.823612 -351.305374)
			(xy 422.864829 -351.341093) (xy 422.900545 -351.382314) (xy 422.930031 -351.428198) (xy 422.952687 -351.477811)
			(xy 422.968052 -351.530143) (xy 422.975814 -351.584129) (xy 422.975814 -351.638666) (xy 424.458662 -351.638666)
			(xy 424.458662 -351.584134) (xy 424.466423 -351.530156) (xy 424.481786 -351.477832) (xy 424.50444 -351.428228)
			(xy 424.533922 -351.382352) (xy 424.569633 -351.341138) (xy 424.610845 -351.305427) (xy 424.656721 -351.275944)
			(xy 424.706325 -351.253289) (xy 424.758648 -351.237925) (xy 424.812626 -351.230163) (xy 424.839892 -351.229676)
			(xy 425.703492 -351.229676) (xy 425.730766 -351.230063) (xy 425.784759 -351.237825) (xy 425.837098 -351.253192)
			(xy 425.886717 -351.275851) (xy 425.932606 -351.305342) (xy 425.973832 -351.341063) (xy 426.009553 -351.382287)
			(xy 426.039045 -351.428176) (xy 426.061705 -351.477794) (xy 426.077073 -351.530133) (xy 426.084836 -351.584126)
			(xy 426.084836 -351.638664) (xy 427.567662 -351.638664) (xy 427.567662 -351.584136) (xy 427.575422 -351.530162)
			(xy 427.590783 -351.477841) (xy 427.613434 -351.428239) (xy 427.642912 -351.382365) (xy 427.678619 -351.341153)
			(xy 427.719826 -351.305441) (xy 427.765697 -351.275957) (xy 427.815296 -351.2533) (xy 427.867615 -351.237932)
			(xy 427.921588 -351.230166) (xy 427.948852 -351.229676) (xy 428.812452 -351.229676) (xy 428.839728 -351.23006)
			(xy 428.893725 -351.237818) (xy 428.946069 -351.253181) (xy 428.995693 -351.275838) (xy 429.041587 -351.305328)
			(xy 429.082817 -351.341049) (xy 429.118544 -351.382274) (xy 429.148039 -351.428165) (xy 429.170702 -351.477786)
			(xy 429.186072 -351.530128) (xy 429.193836 -351.584124) (xy 429.193836 -351.638669) (xy 430.676539 -351.638669)
			(xy 430.676539 -351.584131) (xy 430.684301 -351.530149) (xy 430.699666 -351.47782) (xy 430.722323 -351.428211)
			(xy 430.751808 -351.382331) (xy 430.787524 -351.341115) (xy 430.828741 -351.305401) (xy 430.874622 -351.275917)
			(xy 430.924231 -351.253262) (xy 430.97656 -351.237899) (xy 431.030543 -351.230139) (xy 431.057812 -351.229676)
			(xy 431.921412 -351.229676) (xy 431.948684 -351.230087) (xy 432.002671 -351.237851) (xy 432.055004 -351.253219)
			(xy 432.104618 -351.275878) (xy 432.150502 -351.305367) (xy 432.191722 -351.341086) (xy 432.22744 -351.382308)
			(xy 432.256928 -351.428192) (xy 432.279585 -351.477807) (xy 432.294951 -351.530141) (xy 432.302714 -351.584128)
			(xy 432.302714 -351.638665) (xy 433.785562 -351.638665) (xy 433.785562 -351.584135) (xy 433.793322 -351.530159)
			(xy 433.808685 -351.477837) (xy 433.831337 -351.428233) (xy 433.860817 -351.382358) (xy 433.896526 -351.341146)
			(xy 433.937736 -351.305434) (xy 433.983609 -351.27595) (xy 434.03321 -351.253295) (xy 434.085531 -351.237928)
			(xy 434.139507 -351.230164) (xy 434.166772 -351.229676) (xy 435.030372 -351.229676) (xy 435.057647 -351.230062)
			(xy 435.111642 -351.237821) (xy 435.163984 -351.253187) (xy 435.213605 -351.275845) (xy 435.259497 -351.305335)
			(xy 435.300724 -351.341056) (xy 435.336448 -351.382281) (xy 435.365942 -351.42817) (xy 435.388603 -351.47779)
			(xy 435.403973 -351.53013) (xy 435.411736 -351.584125) (xy 435.411736 -351.63867) (xy 436.894439 -351.63867)
			(xy 436.894439 -351.58413) (xy 436.902202 -351.530146) (xy 436.917568 -351.477816) (xy 436.940226 -351.428206)
			(xy 436.969713 -351.382325) (xy 437.005431 -351.341108) (xy 437.046651 -351.305394) (xy 437.092534 -351.27591)
			(xy 437.142146 -351.253257) (xy 437.194477 -351.237895) (xy 437.248462 -351.230137) (xy 437.275732 -351.229676)
			(xy 438.139332 -351.229676) (xy 438.166603 -351.230089) (xy 438.220588 -351.237855) (xy 438.272919 -351.253224)
			(xy 438.32253 -351.275885) (xy 438.368412 -351.305374) (xy 438.409629 -351.341093) (xy 438.445345 -351.382314)
			(xy 438.474831 -351.428198) (xy 438.497487 -351.477811) (xy 438.512852 -351.530143) (xy 438.520614 -351.584129)
			(xy 438.520614 -351.638666) (xy 440.003462 -351.638666) (xy 440.003462 -351.584134) (xy 440.011223 -351.530156)
			(xy 440.026586 -351.477832) (xy 440.04924 -351.428228) (xy 440.078722 -351.382352) (xy 440.114433 -351.341138)
			(xy 440.155645 -351.305427) (xy 440.201521 -351.275944) (xy 440.251125 -351.253289) (xy 440.303448 -351.237925)
			(xy 440.357426 -351.230163) (xy 440.384692 -351.229676) (xy 441.248292 -351.229676) (xy 441.275566 -351.230063)
			(xy 441.329559 -351.237825) (xy 441.381898 -351.253192) (xy 441.431517 -351.275851) (xy 441.477406 -351.305342)
			(xy 441.518632 -351.341063) (xy 441.554353 -351.382287) (xy 441.583845 -351.428176) (xy 441.606505 -351.477794)
			(xy 441.621873 -351.530133) (xy 441.629636 -351.584126) (xy 441.629636 -351.638674) (xy 441.621873 -351.692667)
			(xy 441.606505 -351.745006) (xy 441.583845 -351.794624) (xy 441.554353 -351.840513) (xy 441.518632 -351.881737)
			(xy 441.477406 -351.917458) (xy 441.431517 -351.946949) (xy 441.381898 -351.969608) (xy 441.329559 -351.984975)
			(xy 441.275566 -351.992737) (xy 441.248292 -351.9932) (xy 440.384692 -351.9932) (xy 440.357426 -351.992637)
			(xy 440.303448 -351.984875) (xy 440.251125 -351.969511) (xy 440.201521 -351.946856) (xy 440.155645 -351.917373)
			(xy 440.114433 -351.881662) (xy 440.078722 -351.840448) (xy 440.04924 -351.794572) (xy 440.026586 -351.744968)
			(xy 440.011223 -351.692644) (xy 440.003462 -351.638666) (xy 438.520614 -351.638666) (xy 438.520614 -351.638671)
			(xy 438.512852 -351.692657) (xy 438.497487 -351.744989) (xy 438.474831 -351.794602) (xy 438.445345 -351.840486)
			(xy 438.409629 -351.881707) (xy 438.368412 -351.917426) (xy 438.32253 -351.946915) (xy 438.272919 -351.969576)
			(xy 438.220588 -351.984945) (xy 438.166603 -351.992711) (xy 438.139332 -351.9932) (xy 437.275732 -351.9932)
			(xy 437.248462 -351.992663) (xy 437.194477 -351.984905) (xy 437.142146 -351.969543) (xy 437.092534 -351.94689)
			(xy 437.046651 -351.917406) (xy 437.005431 -351.881692) (xy 436.969713 -351.840475) (xy 436.940226 -351.794594)
			(xy 436.917568 -351.744984) (xy 436.902202 -351.692654) (xy 436.894439 -351.63867) (xy 435.411736 -351.63867)
			(xy 435.411736 -351.638675) (xy 435.403973 -351.69267) (xy 435.388603 -351.74501) (xy 435.365942 -351.79463)
			(xy 435.336448 -351.840519) (xy 435.300724 -351.881744) (xy 435.259497 -351.917465) (xy 435.213605 -351.946955)
			(xy 435.163984 -351.969613) (xy 435.111642 -351.984979) (xy 435.057647 -351.992738) (xy 435.030372 -351.9932)
			(xy 434.166772 -351.9932) (xy 434.139507 -351.992636) (xy 434.085531 -351.984872) (xy 434.03321 -351.969505)
			(xy 433.983609 -351.94685) (xy 433.937736 -351.917366) (xy 433.896526 -351.881654) (xy 433.860817 -351.840442)
			(xy 433.831337 -351.794567) (xy 433.808685 -351.744963) (xy 433.793322 -351.692641) (xy 433.785562 -351.638665)
			(xy 432.302714 -351.638665) (xy 432.302714 -351.638672) (xy 432.294951 -351.692659) (xy 432.279585 -351.744993)
			(xy 432.256928 -351.794608) (xy 432.22744 -351.840492) (xy 432.191722 -351.881714) (xy 432.150502 -351.917433)
			(xy 432.104618 -351.946922) (xy 432.055004 -351.969581) (xy 432.002671 -351.984949) (xy 431.948684 -351.992713)
			(xy 431.921412 -351.9932) (xy 431.057812 -351.9932) (xy 431.030543 -351.992661) (xy 430.97656 -351.984901)
			(xy 430.924231 -351.969538) (xy 430.874622 -351.946883) (xy 430.828741 -351.917399) (xy 430.787524 -351.881685)
			(xy 430.751808 -351.840469) (xy 430.722323 -351.794589) (xy 430.699666 -351.74498) (xy 430.684301 -351.692651)
			(xy 430.676539 -351.638669) (xy 429.193836 -351.638669) (xy 429.193836 -351.638676) (xy 429.186072 -351.692672)
			(xy 429.170702 -351.745014) (xy 429.148039 -351.794635) (xy 429.118544 -351.840526) (xy 429.082817 -351.881751)
			(xy 429.041587 -351.917472) (xy 428.995693 -351.946962) (xy 428.946069 -351.969619) (xy 428.893725 -351.984982)
			(xy 428.839728 -351.99274) (xy 428.812452 -351.9932) (xy 427.948852 -351.9932) (xy 427.921588 -351.992634)
			(xy 427.867615 -351.984868) (xy 427.815296 -351.9695) (xy 427.765697 -351.946843) (xy 427.719826 -351.917359)
			(xy 427.678619 -351.881647) (xy 427.642912 -351.840435) (xy 427.613434 -351.794561) (xy 427.590783 -351.744959)
			(xy 427.575422 -351.692639) (xy 427.567662 -351.638664) (xy 426.084836 -351.638664) (xy 426.084836 -351.638674)
			(xy 426.077073 -351.692667) (xy 426.061705 -351.745006) (xy 426.039045 -351.794624) (xy 426.009553 -351.840513)
			(xy 425.973832 -351.881737) (xy 425.932606 -351.917458) (xy 425.886717 -351.946949) (xy 425.837098 -351.969608)
			(xy 425.784759 -351.984975) (xy 425.730766 -351.992737) (xy 425.703492 -351.9932) (xy 424.839892 -351.9932)
			(xy 424.812626 -351.992637) (xy 424.758648 -351.984875) (xy 424.706325 -351.969511) (xy 424.656721 -351.946856)
			(xy 424.610845 -351.917373) (xy 424.569633 -351.881662) (xy 424.533922 -351.840448) (xy 424.50444 -351.794572)
			(xy 424.481786 -351.744968) (xy 424.466423 -351.692644) (xy 424.458662 -351.638666) (xy 422.975814 -351.638666)
			(xy 422.975814 -351.638671) (xy 422.968052 -351.692657) (xy 422.952687 -351.744989) (xy 422.930031 -351.794602)
			(xy 422.900545 -351.840486) (xy 422.864829 -351.881707) (xy 422.823612 -351.917426) (xy 422.77773 -351.946915)
			(xy 422.728119 -351.969576) (xy 422.675788 -351.984945) (xy 422.621803 -351.992711) (xy 422.594532 -351.9932)
			(xy 421.730932 -351.9932) (xy 421.703662 -351.992663) (xy 421.649677 -351.984905) (xy 421.597346 -351.969543)
			(xy 421.547734 -351.94689) (xy 421.501851 -351.917406) (xy 421.460631 -351.881692) (xy 421.424913 -351.840475)
			(xy 421.395426 -351.794594) (xy 421.372768 -351.744984) (xy 421.357402 -351.692654) (xy 421.349639 -351.63867)
			(xy 419.866936 -351.63867) (xy 419.866936 -351.638675) (xy 419.859173 -351.69267) (xy 419.843803 -351.74501)
			(xy 419.821142 -351.79463) (xy 419.791648 -351.840519) (xy 419.755924 -351.881744) (xy 419.714697 -351.917465)
			(xy 419.668805 -351.946955) (xy 419.619184 -351.969613) (xy 419.566842 -351.984979) (xy 419.512847 -351.992738)
			(xy 419.485572 -351.9932) (xy 418.621972 -351.9932) (xy 418.594707 -351.992636) (xy 418.540731 -351.984872)
			(xy 418.48841 -351.969505) (xy 418.438809 -351.94685) (xy 418.392936 -351.917366) (xy 418.351726 -351.881654)
			(xy 418.316017 -351.840442) (xy 418.286537 -351.794567) (xy 418.263885 -351.744963) (xy 418.248522 -351.692641)
			(xy 418.240762 -351.638665) (xy 416.757914 -351.638665) (xy 416.757914 -351.638672) (xy 416.750151 -351.692659)
			(xy 416.734785 -351.744993) (xy 416.712128 -351.794608) (xy 416.68264 -351.840492) (xy 416.646922 -351.881714)
			(xy 416.605702 -351.917433) (xy 416.559818 -351.946922) (xy 416.510204 -351.969581) (xy 416.457871 -351.984949)
			(xy 416.403884 -351.992713) (xy 416.376612 -351.9932) (xy 415.513012 -351.9932) (xy 415.485743 -351.992661)
			(xy 415.43176 -351.984901) (xy 415.379431 -351.969538) (xy 415.329822 -351.946883) (xy 415.283941 -351.917399)
			(xy 415.242724 -351.881685) (xy 415.207008 -351.840469) (xy 415.177523 -351.794589) (xy 415.154866 -351.74498)
			(xy 415.139501 -351.692651) (xy 415.131739 -351.638669) (xy 413.649036 -351.638669) (xy 413.649036 -351.638676)
			(xy 413.641272 -351.692672) (xy 413.625902 -351.745014) (xy 413.603239 -351.794635) (xy 413.573744 -351.840526)
			(xy 413.538017 -351.881751) (xy 413.496787 -351.917472) (xy 413.450893 -351.946962) (xy 413.401269 -351.969619)
			(xy 413.348925 -351.984982) (xy 413.294928 -351.99274) (xy 413.267652 -351.9932) (xy 412.404052 -351.9932)
			(xy 412.376788 -351.992634) (xy 412.322815 -351.984868) (xy 412.270496 -351.9695) (xy 412.220897 -351.946843)
			(xy 412.175026 -351.917359) (xy 412.133819 -351.881647) (xy 412.098112 -351.840435) (xy 412.068634 -351.794561)
			(xy 412.045983 -351.744959) (xy 412.030622 -351.692639) (xy 412.022862 -351.638664) (xy 410.540036 -351.638664)
			(xy 410.540036 -351.638674) (xy 410.532273 -351.692667) (xy 410.516905 -351.745006) (xy 410.494245 -351.794624)
			(xy 410.464753 -351.840513) (xy 410.429032 -351.881737) (xy 410.387806 -351.917458) (xy 410.341917 -351.946949)
			(xy 410.292298 -351.969608) (xy 410.239959 -351.984975) (xy 410.185966 -351.992737) (xy 410.158692 -351.9932)
			(xy 409.295092 -351.9932) (xy 409.267826 -351.992637) (xy 409.213848 -351.984875) (xy 409.161525 -351.969511)
			(xy 409.111921 -351.946856) (xy 409.066045 -351.917373) (xy 409.024833 -351.881662) (xy 408.989122 -351.840448)
			(xy 408.95964 -351.794572) (xy 408.936986 -351.744968) (xy 408.921623 -351.692644) (xy 408.913862 -351.638666)
			(xy 403.522536 -351.638666) (xy 403.522536 -351.638675) (xy 403.514773 -351.692669) (xy 403.499404 -351.745008)
			(xy 403.476743 -351.794628) (xy 403.44725 -351.840517) (xy 403.411527 -351.881741) (xy 403.370301 -351.917462)
			(xy 403.32441 -351.946952) (xy 403.274789 -351.969611) (xy 403.222449 -351.984977) (xy 403.168455 -351.992738)
			(xy 403.14118 -351.9932) (xy 402.27758 -351.9932) (xy 402.250314 -351.992636) (xy 402.196338 -351.984873)
			(xy 402.144016 -351.969508) (xy 402.094414 -351.946852) (xy 402.04854 -351.917369) (xy 402.007329 -351.881657)
			(xy 401.971619 -351.840444) (xy 401.942138 -351.794569) (xy 401.919485 -351.744965) (xy 401.904123 -351.692642)
			(xy 401.896362 -351.638666) (xy 400.413514 -351.638666) (xy 400.413514 -351.638671) (xy 400.405752 -351.692658)
			(xy 400.390386 -351.744992) (xy 400.367729 -351.794605) (xy 400.338242 -351.84049) (xy 400.302525 -351.881711)
			(xy 400.261306 -351.91743) (xy 400.215423 -351.946919) (xy 400.16581 -351.969579) (xy 400.113478 -351.984947)
			(xy 400.059491 -351.992712) (xy 400.03222 -351.9932) (xy 399.16862 -351.9932) (xy 399.141351 -351.992662)
			(xy 399.087367 -351.984903) (xy 399.035037 -351.96954) (xy 398.985426 -351.946886) (xy 398.939545 -351.917402)
			(xy 398.898326 -351.881688) (xy 398.86261 -351.840471) (xy 398.833124 -351.794591) (xy 398.810467 -351.744982)
			(xy 398.795101 -351.692652) (xy 398.787339 -351.638669) (xy 397.304636 -351.638669) (xy 397.304636 -351.638676)
			(xy 397.296872 -351.692671) (xy 397.281503 -351.745012) (xy 397.25884 -351.794633) (xy 397.229346 -351.840523)
			(xy 397.19362 -351.881749) (xy 397.152391 -351.91747) (xy 397.106498 -351.946959) (xy 397.056875 -351.969617)
			(xy 397.004532 -351.984981) (xy 396.950536 -351.992739) (xy 396.92326 -351.9932) (xy 396.05966 -351.9932)
			(xy 396.032395 -351.992635) (xy 395.978421 -351.984869) (xy 395.926102 -351.969502) (xy 395.876502 -351.946846)
			(xy 395.83063 -351.917362) (xy 395.789421 -351.88165) (xy 395.753714 -351.840438) (xy 395.724235 -351.794563)
			(xy 395.701584 -351.744961) (xy 395.686222 -351.69264) (xy 395.678462 -351.638665) (xy 394.195613 -351.638665)
			(xy 394.195613 -351.638672) (xy 394.187851 -351.692661) (xy 394.172484 -351.744996) (xy 394.149826 -351.794611)
			(xy 394.120337 -351.840496) (xy 394.084618 -351.881718) (xy 394.043396 -351.917437) (xy 393.997511 -351.946926)
			(xy 393.947896 -351.969584) (xy 393.895561 -351.984951) (xy 393.841572 -351.992713) (xy 393.8143 -351.9932)
			(xy 392.9507 -351.9932) (xy 392.923433 -351.992638) (xy 392.869455 -351.984877) (xy 392.817131 -351.969513)
			(xy 392.767526 -351.946859) (xy 392.721649 -351.917376) (xy 392.680436 -351.881664) (xy 392.644724 -351.840451)
			(xy 392.615241 -351.794574) (xy 392.592587 -351.744969) (xy 392.577223 -351.692645) (xy 392.569462 -351.638667)
			(xy 391.086614 -351.638667) (xy 391.086614 -351.63867) (xy 391.078852 -351.692656) (xy 391.063487 -351.744987)
			(xy 391.040832 -351.7946) (xy 391.011347 -351.840483) (xy 390.975632 -351.881704) (xy 390.934415 -351.917423)
			(xy 390.888535 -351.946913) (xy 390.838925 -351.969573) (xy 390.786595 -351.984944) (xy 390.73261 -351.992711)
			(xy 390.70534 -351.9932) (xy 389.84174 -351.9932) (xy 389.81447 -351.992663) (xy 389.760484 -351.984907)
			(xy 389.708152 -351.969545) (xy 389.658538 -351.946892) (xy 389.612654 -351.917409) (xy 389.571434 -351.881695)
			(xy 389.535715 -351.840478) (xy 389.506227 -351.794597) (xy 389.483569 -351.744986) (xy 389.468202 -351.692655)
			(xy 389.46044 -351.63867) (xy 387.977736 -351.63867) (xy 387.977736 -351.638675) (xy 387.969973 -351.692669)
			(xy 387.954604 -351.745008) (xy 387.931943 -351.794628) (xy 387.90245 -351.840517) (xy 387.866727 -351.881741)
			(xy 387.825501 -351.917462) (xy 387.77961 -351.946952) (xy 387.729989 -351.969611) (xy 387.677649 -351.984977)
			(xy 387.623655 -351.992738) (xy 387.59638 -351.9932) (xy 386.73278 -351.9932) (xy 386.705514 -351.992636)
			(xy 386.651538 -351.984873) (xy 386.599216 -351.969508) (xy 386.549614 -351.946852) (xy 386.50374 -351.917369)
			(xy 386.462529 -351.881657) (xy 386.426819 -351.840444) (xy 386.397338 -351.794569) (xy 386.374685 -351.744965)
			(xy 386.359323 -351.692642) (xy 386.351562 -351.638666) (xy 384.868714 -351.638666) (xy 384.868714 -351.638671)
			(xy 384.860952 -351.692658) (xy 384.845586 -351.744992) (xy 384.822929 -351.794605) (xy 384.793442 -351.84049)
			(xy 384.757725 -351.881711) (xy 384.716506 -351.91743) (xy 384.670623 -351.946919) (xy 384.62101 -351.969579)
			(xy 384.568678 -351.984947) (xy 384.514691 -351.992712) (xy 384.48742 -351.9932) (xy 383.62382 -351.9932)
			(xy 383.596551 -351.992662) (xy 383.542567 -351.984903) (xy 383.490237 -351.96954) (xy 383.440626 -351.946886)
			(xy 383.394745 -351.917402) (xy 383.353526 -351.881688) (xy 383.31781 -351.840471) (xy 383.288324 -351.794591)
			(xy 383.265667 -351.744982) (xy 383.250301 -351.692652) (xy 383.242539 -351.638669) (xy 381.759836 -351.638669)
			(xy 381.759836 -351.638676) (xy 381.752072 -351.692671) (xy 381.736703 -351.745012) (xy 381.71404 -351.794633)
			(xy 381.684546 -351.840523) (xy 381.64882 -351.881749) (xy 381.607591 -351.91747) (xy 381.561698 -351.946959)
			(xy 381.512075 -351.969617) (xy 381.459732 -351.984981) (xy 381.405736 -351.992739) (xy 381.37846 -351.9932)
			(xy 380.51486 -351.9932) (xy 380.487595 -351.992635) (xy 380.433621 -351.984869) (xy 380.381302 -351.969502)
			(xy 380.331702 -351.946846) (xy 380.28583 -351.917362) (xy 380.244621 -351.88165) (xy 380.208914 -351.840438)
			(xy 380.179435 -351.794563) (xy 380.156784 -351.744961) (xy 380.141422 -351.69264) (xy 380.133662 -351.638665)
			(xy 378.650813 -351.638665) (xy 378.650813 -351.638672) (xy 378.643051 -351.692661) (xy 378.627684 -351.744996)
			(xy 378.605026 -351.794611) (xy 378.575537 -351.840496) (xy 378.539818 -351.881718) (xy 378.498596 -351.917437)
			(xy 378.452711 -351.946926) (xy 378.403096 -351.969584) (xy 378.350761 -351.984951) (xy 378.296772 -351.992713)
			(xy 378.2695 -351.9932) (xy 377.4059 -351.9932) (xy 377.378633 -351.992638) (xy 377.324655 -351.984877)
			(xy 377.272331 -351.969513) (xy 377.222726 -351.946859) (xy 377.176849 -351.917376) (xy 377.135636 -351.881664)
			(xy 377.099924 -351.840451) (xy 377.070441 -351.794574) (xy 377.047787 -351.744969) (xy 377.032423 -351.692645)
			(xy 377.024662 -351.638667) (xy 375.541814 -351.638667) (xy 375.541814 -351.63867) (xy 375.534052 -351.692656)
			(xy 375.518687 -351.744987) (xy 375.496032 -351.7946) (xy 375.466547 -351.840483) (xy 375.430832 -351.881704)
			(xy 375.389615 -351.917423) (xy 375.343735 -351.946913) (xy 375.294125 -351.969573) (xy 375.241795 -351.984944)
			(xy 375.18781 -351.992711) (xy 375.16054 -351.9932) (xy 374.29694 -351.9932) (xy 374.26967 -351.992663)
			(xy 374.215684 -351.984907) (xy 374.163352 -351.969545) (xy 374.113738 -351.946892) (xy 374.067854 -351.917409)
			(xy 374.026634 -351.881695) (xy 373.990915 -351.840478) (xy 373.961427 -351.794597) (xy 373.938769 -351.744986)
			(xy 373.923402 -351.692655) (xy 373.91564 -351.63867) (xy 372.432936 -351.63867) (xy 372.432936 -351.638675)
			(xy 372.425173 -351.692669) (xy 372.409804 -351.745008) (xy 372.387143 -351.794628) (xy 372.35765 -351.840517)
			(xy 372.321927 -351.881741) (xy 372.280701 -351.917462) (xy 372.23481 -351.946952) (xy 372.185189 -351.969611)
			(xy 372.132849 -351.984977) (xy 372.078855 -351.992738) (xy 372.05158 -351.9932) (xy 371.18798 -351.9932)
			(xy 371.160714 -351.992636) (xy 371.106738 -351.984873) (xy 371.054416 -351.969508) (xy 371.004814 -351.946852)
			(xy 370.95894 -351.917369) (xy 370.917729 -351.881657) (xy 370.882019 -351.840444) (xy 370.852538 -351.794569)
			(xy 370.829885 -351.744965) (xy 370.814523 -351.692642) (xy 370.806762 -351.638666) (xy 344.837313 -351.638666)
			(xy 344.837313 -351.638672) (xy 344.829551 -351.692661) (xy 344.814184 -351.744995) (xy 344.791526 -351.79461)
			(xy 344.762038 -351.840495) (xy 344.726319 -351.881717) (xy 344.685098 -351.917435) (xy 344.639213 -351.946924)
			(xy 344.589599 -351.969583) (xy 344.537264 -351.98495) (xy 344.483276 -351.992713) (xy 344.456004 -351.9932)
			(xy 343.592404 -351.9932) (xy 343.565136 -351.992661) (xy 343.511154 -351.9849) (xy 343.458826 -351.969536)
			(xy 343.409217 -351.94688) (xy 343.363337 -351.917396) (xy 343.322121 -351.881682) (xy 343.286407 -351.840466)
			(xy 343.256921 -351.794587) (xy 343.234266 -351.744978) (xy 343.218901 -351.69265) (xy 343.211139 -351.638668)
			(xy 341.728314 -351.638668) (xy 341.728314 -351.63867) (xy 341.720552 -351.692655) (xy 341.705188 -351.744986)
			(xy 341.682532 -351.794599) (xy 341.653048 -351.840482) (xy 341.617334 -351.881703) (xy 341.576117 -351.917421)
			(xy 341.530237 -351.946911) (xy 341.480628 -351.969572) (xy 341.428298 -351.984943) (xy 341.374314 -351.99271)
			(xy 341.347044 -351.9932) (xy 340.483444 -351.9932) (xy 340.456174 -351.992664) (xy 340.402187 -351.984907)
			(xy 340.349855 -351.969546) (xy 340.300241 -351.946894) (xy 340.254356 -351.91741) (xy 340.213135 -351.881696)
			(xy 340.177416 -351.840479) (xy 340.147928 -351.794598) (xy 340.125269 -351.744987) (xy 340.109902 -351.692656)
			(xy 340.10214 -351.63867) (xy 338.619436 -351.63867) (xy 338.619436 -351.638674) (xy 338.611673 -351.692668)
			(xy 338.596304 -351.745007) (xy 338.573643 -351.794626) (xy 338.544151 -351.840515) (xy 338.508429 -351.88174)
			(xy 338.467203 -351.917461) (xy 338.421312 -351.946951) (xy 338.371692 -351.96961) (xy 338.319352 -351.984976)
			(xy 338.265358 -351.992738) (xy 338.238084 -351.9932) (xy 337.374484 -351.9932) (xy 337.347218 -351.992637)
			(xy 337.293242 -351.984874) (xy 337.240919 -351.969509) (xy 337.191316 -351.946854) (xy 337.145442 -351.91737)
			(xy 337.10423 -351.881659) (xy 337.06852 -351.840446) (xy 337.039039 -351.79457) (xy 337.016386 -351.744966)
			(xy 337.001023 -351.692643) (xy 336.993262 -351.638666) (xy 335.510414 -351.638666) (xy 335.510414 -351.638671)
			(xy 335.502652 -351.692658) (xy 335.487286 -351.744991) (xy 335.464629 -351.794604) (xy 335.435143 -351.840488)
			(xy 335.399427 -351.88171) (xy 335.358208 -351.917428) (xy 335.312325 -351.946918) (xy 335.262713 -351.969578)
			(xy 335.210381 -351.984947) (xy 335.156395 -351.992712) (xy 335.129124 -351.9932) (xy 334.265524 -351.9932)
			(xy 334.238255 -351.992662) (xy 334.18427 -351.984904) (xy 334.13194 -351.969541) (xy 334.082329 -351.946887)
			(xy 334.036447 -351.917403) (xy 333.995228 -351.881689) (xy 333.959511 -351.840472) (xy 333.930024 -351.794592)
			(xy 333.907367 -351.744982) (xy 333.892001 -351.692653) (xy 333.884239 -351.638669) (xy 332.401536 -351.638669)
			(xy 332.401536 -351.638675) (xy 332.393772 -351.692671) (xy 332.378403 -351.745011) (xy 332.35574 -351.794632)
			(xy 332.326246 -351.840522) (xy 332.290522 -351.881747) (xy 332.249293 -351.917468) (xy 332.2034 -351.946958)
			(xy 332.153778 -351.969615) (xy 332.101436 -351.98498) (xy 332.047439 -351.992739) (xy 332.020164 -351.9932)
			(xy 331.156564 -351.9932) (xy 331.129299 -351.992635) (xy 331.075325 -351.98487) (xy 331.023005 -351.969503)
			(xy 330.973404 -351.946847) (xy 330.927532 -351.917363) (xy 330.886323 -351.881652) (xy 330.850615 -351.840439)
			(xy 330.821136 -351.794564) (xy 330.798484 -351.744962) (xy 330.783122 -351.69264) (xy 330.775362 -351.638665)
			(xy 329.292513 -351.638665) (xy 329.292513 -351.638672) (xy 329.284751 -351.692661) (xy 329.269384 -351.744995)
			(xy 329.246726 -351.79461) (xy 329.217238 -351.840495) (xy 329.181519 -351.881717) (xy 329.140298 -351.917435)
			(xy 329.094413 -351.946924) (xy 329.044799 -351.969583) (xy 328.992464 -351.98495) (xy 328.938476 -351.992713)
			(xy 328.911204 -351.9932) (xy 328.047604 -351.9932) (xy 328.020336 -351.992661) (xy 327.966354 -351.9849)
			(xy 327.914026 -351.969536) (xy 327.864417 -351.94688) (xy 327.818537 -351.917396) (xy 327.777321 -351.881682)
			(xy 327.741607 -351.840466) (xy 327.712121 -351.794587) (xy 327.689466 -351.744978) (xy 327.674101 -351.69265)
			(xy 327.666339 -351.638668) (xy 326.183514 -351.638668) (xy 326.183514 -351.63867) (xy 326.175752 -351.692655)
			(xy 326.160388 -351.744986) (xy 326.137732 -351.794599) (xy 326.108248 -351.840482) (xy 326.072534 -351.881703)
			(xy 326.031317 -351.917421) (xy 325.985437 -351.946911) (xy 325.935828 -351.969572) (xy 325.883498 -351.984943)
			(xy 325.829514 -351.99271) (xy 325.802244 -351.9932) (xy 324.938644 -351.9932) (xy 324.911374 -351.992664)
			(xy 324.857387 -351.984907) (xy 324.805055 -351.969546) (xy 324.755441 -351.946894) (xy 324.709556 -351.91741)
			(xy 324.668335 -351.881696) (xy 324.632616 -351.840479) (xy 324.603128 -351.794598) (xy 324.580469 -351.744987)
			(xy 324.565102 -351.692656) (xy 324.55734 -351.63867) (xy 323.074636 -351.63867) (xy 323.074636 -351.638674)
			(xy 323.066873 -351.692668) (xy 323.051504 -351.745007) (xy 323.028843 -351.794626) (xy 322.999351 -351.840515)
			(xy 322.963629 -351.88174) (xy 322.922403 -351.917461) (xy 322.876512 -351.946951) (xy 322.826892 -351.96961)
			(xy 322.774552 -351.984976) (xy 322.720558 -351.992738) (xy 322.693284 -351.9932) (xy 321.829684 -351.9932)
			(xy 321.802418 -351.992637) (xy 321.748442 -351.984874) (xy 321.696119 -351.969509) (xy 321.646516 -351.946854)
			(xy 321.600642 -351.91737) (xy 321.55943 -351.881659) (xy 321.52372 -351.840446) (xy 321.494239 -351.79457)
			(xy 321.471586 -351.744966) (xy 321.456223 -351.692643) (xy 321.448462 -351.638666) (xy 319.965614 -351.638666)
			(xy 319.965614 -351.638671) (xy 319.957852 -351.692658) (xy 319.942486 -351.744991) (xy 319.919829 -351.794604)
			(xy 319.890343 -351.840488) (xy 319.854627 -351.88171) (xy 319.813408 -351.917428) (xy 319.767525 -351.946918)
			(xy 319.717913 -351.969578) (xy 319.665581 -351.984947) (xy 319.611595 -351.992712) (xy 319.584324 -351.9932)
			(xy 318.720724 -351.9932) (xy 318.693455 -351.992662) (xy 318.63947 -351.984904) (xy 318.58714 -351.969541)
			(xy 318.537529 -351.946887) (xy 318.491647 -351.917403) (xy 318.450428 -351.881689) (xy 318.414711 -351.840472)
			(xy 318.385224 -351.794592) (xy 318.362567 -351.744982) (xy 318.347201 -351.692653) (xy 318.339439 -351.638669)
			(xy 316.856736 -351.638669) (xy 316.856736 -351.638675) (xy 316.848972 -351.692671) (xy 316.833603 -351.745011)
			(xy 316.81094 -351.794632) (xy 316.781446 -351.840522) (xy 316.745722 -351.881747) (xy 316.704493 -351.917468)
			(xy 316.6586 -351.946958) (xy 316.608978 -351.969615) (xy 316.556636 -351.98498) (xy 316.502639 -351.992739)
			(xy 316.475364 -351.9932) (xy 315.611764 -351.9932) (xy 315.584499 -351.992635) (xy 315.530525 -351.98487)
			(xy 315.478205 -351.969503) (xy 315.428604 -351.946847) (xy 315.382732 -351.917363) (xy 315.341523 -351.881652)
			(xy 315.305815 -351.840439) (xy 315.276336 -351.794564) (xy 315.253684 -351.744962) (xy 315.238322 -351.69264)
			(xy 315.230562 -351.638665) (xy 313.747713 -351.638665) (xy 313.747713 -351.638672) (xy 313.739951 -351.692661)
			(xy 313.724584 -351.744995) (xy 313.701926 -351.79461) (xy 313.672438 -351.840495) (xy 313.636719 -351.881717)
			(xy 313.595498 -351.917435) (xy 313.549613 -351.946924) (xy 313.499999 -351.969583) (xy 313.447664 -351.98495)
			(xy 313.393676 -351.992713) (xy 313.366404 -351.9932) (xy 312.502804 -351.9932) (xy 312.475536 -351.992661)
			(xy 312.421554 -351.9849) (xy 312.369226 -351.969536) (xy 312.319617 -351.94688) (xy 312.273737 -351.917396)
			(xy 312.232521 -351.881682) (xy 312.196807 -351.840466) (xy 312.167321 -351.794587) (xy 312.144666 -351.744978)
			(xy 312.129301 -351.69265) (xy 312.121539 -351.638668) (xy 300.231613 -351.638668) (xy 300.231613 -351.638672)
			(xy 300.223851 -351.692661) (xy 300.208484 -351.744995) (xy 300.185826 -351.79461) (xy 300.156337 -351.840496)
			(xy 300.120619 -351.881717) (xy 300.079397 -351.917436) (xy 300.033512 -351.946925) (xy 299.983897 -351.969584)
			(xy 299.931563 -351.984951) (xy 299.877574 -351.992713) (xy 299.850302 -351.9932) (xy 298.986702 -351.9932)
			(xy 298.959434 -351.992661) (xy 298.905452 -351.9849) (xy 298.853124 -351.969535) (xy 298.803516 -351.94688)
			(xy 298.757636 -351.917395) (xy 298.71642 -351.881681) (xy 298.680706 -351.840465) (xy 298.651221 -351.794586)
			(xy 298.628566 -351.744978) (xy 298.613201 -351.69265) (xy 298.605439 -351.638668) (xy 297.122614 -351.638668)
			(xy 297.122614 -351.63867) (xy 297.114852 -351.692655) (xy 297.099488 -351.744987) (xy 297.076832 -351.794599)
			(xy 297.047347 -351.840483) (xy 297.011633 -351.881703) (xy 296.970416 -351.917422) (xy 296.924536 -351.946912)
			(xy 296.874926 -351.969573) (xy 296.822597 -351.984943) (xy 296.768612 -351.992711) (xy 296.741342 -351.9932)
			(xy 295.877742 -351.9932) (xy 295.850472 -351.992663) (xy 295.796486 -351.984907) (xy 295.744153 -351.969546)
			(xy 295.69454 -351.946893) (xy 295.648655 -351.917409) (xy 295.607434 -351.881695) (xy 295.571716 -351.840478)
			(xy 295.542227 -351.794597) (xy 295.519569 -351.744986) (xy 295.504202 -351.692655) (xy 295.49644 -351.63867)
			(xy 294.013736 -351.63867) (xy 294.013736 -351.638675) (xy 294.005973 -351.692668) (xy 293.990604 -351.745008)
			(xy 293.967943 -351.794627) (xy 293.938451 -351.840516) (xy 293.902728 -351.881741) (xy 293.861502 -351.917462)
			(xy 293.815611 -351.946952) (xy 293.765991 -351.969611) (xy 293.713651 -351.984977) (xy 293.659657 -351.992738)
			(xy 293.632382 -351.9932) (xy 292.768782 -351.9932) (xy 292.741516 -351.992636) (xy 292.68754 -351.984873)
			(xy 292.635218 -351.969508) (xy 292.585615 -351.946853) (xy 292.539741 -351.91737) (xy 292.498529 -351.881658)
			(xy 292.46282 -351.840445) (xy 292.433338 -351.794569) (xy 292.410686 -351.744965) (xy 292.395323 -351.692642)
			(xy 292.387562 -351.638666) (xy 290.904714 -351.638666) (xy 290.904714 -351.638671) (xy 290.896952 -351.692658)
			(xy 290.881586 -351.744991) (xy 290.858929 -351.794605) (xy 290.829442 -351.840489) (xy 290.793726 -351.88171)
			(xy 290.752507 -351.917429) (xy 290.706624 -351.946919) (xy 290.657012 -351.969578) (xy 290.60468 -351.984947)
			(xy 290.550693 -351.992712) (xy 290.523422 -351.9932) (xy 289.659822 -351.9932) (xy 289.632553 -351.992662)
			(xy 289.578569 -351.984903) (xy 289.526239 -351.96954) (xy 289.476628 -351.946886) (xy 289.430746 -351.917402)
			(xy 289.389527 -351.881688) (xy 289.353811 -351.840472) (xy 289.324324 -351.794592) (xy 289.301667 -351.744982)
			(xy 289.286301 -351.692653) (xy 289.278539 -351.638669) (xy 287.795836 -351.638669) (xy 287.795836 -351.638675)
			(xy 287.788072 -351.692671) (xy 287.772703 -351.745012) (xy 287.75004 -351.794633) (xy 287.720546 -351.840523)
			(xy 287.684821 -351.881748) (xy 287.643592 -351.917469) (xy 287.597699 -351.946958) (xy 287.548076 -351.969616)
			(xy 287.495734 -351.98498) (xy 287.441737 -351.992739) (xy 287.414462 -351.9932) (xy 286.550862 -351.9932)
			(xy 286.523597 -351.992635) (xy 286.469623 -351.98487) (xy 286.417303 -351.969503) (xy 286.367703 -351.946847)
			(xy 286.321831 -351.917363) (xy 286.280622 -351.881651) (xy 286.244915 -351.840438) (xy 286.215435 -351.794564)
			(xy 286.192784 -351.744961) (xy 286.177422 -351.69264) (xy 286.169662 -351.638665) (xy 284.686813 -351.638665)
			(xy 284.686813 -351.638672) (xy 284.679051 -351.692661) (xy 284.663684 -351.744995) (xy 284.641026 -351.79461)
			(xy 284.611537 -351.840496) (xy 284.575819 -351.881717) (xy 284.534597 -351.917436) (xy 284.488712 -351.946925)
			(xy 284.439097 -351.969584) (xy 284.386763 -351.984951) (xy 284.332774 -351.992713) (xy 284.305502 -351.9932)
			(xy 283.441902 -351.9932) (xy 283.414634 -351.992661) (xy 283.360652 -351.9849) (xy 283.308324 -351.969535)
			(xy 283.258716 -351.94688) (xy 283.212836 -351.917395) (xy 283.17162 -351.881681) (xy 283.135906 -351.840465)
			(xy 283.106421 -351.794586) (xy 283.083766 -351.744978) (xy 283.068401 -351.69265) (xy 283.060639 -351.638668)
			(xy 281.577814 -351.638668) (xy 281.577814 -351.63867) (xy 281.570052 -351.692655) (xy 281.554688 -351.744987)
			(xy 281.532032 -351.794599) (xy 281.502547 -351.840483) (xy 281.466833 -351.881703) (xy 281.425616 -351.917422)
			(xy 281.379736 -351.946912) (xy 281.330126 -351.969573) (xy 281.277797 -351.984943) (xy 281.223812 -351.992711)
			(xy 281.196542 -351.9932) (xy 280.332942 -351.9932) (xy 280.305672 -351.992663) (xy 280.251686 -351.984907)
			(xy 280.199353 -351.969546) (xy 280.14974 -351.946893) (xy 280.103855 -351.917409) (xy 280.062634 -351.881695)
			(xy 280.026916 -351.840478) (xy 279.997427 -351.794597) (xy 279.974769 -351.744986) (xy 279.959402 -351.692655)
			(xy 279.95164 -351.63867) (xy 278.468936 -351.63867) (xy 278.468936 -351.638675) (xy 278.461173 -351.692668)
			(xy 278.445804 -351.745008) (xy 278.423143 -351.794627) (xy 278.393651 -351.840516) (xy 278.357928 -351.881741)
			(xy 278.316702 -351.917462) (xy 278.270811 -351.946952) (xy 278.221191 -351.969611) (xy 278.168851 -351.984977)
			(xy 278.114857 -351.992738) (xy 278.087582 -351.9932) (xy 277.223982 -351.9932) (xy 277.196716 -351.992636)
			(xy 277.14274 -351.984873) (xy 277.090418 -351.969508) (xy 277.040815 -351.946853) (xy 276.994941 -351.91737)
			(xy 276.953729 -351.881658) (xy 276.91802 -351.840445) (xy 276.888538 -351.794569) (xy 276.865886 -351.744965)
			(xy 276.850523 -351.692642) (xy 276.842762 -351.638666) (xy 275.359914 -351.638666) (xy 275.359914 -351.638671)
			(xy 275.352152 -351.692658) (xy 275.336786 -351.744991) (xy 275.314129 -351.794605) (xy 275.284642 -351.840489)
			(xy 275.248926 -351.88171) (xy 275.207707 -351.917429) (xy 275.161824 -351.946919) (xy 275.112212 -351.969578)
			(xy 275.05988 -351.984947) (xy 275.005893 -351.992712) (xy 274.978622 -351.9932) (xy 274.115022 -351.9932)
			(xy 274.087753 -351.992662) (xy 274.033769 -351.984903) (xy 273.981439 -351.96954) (xy 273.931828 -351.946886)
			(xy 273.885946 -351.917402) (xy 273.844727 -351.881688) (xy 273.809011 -351.840472) (xy 273.779524 -351.794592)
			(xy 273.756867 -351.744982) (xy 273.741501 -351.692653) (xy 273.733739 -351.638669) (xy 272.251036 -351.638669)
			(xy 272.251036 -351.638675) (xy 272.243272 -351.692671) (xy 272.227903 -351.745012) (xy 272.20524 -351.794633)
			(xy 272.175746 -351.840523) (xy 272.140021 -351.881748) (xy 272.098792 -351.917469) (xy 272.052899 -351.946958)
			(xy 272.003276 -351.969616) (xy 271.950934 -351.98498) (xy 271.896937 -351.992739) (xy 271.869662 -351.9932)
			(xy 271.006062 -351.9932) (xy 270.978797 -351.992635) (xy 270.924823 -351.98487) (xy 270.872503 -351.969503)
			(xy 270.822903 -351.946847) (xy 270.777031 -351.917363) (xy 270.735822 -351.881651) (xy 270.700115 -351.840438)
			(xy 270.670635 -351.794564) (xy 270.647984 -351.744961) (xy 270.632622 -351.69264) (xy 270.624862 -351.638665)
			(xy 269.142013 -351.638665) (xy 269.142013 -351.638672) (xy 269.134251 -351.692661) (xy 269.118884 -351.744995)
			(xy 269.096226 -351.79461) (xy 269.066737 -351.840496) (xy 269.031019 -351.881717) (xy 268.989797 -351.917436)
			(xy 268.943912 -351.946925) (xy 268.894297 -351.969584) (xy 268.841963 -351.984951) (xy 268.787974 -351.992713)
			(xy 268.760702 -351.9932) (xy 267.897102 -351.9932) (xy 267.869834 -351.992661) (xy 267.815852 -351.9849)
			(xy 267.763524 -351.969535) (xy 267.713916 -351.94688) (xy 267.668036 -351.917395) (xy 267.62682 -351.881681)
			(xy 267.591106 -351.840465) (xy 267.561621 -351.794586) (xy 267.538966 -351.744978) (xy 267.523601 -351.69265)
			(xy 267.515839 -351.638668) (xy 216.123526 -351.638668) (xy 216.080368 -351.642889) (xy 215.896274 -351.652871)
			(xy 215.71192 -351.654868) (xy 215.527653 -351.648877) (xy 215.343818 -351.63491) (xy 215.160761 -351.612992)
			(xy 214.978825 -351.583165) (xy 214.798352 -351.545485) (xy 214.619681 -351.500023) (xy 214.443147 -351.446863)
			(xy 214.269081 -351.386106) (xy 214.097811 -351.317866) (xy 213.929657 -351.24227) (xy 213.764936 -351.159461)
			(xy 213.603957 -351.069595) (xy 213.447022 -350.972839) (xy 213.294425 -350.869376) (xy 213.146454 -350.7594)
			(xy 213.003386 -350.643117) (xy 212.865489 -350.520746) (xy 212.733022 -350.392516) (xy 212.606235 -350.258668)
			(xy 212.485365 -350.119454) (xy 212.370638 -349.975134) (xy 212.262272 -349.82598) (xy 212.160468 -349.672272)
			(xy 212.065418 -349.514298) (xy 211.977301 -349.352354) (xy 211.896281 -349.186746) (xy 211.822512 -349.017783)
			(xy 211.756131 -348.845784) (xy 211.697263 -348.67107) (xy 211.646018 -348.49397) (xy 211.602494 -348.314817)
			(xy 211.566771 -348.133947) (xy 211.538917 -347.951698) (xy 211.518984 -347.768415) (xy 211.507009 -347.584439)
			(xy 211.503015 -347.400118) (xy 8.25588 -347.400118) (xy 8.309695 -347.452301) (xy 8.396695 -347.547736)
			(xy 8.477656 -347.648346) (xy 8.55227 -347.753749) (xy 8.620253 -347.863546) (xy 8.681348 -347.97732)
			(xy 8.735323 -348.094639) (xy 8.781974 -348.215058) (xy 8.821123 -348.338121) (xy 8.852622 -348.46336)
			(xy 8.876351 -348.590301) (xy 8.879169 -348.613059) (xy 18.951174 -348.613059) (xy 18.951174 -348.558521)
			(xy 18.958936 -348.504537) (xy 18.974301 -348.452208) (xy 18.996957 -348.402598) (xy 19.026443 -348.356717)
			(xy 19.062158 -348.315499) (xy 19.103375 -348.279784) (xy 19.149256 -348.250298) (xy 19.198866 -348.227642)
			(xy 19.251195 -348.212276) (xy 19.305179 -348.204515) (xy 19.332448 -348.204028) (xy 20.196048 -348.204028)
			(xy 20.223319 -348.204491) (xy 20.277306 -348.212253) (xy 20.329639 -348.227619) (xy 20.379253 -348.250277)
			(xy 20.425136 -348.279764) (xy 20.466357 -348.315482) (xy 20.502074 -348.356702) (xy 20.531562 -348.402586)
			(xy 20.55422 -348.452199) (xy 20.569586 -348.504532) (xy 20.577349 -348.558519) (xy 20.577349 -348.613061)
			(xy 20.577347 -348.613072) (xy 22.060092 -348.613072) (xy 22.060092 -348.558528) (xy 22.067854 -348.504539)
			(xy 22.083221 -348.452204) (xy 22.10588 -348.402589) (xy 22.135369 -348.356704) (xy 22.171088 -348.315483)
			(xy 22.21231 -348.279764) (xy 22.258196 -348.250276) (xy 22.307812 -348.227618) (xy 22.360147 -348.212252)
			(xy 22.414136 -348.204491) (xy 22.441408 -348.204028) (xy 23.305008 -348.204028) (xy 23.332276 -348.204535)
			(xy 23.386258 -348.212297) (xy 23.438585 -348.227663) (xy 23.488193 -348.250319) (xy 23.534071 -348.279804)
			(xy 23.575287 -348.315519) (xy 23.611 -348.356735) (xy 23.640485 -348.402614) (xy 23.66314 -348.452223)
			(xy 23.678504 -348.50455) (xy 23.686266 -348.558532) (xy 23.686266 -348.613068) (xy 23.686266 -348.613069)
			(xy 25.169114 -348.613069) (xy 25.169114 -348.558531) (xy 25.176875 -348.504549) (xy 25.19224 -348.452221)
			(xy 25.214894 -348.402611) (xy 25.244378 -348.356731) (xy 25.28009 -348.315513) (xy 25.321305 -348.279797)
			(xy 25.367183 -348.250309) (xy 25.416791 -348.227651) (xy 25.469118 -348.212282) (xy 25.523099 -348.204517)
			(xy 25.550368 -348.204028) (xy 26.413968 -348.204028) (xy 26.44124 -348.204509) (xy 26.495229 -348.212268)
			(xy 26.547564 -348.227631) (xy 26.59718 -348.250286) (xy 26.643066 -348.279772) (xy 26.684289 -348.315488)
			(xy 26.720009 -348.356708) (xy 26.749499 -348.402592) (xy 26.772158 -348.452206) (xy 26.787526 -348.50454)
			(xy 26.795288 -348.558528) (xy 26.795288 -348.613072) (xy 26.795288 -348.613073) (xy 28.277992 -348.613073)
			(xy 28.277992 -348.558527) (xy 28.285755 -348.504536) (xy 28.301123 -348.4522) (xy 28.323783 -348.402584)
			(xy 28.353274 -348.356697) (xy 28.388995 -348.315476) (xy 28.43022 -348.279757) (xy 28.476108 -348.25027)
			(xy 28.525726 -348.227613) (xy 28.578064 -348.212249) (xy 28.632055 -348.20449) (xy 28.659328 -348.204028)
			(xy 29.522928 -348.204028) (xy 29.550195 -348.204536) (xy 29.604175 -348.212301) (xy 29.656499 -348.227668)
			(xy 29.706105 -348.250326) (xy 29.751981 -348.279811) (xy 29.793194 -348.315526) (xy 29.828905 -348.356742)
			(xy 29.858388 -348.40262) (xy 29.881041 -348.452227) (xy 29.896405 -348.504553) (xy 29.904166 -348.558533)
			(xy 29.904166 -348.613067) (xy 29.904166 -348.61307) (xy 31.387014 -348.61307) (xy 31.387014 -348.55853)
			(xy 31.394776 -348.504546) (xy 31.410141 -348.452217) (xy 31.432797 -348.402606) (xy 31.462283 -348.356724)
			(xy 31.497997 -348.315506) (xy 31.539215 -348.27979) (xy 31.585095 -348.250303) (xy 31.634705 -348.227645)
			(xy 31.687035 -348.212279) (xy 31.741018 -348.204515) (xy 31.768288 -348.204028) (xy 32.631888 -348.204028)
			(xy 32.659159 -348.204511) (xy 32.713146 -348.212271) (xy 32.765478 -348.227636) (xy 32.815092 -348.250292)
			(xy 32.860976 -348.279779) (xy 32.902196 -348.315495) (xy 32.937914 -348.356715) (xy 32.967402 -348.402598)
			(xy 32.99006 -348.45221) (xy 33.005426 -348.504543) (xy 33.013189 -348.558529) (xy 33.013189 -348.613071)
			(xy 33.013189 -348.613074) (xy 34.495892 -348.613074) (xy 34.495892 -348.558526) (xy 34.503655 -348.504534)
			(xy 34.519024 -348.452196) (xy 34.541686 -348.402578) (xy 34.571179 -348.356691) (xy 34.606902 -348.315468)
			(xy 34.648129 -348.27975) (xy 34.69402 -348.250263) (xy 34.743641 -348.227608) (xy 34.795981 -348.212245)
			(xy 34.849974 -348.204488) (xy 34.877248 -348.204028) (xy 35.740848 -348.204028) (xy 35.768114 -348.204538)
			(xy 35.822091 -348.212305) (xy 35.874414 -348.227674) (xy 35.924017 -348.250332) (xy 35.96989 -348.279819)
			(xy 36.011101 -348.315533) (xy 36.04681 -348.356748) (xy 36.076291 -348.402626) (xy 36.098943 -348.452231)
			(xy 36.114306 -348.504556) (xy 36.122066 -348.558534) (xy 36.122066 -348.613066) (xy 36.122065 -348.613072)
			(xy 37.604892 -348.613072) (xy 37.604892 -348.558528) (xy 37.612654 -348.504539) (xy 37.628021 -348.452204)
			(xy 37.65068 -348.402589) (xy 37.680169 -348.356704) (xy 37.715888 -348.315483) (xy 37.75711 -348.279764)
			(xy 37.802996 -348.250276) (xy 37.852612 -348.227618) (xy 37.904947 -348.212252) (xy 37.958936 -348.204491)
			(xy 37.986208 -348.204028) (xy 38.849808 -348.204028) (xy 38.877076 -348.204535) (xy 38.931058 -348.212297)
			(xy 38.983385 -348.227663) (xy 39.032993 -348.250319) (xy 39.078871 -348.279804) (xy 39.120087 -348.315519)
			(xy 39.1558 -348.356735) (xy 39.185285 -348.402614) (xy 39.20794 -348.452223) (xy 39.223304 -348.50455)
			(xy 39.231066 -348.558532) (xy 39.231066 -348.613068) (xy 39.231066 -348.613069) (xy 40.713914 -348.613069)
			(xy 40.713914 -348.558531) (xy 40.721675 -348.504549) (xy 40.73704 -348.452221) (xy 40.759694 -348.402611)
			(xy 40.789178 -348.356731) (xy 40.82489 -348.315513) (xy 40.866105 -348.279797) (xy 40.911983 -348.250309)
			(xy 40.961591 -348.227651) (xy 41.013918 -348.212282) (xy 41.067899 -348.204517) (xy 41.095168 -348.204028)
			(xy 41.958768 -348.204028) (xy 41.98604 -348.204509) (xy 42.040029 -348.212268) (xy 42.092364 -348.227631)
			(xy 42.14198 -348.250286) (xy 42.187866 -348.279772) (xy 42.229089 -348.315488) (xy 42.264809 -348.356708)
			(xy 42.294299 -348.402592) (xy 42.316958 -348.452206) (xy 42.332326 -348.50454) (xy 42.340088 -348.558528)
			(xy 42.340088 -348.613072) (xy 42.340088 -348.613073) (xy 43.822792 -348.613073) (xy 43.822792 -348.558527)
			(xy 43.830555 -348.504536) (xy 43.845923 -348.4522) (xy 43.868583 -348.402584) (xy 43.898074 -348.356697)
			(xy 43.933795 -348.315476) (xy 43.97502 -348.279757) (xy 44.020908 -348.25027) (xy 44.070526 -348.227613)
			(xy 44.122864 -348.212249) (xy 44.176855 -348.20449) (xy 44.204128 -348.204028) (xy 45.067728 -348.204028)
			(xy 45.094995 -348.204536) (xy 45.148975 -348.212301) (xy 45.201299 -348.227668) (xy 45.250905 -348.250326)
			(xy 45.296781 -348.279811) (xy 45.337994 -348.315526) (xy 45.373705 -348.356742) (xy 45.403188 -348.40262)
			(xy 45.425841 -348.452227) (xy 45.441205 -348.504553) (xy 45.448966 -348.558533) (xy 45.448966 -348.613067)
			(xy 45.448966 -348.61307) (xy 46.931814 -348.61307) (xy 46.931814 -348.55853) (xy 46.939576 -348.504546)
			(xy 46.954941 -348.452217) (xy 46.977597 -348.402606) (xy 47.007083 -348.356724) (xy 47.042797 -348.315506)
			(xy 47.084015 -348.27979) (xy 47.129895 -348.250303) (xy 47.179505 -348.227645) (xy 47.231835 -348.212279)
			(xy 47.285818 -348.204515) (xy 47.313088 -348.204028) (xy 48.176688 -348.204028) (xy 48.203959 -348.204511)
			(xy 48.257946 -348.212271) (xy 48.310278 -348.227636) (xy 48.359892 -348.250292) (xy 48.405776 -348.279779)
			(xy 48.446996 -348.315495) (xy 48.482714 -348.356715) (xy 48.512202 -348.402598) (xy 48.53486 -348.45221)
			(xy 48.550226 -348.504543) (xy 48.557989 -348.558529) (xy 48.557989 -348.613071) (xy 48.557989 -348.613074)
			(xy 50.040692 -348.613074) (xy 50.040692 -348.558526) (xy 50.048455 -348.504534) (xy 50.063824 -348.452196)
			(xy 50.086486 -348.402578) (xy 50.115979 -348.356691) (xy 50.151702 -348.315468) (xy 50.192929 -348.27975)
			(xy 50.23882 -348.250263) (xy 50.288441 -348.227608) (xy 50.340781 -348.212245) (xy 50.394774 -348.204488)
			(xy 50.422048 -348.204028) (xy 51.285648 -348.204028) (xy 51.312914 -348.204538) (xy 51.366891 -348.212305)
			(xy 51.419214 -348.227674) (xy 51.468817 -348.250332) (xy 51.51469 -348.279819) (xy 51.555901 -348.315533)
			(xy 51.59161 -348.356748) (xy 51.621091 -348.402626) (xy 51.643743 -348.452231) (xy 51.659106 -348.504556)
			(xy 51.666866 -348.558534) (xy 51.666866 -348.613066) (xy 51.666865 -348.613074) (xy 60.990892 -348.613074)
			(xy 60.990892 -348.558526) (xy 60.998655 -348.504534) (xy 61.014024 -348.452197) (xy 61.036685 -348.40258)
			(xy 61.066177 -348.356693) (xy 61.1019 -348.315471) (xy 61.143127 -348.279752) (xy 61.189017 -348.250265)
			(xy 61.238636 -348.227609) (xy 61.290976 -348.212246) (xy 61.344968 -348.204489) (xy 61.372242 -348.204028)
			(xy 62.235842 -348.204028) (xy 62.263109 -348.204537) (xy 62.317086 -348.212304) (xy 62.369409 -348.227672)
			(xy 62.419013 -348.25033) (xy 62.464887 -348.279816) (xy 62.506099 -348.315531) (xy 62.541809 -348.356746)
			(xy 62.57129 -348.402624) (xy 62.593943 -348.45223) (xy 62.609305 -348.504555) (xy 62.617066 -348.558533)
			(xy 62.617066 -348.613067) (xy 62.617065 -348.613072) (xy 64.099892 -348.613072) (xy 64.099892 -348.558528)
			(xy 64.107654 -348.50454) (xy 64.123021 -348.452206) (xy 64.145679 -348.402591) (xy 64.175168 -348.356706)
			(xy 64.210886 -348.315485) (xy 64.252108 -348.279766) (xy 64.297993 -348.250278) (xy 64.347607 -348.22762)
			(xy 64.399942 -348.212253) (xy 64.45393 -348.204491) (xy 64.481202 -348.204028) (xy 65.344802 -348.204028)
			(xy 65.372071 -348.204535) (xy 65.426053 -348.212296) (xy 65.47838 -348.227661) (xy 65.527989 -348.250317)
			(xy 65.573869 -348.279802) (xy 65.615085 -348.315517) (xy 65.650799 -348.356733) (xy 65.680284 -348.402613)
			(xy 65.702939 -348.452221) (xy 65.718304 -348.504549) (xy 65.726066 -348.558531) (xy 65.726066 -348.613068)
			(xy 67.208914 -348.613068) (xy 67.208914 -348.558532) (xy 67.216675 -348.50455) (xy 67.232039 -348.452222)
			(xy 67.254693 -348.402613) (xy 67.284176 -348.356733) (xy 67.319888 -348.315515) (xy 67.361102 -348.279799)
			(xy 67.40698 -348.250311) (xy 67.456586 -348.227652) (xy 67.508913 -348.212283) (xy 67.562894 -348.204517)
			(xy 67.590162 -348.204028) (xy 68.453762 -348.204028) (xy 68.481034 -348.204509) (xy 68.535024 -348.212266)
			(xy 68.58736 -348.227629) (xy 68.636976 -348.250284) (xy 68.682863 -348.27977) (xy 68.724087 -348.315486)
			(xy 68.759808 -348.356706) (xy 68.789298 -348.40259) (xy 68.811958 -348.452205) (xy 68.827326 -348.504539)
			(xy 68.835088 -348.558528) (xy 68.835088 -348.613072) (xy 68.835088 -348.613073) (xy 70.317792 -348.613073)
			(xy 70.317792 -348.558527) (xy 70.325554 -348.504537) (xy 70.340922 -348.452201) (xy 70.363582 -348.402585)
			(xy 70.393072 -348.356699) (xy 70.428793 -348.315478) (xy 70.470017 -348.279759) (xy 70.515905 -348.250271)
			(xy 70.565522 -348.227615) (xy 70.617859 -348.21225) (xy 70.671849 -348.20449) (xy 70.699122 -348.204028)
			(xy 71.562722 -348.204028) (xy 71.58999 -348.204536) (xy 71.643969 -348.2123) (xy 71.696295 -348.227667)
			(xy 71.745901 -348.250324) (xy 71.791778 -348.279809) (xy 71.832992 -348.315524) (xy 71.868704 -348.35674)
			(xy 71.898187 -348.402618) (xy 71.920841 -348.452226) (xy 71.936205 -348.504552) (xy 71.943966 -348.558532)
			(xy 71.943966 -348.613068) (xy 71.943966 -348.613069) (xy 73.426814 -348.613069) (xy 73.426814 -348.558531)
			(xy 73.434576 -348.504547) (xy 73.449941 -348.452218) (xy 73.472596 -348.402608) (xy 73.502081 -348.356726)
			(xy 73.537795 -348.315508) (xy 73.579012 -348.279792) (xy 73.624892 -348.250305) (xy 73.674501 -348.227647)
			(xy 73.72683 -348.21228) (xy 73.780813 -348.204516) (xy 73.808082 -348.204028) (xy 74.671682 -348.204028)
			(xy 74.698953 -348.20451) (xy 74.752941 -348.21227) (xy 74.805274 -348.227634) (xy 74.854888 -348.25029)
			(xy 74.900773 -348.279777) (xy 74.941994 -348.315493) (xy 74.977712 -348.356713) (xy 75.007201 -348.402596)
			(xy 75.029859 -348.452209) (xy 75.045226 -348.504542) (xy 75.052988 -348.558529) (xy 75.052988 -348.613071)
			(xy 75.052988 -348.613074) (xy 76.535692 -348.613074) (xy 76.535692 -348.558526) (xy 76.543455 -348.504534)
			(xy 76.558824 -348.452197) (xy 76.581485 -348.40258) (xy 76.610977 -348.356693) (xy 76.6467 -348.315471)
			(xy 76.687927 -348.279752) (xy 76.733817 -348.250265) (xy 76.783436 -348.227609) (xy 76.835776 -348.212246)
			(xy 76.889768 -348.204489) (xy 76.917042 -348.204028) (xy 77.780642 -348.204028) (xy 77.807909 -348.204537)
			(xy 77.861886 -348.212304) (xy 77.914209 -348.227672) (xy 77.963813 -348.25033) (xy 78.009687 -348.279816)
			(xy 78.050899 -348.315531) (xy 78.086609 -348.356746) (xy 78.11609 -348.402624) (xy 78.138743 -348.45223)
			(xy 78.154105 -348.504555) (xy 78.161866 -348.558533) (xy 78.161866 -348.613067) (xy 78.161865 -348.613072)
			(xy 79.644692 -348.613072) (xy 79.644692 -348.558528) (xy 79.652454 -348.50454) (xy 79.667821 -348.452206)
			(xy 79.690479 -348.402591) (xy 79.719968 -348.356706) (xy 79.755686 -348.315485) (xy 79.796908 -348.279766)
			(xy 79.842793 -348.250278) (xy 79.892407 -348.22762) (xy 79.944742 -348.212253) (xy 79.99873 -348.204491)
			(xy 80.026002 -348.204028) (xy 80.889602 -348.204028) (xy 80.916871 -348.204535) (xy 80.970853 -348.212296)
			(xy 81.02318 -348.227661) (xy 81.072789 -348.250317) (xy 81.118669 -348.279802) (xy 81.159885 -348.315517)
			(xy 81.195599 -348.356733) (xy 81.225084 -348.402613) (xy 81.247739 -348.452221) (xy 81.263104 -348.504549)
			(xy 81.270866 -348.558531) (xy 81.270866 -348.613068) (xy 82.753714 -348.613068) (xy 82.753714 -348.558532)
			(xy 82.761475 -348.50455) (xy 82.776839 -348.452222) (xy 82.799493 -348.402613) (xy 82.828976 -348.356733)
			(xy 82.864688 -348.315515) (xy 82.905902 -348.279799) (xy 82.95178 -348.250311) (xy 83.001386 -348.227652)
			(xy 83.053713 -348.212283) (xy 83.107694 -348.204517) (xy 83.134962 -348.204028) (xy 83.998562 -348.204028)
			(xy 84.025834 -348.204509) (xy 84.079824 -348.212266) (xy 84.13216 -348.227629) (xy 84.181776 -348.250284)
			(xy 84.227663 -348.27977) (xy 84.268887 -348.315486) (xy 84.304608 -348.356706) (xy 84.334098 -348.40259)
			(xy 84.356758 -348.452205) (xy 84.372126 -348.504539) (xy 84.379888 -348.558528) (xy 84.379888 -348.613072)
			(xy 84.379888 -348.613073) (xy 85.862592 -348.613073) (xy 85.862592 -348.558527) (xy 85.870354 -348.504537)
			(xy 85.885722 -348.452201) (xy 85.908382 -348.402585) (xy 85.937872 -348.356699) (xy 85.973593 -348.315478)
			(xy 86.014817 -348.279759) (xy 86.060705 -348.250271) (xy 86.110322 -348.227615) (xy 86.162659 -348.21225)
			(xy 86.216649 -348.20449) (xy 86.243922 -348.204028) (xy 87.107522 -348.204028) (xy 87.13479 -348.204536)
			(xy 87.188769 -348.2123) (xy 87.241095 -348.227667) (xy 87.290701 -348.250324) (xy 87.336578 -348.279809)
			(xy 87.377792 -348.315524) (xy 87.413504 -348.35674) (xy 87.442987 -348.402618) (xy 87.465641 -348.452226)
			(xy 87.481005 -348.504552) (xy 87.488766 -348.558532) (xy 87.488766 -348.613068) (xy 87.488766 -348.613069)
			(xy 88.971614 -348.613069) (xy 88.971614 -348.558531) (xy 88.979376 -348.504547) (xy 88.994741 -348.452218)
			(xy 89.017396 -348.402608) (xy 89.046881 -348.356726) (xy 89.082595 -348.315508) (xy 89.123812 -348.279792)
			(xy 89.169692 -348.250305) (xy 89.219301 -348.227647) (xy 89.27163 -348.21228) (xy 89.325613 -348.204516)
			(xy 89.352882 -348.204028) (xy 90.216482 -348.204028) (xy 90.243753 -348.20451) (xy 90.297741 -348.21227)
			(xy 90.350074 -348.227634) (xy 90.399688 -348.25029) (xy 90.445573 -348.279777) (xy 90.486794 -348.315493)
			(xy 90.522512 -348.356713) (xy 90.552001 -348.402596) (xy 90.574659 -348.452209) (xy 90.590026 -348.504542)
			(xy 90.597788 -348.558529) (xy 90.597788 -348.613071) (xy 90.597788 -348.613074) (xy 92.080492 -348.613074)
			(xy 92.080492 -348.558526) (xy 92.088255 -348.504534) (xy 92.103624 -348.452197) (xy 92.126285 -348.40258)
			(xy 92.155777 -348.356693) (xy 92.1915 -348.315471) (xy 92.232727 -348.279752) (xy 92.278617 -348.250265)
			(xy 92.328236 -348.227609) (xy 92.380576 -348.212246) (xy 92.434568 -348.204489) (xy 92.461842 -348.204028)
			(xy 93.325442 -348.204028) (xy 93.352709 -348.204537) (xy 93.406686 -348.212304) (xy 93.459009 -348.227672)
			(xy 93.508613 -348.25033) (xy 93.554487 -348.279816) (xy 93.595699 -348.315531) (xy 93.631409 -348.356746)
			(xy 93.66089 -348.402624) (xy 93.683543 -348.45223) (xy 93.698905 -348.504555) (xy 93.706666 -348.558533)
			(xy 93.706666 -348.613067) (xy 93.706665 -348.613072) (xy 111.480792 -348.613072) (xy 111.480792 -348.558528)
			(xy 111.488554 -348.504539) (xy 111.503921 -348.452204) (xy 111.52658 -348.402589) (xy 111.556069 -348.356704)
			(xy 111.591788 -348.315483) (xy 111.63301 -348.279764) (xy 111.678896 -348.250276) (xy 111.728512 -348.227618)
			(xy 111.780847 -348.212252) (xy 111.834836 -348.204491) (xy 111.862108 -348.204028) (xy 112.725708 -348.204028)
			(xy 112.752976 -348.204535) (xy 112.806958 -348.212297) (xy 112.859285 -348.227663) (xy 112.908893 -348.250319)
			(xy 112.954771 -348.279804) (xy 112.995987 -348.315519) (xy 113.0317 -348.356735) (xy 113.061185 -348.402614)
			(xy 113.08384 -348.452223) (xy 113.099204 -348.50455) (xy 113.106966 -348.558532) (xy 113.106966 -348.613068)
			(xy 113.106966 -348.613069) (xy 114.589814 -348.613069) (xy 114.589814 -348.558531) (xy 114.597575 -348.504549)
			(xy 114.61294 -348.452221) (xy 114.635594 -348.402611) (xy 114.665078 -348.356731) (xy 114.70079 -348.315513)
			(xy 114.742005 -348.279797) (xy 114.787883 -348.250309) (xy 114.837491 -348.227651) (xy 114.889818 -348.212282)
			(xy 114.943799 -348.204517) (xy 114.971068 -348.204028) (xy 115.834668 -348.204028) (xy 115.86194 -348.204509)
			(xy 115.915929 -348.212268) (xy 115.968264 -348.227631) (xy 116.01788 -348.250286) (xy 116.063766 -348.279772)
			(xy 116.104989 -348.315488) (xy 116.140709 -348.356708) (xy 116.170199 -348.402592) (xy 116.192858 -348.452206)
			(xy 116.208226 -348.50454) (xy 116.215988 -348.558528) (xy 116.215988 -348.613072) (xy 116.215988 -348.613073)
			(xy 117.698692 -348.613073) (xy 117.698692 -348.558527) (xy 117.706455 -348.504536) (xy 117.721823 -348.4522)
			(xy 117.744483 -348.402584) (xy 117.773974 -348.356697) (xy 117.809695 -348.315476) (xy 117.85092 -348.279757)
			(xy 117.896808 -348.25027) (xy 117.946426 -348.227613) (xy 117.998764 -348.212249) (xy 118.052755 -348.20449)
			(xy 118.080028 -348.204028) (xy 118.943628 -348.204028) (xy 118.970895 -348.204536) (xy 119.024875 -348.212301)
			(xy 119.077199 -348.227668) (xy 119.126805 -348.250326) (xy 119.172681 -348.279811) (xy 119.213894 -348.315526)
			(xy 119.249605 -348.356742) (xy 119.279088 -348.40262) (xy 119.301741 -348.452227) (xy 119.317105 -348.504553)
			(xy 119.324866 -348.558533) (xy 119.324866 -348.613067) (xy 119.324866 -348.61307) (xy 120.807714 -348.61307)
			(xy 120.807714 -348.55853) (xy 120.815476 -348.504546) (xy 120.830841 -348.452217) (xy 120.853497 -348.402606)
			(xy 120.882983 -348.356724) (xy 120.918697 -348.315506) (xy 120.959915 -348.27979) (xy 121.005795 -348.250303)
			(xy 121.055405 -348.227645) (xy 121.107735 -348.212279) (xy 121.161718 -348.204515) (xy 121.188988 -348.204028)
			(xy 122.052588 -348.204028) (xy 122.079859 -348.204511) (xy 122.133846 -348.212271) (xy 122.186178 -348.227636)
			(xy 122.235792 -348.250292) (xy 122.281676 -348.279779) (xy 122.322896 -348.315495) (xy 122.358614 -348.356715)
			(xy 122.388102 -348.402598) (xy 122.41076 -348.45221) (xy 122.426126 -348.504543) (xy 122.433889 -348.558529)
			(xy 122.433889 -348.613071) (xy 122.433889 -348.613074) (xy 123.916592 -348.613074) (xy 123.916592 -348.558526)
			(xy 123.924355 -348.504534) (xy 123.939724 -348.452196) (xy 123.962386 -348.402578) (xy 123.991879 -348.356691)
			(xy 124.027602 -348.315468) (xy 124.068829 -348.27975) (xy 124.11472 -348.250263) (xy 124.164341 -348.227608)
			(xy 124.216681 -348.212245) (xy 124.270674 -348.204488) (xy 124.297948 -348.204028) (xy 125.161548 -348.204028)
			(xy 125.188814 -348.204538) (xy 125.242791 -348.212305) (xy 125.295114 -348.227674) (xy 125.344717 -348.250332)
			(xy 125.39059 -348.279819) (xy 125.431801 -348.315533) (xy 125.46751 -348.356748) (xy 125.496991 -348.402626)
			(xy 125.519643 -348.452231) (xy 125.535006 -348.504556) (xy 125.542766 -348.558534) (xy 125.542766 -348.613066)
			(xy 125.542765 -348.613072) (xy 127.025592 -348.613072) (xy 127.025592 -348.558528) (xy 127.033354 -348.504539)
			(xy 127.048721 -348.452204) (xy 127.07138 -348.402589) (xy 127.100869 -348.356704) (xy 127.136588 -348.315483)
			(xy 127.17781 -348.279764) (xy 127.223696 -348.250276) (xy 127.273312 -348.227618) (xy 127.325647 -348.212252)
			(xy 127.379636 -348.204491) (xy 127.406908 -348.204028) (xy 128.270508 -348.204028) (xy 128.297776 -348.204535)
			(xy 128.351758 -348.212297) (xy 128.404085 -348.227663) (xy 128.453693 -348.250319) (xy 128.499571 -348.279804)
			(xy 128.540787 -348.315519) (xy 128.5765 -348.356735) (xy 128.605985 -348.402614) (xy 128.62864 -348.452223)
			(xy 128.644004 -348.50455) (xy 128.651766 -348.558532) (xy 128.651766 -348.613068) (xy 128.651766 -348.613069)
			(xy 130.134614 -348.613069) (xy 130.134614 -348.558531) (xy 130.142375 -348.504549) (xy 130.15774 -348.452221)
			(xy 130.180394 -348.402611) (xy 130.209878 -348.356731) (xy 130.24559 -348.315513) (xy 130.286805 -348.279797)
			(xy 130.332683 -348.250309) (xy 130.382291 -348.227651) (xy 130.434618 -348.212282) (xy 130.488599 -348.204517)
			(xy 130.515868 -348.204028) (xy 131.379468 -348.204028) (xy 131.40674 -348.204509) (xy 131.460729 -348.212268)
			(xy 131.513064 -348.227631) (xy 131.56268 -348.250286) (xy 131.608566 -348.279772) (xy 131.649789 -348.315488)
			(xy 131.685509 -348.356708) (xy 131.714999 -348.402592) (xy 131.737658 -348.452206) (xy 131.753026 -348.50454)
			(xy 131.760788 -348.558528) (xy 131.760788 -348.613072) (xy 131.760788 -348.613073) (xy 133.243492 -348.613073)
			(xy 133.243492 -348.558527) (xy 133.251255 -348.504536) (xy 133.266623 -348.4522) (xy 133.289283 -348.402584)
			(xy 133.318774 -348.356697) (xy 133.354495 -348.315476) (xy 133.39572 -348.279757) (xy 133.441608 -348.25027)
			(xy 133.491226 -348.227613) (xy 133.543564 -348.212249) (xy 133.597555 -348.20449) (xy 133.624828 -348.204028)
			(xy 134.488428 -348.204028) (xy 134.515695 -348.204536) (xy 134.569675 -348.212301) (xy 134.621999 -348.227668)
			(xy 134.671605 -348.250326) (xy 134.717481 -348.279811) (xy 134.758694 -348.315526) (xy 134.794405 -348.356742)
			(xy 134.823888 -348.40262) (xy 134.846541 -348.452227) (xy 134.861905 -348.504553) (xy 134.869666 -348.558533)
			(xy 134.869666 -348.613067) (xy 134.869666 -348.61307) (xy 136.352514 -348.61307) (xy 136.352514 -348.55853)
			(xy 136.360276 -348.504546) (xy 136.375641 -348.452217) (xy 136.398297 -348.402606) (xy 136.427783 -348.356724)
			(xy 136.463497 -348.315506) (xy 136.504715 -348.27979) (xy 136.550595 -348.250303) (xy 136.600205 -348.227645)
			(xy 136.652535 -348.212279) (xy 136.706518 -348.204515) (xy 136.733788 -348.204028) (xy 137.597388 -348.204028)
			(xy 137.624659 -348.204511) (xy 137.678646 -348.212271) (xy 137.730978 -348.227636) (xy 137.780592 -348.250292)
			(xy 137.826476 -348.279779) (xy 137.867696 -348.315495) (xy 137.903414 -348.356715) (xy 137.932902 -348.402598)
			(xy 137.95556 -348.45221) (xy 137.970926 -348.504543) (xy 137.978689 -348.558529) (xy 137.978689 -348.613071)
			(xy 137.978689 -348.613074) (xy 139.461392 -348.613074) (xy 139.461392 -348.558526) (xy 139.469155 -348.504534)
			(xy 139.484524 -348.452196) (xy 139.507186 -348.402578) (xy 139.536679 -348.356691) (xy 139.572402 -348.315468)
			(xy 139.613629 -348.27975) (xy 139.65952 -348.250263) (xy 139.709141 -348.227608) (xy 139.761481 -348.212245)
			(xy 139.815474 -348.204488) (xy 139.842748 -348.204028) (xy 140.706348 -348.204028) (xy 140.733614 -348.204538)
			(xy 140.787591 -348.212305) (xy 140.839914 -348.227674) (xy 140.889517 -348.250332) (xy 140.93539 -348.279819)
			(xy 140.976601 -348.315533) (xy 141.01231 -348.356748) (xy 141.041791 -348.402626) (xy 141.064443 -348.452231)
			(xy 141.079806 -348.504556) (xy 141.087566 -348.558534) (xy 141.087566 -348.613066) (xy 141.087565 -348.613072)
			(xy 142.570392 -348.613072) (xy 142.570392 -348.558528) (xy 142.578154 -348.504539) (xy 142.593521 -348.452204)
			(xy 142.61618 -348.402589) (xy 142.645669 -348.356704) (xy 142.681388 -348.315483) (xy 142.72261 -348.279764)
			(xy 142.768496 -348.250276) (xy 142.818112 -348.227618) (xy 142.870447 -348.212252) (xy 142.924436 -348.204491)
			(xy 142.951708 -348.204028) (xy 143.815308 -348.204028) (xy 143.842576 -348.204535) (xy 143.896558 -348.212297)
			(xy 143.948885 -348.227663) (xy 143.998493 -348.250319) (xy 144.044371 -348.279804) (xy 144.085587 -348.315519)
			(xy 144.1213 -348.356735) (xy 144.150785 -348.402614) (xy 144.17344 -348.452223) (xy 144.188804 -348.50455)
			(xy 144.196566 -348.558532) (xy 144.196566 -348.613068) (xy 144.196565 -348.613072) (xy 161.804792 -348.613072)
			(xy 161.804792 -348.558528) (xy 161.812554 -348.504538) (xy 161.827921 -348.452203) (xy 161.850581 -348.402588)
			(xy 161.88007 -348.356703) (xy 161.91579 -348.315481) (xy 161.957012 -348.279763) (xy 162.002899 -348.250275)
			(xy 162.052515 -348.227617) (xy 162.10485 -348.212252) (xy 162.15884 -348.204491) (xy 162.186112 -348.204028)
			(xy 163.049712 -348.204028) (xy 163.07698 -348.204535) (xy 163.130961 -348.212298) (xy 163.183288 -348.227664)
			(xy 163.232895 -348.25032) (xy 163.278773 -348.279806) (xy 163.319988 -348.31552) (xy 163.355701 -348.356736)
			(xy 163.385185 -348.402615) (xy 163.40784 -348.452224) (xy 163.423204 -348.504551) (xy 163.430966 -348.558532)
			(xy 163.430966 -348.613068) (xy 163.430966 -348.613069) (xy 164.913814 -348.613069) (xy 164.913814 -348.558531)
			(xy 164.921576 -348.504549) (xy 164.93694 -348.45222) (xy 164.959595 -348.40261) (xy 164.989079 -348.35673)
			(xy 165.024792 -348.315512) (xy 165.066007 -348.279795) (xy 165.111886 -348.250308) (xy 165.161494 -348.22765)
			(xy 165.213821 -348.212281) (xy 165.267803 -348.204516) (xy 165.295072 -348.204028) (xy 166.158672 -348.204028)
			(xy 166.185944 -348.20451) (xy 166.239932 -348.212268) (xy 166.292267 -348.227632) (xy 166.341882 -348.250287)
			(xy 166.387768 -348.279773) (xy 166.42899 -348.31549) (xy 166.46471 -348.356709) (xy 166.494199 -348.402593)
			(xy 166.516859 -348.452207) (xy 166.532226 -348.504541) (xy 166.539988 -348.558528) (xy 166.539988 -348.613072)
			(xy 166.539988 -348.613073) (xy 168.022692 -348.613073) (xy 168.022692 -348.558527) (xy 168.030455 -348.504536)
			(xy 168.045823 -348.452199) (xy 168.068484 -348.402583) (xy 168.097975 -348.356696) (xy 168.133697 -348.315474)
			(xy 168.174922 -348.279756) (xy 168.220811 -348.250268) (xy 168.270429 -348.227612) (xy 168.322767 -348.212248)
			(xy 168.376759 -348.204489) (xy 168.404032 -348.204028) (xy 169.267632 -348.204028) (xy 169.294899 -348.204537)
			(xy 169.348878 -348.212302) (xy 169.401202 -348.227669) (xy 169.450807 -348.250327) (xy 169.496683 -348.279813)
			(xy 169.537895 -348.315527) (xy 169.573606 -348.356743) (xy 169.603088 -348.402621) (xy 169.625742 -348.452228)
			(xy 169.641105 -348.504553) (xy 169.648866 -348.558533) (xy 169.648866 -348.613067) (xy 169.648866 -348.61307)
			(xy 171.131714 -348.61307) (xy 171.131714 -348.55853) (xy 171.139476 -348.504546) (xy 171.154841 -348.452216)
			(xy 171.177498 -348.402605) (xy 171.206984 -348.356723) (xy 171.242699 -348.315505) (xy 171.283917 -348.279788)
			(xy 171.329798 -348.250301) (xy 171.379408 -348.227644) (xy 171.431738 -348.212278) (xy 171.485722 -348.204515)
			(xy 171.512992 -348.204028) (xy 172.376592 -348.204028) (xy 172.403863 -348.204511) (xy 172.457849 -348.212272)
			(xy 172.510181 -348.227637) (xy 172.559794 -348.250294) (xy 172.605678 -348.27978) (xy 172.646898 -348.315497)
			(xy 172.682615 -348.356716) (xy 172.712103 -348.402599) (xy 172.73476 -348.452211) (xy 172.750126 -348.504543)
			(xy 172.757889 -348.558529) (xy 172.757889 -348.613068) (xy 174.240714 -348.613068) (xy 174.240714 -348.558532)
			(xy 174.248475 -348.504551) (xy 174.263838 -348.452224) (xy 174.286492 -348.402616) (xy 174.315974 -348.356736)
			(xy 174.351685 -348.315519) (xy 174.392898 -348.279803) (xy 174.438774 -348.250315) (xy 174.488379 -348.227655)
			(xy 174.540704 -348.212285) (xy 174.594684 -348.204518) (xy 174.621952 -348.204028) (xy 175.485552 -348.204028)
			(xy 175.512825 -348.204508) (xy 175.566815 -348.212265) (xy 175.619152 -348.227626) (xy 175.66877 -348.250281)
			(xy 175.714659 -348.279766) (xy 175.755883 -348.315483) (xy 175.791605 -348.356703) (xy 175.821096 -348.402588)
			(xy 175.843757 -348.452203) (xy 175.859125 -348.504538) (xy 175.866888 -348.558528) (xy 175.866888 -348.613072)
			(xy 177.349592 -348.613072) (xy 177.349592 -348.558528) (xy 177.357354 -348.504538) (xy 177.372721 -348.452203)
			(xy 177.395381 -348.402588) (xy 177.42487 -348.356703) (xy 177.46059 -348.315481) (xy 177.501812 -348.279763)
			(xy 177.547699 -348.250275) (xy 177.597315 -348.227617) (xy 177.64965 -348.212252) (xy 177.70364 -348.204491)
			(xy 177.730912 -348.204028) (xy 178.594512 -348.204028) (xy 178.62178 -348.204535) (xy 178.675761 -348.212298)
			(xy 178.728088 -348.227664) (xy 178.777695 -348.25032) (xy 178.823573 -348.279806) (xy 178.864788 -348.31552)
			(xy 178.900501 -348.356736) (xy 178.929985 -348.402615) (xy 178.95264 -348.452224) (xy 178.968004 -348.504551)
			(xy 178.975766 -348.558532) (xy 178.975766 -348.613068) (xy 178.975766 -348.613069) (xy 180.458614 -348.613069)
			(xy 180.458614 -348.558531) (xy 180.466376 -348.504549) (xy 180.48174 -348.45222) (xy 180.504395 -348.40261)
			(xy 180.533879 -348.35673) (xy 180.569592 -348.315512) (xy 180.610807 -348.279795) (xy 180.656686 -348.250308)
			(xy 180.706294 -348.22765) (xy 180.758621 -348.212281) (xy 180.812603 -348.204516) (xy 180.839872 -348.204028)
			(xy 181.703472 -348.204028) (xy 181.730744 -348.20451) (xy 181.784732 -348.212268) (xy 181.837067 -348.227632)
			(xy 181.886682 -348.250287) (xy 181.932568 -348.279773) (xy 181.97379 -348.31549) (xy 182.00951 -348.356709)
			(xy 182.038999 -348.402593) (xy 182.061659 -348.452207) (xy 182.077026 -348.504541) (xy 182.084788 -348.558528)
			(xy 182.084788 -348.613072) (xy 182.084788 -348.613073) (xy 183.567492 -348.613073) (xy 183.567492 -348.558527)
			(xy 183.575255 -348.504536) (xy 183.590623 -348.452199) (xy 183.613284 -348.402583) (xy 183.642775 -348.356696)
			(xy 183.678497 -348.315474) (xy 183.719722 -348.279756) (xy 183.765611 -348.250268) (xy 183.815229 -348.227612)
			(xy 183.867567 -348.212248) (xy 183.921559 -348.204489) (xy 183.948832 -348.204028) (xy 184.812432 -348.204028)
			(xy 184.839699 -348.204537) (xy 184.893678 -348.212302) (xy 184.946002 -348.227669) (xy 184.995607 -348.250327)
			(xy 185.041483 -348.279813) (xy 185.082695 -348.315527) (xy 185.118406 -348.356743) (xy 185.147888 -348.402621)
			(xy 185.170542 -348.452228) (xy 185.185905 -348.504553) (xy 185.193666 -348.558533) (xy 185.193666 -348.613067)
			(xy 185.193666 -348.61307) (xy 186.676514 -348.61307) (xy 186.676514 -348.55853) (xy 186.684276 -348.504546)
			(xy 186.699641 -348.452216) (xy 186.722298 -348.402605) (xy 186.751784 -348.356723) (xy 186.787499 -348.315505)
			(xy 186.828717 -348.279788) (xy 186.874598 -348.250301) (xy 186.924208 -348.227644) (xy 186.976538 -348.212278)
			(xy 187.030522 -348.204515) (xy 187.057792 -348.204028) (xy 187.921392 -348.204028) (xy 187.948663 -348.204511)
			(xy 188.002649 -348.212272) (xy 188.054981 -348.227637) (xy 188.104594 -348.250294) (xy 188.150478 -348.27978)
			(xy 188.191698 -348.315497) (xy 188.227415 -348.356716) (xy 188.256903 -348.402599) (xy 188.27956 -348.452211)
			(xy 188.294926 -348.504543) (xy 188.302689 -348.558529) (xy 188.302689 -348.613068) (xy 189.785514 -348.613068)
			(xy 189.785514 -348.558532) (xy 189.793275 -348.504551) (xy 189.808638 -348.452224) (xy 189.831292 -348.402616)
			(xy 189.860774 -348.356736) (xy 189.896485 -348.315519) (xy 189.937698 -348.279803) (xy 189.983574 -348.250315)
			(xy 190.033179 -348.227655) (xy 190.085504 -348.212285) (xy 190.139484 -348.204518) (xy 190.166752 -348.204028)
			(xy 191.030352 -348.204028) (xy 191.057625 -348.204508) (xy 191.111615 -348.212265) (xy 191.163952 -348.227626)
			(xy 191.21357 -348.250281) (xy 191.259459 -348.279766) (xy 191.300683 -348.315483) (xy 191.336405 -348.356703)
			(xy 191.365896 -348.402588) (xy 191.388557 -348.452203) (xy 191.403925 -348.504538) (xy 191.411688 -348.558528)
			(xy 191.411688 -348.613072) (xy 192.894392 -348.613072) (xy 192.894392 -348.558528) (xy 192.902154 -348.504538)
			(xy 192.917521 -348.452203) (xy 192.940181 -348.402588) (xy 192.96967 -348.356703) (xy 193.00539 -348.315481)
			(xy 193.046612 -348.279763) (xy 193.092499 -348.250275) (xy 193.142115 -348.227617) (xy 193.19445 -348.212252)
			(xy 193.24844 -348.204491) (xy 193.275712 -348.204028) (xy 194.139312 -348.204028) (xy 194.16658 -348.204535)
			(xy 194.220561 -348.212298) (xy 194.272888 -348.227664) (xy 194.322495 -348.25032) (xy 194.368373 -348.279806)
			(xy 194.409588 -348.31552) (xy 194.445301 -348.356736) (xy 194.474785 -348.402615) (xy 194.49744 -348.452224)
			(xy 194.512804 -348.504551) (xy 194.520566 -348.558532) (xy 194.520566 -348.613068) (xy 194.512804 -348.667049)
			(xy 194.49744 -348.719376) (xy 194.474785 -348.768985) (xy 194.445301 -348.814864) (xy 194.409588 -348.85608)
			(xy 194.368373 -348.891794) (xy 194.322495 -348.92128) (xy 194.272888 -348.943936) (xy 194.220561 -348.959302)
			(xy 194.16658 -348.967065) (xy 194.139312 -348.967552) (xy 193.275712 -348.967552) (xy 193.24844 -348.967109)
			(xy 193.19445 -348.959348) (xy 193.142115 -348.943983) (xy 193.092499 -348.921325) (xy 193.046612 -348.891837)
			(xy 193.00539 -348.856119) (xy 192.96967 -348.814897) (xy 192.940181 -348.769012) (xy 192.917521 -348.719397)
			(xy 192.902154 -348.667062) (xy 192.894392 -348.613072) (xy 191.411688 -348.613072) (xy 191.403925 -348.667062)
			(xy 191.388557 -348.719397) (xy 191.365896 -348.769012) (xy 191.336405 -348.814897) (xy 191.300683 -348.856117)
			(xy 191.259459 -348.891834) (xy 191.21357 -348.921319) (xy 191.163952 -348.943974) (xy 191.111615 -348.959335)
			(xy 191.057625 -348.967092) (xy 191.030352 -348.967552) (xy 190.166752 -348.967552) (xy 190.139484 -348.967082)
			(xy 190.085504 -348.959315) (xy 190.033179 -348.943945) (xy 189.983574 -348.921285) (xy 189.937698 -348.891797)
			(xy 189.896485 -348.856081) (xy 189.860774 -348.814864) (xy 189.831292 -348.768984) (xy 189.808638 -348.719376)
			(xy 189.793275 -348.667049) (xy 189.785514 -348.613068) (xy 188.302689 -348.613068) (xy 188.302689 -348.613071)
			(xy 188.294926 -348.667057) (xy 188.27956 -348.719389) (xy 188.256903 -348.769001) (xy 188.227415 -348.814884)
			(xy 188.191698 -348.856103) (xy 188.150478 -348.89182) (xy 188.104594 -348.921306) (xy 188.054981 -348.943963)
			(xy 188.002649 -348.959328) (xy 187.948663 -348.967089) (xy 187.921392 -348.967552) (xy 187.057792 -348.967552)
			(xy 187.030522 -348.967085) (xy 186.976538 -348.959322) (xy 186.924208 -348.943956) (xy 186.874598 -348.921299)
			(xy 186.828717 -348.891812) (xy 186.787499 -348.856095) (xy 186.751784 -348.814877) (xy 186.722298 -348.768995)
			(xy 186.699641 -348.719384) (xy 186.684276 -348.667054) (xy 186.676514 -348.61307) (xy 185.193666 -348.61307)
			(xy 185.185905 -348.667047) (xy 185.170542 -348.719372) (xy 185.147888 -348.768979) (xy 185.118406 -348.814857)
			(xy 185.082695 -348.856073) (xy 185.041483 -348.891787) (xy 184.995607 -348.921273) (xy 184.946002 -348.943931)
			(xy 184.893678 -348.959298) (xy 184.839699 -348.967063) (xy 184.812432 -348.967552) (xy 183.948832 -348.967552)
			(xy 183.921559 -348.967111) (xy 183.867567 -348.959352) (xy 183.815229 -348.943988) (xy 183.765611 -348.921332)
			(xy 183.719722 -348.891844) (xy 183.678497 -348.856126) (xy 183.642775 -348.814904) (xy 183.613284 -348.769017)
			(xy 183.590623 -348.719401) (xy 183.575255 -348.667064) (xy 183.567492 -348.613073) (xy 182.084788 -348.613073)
			(xy 182.077026 -348.667059) (xy 182.061659 -348.719393) (xy 182.038999 -348.769007) (xy 182.00951 -348.814891)
			(xy 181.97379 -348.85611) (xy 181.932568 -348.891827) (xy 181.886682 -348.921313) (xy 181.837067 -348.943968)
			(xy 181.784732 -348.959332) (xy 181.730744 -348.96709) (xy 181.703472 -348.967552) (xy 180.839872 -348.967552)
			(xy 180.812603 -348.967084) (xy 180.758621 -348.959319) (xy 180.706294 -348.94395) (xy 180.656686 -348.921292)
			(xy 180.610807 -348.891805) (xy 180.569592 -348.856088) (xy 180.533879 -348.81487) (xy 180.504395 -348.76899)
			(xy 180.48174 -348.71938) (xy 180.466376 -348.667051) (xy 180.458614 -348.613069) (xy 178.975766 -348.613069)
			(xy 178.968004 -348.667049) (xy 178.95264 -348.719376) (xy 178.929985 -348.768985) (xy 178.900501 -348.814864)
			(xy 178.864788 -348.85608) (xy 178.823573 -348.891794) (xy 178.777695 -348.92128) (xy 178.728088 -348.943936)
			(xy 178.675761 -348.959302) (xy 178.62178 -348.967065) (xy 178.594512 -348.967552) (xy 177.730912 -348.967552)
			(xy 177.70364 -348.967109) (xy 177.64965 -348.959348) (xy 177.597315 -348.943983) (xy 177.547699 -348.921325)
			(xy 177.501812 -348.891837) (xy 177.46059 -348.856119) (xy 177.42487 -348.814897) (xy 177.395381 -348.769012)
			(xy 177.372721 -348.719397) (xy 177.357354 -348.667062) (xy 177.349592 -348.613072) (xy 175.866888 -348.613072)
			(xy 175.859125 -348.667062) (xy 175.843757 -348.719397) (xy 175.821096 -348.769012) (xy 175.791605 -348.814897)
			(xy 175.755883 -348.856117) (xy 175.714659 -348.891834) (xy 175.66877 -348.921319) (xy 175.619152 -348.943974)
			(xy 175.566815 -348.959335) (xy 175.512825 -348.967092) (xy 175.485552 -348.967552) (xy 174.621952 -348.967552)
			(xy 174.594684 -348.967082) (xy 174.540704 -348.959315) (xy 174.488379 -348.943945) (xy 174.438774 -348.921285)
			(xy 174.392898 -348.891797) (xy 174.351685 -348.856081) (xy 174.315974 -348.814864) (xy 174.286492 -348.768984)
			(xy 174.263838 -348.719376) (xy 174.248475 -348.667049) (xy 174.240714 -348.613068) (xy 172.757889 -348.613068)
			(xy 172.757889 -348.613071) (xy 172.750126 -348.667057) (xy 172.73476 -348.719389) (xy 172.712103 -348.769001)
			(xy 172.682615 -348.814884) (xy 172.646898 -348.856103) (xy 172.605678 -348.89182) (xy 172.559794 -348.921306)
			(xy 172.510181 -348.943963) (xy 172.457849 -348.959328) (xy 172.403863 -348.967089) (xy 172.376592 -348.967552)
			(xy 171.512992 -348.967552) (xy 171.485722 -348.967085) (xy 171.431738 -348.959322) (xy 171.379408 -348.943956)
			(xy 171.329798 -348.921299) (xy 171.283917 -348.891812) (xy 171.242699 -348.856095) (xy 171.206984 -348.814877)
			(xy 171.177498 -348.768995) (xy 171.154841 -348.719384) (xy 171.139476 -348.667054) (xy 171.131714 -348.61307)
			(xy 169.648866 -348.61307) (xy 169.641105 -348.667047) (xy 169.625742 -348.719372) (xy 169.603088 -348.768979)
			(xy 169.573606 -348.814857) (xy 169.537895 -348.856073) (xy 169.496683 -348.891787) (xy 169.450807 -348.921273)
			(xy 169.401202 -348.943931) (xy 169.348878 -348.959298) (xy 169.294899 -348.967063) (xy 169.267632 -348.967552)
			(xy 168.404032 -348.967552) (xy 168.376759 -348.967111) (xy 168.322767 -348.959352) (xy 168.270429 -348.943988)
			(xy 168.220811 -348.921332) (xy 168.174922 -348.891844) (xy 168.133697 -348.856126) (xy 168.097975 -348.814904)
			(xy 168.068484 -348.769017) (xy 168.045823 -348.719401) (xy 168.030455 -348.667064) (xy 168.022692 -348.613073)
			(xy 166.539988 -348.613073) (xy 166.532226 -348.667059) (xy 166.516859 -348.719393) (xy 166.494199 -348.769007)
			(xy 166.46471 -348.814891) (xy 166.42899 -348.85611) (xy 166.387768 -348.891827) (xy 166.341882 -348.921313)
			(xy 166.292267 -348.943968) (xy 166.239932 -348.959332) (xy 166.185944 -348.96709) (xy 166.158672 -348.967552)
			(xy 165.295072 -348.967552) (xy 165.267803 -348.967084) (xy 165.213821 -348.959319) (xy 165.161494 -348.94395)
			(xy 165.111886 -348.921292) (xy 165.066007 -348.891805) (xy 165.024792 -348.856088) (xy 164.989079 -348.81487)
			(xy 164.959595 -348.76899) (xy 164.93694 -348.71938) (xy 164.921576 -348.667051) (xy 164.913814 -348.613069)
			(xy 163.430966 -348.613069) (xy 163.423204 -348.667049) (xy 163.40784 -348.719376) (xy 163.385185 -348.768985)
			(xy 163.355701 -348.814864) (xy 163.319988 -348.85608) (xy 163.278773 -348.891794) (xy 163.232895 -348.92128)
			(xy 163.183288 -348.943936) (xy 163.130961 -348.959302) (xy 163.07698 -348.967065) (xy 163.049712 -348.967552)
			(xy 162.186112 -348.967552) (xy 162.15884 -348.967109) (xy 162.10485 -348.959348) (xy 162.052515 -348.943983)
			(xy 162.002899 -348.921325) (xy 161.957012 -348.891837) (xy 161.91579 -348.856119) (xy 161.88007 -348.814897)
			(xy 161.850581 -348.769012) (xy 161.827921 -348.719397) (xy 161.812554 -348.667062) (xy 161.804792 -348.613072)
			(xy 144.196565 -348.613072) (xy 144.188804 -348.66705) (xy 144.17344 -348.719377) (xy 144.150785 -348.768986)
			(xy 144.1213 -348.814865) (xy 144.085587 -348.856081) (xy 144.044371 -348.891796) (xy 143.998493 -348.921281)
			(xy 143.948885 -348.943937) (xy 143.896558 -348.959303) (xy 143.842576 -348.967065) (xy 143.815308 -348.967552)
			(xy 142.951708 -348.967552) (xy 142.924436 -348.967109) (xy 142.870447 -348.959348) (xy 142.818112 -348.943982)
			(xy 142.768496 -348.921324) (xy 142.72261 -348.891836) (xy 142.681388 -348.856117) (xy 142.645669 -348.814896)
			(xy 142.61618 -348.769011) (xy 142.593521 -348.719396) (xy 142.578154 -348.667061) (xy 142.570392 -348.613072)
			(xy 141.087565 -348.613072) (xy 141.079806 -348.667044) (xy 141.064443 -348.719369) (xy 141.041791 -348.768974)
			(xy 141.01231 -348.814852) (xy 140.976601 -348.856067) (xy 140.93539 -348.891781) (xy 140.889517 -348.921268)
			(xy 140.839914 -348.943926) (xy 140.787591 -348.959295) (xy 140.733614 -348.967062) (xy 140.706348 -348.967552)
			(xy 139.842748 -348.967552) (xy 139.815474 -348.967112) (xy 139.761481 -348.959355) (xy 139.709141 -348.943992)
			(xy 139.65952 -348.921337) (xy 139.613629 -348.89185) (xy 139.572402 -348.856132) (xy 139.536679 -348.814909)
			(xy 139.507186 -348.769022) (xy 139.484524 -348.719404) (xy 139.469155 -348.667066) (xy 139.461392 -348.613074)
			(xy 137.978689 -348.613074) (xy 137.970926 -348.667057) (xy 137.95556 -348.71939) (xy 137.932902 -348.769002)
			(xy 137.903414 -348.814885) (xy 137.867696 -348.856105) (xy 137.826476 -348.891821) (xy 137.780592 -348.921308)
			(xy 137.730978 -348.943964) (xy 137.678646 -348.959329) (xy 137.624659 -348.967089) (xy 137.597388 -348.967552)
			(xy 136.733788 -348.967552) (xy 136.706518 -348.967085) (xy 136.652535 -348.959321) (xy 136.600205 -348.943955)
			(xy 136.550595 -348.921297) (xy 136.504715 -348.89181) (xy 136.463497 -348.856094) (xy 136.427783 -348.814876)
			(xy 136.398297 -348.768994) (xy 136.375641 -348.719383) (xy 136.360276 -348.667053) (xy 136.352514 -348.61307)
			(xy 134.869666 -348.61307) (xy 134.861905 -348.667047) (xy 134.846541 -348.719373) (xy 134.823888 -348.76898)
			(xy 134.794405 -348.814858) (xy 134.758694 -348.856074) (xy 134.717481 -348.891789) (xy 134.671605 -348.921274)
			(xy 134.621999 -348.943932) (xy 134.569675 -348.959299) (xy 134.515695 -348.967064) (xy 134.488428 -348.967552)
			(xy 133.624828 -348.967552) (xy 133.597555 -348.96711) (xy 133.543564 -348.959351) (xy 133.491226 -348.943987)
			(xy 133.441608 -348.92133) (xy 133.39572 -348.891843) (xy 133.354495 -348.856124) (xy 133.318774 -348.814903)
			(xy 133.289283 -348.769016) (xy 133.266623 -348.7194) (xy 133.251255 -348.667064) (xy 133.243492 -348.613073)
			(xy 131.760788 -348.613073) (xy 131.753026 -348.66706) (xy 131.737658 -348.719394) (xy 131.714999 -348.769008)
			(xy 131.685509 -348.814892) (xy 131.649789 -348.856112) (xy 131.608566 -348.891828) (xy 131.56268 -348.921314)
			(xy 131.513064 -348.943969) (xy 131.460729 -348.959332) (xy 131.40674 -348.967091) (xy 131.379468 -348.967552)
			(xy 130.515868 -348.967552) (xy 130.488599 -348.967083) (xy 130.434618 -348.959318) (xy 130.382291 -348.943949)
			(xy 130.332683 -348.921291) (xy 130.286805 -348.891803) (xy 130.24559 -348.856087) (xy 130.209878 -348.814869)
			(xy 130.180394 -348.768989) (xy 130.15774 -348.719379) (xy 130.142375 -348.667051) (xy 130.134614 -348.613069)
			(xy 128.651766 -348.613069) (xy 128.644004 -348.66705) (xy 128.62864 -348.719377) (xy 128.605985 -348.768986)
			(xy 128.5765 -348.814865) (xy 128.540787 -348.856081) (xy 128.499571 -348.891796) (xy 128.453693 -348.921281)
			(xy 128.404085 -348.943937) (xy 128.351758 -348.959303) (xy 128.297776 -348.967065) (xy 128.270508 -348.967552)
			(xy 127.406908 -348.967552) (xy 127.379636 -348.967109) (xy 127.325647 -348.959348) (xy 127.273312 -348.943982)
			(xy 127.223696 -348.921324) (xy 127.17781 -348.891836) (xy 127.136588 -348.856117) (xy 127.100869 -348.814896)
			(xy 127.07138 -348.769011) (xy 127.048721 -348.719396) (xy 127.033354 -348.667061) (xy 127.025592 -348.613072)
			(xy 125.542765 -348.613072) (xy 125.535006 -348.667044) (xy 125.519643 -348.719369) (xy 125.496991 -348.768974)
			(xy 125.46751 -348.814852) (xy 125.431801 -348.856067) (xy 125.39059 -348.891781) (xy 125.344717 -348.921268)
			(xy 125.295114 -348.943926) (xy 125.242791 -348.959295) (xy 125.188814 -348.967062) (xy 125.161548 -348.967552)
			(xy 124.297948 -348.967552) (xy 124.270674 -348.967112) (xy 124.216681 -348.959355) (xy 124.164341 -348.943992)
			(xy 124.11472 -348.921337) (xy 124.068829 -348.89185) (xy 124.027602 -348.856132) (xy 123.991879 -348.814909)
			(xy 123.962386 -348.769022) (xy 123.939724 -348.719404) (xy 123.924355 -348.667066) (xy 123.916592 -348.613074)
			(xy 122.433889 -348.613074) (xy 122.426126 -348.667057) (xy 122.41076 -348.71939) (xy 122.388102 -348.769002)
			(xy 122.358614 -348.814885) (xy 122.322896 -348.856105) (xy 122.281676 -348.891821) (xy 122.235792 -348.921308)
			(xy 122.186178 -348.943964) (xy 122.133846 -348.959329) (xy 122.079859 -348.967089) (xy 122.052588 -348.967552)
			(xy 121.188988 -348.967552) (xy 121.161718 -348.967085) (xy 121.107735 -348.959321) (xy 121.055405 -348.943955)
			(xy 121.005795 -348.921297) (xy 120.959915 -348.89181) (xy 120.918697 -348.856094) (xy 120.882983 -348.814876)
			(xy 120.853497 -348.768994) (xy 120.830841 -348.719383) (xy 120.815476 -348.667053) (xy 120.807714 -348.61307)
			(xy 119.324866 -348.61307) (xy 119.317105 -348.667047) (xy 119.301741 -348.719373) (xy 119.279088 -348.76898)
			(xy 119.249605 -348.814858) (xy 119.213894 -348.856074) (xy 119.172681 -348.891789) (xy 119.126805 -348.921274)
			(xy 119.077199 -348.943932) (xy 119.024875 -348.959299) (xy 118.970895 -348.967064) (xy 118.943628 -348.967552)
			(xy 118.080028 -348.967552) (xy 118.052755 -348.96711) (xy 117.998764 -348.959351) (xy 117.946426 -348.943987)
			(xy 117.896808 -348.92133) (xy 117.85092 -348.891843) (xy 117.809695 -348.856124) (xy 117.773974 -348.814903)
			(xy 117.744483 -348.769016) (xy 117.721823 -348.7194) (xy 117.706455 -348.667064) (xy 117.698692 -348.613073)
			(xy 116.215988 -348.613073) (xy 116.208226 -348.66706) (xy 116.192858 -348.719394) (xy 116.170199 -348.769008)
			(xy 116.140709 -348.814892) (xy 116.104989 -348.856112) (xy 116.063766 -348.891828) (xy 116.01788 -348.921314)
			(xy 115.968264 -348.943969) (xy 115.915929 -348.959332) (xy 115.86194 -348.967091) (xy 115.834668 -348.967552)
			(xy 114.971068 -348.967552) (xy 114.943799 -348.967083) (xy 114.889818 -348.959318) (xy 114.837491 -348.943949)
			(xy 114.787883 -348.921291) (xy 114.742005 -348.891803) (xy 114.70079 -348.856087) (xy 114.665078 -348.814869)
			(xy 114.635594 -348.768989) (xy 114.61294 -348.719379) (xy 114.597575 -348.667051) (xy 114.589814 -348.613069)
			(xy 113.106966 -348.613069) (xy 113.099204 -348.66705) (xy 113.08384 -348.719377) (xy 113.061185 -348.768986)
			(xy 113.0317 -348.814865) (xy 112.995987 -348.856081) (xy 112.954771 -348.891796) (xy 112.908893 -348.921281)
			(xy 112.859285 -348.943937) (xy 112.806958 -348.959303) (xy 112.752976 -348.967065) (xy 112.725708 -348.967552)
			(xy 111.862108 -348.967552) (xy 111.834836 -348.967109) (xy 111.780847 -348.959348) (xy 111.728512 -348.943982)
			(xy 111.678896 -348.921324) (xy 111.63301 -348.891836) (xy 111.591788 -348.856117) (xy 111.556069 -348.814896)
			(xy 111.52658 -348.769011) (xy 111.503921 -348.719396) (xy 111.488554 -348.667061) (xy 111.480792 -348.613072)
			(xy 93.706665 -348.613072) (xy 93.698905 -348.667045) (xy 93.683543 -348.71937) (xy 93.66089 -348.768976)
			(xy 93.631409 -348.814854) (xy 93.595699 -348.856069) (xy 93.554487 -348.891784) (xy 93.508613 -348.92127)
			(xy 93.459009 -348.943928) (xy 93.406686 -348.959296) (xy 93.352709 -348.967063) (xy 93.325442 -348.967552)
			(xy 92.461842 -348.967552) (xy 92.434568 -348.967111) (xy 92.380576 -348.959354) (xy 92.328236 -348.943991)
			(xy 92.278617 -348.921335) (xy 92.232727 -348.891848) (xy 92.1915 -348.856129) (xy 92.155777 -348.814907)
			(xy 92.126285 -348.76902) (xy 92.103624 -348.719403) (xy 92.088255 -348.667066) (xy 92.080492 -348.613074)
			(xy 90.597788 -348.613074) (xy 90.590026 -348.667058) (xy 90.574659 -348.719391) (xy 90.552001 -348.769004)
			(xy 90.522512 -348.814887) (xy 90.486794 -348.856107) (xy 90.445573 -348.891823) (xy 90.399688 -348.92131)
			(xy 90.350074 -348.943966) (xy 90.297741 -348.95933) (xy 90.243753 -348.96709) (xy 90.216482 -348.967552)
			(xy 89.352882 -348.967552) (xy 89.325613 -348.967084) (xy 89.27163 -348.95932) (xy 89.219301 -348.943953)
			(xy 89.169692 -348.921295) (xy 89.123812 -348.891808) (xy 89.082595 -348.856092) (xy 89.046881 -348.814874)
			(xy 89.017396 -348.768992) (xy 88.994741 -348.719382) (xy 88.979376 -348.667053) (xy 88.971614 -348.613069)
			(xy 87.488766 -348.613069) (xy 87.481005 -348.667048) (xy 87.465641 -348.719374) (xy 87.442987 -348.768982)
			(xy 87.413504 -348.81486) (xy 87.377792 -348.856076) (xy 87.336578 -348.891791) (xy 87.290701 -348.921276)
			(xy 87.241095 -348.943933) (xy 87.188769 -348.9593) (xy 87.13479 -348.967064) (xy 87.107522 -348.967552)
			(xy 86.243922 -348.967552) (xy 86.216649 -348.96711) (xy 86.162659 -348.95935) (xy 86.110322 -348.943985)
			(xy 86.060705 -348.921329) (xy 86.014817 -348.891841) (xy 85.973593 -348.856122) (xy 85.937872 -348.814901)
			(xy 85.908382 -348.769015) (xy 85.885722 -348.719399) (xy 85.870354 -348.667063) (xy 85.862592 -348.613073)
			(xy 84.379888 -348.613073) (xy 84.372126 -348.667061) (xy 84.356758 -348.719395) (xy 84.334098 -348.76901)
			(xy 84.304608 -348.814894) (xy 84.268887 -348.856114) (xy 84.227663 -348.89183) (xy 84.181776 -348.921316)
			(xy 84.13216 -348.943971) (xy 84.079824 -348.959334) (xy 84.025834 -348.967091) (xy 83.998562 -348.967552)
			(xy 83.134962 -348.967552) (xy 83.107694 -348.967083) (xy 83.053713 -348.959317) (xy 83.001386 -348.943948)
			(xy 82.95178 -348.921289) (xy 82.905902 -348.891801) (xy 82.864688 -348.856085) (xy 82.828976 -348.814867)
			(xy 82.799493 -348.768987) (xy 82.776839 -348.719378) (xy 82.761475 -348.66705) (xy 82.753714 -348.613068)
			(xy 81.270866 -348.613068) (xy 81.270866 -348.613069) (xy 81.263104 -348.667051) (xy 81.247739 -348.719379)
			(xy 81.225084 -348.768987) (xy 81.195599 -348.814867) (xy 81.159885 -348.856083) (xy 81.118669 -348.891798)
			(xy 81.072789 -348.921283) (xy 81.02318 -348.943939) (xy 80.970853 -348.959304) (xy 80.916871 -348.967065)
			(xy 80.889602 -348.967552) (xy 80.026002 -348.967552) (xy 79.99873 -348.967109) (xy 79.944742 -348.959347)
			(xy 79.892407 -348.94398) (xy 79.842793 -348.921322) (xy 79.796908 -348.891834) (xy 79.755686 -348.856115)
			(xy 79.719968 -348.814894) (xy 79.690479 -348.769009) (xy 79.667821 -348.719394) (xy 79.652454 -348.66706)
			(xy 79.644692 -348.613072) (xy 78.161865 -348.613072) (xy 78.154105 -348.667045) (xy 78.138743 -348.71937)
			(xy 78.11609 -348.768976) (xy 78.086609 -348.814854) (xy 78.050899 -348.856069) (xy 78.009687 -348.891784)
			(xy 77.963813 -348.92127) (xy 77.914209 -348.943928) (xy 77.861886 -348.959296) (xy 77.807909 -348.967063)
			(xy 77.780642 -348.967552) (xy 76.917042 -348.967552) (xy 76.889768 -348.967111) (xy 76.835776 -348.959354)
			(xy 76.783436 -348.943991) (xy 76.733817 -348.921335) (xy 76.687927 -348.891848) (xy 76.6467 -348.856129)
			(xy 76.610977 -348.814907) (xy 76.581485 -348.76902) (xy 76.558824 -348.719403) (xy 76.543455 -348.667066)
			(xy 76.535692 -348.613074) (xy 75.052988 -348.613074) (xy 75.045226 -348.667058) (xy 75.029859 -348.719391)
			(xy 75.007201 -348.769004) (xy 74.977712 -348.814887) (xy 74.941994 -348.856107) (xy 74.900773 -348.891823)
			(xy 74.854888 -348.92131) (xy 74.805274 -348.943966) (xy 74.752941 -348.95933) (xy 74.698953 -348.96709)
			(xy 74.671682 -348.967552) (xy 73.808082 -348.967552) (xy 73.780813 -348.967084) (xy 73.72683 -348.95932)
			(xy 73.674501 -348.943953) (xy 73.624892 -348.921295) (xy 73.579012 -348.891808) (xy 73.537795 -348.856092)
			(xy 73.502081 -348.814874) (xy 73.472596 -348.768992) (xy 73.449941 -348.719382) (xy 73.434576 -348.667053)
			(xy 73.426814 -348.613069) (xy 71.943966 -348.613069) (xy 71.936205 -348.667048) (xy 71.920841 -348.719374)
			(xy 71.898187 -348.768982) (xy 71.868704 -348.81486) (xy 71.832992 -348.856076) (xy 71.791778 -348.891791)
			(xy 71.745901 -348.921276) (xy 71.696295 -348.943933) (xy 71.643969 -348.9593) (xy 71.58999 -348.967064)
			(xy 71.562722 -348.967552) (xy 70.699122 -348.967552) (xy 70.671849 -348.96711) (xy 70.617859 -348.95935)
			(xy 70.565522 -348.943985) (xy 70.515905 -348.921329) (xy 70.470017 -348.891841) (xy 70.428793 -348.856122)
			(xy 70.393072 -348.814901) (xy 70.363582 -348.769015) (xy 70.340922 -348.719399) (xy 70.325554 -348.667063)
			(xy 70.317792 -348.613073) (xy 68.835088 -348.613073) (xy 68.827326 -348.667061) (xy 68.811958 -348.719395)
			(xy 68.789298 -348.76901) (xy 68.759808 -348.814894) (xy 68.724087 -348.856114) (xy 68.682863 -348.89183)
			(xy 68.636976 -348.921316) (xy 68.58736 -348.943971) (xy 68.535024 -348.959334) (xy 68.481034 -348.967091)
			(xy 68.453762 -348.967552) (xy 67.590162 -348.967552) (xy 67.562894 -348.967083) (xy 67.508913 -348.959317)
			(xy 67.456586 -348.943948) (xy 67.40698 -348.921289) (xy 67.361102 -348.891801) (xy 67.319888 -348.856085)
			(xy 67.284176 -348.814867) (xy 67.254693 -348.768987) (xy 67.232039 -348.719378) (xy 67.216675 -348.66705)
			(xy 67.208914 -348.613068) (xy 65.726066 -348.613068) (xy 65.726066 -348.613069) (xy 65.718304 -348.667051)
			(xy 65.702939 -348.719379) (xy 65.680284 -348.768987) (xy 65.650799 -348.814867) (xy 65.615085 -348.856083)
			(xy 65.573869 -348.891798) (xy 65.527989 -348.921283) (xy 65.47838 -348.943939) (xy 65.426053 -348.959304)
			(xy 65.372071 -348.967065) (xy 65.344802 -348.967552) (xy 64.481202 -348.967552) (xy 64.45393 -348.967109)
			(xy 64.399942 -348.959347) (xy 64.347607 -348.94398) (xy 64.297993 -348.921322) (xy 64.252108 -348.891834)
			(xy 64.210886 -348.856115) (xy 64.175168 -348.814894) (xy 64.145679 -348.769009) (xy 64.123021 -348.719394)
			(xy 64.107654 -348.66706) (xy 64.099892 -348.613072) (xy 62.617065 -348.613072) (xy 62.609305 -348.667045)
			(xy 62.593943 -348.71937) (xy 62.57129 -348.768976) (xy 62.541809 -348.814854) (xy 62.506099 -348.856069)
			(xy 62.464887 -348.891784) (xy 62.419013 -348.92127) (xy 62.369409 -348.943928) (xy 62.317086 -348.959296)
			(xy 62.263109 -348.967063) (xy 62.235842 -348.967552) (xy 61.372242 -348.967552) (xy 61.344968 -348.967111)
			(xy 61.290976 -348.959354) (xy 61.238636 -348.943991) (xy 61.189017 -348.921335) (xy 61.143127 -348.891848)
			(xy 61.1019 -348.856129) (xy 61.066177 -348.814907) (xy 61.036685 -348.76902) (xy 61.014024 -348.719403)
			(xy 60.998655 -348.667066) (xy 60.990892 -348.613074) (xy 51.666865 -348.613074) (xy 51.659106 -348.667044)
			(xy 51.643743 -348.719369) (xy 51.621091 -348.768974) (xy 51.59161 -348.814852) (xy 51.555901 -348.856067)
			(xy 51.51469 -348.891781) (xy 51.468817 -348.921268) (xy 51.419214 -348.943926) (xy 51.366891 -348.959295)
			(xy 51.312914 -348.967062) (xy 51.285648 -348.967552) (xy 50.422048 -348.967552) (xy 50.394774 -348.967112)
			(xy 50.340781 -348.959355) (xy 50.288441 -348.943992) (xy 50.23882 -348.921337) (xy 50.192929 -348.89185)
			(xy 50.151702 -348.856132) (xy 50.115979 -348.814909) (xy 50.086486 -348.769022) (xy 50.063824 -348.719404)
			(xy 50.048455 -348.667066) (xy 50.040692 -348.613074) (xy 48.557989 -348.613074) (xy 48.550226 -348.667057)
			(xy 48.53486 -348.71939) (xy 48.512202 -348.769002) (xy 48.482714 -348.814885) (xy 48.446996 -348.856105)
			(xy 48.405776 -348.891821) (xy 48.359892 -348.921308) (xy 48.310278 -348.943964) (xy 48.257946 -348.959329)
			(xy 48.203959 -348.967089) (xy 48.176688 -348.967552) (xy 47.313088 -348.967552) (xy 47.285818 -348.967085)
			(xy 47.231835 -348.959321) (xy 47.179505 -348.943955) (xy 47.129895 -348.921297) (xy 47.084015 -348.89181)
			(xy 47.042797 -348.856094) (xy 47.007083 -348.814876) (xy 46.977597 -348.768994) (xy 46.954941 -348.719383)
			(xy 46.939576 -348.667053) (xy 46.931814 -348.61307) (xy 45.448966 -348.61307) (xy 45.441205 -348.667047)
			(xy 45.425841 -348.719373) (xy 45.403188 -348.76898) (xy 45.373705 -348.814858) (xy 45.337994 -348.856074)
			(xy 45.296781 -348.891789) (xy 45.250905 -348.921274) (xy 45.201299 -348.943932) (xy 45.148975 -348.959299)
			(xy 45.094995 -348.967064) (xy 45.067728 -348.967552) (xy 44.204128 -348.967552) (xy 44.176855 -348.96711)
			(xy 44.122864 -348.959351) (xy 44.070526 -348.943987) (xy 44.020908 -348.92133) (xy 43.97502 -348.891843)
			(xy 43.933795 -348.856124) (xy 43.898074 -348.814903) (xy 43.868583 -348.769016) (xy 43.845923 -348.7194)
			(xy 43.830555 -348.667064) (xy 43.822792 -348.613073) (xy 42.340088 -348.613073) (xy 42.332326 -348.66706)
			(xy 42.316958 -348.719394) (xy 42.294299 -348.769008) (xy 42.264809 -348.814892) (xy 42.229089 -348.856112)
			(xy 42.187866 -348.891828) (xy 42.14198 -348.921314) (xy 42.092364 -348.943969) (xy 42.040029 -348.959332)
			(xy 41.98604 -348.967091) (xy 41.958768 -348.967552) (xy 41.095168 -348.967552) (xy 41.067899 -348.967083)
			(xy 41.013918 -348.959318) (xy 40.961591 -348.943949) (xy 40.911983 -348.921291) (xy 40.866105 -348.891803)
			(xy 40.82489 -348.856087) (xy 40.789178 -348.814869) (xy 40.759694 -348.768989) (xy 40.73704 -348.719379)
			(xy 40.721675 -348.667051) (xy 40.713914 -348.613069) (xy 39.231066 -348.613069) (xy 39.223304 -348.66705)
			(xy 39.20794 -348.719377) (xy 39.185285 -348.768986) (xy 39.1558 -348.814865) (xy 39.120087 -348.856081)
			(xy 39.078871 -348.891796) (xy 39.032993 -348.921281) (xy 38.983385 -348.943937) (xy 38.931058 -348.959303)
			(xy 38.877076 -348.967065) (xy 38.849808 -348.967552) (xy 37.986208 -348.967552) (xy 37.958936 -348.967109)
			(xy 37.904947 -348.959348) (xy 37.852612 -348.943982) (xy 37.802996 -348.921324) (xy 37.75711 -348.891836)
			(xy 37.715888 -348.856117) (xy 37.680169 -348.814896) (xy 37.65068 -348.769011) (xy 37.628021 -348.719396)
			(xy 37.612654 -348.667061) (xy 37.604892 -348.613072) (xy 36.122065 -348.613072) (xy 36.114306 -348.667044)
			(xy 36.098943 -348.719369) (xy 36.076291 -348.768974) (xy 36.04681 -348.814852) (xy 36.011101 -348.856067)
			(xy 35.96989 -348.891781) (xy 35.924017 -348.921268) (xy 35.874414 -348.943926) (xy 35.822091 -348.959295)
			(xy 35.768114 -348.967062) (xy 35.740848 -348.967552) (xy 34.877248 -348.967552) (xy 34.849974 -348.967112)
			(xy 34.795981 -348.959355) (xy 34.743641 -348.943992) (xy 34.69402 -348.921337) (xy 34.648129 -348.89185)
			(xy 34.606902 -348.856132) (xy 34.571179 -348.814909) (xy 34.541686 -348.769022) (xy 34.519024 -348.719404)
			(xy 34.503655 -348.667066) (xy 34.495892 -348.613074) (xy 33.013189 -348.613074) (xy 33.005426 -348.667057)
			(xy 32.99006 -348.71939) (xy 32.967402 -348.769002) (xy 32.937914 -348.814885) (xy 32.902196 -348.856105)
			(xy 32.860976 -348.891821) (xy 32.815092 -348.921308) (xy 32.765478 -348.943964) (xy 32.713146 -348.959329)
			(xy 32.659159 -348.967089) (xy 32.631888 -348.967552) (xy 31.768288 -348.967552) (xy 31.741018 -348.967085)
			(xy 31.687035 -348.959321) (xy 31.634705 -348.943955) (xy 31.585095 -348.921297) (xy 31.539215 -348.89181)
			(xy 31.497997 -348.856094) (xy 31.462283 -348.814876) (xy 31.432797 -348.768994) (xy 31.410141 -348.719383)
			(xy 31.394776 -348.667053) (xy 31.387014 -348.61307) (xy 29.904166 -348.61307) (xy 29.896405 -348.667047)
			(xy 29.881041 -348.719373) (xy 29.858388 -348.76898) (xy 29.828905 -348.814858) (xy 29.793194 -348.856074)
			(xy 29.751981 -348.891789) (xy 29.706105 -348.921274) (xy 29.656499 -348.943932) (xy 29.604175 -348.959299)
			(xy 29.550195 -348.967064) (xy 29.522928 -348.967552) (xy 28.659328 -348.967552) (xy 28.632055 -348.96711)
			(xy 28.578064 -348.959351) (xy 28.525726 -348.943987) (xy 28.476108 -348.92133) (xy 28.43022 -348.891843)
			(xy 28.388995 -348.856124) (xy 28.353274 -348.814903) (xy 28.323783 -348.769016) (xy 28.301123 -348.7194)
			(xy 28.285755 -348.667064) (xy 28.277992 -348.613073) (xy 26.795288 -348.613073) (xy 26.787526 -348.66706)
			(xy 26.772158 -348.719394) (xy 26.749499 -348.769008) (xy 26.720009 -348.814892) (xy 26.684289 -348.856112)
			(xy 26.643066 -348.891828) (xy 26.59718 -348.921314) (xy 26.547564 -348.943969) (xy 26.495229 -348.959332)
			(xy 26.44124 -348.967091) (xy 26.413968 -348.967552) (xy 25.550368 -348.967552) (xy 25.523099 -348.967083)
			(xy 25.469118 -348.959318) (xy 25.416791 -348.943949) (xy 25.367183 -348.921291) (xy 25.321305 -348.891803)
			(xy 25.28009 -348.856087) (xy 25.244378 -348.814869) (xy 25.214894 -348.768989) (xy 25.19224 -348.719379)
			(xy 25.176875 -348.667051) (xy 25.169114 -348.613069) (xy 23.686266 -348.613069) (xy 23.678504 -348.66705)
			(xy 23.66314 -348.719377) (xy 23.640485 -348.768986) (xy 23.611 -348.814865) (xy 23.575287 -348.856081)
			(xy 23.534071 -348.891796) (xy 23.488193 -348.921281) (xy 23.438585 -348.943937) (xy 23.386258 -348.959303)
			(xy 23.332276 -348.967065) (xy 23.305008 -348.967552) (xy 22.441408 -348.967552) (xy 22.414136 -348.967109)
			(xy 22.360147 -348.959348) (xy 22.307812 -348.943982) (xy 22.258196 -348.921324) (xy 22.21231 -348.891836)
			(xy 22.171088 -348.856117) (xy 22.135369 -348.814896) (xy 22.10588 -348.769011) (xy 22.083221 -348.719396)
			(xy 22.067854 -348.667061) (xy 22.060092 -348.613072) (xy 20.577347 -348.613072) (xy 20.569586 -348.667048)
			(xy 20.55422 -348.719381) (xy 20.531562 -348.768994) (xy 20.502074 -348.814878) (xy 20.466357 -348.856098)
			(xy 20.425136 -348.891816) (xy 20.379253 -348.921303) (xy 20.329639 -348.943961) (xy 20.277306 -348.959327)
			(xy 20.223319 -348.967089) (xy 20.196048 -348.967552) (xy 19.332448 -348.967552) (xy 19.305179 -348.967065)
			(xy 19.251195 -348.959304) (xy 19.198866 -348.943938) (xy 19.149256 -348.921282) (xy 19.103375 -348.891796)
			(xy 19.062158 -348.856081) (xy 19.026443 -348.814863) (xy 18.996957 -348.768982) (xy 18.974301 -348.719372)
			(xy 18.958936 -348.667043) (xy 18.951174 -348.613059) (xy 8.879169 -348.613059) (xy 8.892221 -348.718461)
			(xy 8.900171 -348.847356) (xy 8.900668 -348.911926) (xy 8.900171 -348.976496) (xy 8.892221 -349.105391)
			(xy 8.876351 -349.233551) (xy 8.852622 -349.360492) (xy 8.821123 -349.485731) (xy 8.781974 -349.608794)
			(xy 8.735323 -349.729213) (xy 8.681348 -349.846532) (xy 8.620253 -349.960306) (xy 8.55227 -350.070103)
			(xy 8.477656 -350.175506) (xy 8.396695 -350.276116) (xy 8.309695 -350.371551) (xy 8.216984 -350.46145)
			(xy 8.118914 -350.545471) (xy 8.015859 -350.623295) (xy 7.908208 -350.694627) (xy 7.796369 -350.759197)
			(xy 7.680768 -350.816759) (xy 7.561843 -350.867096) (xy 7.440044 -350.910016) (xy 7.315834 -350.945357)
			(xy 7.189685 -350.972984) (xy 7.062073 -350.992793) (xy 6.933484 -351.004709) (xy 6.804406 -351.008686)
			(xy 6.675328 -351.004709) (xy 6.546739 -350.992793) (xy 6.419127 -350.972984) (xy 6.292978 -350.945357)
			(xy 6.168768 -350.910016) (xy 6.046969 -350.867096) (xy 5.928044 -350.816759) (xy 5.812443 -350.759197)
			(xy 5.700604 -350.694627) (xy 5.592953 -350.623295) (xy 5.489898 -350.545471) (xy 5.391828 -350.46145)
			(xy 5.299117 -350.371551) (xy 5.212117 -350.276116) (xy 5.131156 -350.175506) (xy 5.056542 -350.070103)
			(xy 4.988559 -349.960306) (xy 4.927464 -349.846532) (xy 4.873489 -349.729213) (xy 4.826838 -349.608794)
			(xy 4.787689 -349.485731) (xy 4.75619 -349.360492) (xy 4.732461 -349.233551) (xy 4.716591 -349.105391)
			(xy 4.708641 -348.976496) (xy 1.524 -348.976496) (xy 1.524 -351.638709) (xy 18.951172 -351.638709)
			(xy 18.951172 -351.584171) (xy 18.958934 -351.530187) (xy 18.974299 -351.477857) (xy 18.996956 -351.428247)
			(xy 19.026441 -351.382366) (xy 19.062157 -351.341148) (xy 19.103374 -351.305433) (xy 19.149255 -351.275947)
			(xy 19.198865 -351.25329) (xy 19.251195 -351.237925) (xy 19.305179 -351.230163) (xy 19.332448 -351.229676)
			(xy 20.196048 -351.229676) (xy 20.223319 -351.230143) (xy 20.277306 -351.237905) (xy 20.329638 -351.253271)
			(xy 20.379252 -351.275929) (xy 20.425135 -351.305416) (xy 20.466355 -351.341133) (xy 20.502073 -351.382353)
			(xy 20.53156 -351.428237) (xy 20.554218 -351.47785) (xy 20.569584 -351.530182) (xy 20.577347 -351.584169)
			(xy 20.577347 -351.638669) (xy 22.060139 -351.638669) (xy 22.060139 -351.584131) (xy 22.067901 -351.530149)
			(xy 22.083266 -351.477821) (xy 22.105922 -351.428212) (xy 22.135407 -351.382333) (xy 22.171122 -351.341117)
			(xy 22.212339 -351.305403) (xy 22.258219 -351.275918) (xy 22.307829 -351.253263) (xy 22.360157 -351.237899)
			(xy 22.414139 -351.230139) (xy 22.441408 -351.229676) (xy 23.305008 -351.229676) (xy 23.33228 -351.230087)
			(xy 23.386268 -351.23785) (xy 23.438602 -351.253218) (xy 23.488216 -351.275877) (xy 23.5341 -351.305366)
			(xy 23.575321 -351.341085) (xy 23.611039 -351.382306) (xy 23.640527 -351.428191) (xy 23.663185 -351.477806)
			(xy 23.678551 -351.53014) (xy 23.686314 -351.584128) (xy 23.686314 -351.638665) (xy 25.169162 -351.638665)
			(xy 25.169162 -351.584135) (xy 25.176922 -351.530159) (xy 25.192284 -351.477838) (xy 25.214936 -351.428234)
			(xy 25.244416 -351.38236) (xy 25.280124 -351.341147) (xy 25.321334 -351.305435) (xy 25.367206 -351.275951)
			(xy 25.416808 -351.253296) (xy 25.469128 -351.237929) (xy 25.523103 -351.230165) (xy 25.550368 -351.229676)
			(xy 26.413968 -351.229676) (xy 26.441243 -351.230061) (xy 26.495239 -351.237821) (xy 26.547581 -351.253186)
			(xy 26.597203 -351.275844) (xy 26.643095 -351.305333) (xy 26.684323 -351.341054) (xy 26.720047 -351.382279)
			(xy 26.749541 -351.428169) (xy 26.772203 -351.477789) (xy 26.787573 -351.53013) (xy 26.795336 -351.584125)
			(xy 26.795336 -351.63867) (xy 28.278039 -351.63867) (xy 28.278039 -351.58413) (xy 28.285802 -351.530146)
			(xy 28.301168 -351.477817) (xy 28.323825 -351.428207) (xy 28.353312 -351.382326) (xy 28.389029 -351.341109)
			(xy 28.430249 -351.305396) (xy 28.476131 -351.275912) (xy 28.525743 -351.253258) (xy 28.578074 -351.237896)
			(xy 28.632058 -351.230137) (xy 28.659328 -351.229676) (xy 29.522928 -351.229676) (xy 29.550199 -351.230088)
			(xy 29.604185 -351.237854) (xy 29.656516 -351.253223) (xy 29.706128 -351.275883) (xy 29.75201 -351.305373)
			(xy 29.793228 -351.341092) (xy 29.828944 -351.382313) (xy 29.85843 -351.428197) (xy 29.881086 -351.47781)
			(xy 29.896452 -351.530143) (xy 29.904214 -351.584129) (xy 29.904214 -351.638666) (xy 31.387062 -351.638666)
			(xy 31.387062 -351.584134) (xy 31.394823 -351.530157) (xy 31.410186 -351.477833) (xy 31.432839 -351.428229)
			(xy 31.462321 -351.382353) (xy 31.498031 -351.34114) (xy 31.539243 -351.305428) (xy 31.585118 -351.275945)
			(xy 31.634722 -351.25329) (xy 31.687045 -351.237925) (xy 31.741022 -351.230163) (xy 31.768288 -351.229676)
			(xy 32.631888 -351.229676) (xy 32.659162 -351.230063) (xy 32.713156 -351.237824) (xy 32.765495 -351.253191)
			(xy 32.815115 -351.27585) (xy 32.861004 -351.30534) (xy 32.90223 -351.341061) (xy 32.937952 -351.382286)
			(xy 32.967444 -351.428175) (xy 32.990105 -351.477794) (xy 33.005473 -351.530132) (xy 33.013236 -351.584126)
			(xy 33.013236 -351.63867) (xy 34.49594 -351.63867) (xy 34.49594 -351.58413) (xy 34.503702 -351.530144)
			(xy 34.519069 -351.477812) (xy 34.541728 -351.428201) (xy 34.571217 -351.38232) (xy 34.606936 -351.341102)
			(xy 34.648158 -351.305388) (xy 34.694043 -351.275905) (xy 34.743658 -351.253253) (xy 34.795991 -351.237892)
			(xy 34.849977 -351.230136) (xy 34.877248 -351.229676) (xy 35.740848 -351.229676) (xy 35.768118 -351.23009)
			(xy 35.822102 -351.237858) (xy 35.874431 -351.253229) (xy 35.92404 -351.27589) (xy 35.969919 -351.30538)
			(xy 36.011135 -351.341099) (xy 36.046849 -351.382319) (xy 36.076333 -351.428203) (xy 36.098988 -351.477814)
			(xy 36.114352 -351.530145) (xy 36.122114 -351.58413) (xy 36.122114 -351.638669) (xy 37.604939 -351.638669)
			(xy 37.604939 -351.584131) (xy 37.612701 -351.530149) (xy 37.628066 -351.477821) (xy 37.650722 -351.428212)
			(xy 37.680207 -351.382333) (xy 37.715922 -351.341117) (xy 37.757139 -351.305403) (xy 37.803019 -351.275918)
			(xy 37.852629 -351.253263) (xy 37.904957 -351.237899) (xy 37.958939 -351.230139) (xy 37.986208 -351.229676)
			(xy 38.849808 -351.229676) (xy 38.87708 -351.230087) (xy 38.931068 -351.23785) (xy 38.983402 -351.253218)
			(xy 39.033016 -351.275877) (xy 39.0789 -351.305366) (xy 39.120121 -351.341085) (xy 39.155839 -351.382306)
			(xy 39.185327 -351.428191) (xy 39.207985 -351.477806) (xy 39.223351 -351.53014) (xy 39.231114 -351.584128)
			(xy 39.231114 -351.638665) (xy 40.713962 -351.638665) (xy 40.713962 -351.584135) (xy 40.721722 -351.530159)
			(xy 40.737084 -351.477838) (xy 40.759736 -351.428234) (xy 40.789216 -351.38236) (xy 40.824924 -351.341147)
			(xy 40.866134 -351.305435) (xy 40.912006 -351.275951) (xy 40.961608 -351.253296) (xy 41.013928 -351.237929)
			(xy 41.067903 -351.230165) (xy 41.095168 -351.229676) (xy 41.958768 -351.229676) (xy 41.986043 -351.230061)
			(xy 42.040039 -351.237821) (xy 42.092381 -351.253186) (xy 42.142003 -351.275844) (xy 42.187895 -351.305333)
			(xy 42.229123 -351.341054) (xy 42.264847 -351.382279) (xy 42.294341 -351.428169) (xy 42.317003 -351.477789)
			(xy 42.332373 -351.53013) (xy 42.340136 -351.584125) (xy 42.340136 -351.63867) (xy 43.822839 -351.63867)
			(xy 43.822839 -351.58413) (xy 43.830602 -351.530146) (xy 43.845968 -351.477817) (xy 43.868625 -351.428207)
			(xy 43.898112 -351.382326) (xy 43.933829 -351.341109) (xy 43.975049 -351.305396) (xy 44.020931 -351.275912)
			(xy 44.070543 -351.253258) (xy 44.122874 -351.237896) (xy 44.176858 -351.230137) (xy 44.204128 -351.229676)
			(xy 45.067728 -351.229676) (xy 45.094999 -351.230088) (xy 45.148985 -351.237854) (xy 45.201316 -351.253223)
			(xy 45.250928 -351.275883) (xy 45.29681 -351.305373) (xy 45.338028 -351.341092) (xy 45.373744 -351.382313)
			(xy 45.40323 -351.428197) (xy 45.425886 -351.47781) (xy 45.441252 -351.530143) (xy 45.449014 -351.584129)
			(xy 45.449014 -351.638666) (xy 46.931862 -351.638666) (xy 46.931862 -351.584134) (xy 46.939623 -351.530157)
			(xy 46.954986 -351.477833) (xy 46.977639 -351.428229) (xy 47.007121 -351.382353) (xy 47.042831 -351.34114)
			(xy 47.084043 -351.305428) (xy 47.129918 -351.275945) (xy 47.179522 -351.25329) (xy 47.231845 -351.237925)
			(xy 47.285822 -351.230163) (xy 47.313088 -351.229676) (xy 48.176688 -351.229676) (xy 48.203962 -351.230063)
			(xy 48.257956 -351.237824) (xy 48.310295 -351.253191) (xy 48.359915 -351.27585) (xy 48.405804 -351.30534)
			(xy 48.44703 -351.341061) (xy 48.482752 -351.382286) (xy 48.512244 -351.428175) (xy 48.534905 -351.477794)
			(xy 48.550273 -351.530132) (xy 48.558036 -351.584126) (xy 48.558036 -351.63867) (xy 50.04074 -351.63867)
			(xy 50.04074 -351.58413) (xy 50.048502 -351.530144) (xy 50.063869 -351.477812) (xy 50.086528 -351.428201)
			(xy 50.116017 -351.38232) (xy 50.151736 -351.341102) (xy 50.192958 -351.305388) (xy 50.238843 -351.275905)
			(xy 50.288458 -351.253253) (xy 50.340791 -351.237892) (xy 50.394777 -351.230136) (xy 50.422048 -351.229676)
			(xy 51.285648 -351.229676) (xy 51.312918 -351.23009) (xy 51.366902 -351.237858) (xy 51.419231 -351.253229)
			(xy 51.46884 -351.27589) (xy 51.514719 -351.30538) (xy 51.555935 -351.341099) (xy 51.591649 -351.382319)
			(xy 51.621133 -351.428203) (xy 51.643788 -351.477814) (xy 51.659152 -351.530145) (xy 51.666914 -351.58413)
			(xy 51.666914 -351.63867) (xy 60.99094 -351.63867) (xy 60.99094 -351.58413) (xy 60.998702 -351.530145)
			(xy 61.014069 -351.477814) (xy 61.036727 -351.428203) (xy 61.066216 -351.382322) (xy 61.101934 -351.341105)
			(xy 61.143155 -351.305391) (xy 61.18904 -351.275907) (xy 61.238653 -351.253254) (xy 61.290986 -351.237893)
			(xy 61.344972 -351.230137) (xy 61.372242 -351.229676) (xy 62.235842 -351.229676) (xy 62.263112 -351.230089)
			(xy 62.317097 -351.237857) (xy 62.369426 -351.253227) (xy 62.419036 -351.275888) (xy 62.464916 -351.305378)
			(xy 62.506133 -351.341097) (xy 62.541847 -351.382317) (xy 62.571332 -351.428201) (xy 62.593988 -351.477813)
			(xy 62.609352 -351.530145) (xy 62.617114 -351.58413) (xy 62.617114 -351.638668) (xy 64.099939 -351.638668)
			(xy 64.099939 -351.584132) (xy 64.107701 -351.53015) (xy 64.123066 -351.477822) (xy 64.145721 -351.428214)
			(xy 64.175206 -351.382335) (xy 64.21092 -351.341119) (xy 64.252136 -351.305405) (xy 64.298016 -351.27592)
			(xy 64.347624 -351.253265) (xy 64.399952 -351.2379) (xy 64.453934 -351.230139) (xy 64.481202 -351.229676)
			(xy 65.344802 -351.229676) (xy 65.372074 -351.230087) (xy 65.426063 -351.237849) (xy 65.478397 -351.253216)
			(xy 65.528012 -351.275875) (xy 65.573897 -351.305364) (xy 65.615119 -351.341083) (xy 65.650837 -351.382304)
			(xy 65.680326 -351.42819) (xy 65.702984 -351.477805) (xy 65.718351 -351.530139) (xy 65.726113 -351.584128)
			(xy 65.726113 -351.638665) (xy 67.208962 -351.638665) (xy 67.208962 -351.584135) (xy 67.216722 -351.53016)
			(xy 67.232084 -351.477839) (xy 67.254735 -351.428236) (xy 67.284215 -351.382362) (xy 67.319922 -351.341149)
			(xy 67.361131 -351.305437) (xy 67.407003 -351.275953) (xy 67.456603 -351.253297) (xy 67.508923 -351.23793)
			(xy 67.562897 -351.230165) (xy 67.590162 -351.229676) (xy 68.453762 -351.229676) (xy 68.481037 -351.230061)
			(xy 68.535034 -351.23782) (xy 68.587376 -351.253184) (xy 68.636999 -351.275842) (xy 68.682892 -351.305331)
			(xy 68.724121 -351.341052) (xy 68.759846 -351.382277) (xy 68.78934 -351.428167) (xy 68.812003 -351.477788)
			(xy 68.827372 -351.530129) (xy 68.835136 -351.584125) (xy 68.835136 -351.638669) (xy 70.317839 -351.638669)
			(xy 70.317839 -351.584131) (xy 70.325601 -351.530147) (xy 70.340967 -351.477818) (xy 70.363624 -351.428208)
			(xy 70.393111 -351.382328) (xy 70.428827 -351.341112) (xy 70.470046 -351.305398) (xy 70.515928 -351.275914)
			(xy 70.565539 -351.25326) (xy 70.617869 -351.237897) (xy 70.671853 -351.230138) (xy 70.699122 -351.229676)
			(xy 71.562722 -351.229676) (xy 71.589993 -351.230088) (xy 71.64398 -351.237853) (xy 71.696312 -351.253222)
			(xy 71.745924 -351.275881) (xy 71.791807 -351.305371) (xy 71.833026 -351.34109) (xy 71.868742 -351.382311)
			(xy 71.898229 -351.428195) (xy 71.920886 -351.477809) (xy 71.936252 -351.530142) (xy 71.944014 -351.584129)
			(xy 71.944014 -351.638666) (xy 73.426862 -351.638666) (xy 73.426862 -351.584134) (xy 73.434623 -351.530158)
			(xy 73.449986 -351.477835) (xy 73.472638 -351.428231) (xy 73.50212 -351.382355) (xy 73.537829 -351.341142)
			(xy 73.579041 -351.30543) (xy 73.624915 -351.275947) (xy 73.674518 -351.253292) (xy 73.72684 -351.237927)
			(xy 73.780816 -351.230164) (xy 73.808082 -351.229676) (xy 74.671682 -351.229676) (xy 74.698957 -351.230062)
			(xy 74.752951 -351.237823) (xy 74.805291 -351.253189) (xy 74.854911 -351.275848) (xy 74.900802 -351.305338)
			(xy 74.942028 -351.341059) (xy 74.977751 -351.382284) (xy 75.007243 -351.428173) (xy 75.029904 -351.477792)
			(xy 75.045273 -351.530132) (xy 75.053036 -351.584125) (xy 75.053036 -351.63867) (xy 76.53574 -351.63867)
			(xy 76.53574 -351.58413) (xy 76.543502 -351.530145) (xy 76.558869 -351.477814) (xy 76.581527 -351.428203)
			(xy 76.611016 -351.382322) (xy 76.646734 -351.341105) (xy 76.687955 -351.305391) (xy 76.73384 -351.275907)
			(xy 76.783453 -351.253254) (xy 76.835786 -351.237893) (xy 76.889772 -351.230137) (xy 76.917042 -351.229676)
			(xy 77.780642 -351.229676) (xy 77.807912 -351.230089) (xy 77.861897 -351.237857) (xy 77.914226 -351.253227)
			(xy 77.963836 -351.275888) (xy 78.009716 -351.305378) (xy 78.050933 -351.341097) (xy 78.086647 -351.382317)
			(xy 78.116132 -351.428201) (xy 78.138788 -351.477813) (xy 78.154152 -351.530145) (xy 78.161914 -351.58413)
			(xy 78.161914 -351.638668) (xy 79.644739 -351.638668) (xy 79.644739 -351.584132) (xy 79.652501 -351.53015)
			(xy 79.667866 -351.477822) (xy 79.690521 -351.428214) (xy 79.720006 -351.382335) (xy 79.75572 -351.341119)
			(xy 79.796936 -351.305405) (xy 79.842816 -351.27592) (xy 79.892424 -351.253265) (xy 79.944752 -351.2379)
			(xy 79.998734 -351.230139) (xy 80.026002 -351.229676) (xy 80.889602 -351.229676) (xy 80.916874 -351.230087)
			(xy 80.970863 -351.237849) (xy 81.023197 -351.253216) (xy 81.072812 -351.275875) (xy 81.118697 -351.305364)
			(xy 81.159919 -351.341083) (xy 81.195637 -351.382304) (xy 81.225126 -351.42819) (xy 81.247784 -351.477805)
			(xy 81.263151 -351.530139) (xy 81.270913 -351.584128) (xy 81.270913 -351.638665) (xy 82.753762 -351.638665)
			(xy 82.753762 -351.584135) (xy 82.761522 -351.53016) (xy 82.776884 -351.477839) (xy 82.799535 -351.428236)
			(xy 82.829015 -351.382362) (xy 82.864722 -351.341149) (xy 82.905931 -351.305437) (xy 82.951803 -351.275953)
			(xy 83.001403 -351.253297) (xy 83.053723 -351.23793) (xy 83.107697 -351.230165) (xy 83.134962 -351.229676)
			(xy 83.998562 -351.229676) (xy 84.025837 -351.230061) (xy 84.079834 -351.23782) (xy 84.132176 -351.253184)
			(xy 84.181799 -351.275842) (xy 84.227692 -351.305331) (xy 84.268921 -351.341052) (xy 84.304646 -351.382277)
			(xy 84.33414 -351.428167) (xy 84.356803 -351.477788) (xy 84.372172 -351.530129) (xy 84.379936 -351.584125)
			(xy 84.379936 -351.638669) (xy 85.862639 -351.638669) (xy 85.862639 -351.584131) (xy 85.870401 -351.530147)
			(xy 85.885767 -351.477818) (xy 85.908424 -351.428208) (xy 85.937911 -351.382328) (xy 85.973627 -351.341112)
			(xy 86.014846 -351.305398) (xy 86.060728 -351.275914) (xy 86.110339 -351.25326) (xy 86.162669 -351.237897)
			(xy 86.216653 -351.230138) (xy 86.243922 -351.229676) (xy 87.107522 -351.229676) (xy 87.134793 -351.230088)
			(xy 87.18878 -351.237853) (xy 87.241112 -351.253222) (xy 87.290724 -351.275881) (xy 87.336607 -351.305371)
			(xy 87.377826 -351.34109) (xy 87.413542 -351.382311) (xy 87.443029 -351.428195) (xy 87.465686 -351.477809)
			(xy 87.481052 -351.530142) (xy 87.488814 -351.584129) (xy 87.488814 -351.638666) (xy 88.971662 -351.638666)
			(xy 88.971662 -351.584134) (xy 88.979423 -351.530158) (xy 88.994786 -351.477835) (xy 89.017438 -351.428231)
			(xy 89.04692 -351.382355) (xy 89.082629 -351.341142) (xy 89.123841 -351.30543) (xy 89.169715 -351.275947)
			(xy 89.219318 -351.253292) (xy 89.27164 -351.237927) (xy 89.325616 -351.230164) (xy 89.352882 -351.229676)
			(xy 90.216482 -351.229676) (xy 90.243757 -351.230062) (xy 90.297751 -351.237823) (xy 90.350091 -351.253189)
			(xy 90.399711 -351.275848) (xy 90.445602 -351.305338) (xy 90.486828 -351.341059) (xy 90.522551 -351.382284)
			(xy 90.552043 -351.428173) (xy 90.574704 -351.477792) (xy 90.590073 -351.530132) (xy 90.597836 -351.584125)
			(xy 90.597836 -351.63867) (xy 92.08054 -351.63867) (xy 92.08054 -351.58413) (xy 92.088302 -351.530145)
			(xy 92.103669 -351.477814) (xy 92.126327 -351.428203) (xy 92.155816 -351.382322) (xy 92.191534 -351.341105)
			(xy 92.232755 -351.305391) (xy 92.27864 -351.275907) (xy 92.328253 -351.253254) (xy 92.380586 -351.237893)
			(xy 92.434572 -351.230137) (xy 92.461842 -351.229676) (xy 93.325442 -351.229676) (xy 93.352712 -351.230089)
			(xy 93.406697 -351.237857) (xy 93.459026 -351.253227) (xy 93.508636 -351.275888) (xy 93.554516 -351.305378)
			(xy 93.595733 -351.341097) (xy 93.631447 -351.382317) (xy 93.660932 -351.428201) (xy 93.683588 -351.477813)
			(xy 93.698952 -351.530145) (xy 93.706714 -351.58413) (xy 93.706714 -351.638669) (xy 111.480839 -351.638669)
			(xy 111.480839 -351.584131) (xy 111.488601 -351.530149) (xy 111.503966 -351.477821) (xy 111.526622 -351.428212)
			(xy 111.556107 -351.382333) (xy 111.591822 -351.341117) (xy 111.633039 -351.305403) (xy 111.678919 -351.275918)
			(xy 111.728529 -351.253263) (xy 111.780857 -351.237899) (xy 111.834839 -351.230139) (xy 111.862108 -351.229676)
			(xy 112.725708 -351.229676) (xy 112.75298 -351.230087) (xy 112.806968 -351.23785) (xy 112.859302 -351.253218)
			(xy 112.908916 -351.275877) (xy 112.9548 -351.305366) (xy 112.996021 -351.341085) (xy 113.031739 -351.382306)
			(xy 113.061227 -351.428191) (xy 113.083885 -351.477806) (xy 113.099251 -351.53014) (xy 113.107014 -351.584128)
			(xy 113.107014 -351.638665) (xy 114.589862 -351.638665) (xy 114.589862 -351.584135) (xy 114.597622 -351.530159)
			(xy 114.612984 -351.477838) (xy 114.635636 -351.428234) (xy 114.665116 -351.38236) (xy 114.700824 -351.341147)
			(xy 114.742034 -351.305435) (xy 114.787906 -351.275951) (xy 114.837508 -351.253296) (xy 114.889828 -351.237929)
			(xy 114.943803 -351.230165) (xy 114.971068 -351.229676) (xy 115.834668 -351.229676) (xy 115.861943 -351.230061)
			(xy 115.915939 -351.237821) (xy 115.968281 -351.253186) (xy 116.017903 -351.275844) (xy 116.063795 -351.305333)
			(xy 116.105023 -351.341054) (xy 116.140747 -351.382279) (xy 116.170241 -351.428169) (xy 116.192903 -351.477789)
			(xy 116.208273 -351.53013) (xy 116.216036 -351.584125) (xy 116.216036 -351.63867) (xy 117.698739 -351.63867)
			(xy 117.698739 -351.58413) (xy 117.706502 -351.530146) (xy 117.721868 -351.477817) (xy 117.744525 -351.428207)
			(xy 117.774012 -351.382326) (xy 117.809729 -351.341109) (xy 117.850949 -351.305396) (xy 117.896831 -351.275912)
			(xy 117.946443 -351.253258) (xy 117.998774 -351.237896) (xy 118.052758 -351.230137) (xy 118.080028 -351.229676)
			(xy 118.943628 -351.229676) (xy 118.970899 -351.230088) (xy 119.024885 -351.237854) (xy 119.077216 -351.253223)
			(xy 119.126828 -351.275883) (xy 119.17271 -351.305373) (xy 119.213928 -351.341092) (xy 119.249644 -351.382313)
			(xy 119.27913 -351.428197) (xy 119.301786 -351.47781) (xy 119.317152 -351.530143) (xy 119.324914 -351.584129)
			(xy 119.324914 -351.638666) (xy 120.807762 -351.638666) (xy 120.807762 -351.584134) (xy 120.815523 -351.530157)
			(xy 120.830886 -351.477833) (xy 120.853539 -351.428229) (xy 120.883021 -351.382353) (xy 120.918731 -351.34114)
			(xy 120.959943 -351.305428) (xy 121.005818 -351.275945) (xy 121.055422 -351.25329) (xy 121.107745 -351.237925)
			(xy 121.161722 -351.230163) (xy 121.188988 -351.229676) (xy 122.052588 -351.229676) (xy 122.079862 -351.230063)
			(xy 122.133856 -351.237824) (xy 122.186195 -351.253191) (xy 122.235815 -351.27585) (xy 122.281704 -351.30534)
			(xy 122.32293 -351.341061) (xy 122.358652 -351.382286) (xy 122.388144 -351.428175) (xy 122.410805 -351.477794)
			(xy 122.426173 -351.530132) (xy 122.433936 -351.584126) (xy 122.433936 -351.63867) (xy 123.91664 -351.63867)
			(xy 123.91664 -351.58413) (xy 123.924402 -351.530144) (xy 123.939769 -351.477812) (xy 123.962428 -351.428201)
			(xy 123.991917 -351.38232) (xy 124.027636 -351.341102) (xy 124.068858 -351.305388) (xy 124.114743 -351.275905)
			(xy 124.164358 -351.253253) (xy 124.216691 -351.237892) (xy 124.270677 -351.230136) (xy 124.297948 -351.229676)
			(xy 125.161548 -351.229676) (xy 125.188818 -351.23009) (xy 125.242802 -351.237858) (xy 125.295131 -351.253229)
			(xy 125.34474 -351.27589) (xy 125.390619 -351.30538) (xy 125.431835 -351.341099) (xy 125.467549 -351.382319)
			(xy 125.497033 -351.428203) (xy 125.519688 -351.477814) (xy 125.535052 -351.530145) (xy 125.542814 -351.58413)
			(xy 125.542814 -351.638669) (xy 127.025639 -351.638669) (xy 127.025639 -351.584131) (xy 127.033401 -351.530149)
			(xy 127.048766 -351.477821) (xy 127.071422 -351.428212) (xy 127.100907 -351.382333) (xy 127.136622 -351.341117)
			(xy 127.177839 -351.305403) (xy 127.223719 -351.275918) (xy 127.273329 -351.253263) (xy 127.325657 -351.237899)
			(xy 127.379639 -351.230139) (xy 127.406908 -351.229676) (xy 128.270508 -351.229676) (xy 128.29778 -351.230087)
			(xy 128.351768 -351.23785) (xy 128.404102 -351.253218) (xy 128.453716 -351.275877) (xy 128.4996 -351.305366)
			(xy 128.540821 -351.341085) (xy 128.576539 -351.382306) (xy 128.606027 -351.428191) (xy 128.628685 -351.477806)
			(xy 128.644051 -351.53014) (xy 128.651814 -351.584128) (xy 128.651814 -351.638665) (xy 130.134662 -351.638665)
			(xy 130.134662 -351.584135) (xy 130.142422 -351.530159) (xy 130.157784 -351.477838) (xy 130.180436 -351.428234)
			(xy 130.209916 -351.38236) (xy 130.245624 -351.341147) (xy 130.286834 -351.305435) (xy 130.332706 -351.275951)
			(xy 130.382308 -351.253296) (xy 130.434628 -351.237929) (xy 130.488603 -351.230165) (xy 130.515868 -351.229676)
			(xy 131.379468 -351.229676) (xy 131.406743 -351.230061) (xy 131.460739 -351.237821) (xy 131.513081 -351.253186)
			(xy 131.562703 -351.275844) (xy 131.608595 -351.305333) (xy 131.649823 -351.341054) (xy 131.685547 -351.382279)
			(xy 131.715041 -351.428169) (xy 131.737703 -351.477789) (xy 131.753073 -351.53013) (xy 131.760836 -351.584125)
			(xy 131.760836 -351.63867) (xy 133.243539 -351.63867) (xy 133.243539 -351.58413) (xy 133.251302 -351.530146)
			(xy 133.266668 -351.477817) (xy 133.289325 -351.428207) (xy 133.318812 -351.382326) (xy 133.354529 -351.341109)
			(xy 133.395749 -351.305396) (xy 133.441631 -351.275912) (xy 133.491243 -351.253258) (xy 133.543574 -351.237896)
			(xy 133.597558 -351.230137) (xy 133.624828 -351.229676) (xy 134.488428 -351.229676) (xy 134.515699 -351.230088)
			(xy 134.569685 -351.237854) (xy 134.622016 -351.253223) (xy 134.671628 -351.275883) (xy 134.71751 -351.305373)
			(xy 134.758728 -351.341092) (xy 134.794444 -351.382313) (xy 134.82393 -351.428197) (xy 134.846586 -351.47781)
			(xy 134.861952 -351.530143) (xy 134.869714 -351.584129) (xy 134.869714 -351.638666) (xy 136.352562 -351.638666)
			(xy 136.352562 -351.584134) (xy 136.360323 -351.530157) (xy 136.375686 -351.477833) (xy 136.398339 -351.428229)
			(xy 136.427821 -351.382353) (xy 136.463531 -351.34114) (xy 136.504743 -351.305428) (xy 136.550618 -351.275945)
			(xy 136.600222 -351.25329) (xy 136.652545 -351.237925) (xy 136.706522 -351.230163) (xy 136.733788 -351.229676)
			(xy 137.597388 -351.229676) (xy 137.624662 -351.230063) (xy 137.678656 -351.237824) (xy 137.730995 -351.253191)
			(xy 137.780615 -351.27585) (xy 137.826504 -351.30534) (xy 137.86773 -351.341061) (xy 137.903452 -351.382286)
			(xy 137.932944 -351.428175) (xy 137.955605 -351.477794) (xy 137.970973 -351.530132) (xy 137.978736 -351.584126)
			(xy 137.978736 -351.63867) (xy 139.46144 -351.63867) (xy 139.46144 -351.58413) (xy 139.469202 -351.530144)
			(xy 139.484569 -351.477812) (xy 139.507228 -351.428201) (xy 139.536717 -351.38232) (xy 139.572436 -351.341102)
			(xy 139.613658 -351.305388) (xy 139.659543 -351.275905) (xy 139.709158 -351.253253) (xy 139.761491 -351.237892)
			(xy 139.815477 -351.230136) (xy 139.842748 -351.229676) (xy 140.706348 -351.229676) (xy 140.733618 -351.23009)
			(xy 140.787602 -351.237858) (xy 140.839931 -351.253229) (xy 140.88954 -351.27589) (xy 140.935419 -351.30538)
			(xy 140.976635 -351.341099) (xy 141.012349 -351.382319) (xy 141.041833 -351.428203) (xy 141.064488 -351.477814)
			(xy 141.079852 -351.530145) (xy 141.087614 -351.58413) (xy 141.087614 -351.638669) (xy 142.570439 -351.638669)
			(xy 142.570439 -351.584131) (xy 142.578201 -351.530149) (xy 142.593566 -351.477821) (xy 142.616222 -351.428212)
			(xy 142.645707 -351.382333) (xy 142.681422 -351.341117) (xy 142.722639 -351.305403) (xy 142.768519 -351.275918)
			(xy 142.818129 -351.253263) (xy 142.870457 -351.237899) (xy 142.924439 -351.230139) (xy 142.951708 -351.229676)
			(xy 143.815308 -351.229676) (xy 143.84258 -351.230087) (xy 143.896568 -351.23785) (xy 143.948902 -351.253218)
			(xy 143.998516 -351.275877) (xy 144.0444 -351.305366) (xy 144.085621 -351.341085) (xy 144.121339 -351.382306)
			(xy 144.150827 -351.428191) (xy 144.173485 -351.477806) (xy 144.188851 -351.53014) (xy 144.196614 -351.584128)
			(xy 144.196614 -351.638669) (xy 161.804839 -351.638669) (xy 161.804839 -351.584131) (xy 161.812601 -351.530149)
			(xy 161.827966 -351.47782) (xy 161.850623 -351.428211) (xy 161.880108 -351.382331) (xy 161.915824 -351.341115)
			(xy 161.957041 -351.305401) (xy 162.002922 -351.275917) (xy 162.052531 -351.253262) (xy 162.10486 -351.237899)
			(xy 162.158843 -351.230139) (xy 162.186112 -351.229676) (xy 163.049712 -351.229676) (xy 163.076984 -351.230087)
			(xy 163.130971 -351.237851) (xy 163.183304 -351.253219) (xy 163.232918 -351.275878) (xy 163.278802 -351.305367)
			(xy 163.320022 -351.341086) (xy 163.35574 -351.382308) (xy 163.385228 -351.428192) (xy 163.407885 -351.477807)
			(xy 163.423251 -351.530141) (xy 163.431014 -351.584128) (xy 163.431014 -351.638665) (xy 164.913862 -351.638665)
			(xy 164.913862 -351.584135) (xy 164.921622 -351.530159) (xy 164.936985 -351.477837) (xy 164.959637 -351.428233)
			(xy 164.989117 -351.382358) (xy 165.024826 -351.341146) (xy 165.066036 -351.305434) (xy 165.111909 -351.27595)
			(xy 165.16151 -351.253295) (xy 165.213831 -351.237928) (xy 165.267807 -351.230164) (xy 165.295072 -351.229676)
			(xy 166.158672 -351.229676) (xy 166.185947 -351.230062) (xy 166.239942 -351.237821) (xy 166.292284 -351.253187)
			(xy 166.341905 -351.275845) (xy 166.387797 -351.305335) (xy 166.429024 -351.341056) (xy 166.464748 -351.382281)
			(xy 166.494242 -351.42817) (xy 166.516903 -351.47779) (xy 166.532273 -351.53013) (xy 166.540036 -351.584125)
			(xy 166.540036 -351.63867) (xy 168.022739 -351.63867) (xy 168.022739 -351.58413) (xy 168.030502 -351.530146)
			(xy 168.045868 -351.477816) (xy 168.068526 -351.428206) (xy 168.098013 -351.382325) (xy 168.133731 -351.341108)
			(xy 168.174951 -351.305394) (xy 168.220834 -351.27591) (xy 168.270446 -351.253257) (xy 168.322777 -351.237895)
			(xy 168.376762 -351.230137) (xy 168.404032 -351.229676) (xy 169.267632 -351.229676) (xy 169.294903 -351.230089)
			(xy 169.348888 -351.237855) (xy 169.401219 -351.253224) (xy 169.45083 -351.275885) (xy 169.496712 -351.305374)
			(xy 169.537929 -351.341093) (xy 169.573645 -351.382314) (xy 169.603131 -351.428198) (xy 169.625787 -351.477811)
			(xy 169.641152 -351.530143) (xy 169.648914 -351.584129) (xy 169.648914 -351.638666) (xy 171.131762 -351.638666)
			(xy 171.131762 -351.584134) (xy 171.139523 -351.530156) (xy 171.154886 -351.477832) (xy 171.17754 -351.428228)
			(xy 171.207022 -351.382352) (xy 171.242733 -351.341138) (xy 171.283945 -351.305427) (xy 171.329821 -351.275944)
			(xy 171.379425 -351.253289) (xy 171.431748 -351.237925) (xy 171.485726 -351.230163) (xy 171.512992 -351.229676)
			(xy 172.376592 -351.229676) (xy 172.403866 -351.230063) (xy 172.457859 -351.237825) (xy 172.510198 -351.253192)
			(xy 172.559817 -351.275851) (xy 172.605706 -351.305342) (xy 172.646932 -351.341063) (xy 172.682653 -351.382287)
			(xy 172.712145 -351.428176) (xy 172.734805 -351.477794) (xy 172.750173 -351.530133) (xy 172.757936 -351.584126)
			(xy 172.757936 -351.638664) (xy 174.240762 -351.638664) (xy 174.240762 -351.584136) (xy 174.248522 -351.530162)
			(xy 174.263883 -351.477841) (xy 174.286534 -351.428239) (xy 174.316012 -351.382365) (xy 174.351719 -351.341153)
			(xy 174.392926 -351.305441) (xy 174.438797 -351.275957) (xy 174.488396 -351.2533) (xy 174.540715 -351.237932)
			(xy 174.594688 -351.230166) (xy 174.621952 -351.229676) (xy 175.485552 -351.229676) (xy 175.512828 -351.23006)
			(xy 175.566825 -351.237818) (xy 175.619169 -351.253181) (xy 175.668793 -351.275838) (xy 175.714687 -351.305328)
			(xy 175.755917 -351.341049) (xy 175.791644 -351.382274) (xy 175.821139 -351.428165) (xy 175.843802 -351.477786)
			(xy 175.859172 -351.530128) (xy 175.866936 -351.584124) (xy 175.866936 -351.638669) (xy 177.349639 -351.638669)
			(xy 177.349639 -351.584131) (xy 177.357401 -351.530149) (xy 177.372766 -351.47782) (xy 177.395423 -351.428211)
			(xy 177.424908 -351.382331) (xy 177.460624 -351.341115) (xy 177.501841 -351.305401) (xy 177.547722 -351.275917)
			(xy 177.597331 -351.253262) (xy 177.64966 -351.237899) (xy 177.703643 -351.230139) (xy 177.730912 -351.229676)
			(xy 178.594512 -351.229676) (xy 178.621784 -351.230087) (xy 178.675771 -351.237851) (xy 178.728104 -351.253219)
			(xy 178.777718 -351.275878) (xy 178.823602 -351.305367) (xy 178.864822 -351.341086) (xy 178.90054 -351.382308)
			(xy 178.930028 -351.428192) (xy 178.952685 -351.477807) (xy 178.968051 -351.530141) (xy 178.975814 -351.584128)
			(xy 178.975814 -351.638665) (xy 180.458662 -351.638665) (xy 180.458662 -351.584135) (xy 180.466422 -351.530159)
			(xy 180.481785 -351.477837) (xy 180.504437 -351.428233) (xy 180.533917 -351.382358) (xy 180.569626 -351.341146)
			(xy 180.610836 -351.305434) (xy 180.656709 -351.27595) (xy 180.70631 -351.253295) (xy 180.758631 -351.237928)
			(xy 180.812607 -351.230164) (xy 180.839872 -351.229676) (xy 181.703472 -351.229676) (xy 181.730747 -351.230062)
			(xy 181.784742 -351.237821) (xy 181.837084 -351.253187) (xy 181.886705 -351.275845) (xy 181.932597 -351.305335)
			(xy 181.973824 -351.341056) (xy 182.009548 -351.382281) (xy 182.039042 -351.42817) (xy 182.061703 -351.47779)
			(xy 182.077073 -351.53013) (xy 182.084836 -351.584125) (xy 182.084836 -351.63867) (xy 183.567539 -351.63867)
			(xy 183.567539 -351.58413) (xy 183.575302 -351.530146) (xy 183.590668 -351.477816) (xy 183.613326 -351.428206)
			(xy 183.642813 -351.382325) (xy 183.678531 -351.341108) (xy 183.719751 -351.305394) (xy 183.765634 -351.27591)
			(xy 183.815246 -351.253257) (xy 183.867577 -351.237895) (xy 183.921562 -351.230137) (xy 183.948832 -351.229676)
			(xy 184.812432 -351.229676) (xy 184.839703 -351.230089) (xy 184.893688 -351.237855) (xy 184.946019 -351.253224)
			(xy 184.99563 -351.275885) (xy 185.041512 -351.305374) (xy 185.082729 -351.341093) (xy 185.118445 -351.382314)
			(xy 185.147931 -351.428198) (xy 185.170587 -351.477811) (xy 185.185952 -351.530143) (xy 185.193714 -351.584129)
			(xy 185.193714 -351.638666) (xy 186.676562 -351.638666) (xy 186.676562 -351.584134) (xy 186.684323 -351.530156)
			(xy 186.699686 -351.477832) (xy 186.72234 -351.428228) (xy 186.751822 -351.382352) (xy 186.787533 -351.341138)
			(xy 186.828745 -351.305427) (xy 186.874621 -351.275944) (xy 186.924225 -351.253289) (xy 186.976548 -351.237925)
			(xy 187.030526 -351.230163) (xy 187.057792 -351.229676) (xy 187.921392 -351.229676) (xy 187.948666 -351.230063)
			(xy 188.002659 -351.237825) (xy 188.054998 -351.253192) (xy 188.104617 -351.275851) (xy 188.150506 -351.305342)
			(xy 188.191732 -351.341063) (xy 188.227453 -351.382287) (xy 188.256945 -351.428176) (xy 188.279605 -351.477794)
			(xy 188.294973 -351.530133) (xy 188.302736 -351.584126) (xy 188.302736 -351.638664) (xy 189.785562 -351.638664)
			(xy 189.785562 -351.584136) (xy 189.793322 -351.530162) (xy 189.808683 -351.477841) (xy 189.831334 -351.428239)
			(xy 189.860812 -351.382365) (xy 189.896519 -351.341153) (xy 189.937726 -351.305441) (xy 189.983597 -351.275957)
			(xy 190.033196 -351.2533) (xy 190.085515 -351.237932) (xy 190.139488 -351.230166) (xy 190.166752 -351.229676)
			(xy 191.030352 -351.229676) (xy 191.057628 -351.23006) (xy 191.111625 -351.237818) (xy 191.163969 -351.253181)
			(xy 191.213593 -351.275838) (xy 191.259487 -351.305328) (xy 191.300717 -351.341049) (xy 191.336444 -351.382274)
			(xy 191.365939 -351.428165) (xy 191.388602 -351.477786) (xy 191.403972 -351.530128) (xy 191.411736 -351.584124)
			(xy 191.411736 -351.638669) (xy 192.894439 -351.638669) (xy 192.894439 -351.584131) (xy 192.902201 -351.530149)
			(xy 192.917566 -351.47782) (xy 192.940223 -351.428211) (xy 192.969708 -351.382331) (xy 193.005424 -351.341115)
			(xy 193.046641 -351.305401) (xy 193.092522 -351.275917) (xy 193.142131 -351.253262) (xy 193.19446 -351.237899)
			(xy 193.248443 -351.230139) (xy 193.275712 -351.229676) (xy 194.139312 -351.229676) (xy 194.166584 -351.230087)
			(xy 194.220571 -351.237851) (xy 194.272904 -351.253219) (xy 194.322518 -351.275878) (xy 194.368402 -351.305367)
			(xy 194.409622 -351.341086) (xy 194.44534 -351.382308) (xy 194.474828 -351.428192) (xy 194.497485 -351.477807)
			(xy 194.512851 -351.530141) (xy 194.520614 -351.584128) (xy 194.520614 -351.638672) (xy 194.512851 -351.692659)
			(xy 194.497485 -351.744993) (xy 194.474828 -351.794608) (xy 194.44534 -351.840492) (xy 194.409622 -351.881714)
			(xy 194.368402 -351.917433) (xy 194.322518 -351.946922) (xy 194.272904 -351.969581) (xy 194.220571 -351.984949)
			(xy 194.166584 -351.992713) (xy 194.139312 -351.9932) (xy 193.275712 -351.9932) (xy 193.248443 -351.992661)
			(xy 193.19446 -351.984901) (xy 193.142131 -351.969538) (xy 193.092522 -351.946883) (xy 193.046641 -351.917399)
			(xy 193.005424 -351.881685) (xy 192.969708 -351.840469) (xy 192.940223 -351.794589) (xy 192.917566 -351.74498)
			(xy 192.902201 -351.692651) (xy 192.894439 -351.638669) (xy 191.411736 -351.638669) (xy 191.411736 -351.638676)
			(xy 191.403972 -351.692672) (xy 191.388602 -351.745014) (xy 191.365939 -351.794635) (xy 191.336444 -351.840526)
			(xy 191.300717 -351.881751) (xy 191.259487 -351.917472) (xy 191.213593 -351.946962) (xy 191.163969 -351.969619)
			(xy 191.111625 -351.984982) (xy 191.057628 -351.99274) (xy 191.030352 -351.9932) (xy 190.166752 -351.9932)
			(xy 190.139488 -351.992634) (xy 190.085515 -351.984868) (xy 190.033196 -351.9695) (xy 189.983597 -351.946843)
			(xy 189.937726 -351.917359) (xy 189.896519 -351.881647) (xy 189.860812 -351.840435) (xy 189.831334 -351.794561)
			(xy 189.808683 -351.744959) (xy 189.793322 -351.692639) (xy 189.785562 -351.638664) (xy 188.302736 -351.638664)
			(xy 188.302736 -351.638674) (xy 188.294973 -351.692667) (xy 188.279605 -351.745006) (xy 188.256945 -351.794624)
			(xy 188.227453 -351.840513) (xy 188.191732 -351.881737) (xy 188.150506 -351.917458) (xy 188.104617 -351.946949)
			(xy 188.054998 -351.969608) (xy 188.002659 -351.984975) (xy 187.948666 -351.992737) (xy 187.921392 -351.9932)
			(xy 187.057792 -351.9932) (xy 187.030526 -351.992637) (xy 186.976548 -351.984875) (xy 186.924225 -351.969511)
			(xy 186.874621 -351.946856) (xy 186.828745 -351.917373) (xy 186.787533 -351.881662) (xy 186.751822 -351.840448)
			(xy 186.72234 -351.794572) (xy 186.699686 -351.744968) (xy 186.684323 -351.692644) (xy 186.676562 -351.638666)
			(xy 185.193714 -351.638666) (xy 185.193714 -351.638671) (xy 185.185952 -351.692657) (xy 185.170587 -351.744989)
			(xy 185.147931 -351.794602) (xy 185.118445 -351.840486) (xy 185.082729 -351.881707) (xy 185.041512 -351.917426)
			(xy 184.99563 -351.946915) (xy 184.946019 -351.969576) (xy 184.893688 -351.984945) (xy 184.839703 -351.992711)
			(xy 184.812432 -351.9932) (xy 183.948832 -351.9932) (xy 183.921562 -351.992663) (xy 183.867577 -351.984905)
			(xy 183.815246 -351.969543) (xy 183.765634 -351.94689) (xy 183.719751 -351.917406) (xy 183.678531 -351.881692)
			(xy 183.642813 -351.840475) (xy 183.613326 -351.794594) (xy 183.590668 -351.744984) (xy 183.575302 -351.692654)
			(xy 183.567539 -351.63867) (xy 182.084836 -351.63867) (xy 182.084836 -351.638675) (xy 182.077073 -351.69267)
			(xy 182.061703 -351.74501) (xy 182.039042 -351.79463) (xy 182.009548 -351.840519) (xy 181.973824 -351.881744)
			(xy 181.932597 -351.917465) (xy 181.886705 -351.946955) (xy 181.837084 -351.969613) (xy 181.784742 -351.984979)
			(xy 181.730747 -351.992738) (xy 181.703472 -351.9932) (xy 180.839872 -351.9932) (xy 180.812607 -351.992636)
			(xy 180.758631 -351.984872) (xy 180.70631 -351.969505) (xy 180.656709 -351.94685) (xy 180.610836 -351.917366)
			(xy 180.569626 -351.881654) (xy 180.533917 -351.840442) (xy 180.504437 -351.794567) (xy 180.481785 -351.744963)
			(xy 180.466422 -351.692641) (xy 180.458662 -351.638665) (xy 178.975814 -351.638665) (xy 178.975814 -351.638672)
			(xy 178.968051 -351.692659) (xy 178.952685 -351.744993) (xy 178.930028 -351.794608) (xy 178.90054 -351.840492)
			(xy 178.864822 -351.881714) (xy 178.823602 -351.917433) (xy 178.777718 -351.946922) (xy 178.728104 -351.969581)
			(xy 178.675771 -351.984949) (xy 178.621784 -351.992713) (xy 178.594512 -351.9932) (xy 177.730912 -351.9932)
			(xy 177.703643 -351.992661) (xy 177.64966 -351.984901) (xy 177.597331 -351.969538) (xy 177.547722 -351.946883)
			(xy 177.501841 -351.917399) (xy 177.460624 -351.881685) (xy 177.424908 -351.840469) (xy 177.395423 -351.794589)
			(xy 177.372766 -351.74498) (xy 177.357401 -351.692651) (xy 177.349639 -351.638669) (xy 175.866936 -351.638669)
			(xy 175.866936 -351.638676) (xy 175.859172 -351.692672) (xy 175.843802 -351.745014) (xy 175.821139 -351.794635)
			(xy 175.791644 -351.840526) (xy 175.755917 -351.881751) (xy 175.714687 -351.917472) (xy 175.668793 -351.946962)
			(xy 175.619169 -351.969619) (xy 175.566825 -351.984982) (xy 175.512828 -351.99274) (xy 175.485552 -351.9932)
			(xy 174.621952 -351.9932) (xy 174.594688 -351.992634) (xy 174.540715 -351.984868) (xy 174.488396 -351.9695)
			(xy 174.438797 -351.946843) (xy 174.392926 -351.917359) (xy 174.351719 -351.881647) (xy 174.316012 -351.840435)
			(xy 174.286534 -351.794561) (xy 174.263883 -351.744959) (xy 174.248522 -351.692639) (xy 174.240762 -351.638664)
			(xy 172.757936 -351.638664) (xy 172.757936 -351.638674) (xy 172.750173 -351.692667) (xy 172.734805 -351.745006)
			(xy 172.712145 -351.794624) (xy 172.682653 -351.840513) (xy 172.646932 -351.881737) (xy 172.605706 -351.917458)
			(xy 172.559817 -351.946949) (xy 172.510198 -351.969608) (xy 172.457859 -351.984975) (xy 172.403866 -351.992737)
			(xy 172.376592 -351.9932) (xy 171.512992 -351.9932) (xy 171.485726 -351.992637) (xy 171.431748 -351.984875)
			(xy 171.379425 -351.969511) (xy 171.329821 -351.946856) (xy 171.283945 -351.917373) (xy 171.242733 -351.881662)
			(xy 171.207022 -351.840448) (xy 171.17754 -351.794572) (xy 171.154886 -351.744968) (xy 171.139523 -351.692644)
			(xy 171.131762 -351.638666) (xy 169.648914 -351.638666) (xy 169.648914 -351.638671) (xy 169.641152 -351.692657)
			(xy 169.625787 -351.744989) (xy 169.603131 -351.794602) (xy 169.573645 -351.840486) (xy 169.537929 -351.881707)
			(xy 169.496712 -351.917426) (xy 169.45083 -351.946915) (xy 169.401219 -351.969576) (xy 169.348888 -351.984945)
			(xy 169.294903 -351.992711) (xy 169.267632 -351.9932) (xy 168.404032 -351.9932) (xy 168.376762 -351.992663)
			(xy 168.322777 -351.984905) (xy 168.270446 -351.969543) (xy 168.220834 -351.94689) (xy 168.174951 -351.917406)
			(xy 168.133731 -351.881692) (xy 168.098013 -351.840475) (xy 168.068526 -351.794594) (xy 168.045868 -351.744984)
			(xy 168.030502 -351.692654) (xy 168.022739 -351.63867) (xy 166.540036 -351.63867) (xy 166.540036 -351.638675)
			(xy 166.532273 -351.69267) (xy 166.516903 -351.74501) (xy 166.494242 -351.79463) (xy 166.464748 -351.840519)
			(xy 166.429024 -351.881744) (xy 166.387797 -351.917465) (xy 166.341905 -351.946955) (xy 166.292284 -351.969613)
			(xy 166.239942 -351.984979) (xy 166.185947 -351.992738) (xy 166.158672 -351.9932) (xy 165.295072 -351.9932)
			(xy 165.267807 -351.992636) (xy 165.213831 -351.984872) (xy 165.16151 -351.969505) (xy 165.111909 -351.94685)
			(xy 165.066036 -351.917366) (xy 165.024826 -351.881654) (xy 164.989117 -351.840442) (xy 164.959637 -351.794567)
			(xy 164.936985 -351.744963) (xy 164.921622 -351.692641) (xy 164.913862 -351.638665) (xy 163.431014 -351.638665)
			(xy 163.431014 -351.638672) (xy 163.423251 -351.692659) (xy 163.407885 -351.744993) (xy 163.385228 -351.794608)
			(xy 163.35574 -351.840492) (xy 163.320022 -351.881714) (xy 163.278802 -351.917433) (xy 163.232918 -351.946922)
			(xy 163.183304 -351.969581) (xy 163.130971 -351.984949) (xy 163.076984 -351.992713) (xy 163.049712 -351.9932)
			(xy 162.186112 -351.9932) (xy 162.158843 -351.992661) (xy 162.10486 -351.984901) (xy 162.052531 -351.969538)
			(xy 162.002922 -351.946883) (xy 161.957041 -351.917399) (xy 161.915824 -351.881685) (xy 161.880108 -351.840469)
			(xy 161.850623 -351.794589) (xy 161.827966 -351.74498) (xy 161.812601 -351.692651) (xy 161.804839 -351.638669)
			(xy 144.196614 -351.638669) (xy 144.196614 -351.638672) (xy 144.188851 -351.69266) (xy 144.173485 -351.744994)
			(xy 144.150827 -351.794609) (xy 144.121339 -351.840494) (xy 144.085621 -351.881715) (xy 144.0444 -351.917434)
			(xy 143.998516 -351.946923) (xy 143.948902 -351.969582) (xy 143.896568 -351.98495) (xy 143.84258 -351.992713)
			(xy 143.815308 -351.9932) (xy 142.951708 -351.9932) (xy 142.924439 -351.992661) (xy 142.870457 -351.984901)
			(xy 142.818129 -351.969537) (xy 142.768519 -351.946882) (xy 142.722639 -351.917397) (xy 142.681422 -351.881683)
			(xy 142.645707 -351.840467) (xy 142.616222 -351.794588) (xy 142.593566 -351.744979) (xy 142.578201 -351.692651)
			(xy 142.570439 -351.638669) (xy 141.087614 -351.638669) (xy 141.087614 -351.63867) (xy 141.079852 -351.692655)
			(xy 141.064488 -351.744986) (xy 141.041833 -351.794597) (xy 141.012349 -351.840481) (xy 140.976635 -351.881701)
			(xy 140.935419 -351.91742) (xy 140.88954 -351.94691) (xy 140.839931 -351.969571) (xy 140.787602 -351.984942)
			(xy 140.733618 -351.99271) (xy 140.706348 -351.9932) (xy 139.842748 -351.9932) (xy 139.815477 -351.992664)
			(xy 139.761491 -351.984908) (xy 139.709158 -351.969547) (xy 139.659543 -351.946895) (xy 139.613658 -351.917411)
			(xy 139.572436 -351.881698) (xy 139.536717 -351.84048) (xy 139.507228 -351.794599) (xy 139.484569 -351.744987)
			(xy 139.469202 -351.692656) (xy 139.46144 -351.63867) (xy 137.978736 -351.63867) (xy 137.978736 -351.638674)
			(xy 137.970973 -351.692668) (xy 137.955605 -351.745006) (xy 137.932944 -351.794625) (xy 137.903452 -351.840514)
			(xy 137.86773 -351.881739) (xy 137.826504 -351.91746) (xy 137.780615 -351.94695) (xy 137.730995 -351.969609)
			(xy 137.678656 -351.984976) (xy 137.624662 -351.992737) (xy 137.597388 -351.9932) (xy 136.733788 -351.9932)
			(xy 136.706522 -351.992637) (xy 136.652545 -351.984875) (xy 136.600222 -351.96951) (xy 136.550618 -351.946855)
			(xy 136.504744 -351.917372) (xy 136.463531 -351.88166) (xy 136.427821 -351.840447) (xy 136.398339 -351.794571)
			(xy 136.375686 -351.744967) (xy 136.360323 -351.692643) (xy 136.352562 -351.638666) (xy 134.869714 -351.638666)
			(xy 134.869714 -351.638671) (xy 134.861952 -351.692657) (xy 134.846586 -351.74499) (xy 134.82393 -351.794603)
			(xy 134.794444 -351.840487) (xy 134.758728 -351.881708) (xy 134.71751 -351.917427) (xy 134.671628 -351.946917)
			(xy 134.622016 -351.969577) (xy 134.569685 -351.984946) (xy 134.515699 -351.992712) (xy 134.488428 -351.9932)
			(xy 133.624828 -351.9932) (xy 133.597558 -351.992663) (xy 133.543574 -351.984904) (xy 133.491243 -351.969542)
			(xy 133.441631 -351.946888) (xy 133.395749 -351.917404) (xy 133.354529 -351.881691) (xy 133.318812 -351.840474)
			(xy 133.289325 -351.794593) (xy 133.266668 -351.744983) (xy 133.251302 -351.692654) (xy 133.243539 -351.63867)
			(xy 131.760836 -351.63867) (xy 131.760836 -351.638675) (xy 131.753073 -351.69267) (xy 131.737703 -351.745011)
			(xy 131.715041 -351.794631) (xy 131.685547 -351.840521) (xy 131.649823 -351.881746) (xy 131.608595 -351.917467)
			(xy 131.562703 -351.946956) (xy 131.513081 -351.969614) (xy 131.460739 -351.984979) (xy 131.406743 -351.992739)
			(xy 131.379468 -351.9932) (xy 130.515868 -351.9932) (xy 130.488603 -351.992635) (xy 130.434628 -351.984871)
			(xy 130.382308 -351.969504) (xy 130.332706 -351.946849) (xy 130.286834 -351.917365) (xy 130.245624 -351.881653)
			(xy 130.209916 -351.84044) (xy 130.180436 -351.794566) (xy 130.157784 -351.744962) (xy 130.142422 -351.692641)
			(xy 130.134662 -351.638665) (xy 128.651814 -351.638665) (xy 128.651814 -351.638672) (xy 128.644051 -351.69266)
			(xy 128.628685 -351.744994) (xy 128.606027 -351.794609) (xy 128.576539 -351.840494) (xy 128.540821 -351.881715)
			(xy 128.4996 -351.917434) (xy 128.453716 -351.946923) (xy 128.404102 -351.969582) (xy 128.351768 -351.98495)
			(xy 128.29778 -351.992713) (xy 128.270508 -351.9932) (xy 127.406908 -351.9932) (xy 127.379639 -351.992661)
			(xy 127.325657 -351.984901) (xy 127.273329 -351.969537) (xy 127.223719 -351.946882) (xy 127.177839 -351.917397)
			(xy 127.136622 -351.881683) (xy 127.100907 -351.840467) (xy 127.071422 -351.794588) (xy 127.048766 -351.744979)
			(xy 127.033401 -351.692651) (xy 127.025639 -351.638669) (xy 125.542814 -351.638669) (xy 125.542814 -351.63867)
			(xy 125.535052 -351.692655) (xy 125.519688 -351.744986) (xy 125.497033 -351.794597) (xy 125.467549 -351.840481)
			(xy 125.431835 -351.881701) (xy 125.390619 -351.91742) (xy 125.34474 -351.94691) (xy 125.295131 -351.969571)
			(xy 125.242802 -351.984942) (xy 125.188818 -351.99271) (xy 125.161548 -351.9932) (xy 124.297948 -351.9932)
			(xy 124.270677 -351.992664) (xy 124.216691 -351.984908) (xy 124.164358 -351.969547) (xy 124.114743 -351.946895)
			(xy 124.068858 -351.917411) (xy 124.027636 -351.881698) (xy 123.991917 -351.84048) (xy 123.962428 -351.794599)
			(xy 123.939769 -351.744987) (xy 123.924402 -351.692656) (xy 123.91664 -351.63867) (xy 122.433936 -351.63867)
			(xy 122.433936 -351.638674) (xy 122.426173 -351.692668) (xy 122.410805 -351.745006) (xy 122.388144 -351.794625)
			(xy 122.358652 -351.840514) (xy 122.32293 -351.881739) (xy 122.281704 -351.91746) (xy 122.235815 -351.94695)
			(xy 122.186195 -351.969609) (xy 122.133856 -351.984976) (xy 122.079862 -351.992737) (xy 122.052588 -351.9932)
			(xy 121.188988 -351.9932) (xy 121.161722 -351.992637) (xy 121.107745 -351.984875) (xy 121.055422 -351.96951)
			(xy 121.005818 -351.946855) (xy 120.959944 -351.917372) (xy 120.918731 -351.88166) (xy 120.883021 -351.840447)
			(xy 120.853539 -351.794571) (xy 120.830886 -351.744967) (xy 120.815523 -351.692643) (xy 120.807762 -351.638666)
			(xy 119.324914 -351.638666) (xy 119.324914 -351.638671) (xy 119.317152 -351.692657) (xy 119.301786 -351.74499)
			(xy 119.27913 -351.794603) (xy 119.249644 -351.840487) (xy 119.213928 -351.881708) (xy 119.17271 -351.917427)
			(xy 119.126828 -351.946917) (xy 119.077216 -351.969577) (xy 119.024885 -351.984946) (xy 118.970899 -351.992712)
			(xy 118.943628 -351.9932) (xy 118.080028 -351.9932) (xy 118.052758 -351.992663) (xy 117.998774 -351.984904)
			(xy 117.946443 -351.969542) (xy 117.896831 -351.946888) (xy 117.850949 -351.917404) (xy 117.809729 -351.881691)
			(xy 117.774012 -351.840474) (xy 117.744525 -351.794593) (xy 117.721868 -351.744983) (xy 117.706502 -351.692654)
			(xy 117.698739 -351.63867) (xy 116.216036 -351.63867) (xy 116.216036 -351.638675) (xy 116.208273 -351.69267)
			(xy 116.192903 -351.745011) (xy 116.170241 -351.794631) (xy 116.140747 -351.840521) (xy 116.105023 -351.881746)
			(xy 116.063795 -351.917467) (xy 116.017903 -351.946956) (xy 115.968281 -351.969614) (xy 115.915939 -351.984979)
			(xy 115.861943 -351.992739) (xy 115.834668 -351.9932) (xy 114.971068 -351.9932) (xy 114.943803 -351.992635)
			(xy 114.889828 -351.984871) (xy 114.837508 -351.969504) (xy 114.787906 -351.946849) (xy 114.742034 -351.917365)
			(xy 114.700824 -351.881653) (xy 114.665116 -351.84044) (xy 114.635636 -351.794566) (xy 114.612984 -351.744962)
			(xy 114.597622 -351.692641) (xy 114.589862 -351.638665) (xy 113.107014 -351.638665) (xy 113.107014 -351.638672)
			(xy 113.099251 -351.69266) (xy 113.083885 -351.744994) (xy 113.061227 -351.794609) (xy 113.031739 -351.840494)
			(xy 112.996021 -351.881715) (xy 112.9548 -351.917434) (xy 112.908916 -351.946923) (xy 112.859302 -351.969582)
			(xy 112.806968 -351.98495) (xy 112.75298 -351.992713) (xy 112.725708 -351.9932) (xy 111.862108 -351.9932)
			(xy 111.834839 -351.992661) (xy 111.780857 -351.984901) (xy 111.728529 -351.969537) (xy 111.678919 -351.946882)
			(xy 111.633039 -351.917397) (xy 111.591822 -351.881683) (xy 111.556107 -351.840467) (xy 111.526622 -351.794588)
			(xy 111.503966 -351.744979) (xy 111.488601 -351.692651) (xy 111.480839 -351.638669) (xy 93.706714 -351.638669)
			(xy 93.706714 -351.63867) (xy 93.698952 -351.692655) (xy 93.683588 -351.744987) (xy 93.660932 -351.794599)
			(xy 93.631447 -351.840483) (xy 93.595733 -351.881703) (xy 93.554516 -351.917422) (xy 93.508636 -351.946912)
			(xy 93.459026 -351.969573) (xy 93.406697 -351.984943) (xy 93.352712 -351.992711) (xy 93.325442 -351.9932)
			(xy 92.461842 -351.9932) (xy 92.434572 -351.992663) (xy 92.380586 -351.984907) (xy 92.328253 -351.969546)
			(xy 92.27864 -351.946893) (xy 92.232755 -351.917409) (xy 92.191534 -351.881695) (xy 92.155816 -351.840478)
			(xy 92.126327 -351.794597) (xy 92.103669 -351.744986) (xy 92.088302 -351.692655) (xy 92.08054 -351.63867)
			(xy 90.597836 -351.63867) (xy 90.597836 -351.638675) (xy 90.590073 -351.692668) (xy 90.574704 -351.745008)
			(xy 90.552043 -351.794627) (xy 90.522551 -351.840516) (xy 90.486828 -351.881741) (xy 90.445602 -351.917462)
			(xy 90.399711 -351.946952) (xy 90.350091 -351.969611) (xy 90.297751 -351.984977) (xy 90.243757 -351.992738)
			(xy 90.216482 -351.9932) (xy 89.352882 -351.9932) (xy 89.325616 -351.992636) (xy 89.27164 -351.984873)
			(xy 89.219318 -351.969508) (xy 89.169715 -351.946853) (xy 89.123841 -351.91737) (xy 89.082629 -351.881658)
			(xy 89.04692 -351.840445) (xy 89.017438 -351.794569) (xy 88.994786 -351.744965) (xy 88.979423 -351.692642)
			(xy 88.971662 -351.638666) (xy 87.488814 -351.638666) (xy 87.488814 -351.638671) (xy 87.481052 -351.692658)
			(xy 87.465686 -351.744991) (xy 87.443029 -351.794605) (xy 87.413542 -351.840489) (xy 87.377826 -351.88171)
			(xy 87.336607 -351.917429) (xy 87.290724 -351.946919) (xy 87.241112 -351.969578) (xy 87.18878 -351.984947)
			(xy 87.134793 -351.992712) (xy 87.107522 -351.9932) (xy 86.243922 -351.9932) (xy 86.216653 -351.992662)
			(xy 86.162669 -351.984903) (xy 86.110339 -351.96954) (xy 86.060728 -351.946886) (xy 86.014846 -351.917402)
			(xy 85.973627 -351.881688) (xy 85.937911 -351.840472) (xy 85.908424 -351.794592) (xy 85.885767 -351.744982)
			(xy 85.870401 -351.692653) (xy 85.862639 -351.638669) (xy 84.379936 -351.638669) (xy 84.379936 -351.638675)
			(xy 84.372172 -351.692671) (xy 84.356803 -351.745012) (xy 84.33414 -351.794633) (xy 84.304646 -351.840523)
			(xy 84.268921 -351.881748) (xy 84.227692 -351.917469) (xy 84.181799 -351.946958) (xy 84.132176 -351.969616)
			(xy 84.079834 -351.98498) (xy 84.025837 -351.992739) (xy 83.998562 -351.9932) (xy 83.134962 -351.9932)
			(xy 83.107697 -351.992635) (xy 83.053723 -351.98487) (xy 83.001403 -351.969503) (xy 82.951803 -351.946847)
			(xy 82.905931 -351.917363) (xy 82.864722 -351.881651) (xy 82.829015 -351.840438) (xy 82.799535 -351.794564)
			(xy 82.776884 -351.744961) (xy 82.761522 -351.69264) (xy 82.753762 -351.638665) (xy 81.270913 -351.638665)
			(xy 81.270913 -351.638672) (xy 81.263151 -351.692661) (xy 81.247784 -351.744995) (xy 81.225126 -351.79461)
			(xy 81.195637 -351.840496) (xy 81.159919 -351.881717) (xy 81.118697 -351.917436) (xy 81.072812 -351.946925)
			(xy 81.023197 -351.969584) (xy 80.970863 -351.984951) (xy 80.916874 -351.992713) (xy 80.889602 -351.9932)
			(xy 80.026002 -351.9932) (xy 79.998734 -351.992661) (xy 79.944752 -351.9849) (xy 79.892424 -351.969535)
			(xy 79.842816 -351.94688) (xy 79.796936 -351.917395) (xy 79.75572 -351.881681) (xy 79.720006 -351.840465)
			(xy 79.690521 -351.794586) (xy 79.667866 -351.744978) (xy 79.652501 -351.69265) (xy 79.644739 -351.638668)
			(xy 78.161914 -351.638668) (xy 78.161914 -351.63867) (xy 78.154152 -351.692655) (xy 78.138788 -351.744987)
			(xy 78.116132 -351.794599) (xy 78.086647 -351.840483) (xy 78.050933 -351.881703) (xy 78.009716 -351.917422)
			(xy 77.963836 -351.946912) (xy 77.914226 -351.969573) (xy 77.861897 -351.984943) (xy 77.807912 -351.992711)
			(xy 77.780642 -351.9932) (xy 76.917042 -351.9932) (xy 76.889772 -351.992663) (xy 76.835786 -351.984907)
			(xy 76.783453 -351.969546) (xy 76.73384 -351.946893) (xy 76.687955 -351.917409) (xy 76.646734 -351.881695)
			(xy 76.611016 -351.840478) (xy 76.581527 -351.794597) (xy 76.558869 -351.744986) (xy 76.543502 -351.692655)
			(xy 76.53574 -351.63867) (xy 75.053036 -351.63867) (xy 75.053036 -351.638675) (xy 75.045273 -351.692668)
			(xy 75.029904 -351.745008) (xy 75.007243 -351.794627) (xy 74.977751 -351.840516) (xy 74.942028 -351.881741)
			(xy 74.900802 -351.917462) (xy 74.854911 -351.946952) (xy 74.805291 -351.969611) (xy 74.752951 -351.984977)
			(xy 74.698957 -351.992738) (xy 74.671682 -351.9932) (xy 73.808082 -351.9932) (xy 73.780816 -351.992636)
			(xy 73.72684 -351.984873) (xy 73.674518 -351.969508) (xy 73.624915 -351.946853) (xy 73.579041 -351.91737)
			(xy 73.537829 -351.881658) (xy 73.50212 -351.840445) (xy 73.472638 -351.794569) (xy 73.449986 -351.744965)
			(xy 73.434623 -351.692642) (xy 73.426862 -351.638666) (xy 71.944014 -351.638666) (xy 71.944014 -351.638671)
			(xy 71.936252 -351.692658) (xy 71.920886 -351.744991) (xy 71.898229 -351.794605) (xy 71.868742 -351.840489)
			(xy 71.833026 -351.88171) (xy 71.791807 -351.917429) (xy 71.745924 -351.946919) (xy 71.696312 -351.969578)
			(xy 71.64398 -351.984947) (xy 71.589993 -351.992712) (xy 71.562722 -351.9932) (xy 70.699122 -351.9932)
			(xy 70.671853 -351.992662) (xy 70.617869 -351.984903) (xy 70.565539 -351.96954) (xy 70.515928 -351.946886)
			(xy 70.470046 -351.917402) (xy 70.428827 -351.881688) (xy 70.393111 -351.840472) (xy 70.363624 -351.794592)
			(xy 70.340967 -351.744982) (xy 70.325601 -351.692653) (xy 70.317839 -351.638669) (xy 68.835136 -351.638669)
			(xy 68.835136 -351.638675) (xy 68.827372 -351.692671) (xy 68.812003 -351.745012) (xy 68.78934 -351.794633)
			(xy 68.759846 -351.840523) (xy 68.724121 -351.881748) (xy 68.682892 -351.917469) (xy 68.636999 -351.946958)
			(xy 68.587376 -351.969616) (xy 68.535034 -351.98498) (xy 68.481037 -351.992739) (xy 68.453762 -351.9932)
			(xy 67.590162 -351.9932) (xy 67.562897 -351.992635) (xy 67.508923 -351.98487) (xy 67.456603 -351.969503)
			(xy 67.407003 -351.946847) (xy 67.361131 -351.917363) (xy 67.319922 -351.881651) (xy 67.284215 -351.840438)
			(xy 67.254735 -351.794564) (xy 67.232084 -351.744961) (xy 67.216722 -351.69264) (xy 67.208962 -351.638665)
			(xy 65.726113 -351.638665) (xy 65.726113 -351.638672) (xy 65.718351 -351.692661) (xy 65.702984 -351.744995)
			(xy 65.680326 -351.79461) (xy 65.650837 -351.840496) (xy 65.615119 -351.881717) (xy 65.573897 -351.917436)
			(xy 65.528012 -351.946925) (xy 65.478397 -351.969584) (xy 65.426063 -351.984951) (xy 65.372074 -351.992713)
			(xy 65.344802 -351.9932) (xy 64.481202 -351.9932) (xy 64.453934 -351.992661) (xy 64.399952 -351.9849)
			(xy 64.347624 -351.969535) (xy 64.298016 -351.94688) (xy 64.252136 -351.917395) (xy 64.21092 -351.881681)
			(xy 64.175206 -351.840465) (xy 64.145721 -351.794586) (xy 64.123066 -351.744978) (xy 64.107701 -351.69265)
			(xy 64.099939 -351.638668) (xy 62.617114 -351.638668) (xy 62.617114 -351.63867) (xy 62.609352 -351.692655)
			(xy 62.593988 -351.744987) (xy 62.571332 -351.794599) (xy 62.541847 -351.840483) (xy 62.506133 -351.881703)
			(xy 62.464916 -351.917422) (xy 62.419036 -351.946912) (xy 62.369426 -351.969573) (xy 62.317097 -351.984943)
			(xy 62.263112 -351.992711) (xy 62.235842 -351.9932) (xy 61.372242 -351.9932) (xy 61.344972 -351.992663)
			(xy 61.290986 -351.984907) (xy 61.238653 -351.969546) (xy 61.18904 -351.946893) (xy 61.143155 -351.917409)
			(xy 61.101934 -351.881695) (xy 61.066216 -351.840478) (xy 61.036727 -351.794597) (xy 61.014069 -351.744986)
			(xy 60.998702 -351.692655) (xy 60.99094 -351.63867) (xy 51.666914 -351.63867) (xy 51.659152 -351.692655)
			(xy 51.643788 -351.744986) (xy 51.621133 -351.794597) (xy 51.591649 -351.840481) (xy 51.555935 -351.881701)
			(xy 51.514719 -351.91742) (xy 51.46884 -351.94691) (xy 51.419231 -351.969571) (xy 51.366902 -351.984942)
			(xy 51.312918 -351.99271) (xy 51.285648 -351.9932) (xy 50.422048 -351.9932) (xy 50.394777 -351.992664)
			(xy 50.340791 -351.984908) (xy 50.288458 -351.969547) (xy 50.238843 -351.946895) (xy 50.192958 -351.917411)
			(xy 50.151736 -351.881698) (xy 50.116017 -351.84048) (xy 50.086528 -351.794599) (xy 50.063869 -351.744987)
			(xy 50.048502 -351.692656) (xy 50.04074 -351.63867) (xy 48.558036 -351.63867) (xy 48.558036 -351.638674)
			(xy 48.550273 -351.692668) (xy 48.534905 -351.745006) (xy 48.512244 -351.794625) (xy 48.482752 -351.840514)
			(xy 48.44703 -351.881739) (xy 48.405804 -351.91746) (xy 48.359915 -351.94695) (xy 48.310295 -351.969609)
			(xy 48.257956 -351.984976) (xy 48.203962 -351.992737) (xy 48.176688 -351.9932) (xy 47.313088 -351.9932)
			(xy 47.285822 -351.992637) (xy 47.231845 -351.984875) (xy 47.179522 -351.96951) (xy 47.129918 -351.946855)
			(xy 47.084044 -351.917372) (xy 47.042831 -351.88166) (xy 47.007121 -351.840447) (xy 46.977639 -351.794571)
			(xy 46.954986 -351.744967) (xy 46.939623 -351.692643) (xy 46.931862 -351.638666) (xy 45.449014 -351.638666)
			(xy 45.449014 -351.638671) (xy 45.441252 -351.692657) (xy 45.425886 -351.74499) (xy 45.40323 -351.794603)
			(xy 45.373744 -351.840487) (xy 45.338028 -351.881708) (xy 45.29681 -351.917427) (xy 45.250928 -351.946917)
			(xy 45.201316 -351.969577) (xy 45.148985 -351.984946) (xy 45.094999 -351.992712) (xy 45.067728 -351.9932)
			(xy 44.204128 -351.9932) (xy 44.176858 -351.992663) (xy 44.122874 -351.984904) (xy 44.070543 -351.969542)
			(xy 44.020931 -351.946888) (xy 43.975049 -351.917404) (xy 43.933829 -351.881691) (xy 43.898112 -351.840474)
			(xy 43.868625 -351.794593) (xy 43.845968 -351.744983) (xy 43.830602 -351.692654) (xy 43.822839 -351.63867)
			(xy 42.340136 -351.63867) (xy 42.340136 -351.638675) (xy 42.332373 -351.69267) (xy 42.317003 -351.745011)
			(xy 42.294341 -351.794631) (xy 42.264847 -351.840521) (xy 42.229123 -351.881746) (xy 42.187895 -351.917467)
			(xy 42.142003 -351.946956) (xy 42.092381 -351.969614) (xy 42.040039 -351.984979) (xy 41.986043 -351.992739)
			(xy 41.958768 -351.9932) (xy 41.095168 -351.9932) (xy 41.067903 -351.992635) (xy 41.013928 -351.984871)
			(xy 40.961608 -351.969504) (xy 40.912006 -351.946849) (xy 40.866134 -351.917365) (xy 40.824924 -351.881653)
			(xy 40.789216 -351.84044) (xy 40.759736 -351.794566) (xy 40.737084 -351.744962) (xy 40.721722 -351.692641)
			(xy 40.713962 -351.638665) (xy 39.231114 -351.638665) (xy 39.231114 -351.638672) (xy 39.223351 -351.69266)
			(xy 39.207985 -351.744994) (xy 39.185327 -351.794609) (xy 39.155839 -351.840494) (xy 39.120121 -351.881715)
			(xy 39.0789 -351.917434) (xy 39.033016 -351.946923) (xy 38.983402 -351.969582) (xy 38.931068 -351.98495)
			(xy 38.87708 -351.992713) (xy 38.849808 -351.9932) (xy 37.986208 -351.9932) (xy 37.958939 -351.992661)
			(xy 37.904957 -351.984901) (xy 37.852629 -351.969537) (xy 37.803019 -351.946882) (xy 37.757139 -351.917397)
			(xy 37.715922 -351.881683) (xy 37.680207 -351.840467) (xy 37.650722 -351.794588) (xy 37.628066 -351.744979)
			(xy 37.612701 -351.692651) (xy 37.604939 -351.638669) (xy 36.122114 -351.638669) (xy 36.122114 -351.63867)
			(xy 36.114352 -351.692655) (xy 36.098988 -351.744986) (xy 36.076333 -351.794597) (xy 36.046849 -351.840481)
			(xy 36.011135 -351.881701) (xy 35.969919 -351.91742) (xy 35.92404 -351.94691) (xy 35.874431 -351.969571)
			(xy 35.822102 -351.984942) (xy 35.768118 -351.99271) (xy 35.740848 -351.9932) (xy 34.877248 -351.9932)
			(xy 34.849977 -351.992664) (xy 34.795991 -351.984908) (xy 34.743658 -351.969547) (xy 34.694043 -351.946895)
			(xy 34.648158 -351.917411) (xy 34.606936 -351.881698) (xy 34.571217 -351.84048) (xy 34.541728 -351.794599)
			(xy 34.519069 -351.744987) (xy 34.503702 -351.692656) (xy 34.49594 -351.63867) (xy 33.013236 -351.63867)
			(xy 33.013236 -351.638674) (xy 33.005473 -351.692668) (xy 32.990105 -351.745006) (xy 32.967444 -351.794625)
			(xy 32.937952 -351.840514) (xy 32.90223 -351.881739) (xy 32.861004 -351.91746) (xy 32.815115 -351.94695)
			(xy 32.765495 -351.969609) (xy 32.713156 -351.984976) (xy 32.659162 -351.992737) (xy 32.631888 -351.9932)
			(xy 31.768288 -351.9932) (xy 31.741022 -351.992637) (xy 31.687045 -351.984875) (xy 31.634722 -351.96951)
			(xy 31.585118 -351.946855) (xy 31.539244 -351.917372) (xy 31.498031 -351.88166) (xy 31.462321 -351.840447)
			(xy 31.432839 -351.794571) (xy 31.410186 -351.744967) (xy 31.394823 -351.692643) (xy 31.387062 -351.638666)
			(xy 29.904214 -351.638666) (xy 29.904214 -351.638671) (xy 29.896452 -351.692657) (xy 29.881086 -351.74499)
			(xy 29.85843 -351.794603) (xy 29.828944 -351.840487) (xy 29.793228 -351.881708) (xy 29.75201 -351.917427)
			(xy 29.706128 -351.946917) (xy 29.656516 -351.969577) (xy 29.604185 -351.984946) (xy 29.550199 -351.992712)
			(xy 29.522928 -351.9932) (xy 28.659328 -351.9932) (xy 28.632058 -351.992663) (xy 28.578074 -351.984904)
			(xy 28.525743 -351.969542) (xy 28.476131 -351.946888) (xy 28.430249 -351.917404) (xy 28.389029 -351.881691)
			(xy 28.353312 -351.840474) (xy 28.323825 -351.794593) (xy 28.301168 -351.744983) (xy 28.285802 -351.692654)
			(xy 28.278039 -351.63867) (xy 26.795336 -351.63867) (xy 26.795336 -351.638675) (xy 26.787573 -351.69267)
			(xy 26.772203 -351.745011) (xy 26.749541 -351.794631) (xy 26.720047 -351.840521) (xy 26.684323 -351.881746)
			(xy 26.643095 -351.917467) (xy 26.597203 -351.946956) (xy 26.547581 -351.969614) (xy 26.495239 -351.984979)
			(xy 26.441243 -351.992739) (xy 26.413968 -351.9932) (xy 25.550368 -351.9932) (xy 25.523103 -351.992635)
			(xy 25.469128 -351.984871) (xy 25.416808 -351.969504) (xy 25.367206 -351.946849) (xy 25.321334 -351.917365)
			(xy 25.280124 -351.881653) (xy 25.244416 -351.84044) (xy 25.214936 -351.794566) (xy 25.192284 -351.744962)
			(xy 25.176922 -351.692641) (xy 25.169162 -351.638665) (xy 23.686314 -351.638665) (xy 23.686314 -351.638672)
			(xy 23.678551 -351.69266) (xy 23.663185 -351.744994) (xy 23.640527 -351.794609) (xy 23.611039 -351.840494)
			(xy 23.575321 -351.881715) (xy 23.5341 -351.917434) (xy 23.488216 -351.946923) (xy 23.438602 -351.969582)
			(xy 23.386268 -351.98495) (xy 23.33228 -351.992713) (xy 23.305008 -351.9932) (xy 22.441408 -351.9932)
			(xy 22.414139 -351.992661) (xy 22.360157 -351.984901) (xy 22.307829 -351.969537) (xy 22.258219 -351.946882)
			(xy 22.212339 -351.917397) (xy 22.171122 -351.881683) (xy 22.135407 -351.840467) (xy 22.105922 -351.794588)
			(xy 22.083266 -351.744979) (xy 22.067901 -351.692651) (xy 22.060139 -351.638669) (xy 20.577347 -351.638669)
			(xy 20.577347 -351.638711) (xy 20.569584 -351.692698) (xy 20.554218 -351.74503) (xy 20.53156 -351.794643)
			(xy 20.502073 -351.840527) (xy 20.466355 -351.881747) (xy 20.425135 -351.917464) (xy 20.379252 -351.946951)
			(xy 20.329638 -351.969609) (xy 20.277306 -351.984975) (xy 20.223319 -351.992737) (xy 20.196048 -351.9932)
			(xy 19.332448 -351.9932) (xy 19.305179 -351.992717) (xy 19.251195 -351.984955) (xy 19.198865 -351.96959)
			(xy 19.149255 -351.946933) (xy 19.103374 -351.917447) (xy 19.062157 -351.881732) (xy 19.026441 -351.840514)
			(xy 18.996956 -351.794633) (xy 18.974299 -351.745023) (xy 18.958934 -351.692693) (xy 18.951172 -351.638709)
			(xy 1.524 -351.638709) (xy 1.524 -354.759373) (xy 22.060084 -354.759373) (xy 22.060084 -354.704827)
			(xy 22.067846 -354.650837) (xy 22.083214 -354.598501) (xy 22.105873 -354.548885) (xy 22.135363 -354.502999)
			(xy 22.171083 -354.461777) (xy 22.212306 -354.426058) (xy 22.258192 -354.396569) (xy 22.307809 -354.373911)
			(xy 22.360145 -354.358545) (xy 22.414135 -354.350783) (xy 22.441408 -354.35032) (xy 23.305008 -354.35032)
			(xy 23.332276 -354.350843) (xy 23.386256 -354.358605) (xy 23.438582 -354.37397) (xy 23.488189 -354.396626)
			(xy 23.534067 -354.426111) (xy 23.575281 -354.461824) (xy 23.610994 -354.50304) (xy 23.640478 -354.548918)
			(xy 23.663132 -354.598525) (xy 23.678497 -354.650852) (xy 23.686258 -354.704832) (xy 23.686258 -354.759368)
			(xy 23.686258 -354.759369) (xy 25.169106 -354.759369) (xy 25.169106 -354.704831) (xy 25.176868 -354.650847)
			(xy 25.192232 -354.598518) (xy 25.214887 -354.548908) (xy 25.244371 -354.503026) (xy 25.280085 -354.461807)
			(xy 25.3213 -354.42609) (xy 25.36718 -354.396602) (xy 25.416788 -354.373943) (xy 25.469116 -354.358574)
			(xy 25.523099 -354.350809) (xy 25.550368 -354.35032) (xy 26.413968 -354.35032) (xy 26.441239 -354.350817)
			(xy 26.495227 -354.358575) (xy 26.547561 -354.373938) (xy 26.597176 -354.396593) (xy 26.643061 -354.426078)
			(xy 26.684283 -354.461794) (xy 26.720003 -354.503013) (xy 26.749492 -354.548896) (xy 26.772151 -354.598509)
			(xy 26.787518 -354.650842) (xy 26.79528 -354.704829) (xy 26.79528 -354.759371) (xy 26.79528 -354.759374)
			(xy 28.277984 -354.759374) (xy 28.277984 -354.704826) (xy 28.285747 -354.650835) (xy 28.301115 -354.598497)
			(xy 28.323776 -354.54888) (xy 28.353268 -354.502993) (xy 28.38899 -354.46177) (xy 28.430215 -354.426051)
			(xy 28.476104 -354.396562) (xy 28.525723 -354.373905) (xy 28.578062 -354.358541) (xy 28.632054 -354.350782)
			(xy 28.659328 -354.35032) (xy 29.522928 -354.35032) (xy 29.550195 -354.350844) (xy 29.604173 -354.358609)
			(xy 29.656497 -354.373976) (xy 29.706101 -354.396633) (xy 29.751976 -354.426118) (xy 29.793188 -354.461831)
			(xy 29.828899 -354.503046) (xy 29.858381 -354.548924) (xy 29.881034 -354.59853) (xy 29.896397 -354.650855)
			(xy 29.904158 -354.704833) (xy 29.904158 -354.759367) (xy 29.904158 -354.75937) (xy 31.387006 -354.75937)
			(xy 31.387006 -354.70483) (xy 31.394768 -354.650845) (xy 31.410134 -354.598514) (xy 31.43279 -354.548902)
			(xy 31.462276 -354.50302) (xy 31.497992 -354.4618) (xy 31.53921 -354.426083) (xy 31.585091 -354.396596)
			(xy 31.634703 -354.373938) (xy 31.687033 -354.358571) (xy 31.741018 -354.350807) (xy 31.768288 -354.35032)
			(xy 32.631888 -354.35032) (xy 32.659158 -354.350819) (xy 32.713144 -354.358579) (xy 32.765476 -354.373944)
			(xy 32.815088 -354.396599) (xy 32.860971 -354.426085) (xy 32.902191 -354.461801) (xy 32.937908 -354.503019)
			(xy 32.967395 -354.548902) (xy 32.990052 -354.598513) (xy 33.005418 -354.650844) (xy 33.013181 -354.70483)
			(xy 33.013181 -354.75937) (xy 33.01318 -354.759374) (xy 34.495884 -354.759374) (xy 34.495884 -354.704826)
			(xy 34.503647 -354.650832) (xy 34.519017 -354.598493) (xy 34.541679 -354.548874) (xy 34.571172 -354.502986)
			(xy 34.606897 -354.461763) (xy 34.648125 -354.426044) (xy 34.694016 -354.396556) (xy 34.743638 -354.3739)
			(xy 34.795979 -354.358537) (xy 34.849973 -354.35078) (xy 34.877248 -354.35032) (xy 35.740848 -354.35032)
			(xy 35.768114 -354.350846) (xy 35.82209 -354.358613) (xy 35.874411 -354.373981) (xy 35.924013 -354.396639)
			(xy 35.969886 -354.426125) (xy 36.011095 -354.461839) (xy 36.046804 -354.503053) (xy 36.076284 -354.548929)
			(xy 36.098936 -354.598534) (xy 36.114298 -354.650857) (xy 36.122058 -354.704834) (xy 36.122058 -354.759366)
			(xy 36.122057 -354.759373) (xy 37.604884 -354.759373) (xy 37.604884 -354.704827) (xy 37.612646 -354.650837)
			(xy 37.628014 -354.598501) (xy 37.650673 -354.548885) (xy 37.680163 -354.502999) (xy 37.715883 -354.461777)
			(xy 37.757106 -354.426058) (xy 37.802992 -354.396569) (xy 37.852609 -354.373911) (xy 37.904945 -354.358545)
			(xy 37.958935 -354.350783) (xy 37.986208 -354.35032) (xy 38.849808 -354.35032) (xy 38.877076 -354.350843)
			(xy 38.931056 -354.358605) (xy 38.983382 -354.37397) (xy 39.032989 -354.396626) (xy 39.078867 -354.426111)
			(xy 39.120081 -354.461824) (xy 39.155794 -354.50304) (xy 39.185278 -354.548918) (xy 39.207932 -354.598525)
			(xy 39.223297 -354.650852) (xy 39.231058 -354.704832) (xy 39.231058 -354.759368) (xy 39.231058 -354.759369)
			(xy 40.713906 -354.759369) (xy 40.713906 -354.704831) (xy 40.721668 -354.650847) (xy 40.737032 -354.598518)
			(xy 40.759687 -354.548908) (xy 40.789171 -354.503026) (xy 40.824885 -354.461807) (xy 40.8661 -354.42609)
			(xy 40.91198 -354.396602) (xy 40.961588 -354.373943) (xy 41.013916 -354.358574) (xy 41.067899 -354.350809)
			(xy 41.095168 -354.35032) (xy 41.958768 -354.35032) (xy 41.986039 -354.350817) (xy 42.040027 -354.358575)
			(xy 42.092361 -354.373938) (xy 42.141976 -354.396593) (xy 42.187861 -354.426078) (xy 42.229083 -354.461794)
			(xy 42.264803 -354.503013) (xy 42.294292 -354.548896) (xy 42.316951 -354.598509) (xy 42.332318 -354.650842)
			(xy 42.34008 -354.704829) (xy 42.34008 -354.759371) (xy 42.34008 -354.759374) (xy 43.822784 -354.759374)
			(xy 43.822784 -354.704826) (xy 43.830547 -354.650835) (xy 43.845915 -354.598497) (xy 43.868576 -354.54888)
			(xy 43.898068 -354.502993) (xy 43.93379 -354.46177) (xy 43.975015 -354.426051) (xy 44.020904 -354.396562)
			(xy 44.070523 -354.373905) (xy 44.122862 -354.358541) (xy 44.176854 -354.350782) (xy 44.204128 -354.35032)
			(xy 45.067728 -354.35032) (xy 45.094995 -354.350844) (xy 45.148973 -354.358609) (xy 45.201297 -354.373976)
			(xy 45.250901 -354.396633) (xy 45.296776 -354.426118) (xy 45.337988 -354.461831) (xy 45.373699 -354.503046)
			(xy 45.403181 -354.548924) (xy 45.425834 -354.59853) (xy 45.441197 -354.650855) (xy 45.448958 -354.704833)
			(xy 45.448958 -354.759367) (xy 45.448958 -354.75937) (xy 46.931806 -354.75937) (xy 46.931806 -354.70483)
			(xy 46.939568 -354.650845) (xy 46.954934 -354.598514) (xy 46.97759 -354.548902) (xy 47.007076 -354.50302)
			(xy 47.042792 -354.4618) (xy 47.08401 -354.426083) (xy 47.129891 -354.396596) (xy 47.179503 -354.373938)
			(xy 47.231833 -354.358571) (xy 47.285818 -354.350807) (xy 47.313088 -354.35032) (xy 48.176688 -354.35032)
			(xy 48.203958 -354.350819) (xy 48.257944 -354.358579) (xy 48.310276 -354.373944) (xy 48.359888 -354.396599)
			(xy 48.405771 -354.426085) (xy 48.446991 -354.461801) (xy 48.482708 -354.503019) (xy 48.512195 -354.548902)
			(xy 48.534852 -354.598513) (xy 48.550218 -354.650844) (xy 48.557981 -354.70483) (xy 48.557981 -354.75937)
			(xy 48.55798 -354.759374) (xy 50.040684 -354.759374) (xy 50.040684 -354.704826) (xy 50.048447 -354.650832)
			(xy 50.063817 -354.598493) (xy 50.086479 -354.548874) (xy 50.115972 -354.502986) (xy 50.151697 -354.461763)
			(xy 50.192925 -354.426044) (xy 50.238816 -354.396556) (xy 50.288438 -354.3739) (xy 50.340779 -354.358537)
			(xy 50.394773 -354.35078) (xy 50.422048 -354.35032) (xy 51.285648 -354.35032) (xy 51.312914 -354.350846)
			(xy 51.36689 -354.358613) (xy 51.419211 -354.373981) (xy 51.468813 -354.396639) (xy 51.514686 -354.426125)
			(xy 51.555895 -354.461839) (xy 51.591604 -354.503053) (xy 51.621084 -354.548929) (xy 51.643736 -354.598534)
			(xy 51.659098 -354.650857) (xy 51.666858 -354.704834) (xy 51.666858 -354.759366) (xy 51.666857 -354.759372)
			(xy 64.099884 -354.759372) (xy 64.099884 -354.704828) (xy 64.107646 -354.650838) (xy 64.123013 -354.598503)
			(xy 64.145672 -354.548887) (xy 64.175161 -354.503001) (xy 64.210881 -354.461779) (xy 64.252103 -354.42606)
			(xy 64.297989 -354.396571) (xy 64.347605 -354.373912) (xy 64.39994 -354.358546) (xy 64.45393 -354.350783)
			(xy 64.481202 -354.35032) (xy 65.344802 -354.35032) (xy 65.37207 -354.350843) (xy 65.426051 -354.358604)
			(xy 65.478378 -354.373969) (xy 65.527985 -354.396624) (xy 65.573864 -354.426109) (xy 65.615079 -354.461822)
			(xy 65.650793 -354.503038) (xy 65.680277 -354.548917) (xy 65.702932 -354.598524) (xy 65.718296 -354.650851)
			(xy 65.726058 -354.704832) (xy 65.726058 -354.759368) (xy 65.726058 -354.759369) (xy 67.208906 -354.759369)
			(xy 67.208906 -354.704831) (xy 67.216667 -354.650848) (xy 67.232032 -354.598519) (xy 67.254686 -354.548909)
			(xy 67.28417 -354.503028) (xy 67.319883 -354.46181) (xy 67.361098 -354.426093) (xy 67.406976 -354.396604)
			(xy 67.456584 -354.373945) (xy 67.508911 -354.358575) (xy 67.562893 -354.350809) (xy 67.590162 -354.35032)
			(xy 68.453762 -354.35032) (xy 68.481033 -354.350817) (xy 68.535022 -354.358574) (xy 68.587357 -354.373936)
			(xy 68.636972 -354.396591) (xy 68.682859 -354.426076) (xy 68.724081 -354.461792) (xy 68.759801 -354.503011)
			(xy 68.789291 -354.548894) (xy 68.81195 -354.598508) (xy 68.827318 -354.650841) (xy 68.83508 -354.704829)
			(xy 68.83508 -354.759371) (xy 68.83508 -354.759373) (xy 70.317784 -354.759373) (xy 70.317784 -354.704827)
			(xy 70.325547 -354.650835) (xy 70.340915 -354.598498) (xy 70.363575 -354.548882) (xy 70.393066 -354.502995)
			(xy 70.428788 -354.461772) (xy 70.470012 -354.426053) (xy 70.515901 -354.396564) (xy 70.565519 -354.373907)
			(xy 70.617857 -354.358542) (xy 70.671849 -354.350782) (xy 70.699122 -354.35032) (xy 71.562722 -354.35032)
			(xy 71.589989 -354.350844) (xy 71.643968 -354.358608) (xy 71.696292 -354.373974) (xy 71.745897 -354.396631)
			(xy 71.791773 -354.426116) (xy 71.832986 -354.461829) (xy 71.868697 -354.503044) (xy 71.89818 -354.548922)
			(xy 71.920833 -354.598528) (xy 71.936197 -354.650854) (xy 71.943958 -354.704833) (xy 71.943958 -354.759367)
			(xy 71.943958 -354.75937) (xy 73.426806 -354.75937) (xy 73.426806 -354.70483) (xy 73.434568 -354.650846)
			(xy 73.449933 -354.598515) (xy 73.472589 -354.548904) (xy 73.502075 -354.503022) (xy 73.53779 -354.461802)
			(xy 73.579007 -354.426085) (xy 73.624888 -354.396598) (xy 73.674498 -354.373939) (xy 73.726828 -354.358572)
			(xy 73.780812 -354.350808) (xy 73.808082 -354.35032) (xy 74.671682 -354.35032) (xy 74.698953 -354.350818)
			(xy 74.752939 -354.358578) (xy 74.805271 -354.373942) (xy 74.854884 -354.396597) (xy 74.900768 -354.426083)
			(xy 74.941988 -354.461799) (xy 74.977706 -354.503018) (xy 75.007194 -354.5489) (xy 75.029852 -354.598512)
			(xy 75.045218 -354.650844) (xy 75.052981 -354.704829) (xy 75.052981 -354.759371) (xy 75.052981 -354.759374)
			(xy 76.535684 -354.759374) (xy 76.535684 -354.704826) (xy 76.543447 -354.650833) (xy 76.558816 -354.598494)
			(xy 76.581478 -354.548876) (xy 76.610971 -354.502988) (xy 76.646695 -354.461765) (xy 76.687922 -354.426046)
			(xy 76.733813 -354.396558) (xy 76.783434 -354.373902) (xy 76.835774 -354.358538) (xy 76.889768 -354.350781)
			(xy 76.917042 -354.35032) (xy 77.780642 -354.35032) (xy 77.807908 -354.350845) (xy 77.861885 -354.358611)
			(xy 77.914207 -354.37398) (xy 77.963809 -354.396637) (xy 78.009683 -354.426123) (xy 78.050893 -354.461836)
			(xy 78.086602 -354.503051) (xy 78.116083 -354.548928) (xy 78.138735 -354.598533) (xy 78.154098 -354.650856)
			(xy 78.161858 -354.704834) (xy 78.161858 -354.759366) (xy 78.161857 -354.759372) (xy 79.644684 -354.759372)
			(xy 79.644684 -354.704828) (xy 79.652446 -354.650838) (xy 79.667813 -354.598503) (xy 79.690472 -354.548887)
			(xy 79.719961 -354.503001) (xy 79.755681 -354.461779) (xy 79.796903 -354.42606) (xy 79.842789 -354.396571)
			(xy 79.892405 -354.373912) (xy 79.94474 -354.358546) (xy 79.99873 -354.350783) (xy 80.026002 -354.35032)
			(xy 80.889602 -354.35032) (xy 80.91687 -354.350843) (xy 80.970851 -354.358604) (xy 81.023178 -354.373969)
			(xy 81.072785 -354.396624) (xy 81.118664 -354.426109) (xy 81.159879 -354.461822) (xy 81.195593 -354.503038)
			(xy 81.225077 -354.548917) (xy 81.247732 -354.598524) (xy 81.263096 -354.650851) (xy 81.270858 -354.704832)
			(xy 81.270858 -354.759368) (xy 81.270858 -354.759369) (xy 82.753706 -354.759369) (xy 82.753706 -354.704831)
			(xy 82.761467 -354.650848) (xy 82.776832 -354.598519) (xy 82.799486 -354.548909) (xy 82.82897 -354.503028)
			(xy 82.864683 -354.46181) (xy 82.905898 -354.426093) (xy 82.951776 -354.396604) (xy 83.001384 -354.373945)
			(xy 83.053711 -354.358575) (xy 83.107693 -354.350809) (xy 83.134962 -354.35032) (xy 83.998562 -354.35032)
			(xy 84.025833 -354.350817) (xy 84.079822 -354.358574) (xy 84.132157 -354.373936) (xy 84.181772 -354.396591)
			(xy 84.227659 -354.426076) (xy 84.268881 -354.461792) (xy 84.304601 -354.503011) (xy 84.334091 -354.548894)
			(xy 84.35675 -354.598508) (xy 84.372118 -354.650841) (xy 84.37988 -354.704829) (xy 84.37988 -354.759371)
			(xy 84.37988 -354.759373) (xy 85.862584 -354.759373) (xy 85.862584 -354.704827) (xy 85.870347 -354.650835)
			(xy 85.885715 -354.598498) (xy 85.908375 -354.548882) (xy 85.937866 -354.502995) (xy 85.973588 -354.461772)
			(xy 86.014812 -354.426053) (xy 86.060701 -354.396564) (xy 86.110319 -354.373907) (xy 86.162657 -354.358542)
			(xy 86.216649 -354.350782) (xy 86.243922 -354.35032) (xy 87.107522 -354.35032) (xy 87.134789 -354.350844)
			(xy 87.188768 -354.358608) (xy 87.241092 -354.373974) (xy 87.290697 -354.396631) (xy 87.336573 -354.426116)
			(xy 87.377786 -354.461829) (xy 87.413497 -354.503044) (xy 87.44298 -354.548922) (xy 87.465633 -354.598528)
			(xy 87.480997 -354.650854) (xy 87.488758 -354.704833) (xy 87.488758 -354.759367) (xy 87.488758 -354.75937)
			(xy 88.971606 -354.75937) (xy 88.971606 -354.70483) (xy 88.979368 -354.650846) (xy 88.994733 -354.598515)
			(xy 89.017389 -354.548904) (xy 89.046875 -354.503022) (xy 89.08259 -354.461802) (xy 89.123807 -354.426085)
			(xy 89.169688 -354.396598) (xy 89.219298 -354.373939) (xy 89.271628 -354.358572) (xy 89.325612 -354.350808)
			(xy 89.352882 -354.35032) (xy 90.216482 -354.35032) (xy 90.243753 -354.350818) (xy 90.297739 -354.358578)
			(xy 90.350071 -354.373942) (xy 90.399684 -354.396597) (xy 90.445568 -354.426083) (xy 90.486788 -354.461799)
			(xy 90.522506 -354.503018) (xy 90.551994 -354.5489) (xy 90.574652 -354.598512) (xy 90.590018 -354.650844)
			(xy 90.597781 -354.704829) (xy 90.597781 -354.759371) (xy 90.597781 -354.759374) (xy 92.080484 -354.759374)
			(xy 92.080484 -354.704826) (xy 92.088247 -354.650833) (xy 92.103616 -354.598494) (xy 92.126278 -354.548876)
			(xy 92.155771 -354.502988) (xy 92.191495 -354.461765) (xy 92.232722 -354.426046) (xy 92.278613 -354.396558)
			(xy 92.328234 -354.373902) (xy 92.380574 -354.358538) (xy 92.434568 -354.350781) (xy 92.461842 -354.35032)
			(xy 93.325442 -354.35032) (xy 93.352708 -354.350845) (xy 93.406685 -354.358611) (xy 93.459007 -354.37398)
			(xy 93.508609 -354.396637) (xy 93.554483 -354.426123) (xy 93.595693 -354.461836) (xy 93.631402 -354.503051)
			(xy 93.660883 -354.548928) (xy 93.683535 -354.598533) (xy 93.698898 -354.650856) (xy 93.706658 -354.704834)
			(xy 93.706658 -354.759366) (xy 93.706658 -354.759369) (xy 114.589806 -354.759369) (xy 114.589806 -354.704831)
			(xy 114.597568 -354.650847) (xy 114.612932 -354.598518) (xy 114.635587 -354.548908) (xy 114.665071 -354.503026)
			(xy 114.700785 -354.461807) (xy 114.742 -354.42609) (xy 114.78788 -354.396602) (xy 114.837488 -354.373943)
			(xy 114.889816 -354.358574) (xy 114.943799 -354.350809) (xy 114.971068 -354.35032) (xy 115.834668 -354.35032)
			(xy 115.861939 -354.350817) (xy 115.915927 -354.358575) (xy 115.968261 -354.373938) (xy 116.017876 -354.396593)
			(xy 116.063761 -354.426078) (xy 116.104983 -354.461794) (xy 116.140703 -354.503013) (xy 116.170192 -354.548896)
			(xy 116.192851 -354.598509) (xy 116.208218 -354.650842) (xy 116.21598 -354.704829) (xy 116.21598 -354.759371)
			(xy 116.21598 -354.759374) (xy 117.698684 -354.759374) (xy 117.698684 -354.704826) (xy 117.706447 -354.650835)
			(xy 117.721815 -354.598497) (xy 117.744476 -354.54888) (xy 117.773968 -354.502993) (xy 117.80969 -354.46177)
			(xy 117.850915 -354.426051) (xy 117.896804 -354.396562) (xy 117.946423 -354.373905) (xy 117.998762 -354.358541)
			(xy 118.052754 -354.350782) (xy 118.080028 -354.35032) (xy 118.943628 -354.35032) (xy 118.970895 -354.350844)
			(xy 119.024873 -354.358609) (xy 119.077197 -354.373976) (xy 119.126801 -354.396633) (xy 119.172676 -354.426118)
			(xy 119.213888 -354.461831) (xy 119.249599 -354.503046) (xy 119.279081 -354.548924) (xy 119.301734 -354.59853)
			(xy 119.317097 -354.650855) (xy 119.324858 -354.704833) (xy 119.324858 -354.759367) (xy 119.324858 -354.75937)
			(xy 120.807706 -354.75937) (xy 120.807706 -354.70483) (xy 120.815468 -354.650845) (xy 120.830834 -354.598514)
			(xy 120.85349 -354.548902) (xy 120.882976 -354.50302) (xy 120.918692 -354.4618) (xy 120.95991 -354.426083)
			(xy 121.005791 -354.396596) (xy 121.055403 -354.373938) (xy 121.107733 -354.358571) (xy 121.161718 -354.350807)
			(xy 121.188988 -354.35032) (xy 122.052588 -354.35032) (xy 122.079858 -354.350819) (xy 122.133844 -354.358579)
			(xy 122.186176 -354.373944) (xy 122.235788 -354.396599) (xy 122.281671 -354.426085) (xy 122.322891 -354.461801)
			(xy 122.358608 -354.503019) (xy 122.388095 -354.548902) (xy 122.410752 -354.598513) (xy 122.426118 -354.650844)
			(xy 122.433881 -354.70483) (xy 122.433881 -354.75937) (xy 122.43388 -354.759374) (xy 123.916584 -354.759374)
			(xy 123.916584 -354.704826) (xy 123.924347 -354.650832) (xy 123.939717 -354.598493) (xy 123.962379 -354.548874)
			(xy 123.991872 -354.502986) (xy 124.027597 -354.461763) (xy 124.068825 -354.426044) (xy 124.114716 -354.396556)
			(xy 124.164338 -354.3739) (xy 124.216679 -354.358537) (xy 124.270673 -354.35078) (xy 124.297948 -354.35032)
			(xy 125.161548 -354.35032) (xy 125.188814 -354.350846) (xy 125.24279 -354.358613) (xy 125.295111 -354.373981)
			(xy 125.344713 -354.396639) (xy 125.390586 -354.426125) (xy 125.431795 -354.461839) (xy 125.467504 -354.503053)
			(xy 125.496984 -354.548929) (xy 125.519636 -354.598534) (xy 125.534998 -354.650857) (xy 125.542758 -354.704834)
			(xy 125.542758 -354.759366) (xy 125.542757 -354.759373) (xy 127.025584 -354.759373) (xy 127.025584 -354.704827)
			(xy 127.033346 -354.650837) (xy 127.048714 -354.598501) (xy 127.071373 -354.548885) (xy 127.100863 -354.502999)
			(xy 127.136583 -354.461777) (xy 127.177806 -354.426058) (xy 127.223692 -354.396569) (xy 127.273309 -354.373911)
			(xy 127.325645 -354.358545) (xy 127.379635 -354.350783) (xy 127.406908 -354.35032) (xy 128.270508 -354.35032)
			(xy 128.297776 -354.350843) (xy 128.351756 -354.358605) (xy 128.404082 -354.37397) (xy 128.453689 -354.396626)
			(xy 128.499567 -354.426111) (xy 128.540781 -354.461824) (xy 128.576494 -354.50304) (xy 128.605978 -354.548918)
			(xy 128.628632 -354.598525) (xy 128.643997 -354.650852) (xy 128.651758 -354.704832) (xy 128.651758 -354.759368)
			(xy 128.651758 -354.759369) (xy 130.134606 -354.759369) (xy 130.134606 -354.704831) (xy 130.142368 -354.650847)
			(xy 130.157732 -354.598518) (xy 130.180387 -354.548908) (xy 130.209871 -354.503026) (xy 130.245585 -354.461807)
			(xy 130.2868 -354.42609) (xy 130.33268 -354.396602) (xy 130.382288 -354.373943) (xy 130.434616 -354.358574)
			(xy 130.488599 -354.350809) (xy 130.515868 -354.35032) (xy 131.379468 -354.35032) (xy 131.406739 -354.350817)
			(xy 131.460727 -354.358575) (xy 131.513061 -354.373938) (xy 131.562676 -354.396593) (xy 131.608561 -354.426078)
			(xy 131.649783 -354.461794) (xy 131.685503 -354.503013) (xy 131.714992 -354.548896) (xy 131.737651 -354.598509)
			(xy 131.753018 -354.650842) (xy 131.76078 -354.704829) (xy 131.76078 -354.759371) (xy 131.76078 -354.759374)
			(xy 133.243484 -354.759374) (xy 133.243484 -354.704826) (xy 133.251247 -354.650835) (xy 133.266615 -354.598497)
			(xy 133.289276 -354.54888) (xy 133.318768 -354.502993) (xy 133.35449 -354.46177) (xy 133.395715 -354.426051)
			(xy 133.441604 -354.396562) (xy 133.491223 -354.373905) (xy 133.543562 -354.358541) (xy 133.597554 -354.350782)
			(xy 133.624828 -354.35032) (xy 134.488428 -354.35032) (xy 134.515695 -354.350844) (xy 134.569673 -354.358609)
			(xy 134.621997 -354.373976) (xy 134.671601 -354.396633) (xy 134.717476 -354.426118) (xy 134.758688 -354.461831)
			(xy 134.794399 -354.503046) (xy 134.823881 -354.548924) (xy 134.846534 -354.59853) (xy 134.861897 -354.650855)
			(xy 134.869658 -354.704833) (xy 134.869658 -354.759367) (xy 134.869658 -354.75937) (xy 136.352506 -354.75937)
			(xy 136.352506 -354.70483) (xy 136.360268 -354.650845) (xy 136.375634 -354.598514) (xy 136.39829 -354.548902)
			(xy 136.427776 -354.50302) (xy 136.463492 -354.4618) (xy 136.50471 -354.426083) (xy 136.550591 -354.396596)
			(xy 136.600203 -354.373938) (xy 136.652533 -354.358571) (xy 136.706518 -354.350807) (xy 136.733788 -354.35032)
			(xy 137.597388 -354.35032) (xy 137.624658 -354.350819) (xy 137.678644 -354.358579) (xy 137.730976 -354.373944)
			(xy 137.780588 -354.396599) (xy 137.826471 -354.426085) (xy 137.867691 -354.461801) (xy 137.903408 -354.503019)
			(xy 137.932895 -354.548902) (xy 137.955552 -354.598513) (xy 137.970918 -354.650844) (xy 137.978681 -354.70483)
			(xy 137.978681 -354.75937) (xy 137.97868 -354.759374) (xy 139.461384 -354.759374) (xy 139.461384 -354.704826)
			(xy 139.469147 -354.650832) (xy 139.484517 -354.598493) (xy 139.507179 -354.548874) (xy 139.536672 -354.502986)
			(xy 139.572397 -354.461763) (xy 139.613625 -354.426044) (xy 139.659516 -354.396556) (xy 139.709138 -354.3739)
			(xy 139.761479 -354.358537) (xy 139.815473 -354.35078) (xy 139.842748 -354.35032) (xy 140.706348 -354.35032)
			(xy 140.733614 -354.350846) (xy 140.78759 -354.358613) (xy 140.839911 -354.373981) (xy 140.889513 -354.396639)
			(xy 140.935386 -354.426125) (xy 140.976595 -354.461839) (xy 141.012304 -354.503053) (xy 141.041784 -354.548929)
			(xy 141.064436 -354.598534) (xy 141.079798 -354.650857) (xy 141.087558 -354.704834) (xy 141.087558 -354.759366)
			(xy 141.087557 -354.759373) (xy 142.570384 -354.759373) (xy 142.570384 -354.704827) (xy 142.578146 -354.650837)
			(xy 142.593514 -354.598501) (xy 142.616173 -354.548885) (xy 142.645663 -354.502999) (xy 142.681383 -354.461777)
			(xy 142.722606 -354.426058) (xy 142.768492 -354.396569) (xy 142.818109 -354.373911) (xy 142.870445 -354.358545)
			(xy 142.924435 -354.350783) (xy 142.951708 -354.35032) (xy 143.815308 -354.35032) (xy 143.842576 -354.350843)
			(xy 143.896556 -354.358605) (xy 143.948882 -354.37397) (xy 143.998489 -354.396626) (xy 144.044367 -354.426111)
			(xy 144.085581 -354.461824) (xy 144.121294 -354.50304) (xy 144.150778 -354.548918) (xy 144.173432 -354.598525)
			(xy 144.188797 -354.650852) (xy 144.196558 -354.704832) (xy 144.196558 -354.759368) (xy 158.695906 -354.759368)
			(xy 158.695906 -354.704832) (xy 158.703667 -354.65085) (xy 158.719031 -354.598521) (xy 158.741685 -354.548912)
			(xy 158.771167 -354.503031) (xy 158.806879 -354.461813) (xy 158.848093 -354.426096) (xy 158.89397 -354.396608)
			(xy 158.943576 -354.373948) (xy 158.995903 -354.358577) (xy 159.049884 -354.35081) (xy 159.077152 -354.35032)
			(xy 159.940752 -354.35032) (xy 159.968024 -354.350816) (xy 160.022013 -354.358572) (xy 160.074349 -354.373934)
			(xy 160.123966 -354.396588) (xy 160.169854 -354.426072) (xy 160.211078 -354.461788) (xy 160.246799 -354.503008)
			(xy 160.276289 -354.548891) (xy 160.298949 -354.598506) (xy 160.314317 -354.65084) (xy 160.32208 -354.704828)
			(xy 160.32208 -354.759372) (xy 160.32208 -354.759373) (xy 161.804784 -354.759373) (xy 161.804784 -354.704827)
			(xy 161.812546 -354.650837) (xy 161.827914 -354.598501) (xy 161.850573 -354.548884) (xy 161.880064 -354.502998)
			(xy 161.915784 -354.461776) (xy 161.957008 -354.426056) (xy 162.002895 -354.396568) (xy 162.052512 -354.37391)
			(xy 162.104848 -354.358544) (xy 162.158839 -354.350783) (xy 162.186112 -354.35032) (xy 163.049712 -354.35032)
			(xy 163.07698 -354.350843) (xy 163.130959 -354.358606) (xy 163.183285 -354.373972) (xy 163.232891 -354.396627)
			(xy 163.278768 -354.426112) (xy 163.319983 -354.461826) (xy 163.355695 -354.503041) (xy 163.385178 -354.548919)
			(xy 163.407833 -354.598526) (xy 163.423197 -354.650852) (xy 163.430958 -354.704832) (xy 163.430958 -354.759368)
			(xy 163.430958 -354.759369) (xy 164.913806 -354.759369) (xy 164.913806 -354.704831) (xy 164.921568 -354.650847)
			(xy 164.936932 -354.598517) (xy 164.959588 -354.548907) (xy 164.989072 -354.503025) (xy 165.024786 -354.461806)
			(xy 165.066002 -354.426089) (xy 165.111882 -354.396601) (xy 165.161491 -354.373942) (xy 165.21382 -354.358574)
			(xy 165.267803 -354.350808) (xy 165.295072 -354.35032) (xy 166.158672 -354.35032) (xy 166.185943 -354.350818)
			(xy 166.23993 -354.358576) (xy 166.292264 -354.373939) (xy 166.341878 -354.396594) (xy 166.387763 -354.42608)
			(xy 166.428985 -354.461795) (xy 166.464704 -354.503014) (xy 166.494192 -354.548897) (xy 166.516851 -354.59851)
			(xy 166.532218 -354.650842) (xy 166.53998 -354.704829) (xy 166.53998 -354.759371) (xy 166.53998 -354.759374)
			(xy 168.022684 -354.759374) (xy 168.022684 -354.704826) (xy 168.030447 -354.650834) (xy 168.045816 -354.598496)
			(xy 168.068477 -354.548879) (xy 168.097969 -354.502991) (xy 168.133691 -354.461768) (xy 168.174917 -354.426049)
			(xy 168.220807 -354.396561) (xy 168.270426 -354.373904) (xy 168.322765 -354.35854) (xy 168.376758 -354.350781)
			(xy 168.404032 -354.35032) (xy 169.267632 -354.35032) (xy 169.294899 -354.350845) (xy 169.348876 -354.35861)
			(xy 169.401199 -354.373977) (xy 169.450803 -354.396634) (xy 169.496678 -354.426119) (xy 169.53789 -354.461833)
			(xy 169.5736 -354.503048) (xy 169.603081 -354.548925) (xy 169.625734 -354.598531) (xy 169.641097 -354.650855)
			(xy 169.648858 -354.704833) (xy 169.648858 -354.759367) (xy 169.648858 -354.75937) (xy 171.131706 -354.75937)
			(xy 171.131706 -354.70483) (xy 171.139468 -354.650844) (xy 171.154834 -354.598513) (xy 171.177491 -354.548901)
			(xy 171.206977 -354.503018) (xy 171.242693 -354.461799) (xy 171.283912 -354.426082) (xy 171.329794 -354.396594)
			(xy 171.379405 -354.373937) (xy 171.431736 -354.35857) (xy 171.485722 -354.350807) (xy 171.512992 -354.35032)
			(xy 172.376592 -354.35032) (xy 172.403862 -354.350819) (xy 172.457847 -354.35858) (xy 172.510178 -354.373945)
			(xy 172.55979 -354.396601) (xy 172.605673 -354.426087) (xy 172.646892 -354.461802) (xy 172.682609 -354.503021)
			(xy 172.712096 -354.548903) (xy 172.734753 -354.598514) (xy 172.750119 -354.650845) (xy 172.757881 -354.70483)
			(xy 172.757881 -354.759368) (xy 174.240706 -354.759368) (xy 174.240706 -354.704832) (xy 174.248467 -354.65085)
			(xy 174.263831 -354.598521) (xy 174.286485 -354.548912) (xy 174.315967 -354.503031) (xy 174.351679 -354.461813)
			(xy 174.392893 -354.426096) (xy 174.43877 -354.396608) (xy 174.488376 -354.373948) (xy 174.540703 -354.358577)
			(xy 174.594684 -354.35081) (xy 174.621952 -354.35032) (xy 175.485552 -354.35032) (xy 175.512824 -354.350816)
			(xy 175.566813 -354.358572) (xy 175.619149 -354.373934) (xy 175.668766 -354.396588) (xy 175.714654 -354.426072)
			(xy 175.755878 -354.461788) (xy 175.791599 -354.503008) (xy 175.821089 -354.548891) (xy 175.843749 -354.598506)
			(xy 175.859117 -354.65084) (xy 175.86688 -354.704828) (xy 175.86688 -354.759372) (xy 175.86688 -354.759373)
			(xy 177.349584 -354.759373) (xy 177.349584 -354.704827) (xy 177.357346 -354.650837) (xy 177.372714 -354.598501)
			(xy 177.395373 -354.548884) (xy 177.424864 -354.502998) (xy 177.460584 -354.461776) (xy 177.501808 -354.426056)
			(xy 177.547695 -354.396568) (xy 177.597312 -354.37391) (xy 177.649648 -354.358544) (xy 177.703639 -354.350783)
			(xy 177.730912 -354.35032) (xy 178.594512 -354.35032) (xy 178.62178 -354.350843) (xy 178.675759 -354.358606)
			(xy 178.728085 -354.373972) (xy 178.777691 -354.396627) (xy 178.823568 -354.426112) (xy 178.864783 -354.461826)
			(xy 178.900495 -354.503041) (xy 178.929978 -354.548919) (xy 178.952633 -354.598526) (xy 178.967997 -354.650852)
			(xy 178.975758 -354.704832) (xy 178.975758 -354.759368) (xy 178.975758 -354.759369) (xy 180.458606 -354.759369)
			(xy 180.458606 -354.704831) (xy 180.466368 -354.650847) (xy 180.481732 -354.598517) (xy 180.504388 -354.548907)
			(xy 180.533872 -354.503025) (xy 180.569586 -354.461806) (xy 180.610802 -354.426089) (xy 180.656682 -354.396601)
			(xy 180.706291 -354.373942) (xy 180.75862 -354.358574) (xy 180.812603 -354.350808) (xy 180.839872 -354.35032)
			(xy 181.703472 -354.35032) (xy 181.730743 -354.350818) (xy 181.78473 -354.358576) (xy 181.837064 -354.373939)
			(xy 181.886678 -354.396594) (xy 181.932563 -354.42608) (xy 181.973785 -354.461795) (xy 182.009504 -354.503014)
			(xy 182.038992 -354.548897) (xy 182.061651 -354.59851) (xy 182.077018 -354.650842) (xy 182.08478 -354.704829)
			(xy 182.08478 -354.735472) (xy 183.567508 -354.735472) (xy 183.567508 -354.680928) (xy 183.57527 -354.626939)
			(xy 183.590638 -354.574605) (xy 183.613298 -354.52499) (xy 183.642788 -354.479106) (xy 183.678508 -354.437885)
			(xy 183.719731 -354.402169) (xy 183.765618 -354.372682) (xy 183.815235 -354.350027) (xy 183.86757 -354.334664)
			(xy 183.92156 -354.326905) (xy 183.948832 -354.326444) (xy 184.812432 -354.326444) (xy 184.8397 -354.326921)
			(xy 184.893681 -354.334686) (xy 184.946008 -354.350054) (xy 184.995615 -354.372713) (xy 185.041492 -354.4022)
			(xy 185.082707 -354.437916) (xy 185.118419 -354.479133) (xy 185.147903 -354.525013) (xy 185.170557 -354.574622)
			(xy 185.185921 -354.62695) (xy 185.193682 -354.680932) (xy 185.193682 -354.735468) (xy 185.193682 -354.735469)
			(xy 186.67653 -354.735469) (xy 186.67653 -354.680931) (xy 186.684292 -354.626949) (xy 186.699656 -354.574621)
			(xy 186.722312 -354.525012) (xy 186.751796 -354.479133) (xy 186.78751 -354.437916) (xy 186.828726 -354.402201)
			(xy 186.874605 -354.372716) (xy 186.924214 -354.350059) (xy 186.976542 -354.334693) (xy 187.030523 -354.326931)
			(xy 187.057792 -354.326444) (xy 187.921392 -354.326444) (xy 187.948664 -354.326895) (xy 188.002652 -354.334656)
			(xy 188.054987 -354.350022) (xy 188.104602 -354.37268) (xy 188.150487 -354.402167) (xy 188.191709 -354.437885)
			(xy 188.227428 -354.479106) (xy 188.256917 -354.524991) (xy 188.279575 -354.574606) (xy 188.294942 -354.62694)
			(xy 188.302704 -354.680928) (xy 188.302704 -354.735472) (xy 188.299268 -354.759369) (xy 270.624806 -354.759369)
			(xy 270.624806 -354.704831) (xy 270.632567 -354.650848) (xy 270.647932 -354.598519) (xy 270.670586 -354.548909)
			(xy 270.70007 -354.503028) (xy 270.735783 -354.46181) (xy 270.776998 -354.426093) (xy 270.822876 -354.396604)
			(xy 270.872484 -354.373945) (xy 270.924811 -354.358575) (xy 270.978793 -354.350809) (xy 271.006062 -354.35032)
			(xy 271.869662 -354.35032) (xy 271.896933 -354.350817) (xy 271.950922 -354.358574) (xy 272.003257 -354.373936)
			(xy 272.052872 -354.396591) (xy 272.098759 -354.426076) (xy 272.139981 -354.461792) (xy 272.175701 -354.503011)
			(xy 272.205191 -354.548894) (xy 272.22785 -354.598508) (xy 272.243218 -354.650841) (xy 272.25098 -354.704829)
			(xy 272.25098 -354.759371) (xy 272.25098 -354.759373) (xy 273.733684 -354.759373) (xy 273.733684 -354.704827)
			(xy 273.741447 -354.650835) (xy 273.756815 -354.598498) (xy 273.779475 -354.548882) (xy 273.808966 -354.502995)
			(xy 273.844688 -354.461772) (xy 273.885912 -354.426053) (xy 273.931801 -354.396564) (xy 273.981419 -354.373907)
			(xy 274.033757 -354.358542) (xy 274.087749 -354.350782) (xy 274.115022 -354.35032) (xy 274.978622 -354.35032)
			(xy 275.005889 -354.350844) (xy 275.059868 -354.358608) (xy 275.112192 -354.373974) (xy 275.161797 -354.396631)
			(xy 275.207673 -354.426116) (xy 275.248886 -354.461829) (xy 275.284597 -354.503044) (xy 275.31408 -354.548922)
			(xy 275.336733 -354.598528) (xy 275.352097 -354.650854) (xy 275.359858 -354.704833) (xy 275.359858 -354.759367)
			(xy 275.359858 -354.75937) (xy 276.842706 -354.75937) (xy 276.842706 -354.70483) (xy 276.850468 -354.650846)
			(xy 276.865833 -354.598515) (xy 276.888489 -354.548904) (xy 276.917975 -354.503022) (xy 276.95369 -354.461802)
			(xy 276.994907 -354.426085) (xy 277.040788 -354.396598) (xy 277.090398 -354.373939) (xy 277.142728 -354.358572)
			(xy 277.196712 -354.350808) (xy 277.223982 -354.35032) (xy 278.087582 -354.35032) (xy 278.114853 -354.350818)
			(xy 278.168839 -354.358578) (xy 278.221171 -354.373942) (xy 278.270784 -354.396597) (xy 278.316668 -354.426083)
			(xy 278.357888 -354.461799) (xy 278.393606 -354.503018) (xy 278.423094 -354.5489) (xy 278.445752 -354.598512)
			(xy 278.461118 -354.650844) (xy 278.468881 -354.704829) (xy 278.468881 -354.759371) (xy 278.468881 -354.759374)
			(xy 279.951584 -354.759374) (xy 279.951584 -354.704826) (xy 279.959347 -354.650833) (xy 279.974716 -354.598494)
			(xy 279.997378 -354.548876) (xy 280.026871 -354.502988) (xy 280.062595 -354.461765) (xy 280.103822 -354.426046)
			(xy 280.149713 -354.396558) (xy 280.199334 -354.373902) (xy 280.251674 -354.358538) (xy 280.305668 -354.350781)
			(xy 280.332942 -354.35032) (xy 281.196542 -354.35032) (xy 281.223808 -354.350845) (xy 281.277785 -354.358611)
			(xy 281.330107 -354.37398) (xy 281.379709 -354.396637) (xy 281.425583 -354.426123) (xy 281.466793 -354.461836)
			(xy 281.502502 -354.503051) (xy 281.531983 -354.548928) (xy 281.554635 -354.598533) (xy 281.569998 -354.650856)
			(xy 281.577758 -354.704834) (xy 281.577758 -354.759366) (xy 281.577757 -354.759372) (xy 283.060584 -354.759372)
			(xy 283.060584 -354.704828) (xy 283.068346 -354.650838) (xy 283.083713 -354.598503) (xy 283.106372 -354.548887)
			(xy 283.135861 -354.503001) (xy 283.171581 -354.461779) (xy 283.212803 -354.42606) (xy 283.258689 -354.396571)
			(xy 283.308305 -354.373912) (xy 283.36064 -354.358546) (xy 283.41463 -354.350783) (xy 283.441902 -354.35032)
			(xy 284.305502 -354.35032) (xy 284.33277 -354.350843) (xy 284.386751 -354.358604) (xy 284.439078 -354.373969)
			(xy 284.488685 -354.396624) (xy 284.534564 -354.426109) (xy 284.575779 -354.461822) (xy 284.611493 -354.503038)
			(xy 284.640977 -354.548917) (xy 284.663632 -354.598524) (xy 284.678996 -354.650851) (xy 284.686758 -354.704832)
			(xy 284.686758 -354.759368) (xy 284.686758 -354.759369) (xy 286.169606 -354.759369) (xy 286.169606 -354.704831)
			(xy 286.177367 -354.650848) (xy 286.192732 -354.598519) (xy 286.215386 -354.548909) (xy 286.24487 -354.503028)
			(xy 286.280583 -354.46181) (xy 286.321798 -354.426093) (xy 286.367676 -354.396604) (xy 286.417284 -354.373945)
			(xy 286.469611 -354.358575) (xy 286.523593 -354.350809) (xy 286.550862 -354.35032) (xy 287.414462 -354.35032)
			(xy 287.441733 -354.350817) (xy 287.495722 -354.358574) (xy 287.548057 -354.373936) (xy 287.597672 -354.396591)
			(xy 287.643559 -354.426076) (xy 287.684781 -354.461792) (xy 287.720501 -354.503011) (xy 287.749991 -354.548894)
			(xy 287.77265 -354.598508) (xy 287.788018 -354.650841) (xy 287.79578 -354.704829) (xy 287.79578 -354.759371)
			(xy 287.79578 -354.759373) (xy 289.278484 -354.759373) (xy 289.278484 -354.704827) (xy 289.286247 -354.650835)
			(xy 289.301615 -354.598498) (xy 289.324275 -354.548882) (xy 289.353766 -354.502995) (xy 289.389488 -354.461772)
			(xy 289.430712 -354.426053) (xy 289.476601 -354.396564) (xy 289.526219 -354.373907) (xy 289.578557 -354.358542)
			(xy 289.632549 -354.350782) (xy 289.659822 -354.35032) (xy 290.523422 -354.35032) (xy 290.550689 -354.350844)
			(xy 290.604668 -354.358608) (xy 290.656992 -354.373974) (xy 290.706597 -354.396631) (xy 290.752473 -354.426116)
			(xy 290.793686 -354.461829) (xy 290.829397 -354.503044) (xy 290.85888 -354.548922) (xy 290.881533 -354.598528)
			(xy 290.896897 -354.650854) (xy 290.904658 -354.704833) (xy 290.904658 -354.759367) (xy 290.904658 -354.75937)
			(xy 292.387506 -354.75937) (xy 292.387506 -354.70483) (xy 292.395268 -354.650846) (xy 292.410633 -354.598515)
			(xy 292.433289 -354.548904) (xy 292.462775 -354.503022) (xy 292.49849 -354.461802) (xy 292.539707 -354.426085)
			(xy 292.585588 -354.396598) (xy 292.635198 -354.373939) (xy 292.687528 -354.358572) (xy 292.741512 -354.350808)
			(xy 292.768782 -354.35032) (xy 293.632382 -354.35032) (xy 293.659653 -354.350818) (xy 293.713639 -354.358578)
			(xy 293.765971 -354.373942) (xy 293.815584 -354.396597) (xy 293.861468 -354.426083) (xy 293.902688 -354.461799)
			(xy 293.938406 -354.503018) (xy 293.967894 -354.5489) (xy 293.990552 -354.598512) (xy 294.005918 -354.650844)
			(xy 294.013681 -354.704829) (xy 294.013681 -354.759371) (xy 294.013681 -354.759374) (xy 295.496384 -354.759374)
			(xy 295.496384 -354.704826) (xy 295.504147 -354.650833) (xy 295.519516 -354.598494) (xy 295.542178 -354.548876)
			(xy 295.571671 -354.502988) (xy 295.607395 -354.461765) (xy 295.648622 -354.426046) (xy 295.694513 -354.396558)
			(xy 295.744134 -354.373902) (xy 295.796474 -354.358538) (xy 295.850468 -354.350781) (xy 295.877742 -354.35032)
			(xy 296.741342 -354.35032) (xy 296.768608 -354.350845) (xy 296.822585 -354.358611) (xy 296.874907 -354.37398)
			(xy 296.924509 -354.396637) (xy 296.970383 -354.426123) (xy 297.011593 -354.461836) (xy 297.047302 -354.503051)
			(xy 297.076783 -354.548928) (xy 297.099435 -354.598533) (xy 297.114798 -354.650856) (xy 297.122558 -354.704834)
			(xy 297.122558 -354.759366) (xy 297.122557 -354.759372) (xy 298.605384 -354.759372) (xy 298.605384 -354.704828)
			(xy 298.613146 -354.650838) (xy 298.628513 -354.598503) (xy 298.651172 -354.548887) (xy 298.680661 -354.503001)
			(xy 298.716381 -354.461779) (xy 298.757603 -354.42606) (xy 298.803489 -354.396571) (xy 298.853105 -354.373912)
			(xy 298.90544 -354.358546) (xy 298.95943 -354.350783) (xy 298.986702 -354.35032) (xy 299.850302 -354.35032)
			(xy 299.87757 -354.350843) (xy 299.931551 -354.358604) (xy 299.983878 -354.373969) (xy 300.033485 -354.396624)
			(xy 300.079364 -354.426109) (xy 300.120579 -354.461822) (xy 300.156293 -354.503038) (xy 300.185777 -354.548917)
			(xy 300.208432 -354.598524) (xy 300.223796 -354.650851) (xy 300.231558 -354.704832) (xy 300.231558 -354.759368)
			(xy 300.231558 -354.759369) (xy 315.230506 -354.759369) (xy 315.230506 -354.704831) (xy 315.238267 -354.650848)
			(xy 315.253632 -354.598519) (xy 315.276286 -354.548909) (xy 315.30577 -354.503027) (xy 315.341483 -354.461809)
			(xy 315.382699 -354.426092) (xy 315.428577 -354.396604) (xy 315.478185 -354.373944) (xy 315.530513 -354.358575)
			(xy 315.584495 -354.350809) (xy 315.611764 -354.35032) (xy 316.475364 -354.35032) (xy 316.502635 -354.350817)
			(xy 316.556624 -354.358575) (xy 316.608958 -354.373937) (xy 316.658574 -354.396591) (xy 316.70446 -354.426077)
			(xy 316.745682 -354.461793) (xy 316.781402 -354.503012) (xy 316.810891 -354.548895) (xy 316.83355 -354.598508)
			(xy 316.848918 -354.650841) (xy 316.85668 -354.704829) (xy 316.85668 -354.759371) (xy 316.85668 -354.759373)
			(xy 318.339384 -354.759373) (xy 318.339384 -354.704827) (xy 318.347147 -354.650835) (xy 318.362515 -354.598498)
			(xy 318.385175 -354.548881) (xy 318.414667 -354.502994) (xy 318.450388 -354.461771) (xy 318.491613 -354.426052)
			(xy 318.537502 -354.396564) (xy 318.587121 -354.373907) (xy 318.639459 -354.358542) (xy 318.693451 -354.350782)
			(xy 318.720724 -354.35032) (xy 319.584324 -354.35032) (xy 319.611591 -354.350844) (xy 319.665569 -354.358608)
			(xy 319.717894 -354.373975) (xy 319.767498 -354.396631) (xy 319.813374 -354.426116) (xy 319.854587 -354.46183)
			(xy 319.890298 -354.503045) (xy 319.91978 -354.548923) (xy 319.942434 -354.598529) (xy 319.957797 -354.650854)
			(xy 319.965558 -354.704833) (xy 319.965558 -354.759367) (xy 319.965558 -354.75937) (xy 321.448406 -354.75937)
			(xy 321.448406 -354.70483) (xy 321.456168 -354.650845) (xy 321.471533 -354.598515) (xy 321.494189 -354.548903)
			(xy 321.523675 -354.503021) (xy 321.55939 -354.461802) (xy 321.600608 -354.426085) (xy 321.646489 -354.396597)
			(xy 321.6961 -354.373939) (xy 321.74843 -354.358571) (xy 321.802414 -354.350808) (xy 321.829684 -354.35032)
			(xy 322.693284 -354.35032) (xy 322.720554 -354.350818) (xy 322.774541 -354.358578) (xy 322.826873 -354.373942)
			(xy 322.876485 -354.396598) (xy 322.922369 -354.426084) (xy 322.963589 -354.4618) (xy 322.999307 -354.503018)
			(xy 323.028794 -354.5489) (xy 323.051452 -354.598512) (xy 323.066818 -354.650844) (xy 323.074581 -354.70483)
			(xy 323.074581 -354.75937) (xy 323.07458 -354.759374) (xy 324.557284 -354.759374) (xy 324.557284 -354.704826)
			(xy 324.565047 -354.650832) (xy 324.580417 -354.598494) (xy 324.603078 -354.548875) (xy 324.632571 -354.502987)
			(xy 324.668295 -354.461764) (xy 324.709523 -354.426045) (xy 324.755414 -354.396557) (xy 324.805035 -354.373901)
			(xy 324.857375 -354.358538) (xy 324.91137 -354.350781) (xy 324.938644 -354.35032) (xy 325.802244 -354.35032)
			(xy 325.82951 -354.350845) (xy 325.883486 -354.358612) (xy 325.935808 -354.37398) (xy 325.98541 -354.396638)
			(xy 326.031284 -354.426124) (xy 326.072494 -354.461837) (xy 326.108203 -354.503052) (xy 326.137683 -354.548928)
			(xy 326.160335 -354.598533) (xy 326.175698 -354.650857) (xy 326.183458 -354.704834) (xy 326.183458 -354.759366)
			(xy 326.183457 -354.759372) (xy 327.666284 -354.759372) (xy 327.666284 -354.704828) (xy 327.674046 -354.650838)
			(xy 327.689413 -354.598502) (xy 327.712072 -354.548887) (xy 327.741562 -354.503001) (xy 327.777281 -354.461778)
			(xy 327.818504 -354.426059) (xy 327.86439 -354.39657) (xy 327.914006 -354.373912) (xy 327.966342 -354.358545)
			(xy 328.020332 -354.350783) (xy 328.047604 -354.35032) (xy 328.911204 -354.35032) (xy 328.938472 -354.350843)
			(xy 328.992453 -354.358604) (xy 329.044779 -354.373969) (xy 329.094386 -354.396625) (xy 329.140265 -354.426109)
			(xy 329.18148 -354.461823) (xy 329.217193 -354.503039) (xy 329.246677 -354.548917) (xy 329.269332 -354.598525)
			(xy 329.284696 -354.650851) (xy 329.292458 -354.704832) (xy 329.292458 -354.759368) (xy 329.292458 -354.759369)
			(xy 330.775306 -354.759369) (xy 330.775306 -354.704831) (xy 330.783067 -354.650848) (xy 330.798432 -354.598519)
			(xy 330.821086 -354.548909) (xy 330.85057 -354.503027) (xy 330.886283 -354.461809) (xy 330.927499 -354.426092)
			(xy 330.973377 -354.396604) (xy 331.022985 -354.373944) (xy 331.075313 -354.358575) (xy 331.129295 -354.350809)
			(xy 331.156564 -354.35032) (xy 332.020164 -354.35032) (xy 332.047435 -354.350817) (xy 332.101424 -354.358575)
			(xy 332.153758 -354.373937) (xy 332.203374 -354.396591) (xy 332.24926 -354.426077) (xy 332.290482 -354.461793)
			(xy 332.326202 -354.503012) (xy 332.355691 -354.548895) (xy 332.37835 -354.598508) (xy 332.393718 -354.650841)
			(xy 332.40148 -354.704829) (xy 332.40148 -354.759371) (xy 332.40148 -354.759373) (xy 333.884184 -354.759373)
			(xy 333.884184 -354.704827) (xy 333.891947 -354.650835) (xy 333.907315 -354.598498) (xy 333.929975 -354.548881)
			(xy 333.959467 -354.502994) (xy 333.995188 -354.461771) (xy 334.036413 -354.426052) (xy 334.082302 -354.396564)
			(xy 334.131921 -354.373907) (xy 334.184259 -354.358542) (xy 334.238251 -354.350782) (xy 334.265524 -354.35032)
			(xy 335.129124 -354.35032) (xy 335.156391 -354.350844) (xy 335.210369 -354.358608) (xy 335.262694 -354.373975)
			(xy 335.312298 -354.396631) (xy 335.358174 -354.426116) (xy 335.399387 -354.46183) (xy 335.435098 -354.503045)
			(xy 335.46458 -354.548923) (xy 335.487234 -354.598529) (xy 335.502597 -354.650854) (xy 335.510358 -354.704833)
			(xy 335.510358 -354.759367) (xy 335.510358 -354.75937) (xy 336.993206 -354.75937) (xy 336.993206 -354.70483)
			(xy 337.000968 -354.650845) (xy 337.016333 -354.598515) (xy 337.038989 -354.548903) (xy 337.068475 -354.503021)
			(xy 337.10419 -354.461802) (xy 337.145408 -354.426085) (xy 337.191289 -354.396597) (xy 337.2409 -354.373939)
			(xy 337.29323 -354.358571) (xy 337.347214 -354.350808) (xy 337.374484 -354.35032) (xy 338.238084 -354.35032)
			(xy 338.265354 -354.350818) (xy 338.319341 -354.358578) (xy 338.371673 -354.373942) (xy 338.421285 -354.396598)
			(xy 338.467169 -354.426084) (xy 338.508389 -354.4618) (xy 338.544107 -354.503018) (xy 338.573594 -354.5489)
			(xy 338.596252 -354.598512) (xy 338.611618 -354.650844) (xy 338.619381 -354.70483) (xy 338.619381 -354.75937)
			(xy 338.61938 -354.759374) (xy 340.102084 -354.759374) (xy 340.102084 -354.704826) (xy 340.109847 -354.650832)
			(xy 340.125217 -354.598494) (xy 340.147878 -354.548875) (xy 340.177371 -354.502987) (xy 340.213095 -354.461764)
			(xy 340.254323 -354.426045) (xy 340.300214 -354.396557) (xy 340.349835 -354.373901) (xy 340.402175 -354.358538)
			(xy 340.45617 -354.350781) (xy 340.483444 -354.35032) (xy 341.347044 -354.35032) (xy 341.37431 -354.350845)
			(xy 341.428286 -354.358612) (xy 341.480608 -354.37398) (xy 341.53021 -354.396638) (xy 341.576084 -354.426124)
			(xy 341.617294 -354.461837) (xy 341.653003 -354.503052) (xy 341.682483 -354.548928) (xy 341.705135 -354.598533)
			(xy 341.720498 -354.650857) (xy 341.728258 -354.704834) (xy 341.728258 -354.759366) (xy 341.728257 -354.759372)
			(xy 343.211084 -354.759372) (xy 343.211084 -354.704828) (xy 343.218846 -354.650838) (xy 343.234213 -354.598502)
			(xy 343.256872 -354.548887) (xy 343.286362 -354.503001) (xy 343.322081 -354.461778) (xy 343.363304 -354.426059)
			(xy 343.40919 -354.39657) (xy 343.458806 -354.373912) (xy 343.511142 -354.358545) (xy 343.565132 -354.350783)
			(xy 343.592404 -354.35032) (xy 344.456004 -354.35032) (xy 344.483272 -354.350843) (xy 344.537253 -354.358604)
			(xy 344.589579 -354.373969) (xy 344.639186 -354.396625) (xy 344.685065 -354.426109) (xy 344.72628 -354.461823)
			(xy 344.761993 -354.503039) (xy 344.791477 -354.548917) (xy 344.814132 -354.598525) (xy 344.829496 -354.650851)
			(xy 344.837258 -354.704832) (xy 344.837258 -354.759368) (xy 344.837257 -354.759374) (xy 373.915584 -354.759374)
			(xy 373.915584 -354.704826) (xy 373.923347 -354.650833) (xy 373.938716 -354.598495) (xy 373.961378 -354.548876)
			(xy 373.990871 -354.502989) (xy 374.026594 -354.461766) (xy 374.067821 -354.426047) (xy 374.113712 -354.396559)
			(xy 374.163332 -354.373902) (xy 374.215672 -354.358539) (xy 374.269666 -354.350781) (xy 374.29694 -354.35032)
			(xy 375.16054 -354.35032) (xy 375.187806 -354.350845) (xy 375.241783 -354.358611) (xy 375.294105 -354.373979)
			(xy 375.343708 -354.396637) (xy 375.389582 -354.426122) (xy 375.430793 -354.461836) (xy 375.466502 -354.50305)
			(xy 375.495983 -354.548927) (xy 375.518635 -354.598532) (xy 375.533997 -354.650856) (xy 375.541758 -354.704834)
			(xy 375.541758 -354.759366) (xy 375.541757 -354.759371) (xy 377.024606 -354.759371) (xy 377.024606 -354.704829)
			(xy 377.032369 -354.650843) (xy 377.047735 -354.598511) (xy 377.070392 -354.548899) (xy 377.099879 -354.503016)
			(xy 377.135596 -354.461796) (xy 377.176816 -354.426079) (xy 377.222699 -354.396592) (xy 377.272311 -354.373935)
			(xy 377.324643 -354.358569) (xy 377.378629 -354.350806) (xy 377.4059 -354.35032) (xy 378.2695 -354.35032)
			(xy 378.296768 -354.350842) (xy 378.350749 -354.358604) (xy 378.403076 -354.373968) (xy 378.452684 -354.396623)
			(xy 378.498563 -354.426108) (xy 378.539778 -354.461822) (xy 378.575492 -354.503037) (xy 378.604977 -354.548916)
			(xy 378.627632 -354.598524) (xy 378.642996 -354.650851) (xy 378.650758 -354.704832) (xy 378.650758 -354.759368)
			(xy 378.650758 -354.759369) (xy 380.133606 -354.759369) (xy 380.133606 -354.704831) (xy 380.141367 -354.650849)
			(xy 380.156731 -354.59852) (xy 380.179386 -354.54891) (xy 380.208869 -354.503029) (xy 380.244582 -354.46181)
			(xy 380.285797 -354.426093) (xy 380.331675 -354.396605) (xy 380.381282 -354.373945) (xy 380.433609 -354.358576)
			(xy 380.487591 -354.350809) (xy 380.51486 -354.35032) (xy 381.37846 -354.35032) (xy 381.405732 -354.350817)
			(xy 381.45972 -354.358574) (xy 381.512055 -354.373936) (xy 381.561671 -354.39659) (xy 381.607558 -354.426075)
			(xy 381.648781 -354.461791) (xy 381.684501 -354.50301) (xy 381.713991 -354.548894) (xy 381.73665 -354.598507)
			(xy 381.752018 -354.650841) (xy 381.75978 -354.704828) (xy 381.75978 -354.759372) (xy 381.75978 -354.759373)
			(xy 383.242484 -354.759373) (xy 383.242484 -354.704827) (xy 383.250247 -354.650836) (xy 383.265615 -354.598499)
			(xy 383.288275 -354.548882) (xy 383.317766 -354.502995) (xy 383.353487 -354.461773) (xy 383.394711 -354.426054)
			(xy 383.4406 -354.396565) (xy 383.490218 -354.373908) (xy 383.542555 -354.358542) (xy 383.596547 -354.350782)
			(xy 383.62382 -354.35032) (xy 384.48742 -354.35032) (xy 384.514687 -354.350844) (xy 384.568666 -354.358607)
			(xy 384.620991 -354.373974) (xy 384.670596 -354.39663) (xy 384.716472 -354.426115) (xy 384.757686 -354.461829)
			(xy 384.793397 -354.503044) (xy 384.82288 -354.548922) (xy 384.845533 -354.598528) (xy 384.860897 -354.650854)
			(xy 384.868658 -354.704833) (xy 384.868658 -354.759367) (xy 384.868658 -354.75937) (xy 386.351506 -354.75937)
			(xy 386.351506 -354.70483) (xy 386.359268 -354.650846) (xy 386.374633 -354.598515) (xy 386.397289 -354.548904)
			(xy 386.426774 -354.503022) (xy 386.462489 -354.461803) (xy 386.503706 -354.426086) (xy 386.549587 -354.396598)
			(xy 386.599197 -354.37394) (xy 386.651526 -354.358572) (xy 386.70551 -354.350808) (xy 386.73278 -354.35032)
			(xy 387.59638 -354.35032) (xy 387.623651 -354.350818) (xy 387.677637 -354.358578) (xy 387.72997 -354.373941)
			(xy 387.779583 -354.396597) (xy 387.825467 -354.426082) (xy 387.866688 -354.461798) (xy 387.902406 -354.503017)
			(xy 387.931894 -354.548899) (xy 387.954552 -354.598511) (xy 387.969918 -354.650843) (xy 387.97768 -354.704829)
			(xy 387.97768 -354.759371) (xy 387.97768 -354.759374) (xy 389.460384 -354.759374) (xy 389.460384 -354.704826)
			(xy 389.468147 -354.650833) (xy 389.483516 -354.598495) (xy 389.506178 -354.548876) (xy 389.535671 -354.502989)
			(xy 389.571394 -354.461766) (xy 389.612621 -354.426047) (xy 389.658512 -354.396559) (xy 389.708132 -354.373902)
			(xy 389.760472 -354.358539) (xy 389.814466 -354.350781) (xy 389.84174 -354.35032) (xy 390.70534 -354.35032)
			(xy 390.732606 -354.350845) (xy 390.786583 -354.358611) (xy 390.838905 -354.373979) (xy 390.888508 -354.396637)
			(xy 390.934382 -354.426122) (xy 390.975593 -354.461836) (xy 391.011302 -354.50305) (xy 391.040783 -354.548927)
			(xy 391.063435 -354.598532) (xy 391.078797 -354.650856) (xy 391.086558 -354.704834) (xy 391.086558 -354.759366)
			(xy 391.086557 -354.759371) (xy 392.569406 -354.759371) (xy 392.569406 -354.704829) (xy 392.577169 -354.650843)
			(xy 392.592535 -354.598511) (xy 392.615192 -354.548899) (xy 392.644679 -354.503016) (xy 392.680396 -354.461796)
			(xy 392.721616 -354.426079) (xy 392.767499 -354.396592) (xy 392.817111 -354.373935) (xy 392.869443 -354.358569)
			(xy 392.923429 -354.350806) (xy 392.9507 -354.35032) (xy 393.8143 -354.35032) (xy 393.841568 -354.350842)
			(xy 393.895549 -354.358604) (xy 393.947876 -354.373968) (xy 393.997484 -354.396623) (xy 394.043363 -354.426108)
			(xy 394.084578 -354.461822) (xy 394.120292 -354.503037) (xy 394.149777 -354.548916) (xy 394.172432 -354.598524)
			(xy 394.187796 -354.650851) (xy 394.195558 -354.704832) (xy 394.195558 -354.759368) (xy 394.195558 -354.759369)
			(xy 395.678406 -354.759369) (xy 395.678406 -354.704831) (xy 395.686167 -354.650849) (xy 395.701531 -354.59852)
			(xy 395.724186 -354.54891) (xy 395.753669 -354.503029) (xy 395.789382 -354.46181) (xy 395.830597 -354.426093)
			(xy 395.876475 -354.396605) (xy 395.926082 -354.373945) (xy 395.978409 -354.358576) (xy 396.032391 -354.350809)
			(xy 396.05966 -354.35032) (xy 396.92326 -354.35032) (xy 396.950532 -354.350817) (xy 397.00452 -354.358574)
			(xy 397.056855 -354.373936) (xy 397.106471 -354.39659) (xy 397.152358 -354.426075) (xy 397.193581 -354.461791)
			(xy 397.229301 -354.50301) (xy 397.258791 -354.548894) (xy 397.28145 -354.598507) (xy 397.296818 -354.650841)
			(xy 397.30458 -354.704828) (xy 397.30458 -354.759372) (xy 397.30458 -354.759373) (xy 398.787284 -354.759373)
			(xy 398.787284 -354.704827) (xy 398.795047 -354.650836) (xy 398.810415 -354.598499) (xy 398.833075 -354.548882)
			(xy 398.862566 -354.502995) (xy 398.898287 -354.461773) (xy 398.939511 -354.426054) (xy 398.9854 -354.396565)
			(xy 399.035018 -354.373908) (xy 399.087355 -354.358542) (xy 399.141347 -354.350782) (xy 399.16862 -354.35032)
			(xy 400.03222 -354.35032) (xy 400.059487 -354.350844) (xy 400.113466 -354.358607) (xy 400.165791 -354.373974)
			(xy 400.215396 -354.39663) (xy 400.261272 -354.426115) (xy 400.302486 -354.461829) (xy 400.338197 -354.503044)
			(xy 400.36768 -354.548922) (xy 400.390333 -354.598528) (xy 400.405697 -354.650854) (xy 400.413458 -354.704833)
			(xy 400.413458 -354.759367) (xy 400.413458 -354.75937) (xy 401.896306 -354.75937) (xy 401.896306 -354.70483)
			(xy 401.904068 -354.650846) (xy 401.919433 -354.598515) (xy 401.942089 -354.548904) (xy 401.971574 -354.503022)
			(xy 402.007289 -354.461803) (xy 402.048506 -354.426086) (xy 402.094387 -354.396598) (xy 402.143997 -354.37394)
			(xy 402.196326 -354.358572) (xy 402.25031 -354.350808) (xy 402.27758 -354.35032) (xy 403.14118 -354.35032)
			(xy 403.168451 -354.350818) (xy 403.222437 -354.358578) (xy 403.27477 -354.373941) (xy 403.324383 -354.396597)
			(xy 403.370267 -354.426082) (xy 403.411488 -354.461798) (xy 403.447206 -354.503017) (xy 403.476694 -354.548899)
			(xy 403.499352 -354.598511) (xy 403.514718 -354.650843) (xy 403.52248 -354.704829) (xy 403.52248 -354.759368)
			(xy 412.022806 -354.759368) (xy 412.022806 -354.704832) (xy 412.030567 -354.65085) (xy 412.045931 -354.598521)
			(xy 412.068585 -354.548912) (xy 412.098067 -354.503031) (xy 412.133779 -354.461813) (xy 412.174993 -354.426096)
			(xy 412.22087 -354.396608) (xy 412.270476 -354.373948) (xy 412.322803 -354.358577) (xy 412.376784 -354.35081)
			(xy 412.404052 -354.35032) (xy 413.267652 -354.35032) (xy 413.294924 -354.350816) (xy 413.348913 -354.358572)
			(xy 413.401249 -354.373934) (xy 413.450866 -354.396588) (xy 413.496754 -354.426072) (xy 413.537978 -354.461788)
			(xy 413.573699 -354.503008) (xy 413.603189 -354.548891) (xy 413.625849 -354.598506) (xy 413.641217 -354.65084)
			(xy 413.64898 -354.704828) (xy 413.64898 -354.759372) (xy 413.64898 -354.759373) (xy 415.131684 -354.759373)
			(xy 415.131684 -354.704827) (xy 415.139446 -354.650837) (xy 415.154814 -354.598501) (xy 415.177473 -354.548884)
			(xy 415.206964 -354.502998) (xy 415.242684 -354.461776) (xy 415.283908 -354.426056) (xy 415.329795 -354.396568)
			(xy 415.379412 -354.37391) (xy 415.431748 -354.358544) (xy 415.485739 -354.350783) (xy 415.513012 -354.35032)
			(xy 416.376612 -354.35032) (xy 416.40388 -354.350843) (xy 416.457859 -354.358606) (xy 416.510185 -354.373972)
			(xy 416.559791 -354.396627) (xy 416.605668 -354.426112) (xy 416.646883 -354.461826) (xy 416.682595 -354.503041)
			(xy 416.712078 -354.548919) (xy 416.734733 -354.598526) (xy 416.750097 -354.650852) (xy 416.757858 -354.704832)
			(xy 416.757858 -354.759368) (xy 416.757858 -354.759369) (xy 418.240706 -354.759369) (xy 418.240706 -354.704831)
			(xy 418.248468 -354.650847) (xy 418.263832 -354.598517) (xy 418.286488 -354.548907) (xy 418.315972 -354.503025)
			(xy 418.351686 -354.461806) (xy 418.392902 -354.426089) (xy 418.438782 -354.396601) (xy 418.488391 -354.373942)
			(xy 418.54072 -354.358574) (xy 418.594703 -354.350808) (xy 418.621972 -354.35032) (xy 419.485572 -354.35032)
			(xy 419.512843 -354.350818) (xy 419.56683 -354.358576) (xy 419.619164 -354.373939) (xy 419.668778 -354.396594)
			(xy 419.714663 -354.42608) (xy 419.755885 -354.461795) (xy 419.791604 -354.503014) (xy 419.821092 -354.548897)
			(xy 419.843751 -354.59851) (xy 419.859118 -354.650842) (xy 419.86688 -354.704829) (xy 419.86688 -354.759371)
			(xy 419.86688 -354.759374) (xy 421.349584 -354.759374) (xy 421.349584 -354.704826) (xy 421.357347 -354.650834)
			(xy 421.372716 -354.598496) (xy 421.395377 -354.548879) (xy 421.424869 -354.502991) (xy 421.460591 -354.461768)
			(xy 421.501817 -354.426049) (xy 421.547707 -354.396561) (xy 421.597326 -354.373904) (xy 421.649665 -354.35854)
			(xy 421.703658 -354.350781) (xy 421.730932 -354.35032) (xy 422.594532 -354.35032) (xy 422.621799 -354.350845)
			(xy 422.675776 -354.35861) (xy 422.728099 -354.373977) (xy 422.777703 -354.396634) (xy 422.823578 -354.426119)
			(xy 422.86479 -354.461833) (xy 422.9005 -354.503048) (xy 422.929981 -354.548925) (xy 422.952634 -354.598531)
			(xy 422.967997 -354.650855) (xy 422.975758 -354.704833) (xy 422.975758 -354.759367) (xy 422.975758 -354.75937)
			(xy 424.458606 -354.75937) (xy 424.458606 -354.70483) (xy 424.466368 -354.650844) (xy 424.481734 -354.598513)
			(xy 424.504391 -354.548901) (xy 424.533877 -354.503018) (xy 424.569593 -354.461799) (xy 424.610812 -354.426082)
			(xy 424.656694 -354.396594) (xy 424.706305 -354.373937) (xy 424.758636 -354.35857) (xy 424.812622 -354.350807)
			(xy 424.839892 -354.35032) (xy 425.703492 -354.35032) (xy 425.730762 -354.350819) (xy 425.784747 -354.35858)
			(xy 425.837078 -354.373945) (xy 425.88669 -354.396601) (xy 425.932573 -354.426087) (xy 425.973792 -354.461802)
			(xy 426.009509 -354.503021) (xy 426.038996 -354.548903) (xy 426.061653 -354.598514) (xy 426.077019 -354.650845)
			(xy 426.084781 -354.70483) (xy 426.084781 -354.759368) (xy 427.567606 -354.759368) (xy 427.567606 -354.704832)
			(xy 427.575367 -354.65085) (xy 427.590731 -354.598521) (xy 427.613385 -354.548912) (xy 427.642867 -354.503031)
			(xy 427.678579 -354.461813) (xy 427.719793 -354.426096) (xy 427.76567 -354.396608) (xy 427.815276 -354.373948)
			(xy 427.867603 -354.358577) (xy 427.921584 -354.35081) (xy 427.948852 -354.35032) (xy 428.812452 -354.35032)
			(xy 428.839724 -354.350816) (xy 428.893713 -354.358572) (xy 428.946049 -354.373934) (xy 428.995666 -354.396588)
			(xy 429.041554 -354.426072) (xy 429.082778 -354.461788) (xy 429.118499 -354.503008) (xy 429.147989 -354.548891)
			(xy 429.170649 -354.598506) (xy 429.186017 -354.65084) (xy 429.19378 -354.704828) (xy 429.19378 -354.759372)
			(xy 429.19378 -354.759373) (xy 430.676484 -354.759373) (xy 430.676484 -354.704827) (xy 430.684246 -354.650837)
			(xy 430.699614 -354.598501) (xy 430.722273 -354.548884) (xy 430.751764 -354.502998) (xy 430.787484 -354.461776)
			(xy 430.828708 -354.426056) (xy 430.874595 -354.396568) (xy 430.924212 -354.37391) (xy 430.976548 -354.358544)
			(xy 431.030539 -354.350783) (xy 431.057812 -354.35032) (xy 431.921412 -354.35032) (xy 431.94868 -354.350843)
			(xy 432.002659 -354.358606) (xy 432.054985 -354.373972) (xy 432.104591 -354.396627) (xy 432.150468 -354.426112)
			(xy 432.191683 -354.461826) (xy 432.227395 -354.503041) (xy 432.256878 -354.548919) (xy 432.279533 -354.598526)
			(xy 432.294897 -354.650852) (xy 432.302658 -354.704832) (xy 432.302658 -354.759368) (xy 432.302658 -354.759369)
			(xy 433.785506 -354.759369) (xy 433.785506 -354.704831) (xy 433.793268 -354.650847) (xy 433.808632 -354.598517)
			(xy 433.831288 -354.548907) (xy 433.860772 -354.503025) (xy 433.896486 -354.461806) (xy 433.937702 -354.426089)
			(xy 433.983582 -354.396601) (xy 434.033191 -354.373942) (xy 434.08552 -354.358574) (xy 434.139503 -354.350808)
			(xy 434.166772 -354.35032) (xy 435.030372 -354.35032) (xy 435.057643 -354.350818) (xy 435.11163 -354.358576)
			(xy 435.163964 -354.373939) (xy 435.213578 -354.396594) (xy 435.259463 -354.42608) (xy 435.300685 -354.461795)
			(xy 435.336404 -354.503014) (xy 435.365892 -354.548897) (xy 435.388551 -354.59851) (xy 435.403918 -354.650842)
			(xy 435.41168 -354.704829) (xy 435.41168 -354.759371) (xy 435.41168 -354.759374) (xy 436.894384 -354.759374)
			(xy 436.894384 -354.704826) (xy 436.902147 -354.650834) (xy 436.917516 -354.598496) (xy 436.940177 -354.548879)
			(xy 436.969669 -354.502991) (xy 437.005391 -354.461768) (xy 437.046617 -354.426049) (xy 437.092507 -354.396561)
			(xy 437.142126 -354.373904) (xy 437.194465 -354.35854) (xy 437.248458 -354.350781) (xy 437.275732 -354.35032)
			(xy 438.139332 -354.35032) (xy 438.166599 -354.350845) (xy 438.220576 -354.35861) (xy 438.272899 -354.373977)
			(xy 438.322503 -354.396634) (xy 438.368378 -354.426119) (xy 438.40959 -354.461833) (xy 438.4453 -354.503048)
			(xy 438.474781 -354.548925) (xy 438.497434 -354.598531) (xy 438.512797 -354.650855) (xy 438.520558 -354.704833)
			(xy 438.520558 -354.759367) (xy 438.520558 -354.75937) (xy 440.003406 -354.75937) (xy 440.003406 -354.70483)
			(xy 440.011168 -354.650844) (xy 440.026534 -354.598513) (xy 440.049191 -354.548901) (xy 440.078677 -354.503018)
			(xy 440.114393 -354.461799) (xy 440.155612 -354.426082) (xy 440.201494 -354.396594) (xy 440.251105 -354.373937)
			(xy 440.303436 -354.35857) (xy 440.357422 -354.350807) (xy 440.384692 -354.35032) (xy 441.248292 -354.35032)
			(xy 441.275562 -354.350819) (xy 441.329547 -354.35858) (xy 441.381878 -354.373945) (xy 441.43149 -354.396601)
			(xy 441.477373 -354.426087) (xy 441.518592 -354.461802) (xy 441.554309 -354.503021) (xy 441.583796 -354.548903)
			(xy 441.606453 -354.598514) (xy 441.621819 -354.650845) (xy 441.629581 -354.70483) (xy 441.629581 -354.75937)
			(xy 441.621819 -354.813355) (xy 441.606453 -354.865686) (xy 441.583796 -354.915297) (xy 441.554309 -354.961179)
			(xy 441.518592 -355.002398) (xy 441.477373 -355.038113) (xy 441.43149 -355.067599) (xy 441.381878 -355.090255)
			(xy 441.329547 -355.10562) (xy 441.275562 -355.113381) (xy 441.248292 -355.113844) (xy 440.384692 -355.113844)
			(xy 440.357422 -355.113393) (xy 440.303436 -355.10563) (xy 440.251105 -355.090263) (xy 440.201494 -355.067606)
			(xy 440.155612 -355.038118) (xy 440.114393 -355.002401) (xy 440.078677 -354.961182) (xy 440.049191 -354.915299)
			(xy 440.026534 -354.865687) (xy 440.011168 -354.813356) (xy 440.003406 -354.75937) (xy 438.520558 -354.75937)
			(xy 438.512797 -354.813345) (xy 438.497434 -354.865669) (xy 438.474781 -354.915275) (xy 438.4453 -354.961152)
			(xy 438.40959 -355.002367) (xy 438.368378 -355.038081) (xy 438.322503 -355.067566) (xy 438.272899 -355.090223)
			(xy 438.220576 -355.10559) (xy 438.166599 -355.113355) (xy 438.139332 -355.113844) (xy 437.275732 -355.113844)
			(xy 437.248458 -355.113419) (xy 437.194465 -355.10566) (xy 437.142126 -355.090296) (xy 437.092507 -355.067639)
			(xy 437.046617 -355.038151) (xy 437.005391 -355.002432) (xy 436.969669 -354.961209) (xy 436.940177 -354.915321)
			(xy 436.917516 -354.865704) (xy 436.902147 -354.813366) (xy 436.894384 -354.759374) (xy 435.41168 -354.759374)
			(xy 435.403918 -354.813358) (xy 435.388551 -354.86569) (xy 435.365892 -354.915303) (xy 435.336404 -354.961186)
			(xy 435.300685 -355.002405) (xy 435.259463 -355.03812) (xy 435.213578 -355.067606) (xy 435.163964 -355.090261)
			(xy 435.11163 -355.105624) (xy 435.057643 -355.113382) (xy 435.030372 -355.113844) (xy 434.166772 -355.113844)
			(xy 434.139503 -355.113392) (xy 434.08552 -355.105626) (xy 434.033191 -355.090258) (xy 433.983582 -355.067599)
			(xy 433.937702 -355.038111) (xy 433.896486 -355.002394) (xy 433.860772 -354.961175) (xy 433.831288 -354.915293)
			(xy 433.808632 -354.865683) (xy 433.793268 -354.813353) (xy 433.785506 -354.759369) (xy 432.302658 -354.759369)
			(xy 432.294897 -354.813348) (xy 432.279533 -354.865674) (xy 432.256878 -354.915281) (xy 432.227395 -354.961159)
			(xy 432.191683 -355.002374) (xy 432.150468 -355.038088) (xy 432.104591 -355.067573) (xy 432.054985 -355.090228)
			(xy 432.002659 -355.105594) (xy 431.94868 -355.113357) (xy 431.921412 -355.113844) (xy 431.057812 -355.113844)
			(xy 431.030539 -355.113417) (xy 430.976548 -355.105656) (xy 430.924212 -355.09029) (xy 430.874595 -355.067632)
			(xy 430.828708 -355.038144) (xy 430.787484 -355.002424) (xy 430.751764 -354.961202) (xy 430.722273 -354.915316)
			(xy 430.699614 -354.865699) (xy 430.684246 -354.813363) (xy 430.676484 -354.759373) (xy 429.19378 -354.759373)
			(xy 429.186017 -354.81336) (xy 429.170649 -354.865694) (xy 429.147989 -354.915309) (xy 429.118499 -354.961192)
			(xy 429.082778 -355.002412) (xy 429.041554 -355.038128) (xy 428.995666 -355.067612) (xy 428.946049 -355.090266)
			(xy 428.893713 -355.105628) (xy 428.839724 -355.113384) (xy 428.812452 -355.113844) (xy 427.948852 -355.113844)
			(xy 427.921584 -355.11339) (xy 427.867603 -355.105623) (xy 427.815276 -355.090252) (xy 427.76567 -355.067592)
			(xy 427.719793 -355.038104) (xy 427.678579 -355.002387) (xy 427.642867 -354.961169) (xy 427.613385 -354.915288)
			(xy 427.590731 -354.865679) (xy 427.575367 -354.81335) (xy 427.567606 -354.759368) (xy 426.084781 -354.759368)
			(xy 426.084781 -354.75937) (xy 426.077019 -354.813355) (xy 426.061653 -354.865686) (xy 426.038996 -354.915297)
			(xy 426.009509 -354.961179) (xy 425.973792 -355.002398) (xy 425.932573 -355.038113) (xy 425.88669 -355.067599)
			(xy 425.837078 -355.090255) (xy 425.784747 -355.10562) (xy 425.730762 -355.113381) (xy 425.703492 -355.113844)
			(xy 424.839892 -355.113844) (xy 424.812622 -355.113393) (xy 424.758636 -355.10563) (xy 424.706305 -355.090263)
			(xy 424.656694 -355.067606) (xy 424.610812 -355.038118) (xy 424.569593 -355.002401) (xy 424.533877 -354.961182)
			(xy 424.504391 -354.915299) (xy 424.481734 -354.865687) (xy 424.466368 -354.813356) (xy 424.458606 -354.75937)
			(xy 422.975758 -354.75937) (xy 422.967997 -354.813345) (xy 422.952634 -354.865669) (xy 422.929981 -354.915275)
			(xy 422.9005 -354.961152) (xy 422.86479 -355.002367) (xy 422.823578 -355.038081) (xy 422.777703 -355.067566)
			(xy 422.728099 -355.090223) (xy 422.675776 -355.10559) (xy 422.621799 -355.113355) (xy 422.594532 -355.113844)
			(xy 421.730932 -355.113844) (xy 421.703658 -355.113419) (xy 421.649665 -355.10566) (xy 421.597326 -355.090296)
			(xy 421.547707 -355.067639) (xy 421.501817 -355.038151) (xy 421.460591 -355.002432) (xy 421.424869 -354.961209)
			(xy 421.395377 -354.915321) (xy 421.372716 -354.865704) (xy 421.357347 -354.813366) (xy 421.349584 -354.759374)
			(xy 419.86688 -354.759374) (xy 419.859118 -354.813358) (xy 419.843751 -354.86569) (xy 419.821092 -354.915303)
			(xy 419.791604 -354.961186) (xy 419.755885 -355.002405) (xy 419.714663 -355.03812) (xy 419.668778 -355.067606)
			(xy 419.619164 -355.090261) (xy 419.56683 -355.105624) (xy 419.512843 -355.113382) (xy 419.485572 -355.113844)
			(xy 418.621972 -355.113844) (xy 418.594703 -355.113392) (xy 418.54072 -355.105626) (xy 418.488391 -355.090258)
			(xy 418.438782 -355.067599) (xy 418.392902 -355.038111) (xy 418.351686 -355.002394) (xy 418.315972 -354.961175)
			(xy 418.286488 -354.915293) (xy 418.263832 -354.865683) (xy 418.248468 -354.813353) (xy 418.240706 -354.759369)
			(xy 416.757858 -354.759369) (xy 416.750097 -354.813348) (xy 416.734733 -354.865674) (xy 416.712078 -354.915281)
			(xy 416.682595 -354.961159) (xy 416.646883 -355.002374) (xy 416.605668 -355.038088) (xy 416.559791 -355.067573)
			(xy 416.510185 -355.090228) (xy 416.457859 -355.105594) (xy 416.40388 -355.113357) (xy 416.376612 -355.113844)
			(xy 415.513012 -355.113844) (xy 415.485739 -355.113417) (xy 415.431748 -355.105656) (xy 415.379412 -355.09029)
			(xy 415.329795 -355.067632) (xy 415.283908 -355.038144) (xy 415.242684 -355.002424) (xy 415.206964 -354.961202)
			(xy 415.177473 -354.915316) (xy 415.154814 -354.865699) (xy 415.139446 -354.813363) (xy 415.131684 -354.759373)
			(xy 413.64898 -354.759373) (xy 413.641217 -354.81336) (xy 413.625849 -354.865694) (xy 413.603189 -354.915309)
			(xy 413.573699 -354.961192) (xy 413.537978 -355.002412) (xy 413.496754 -355.038128) (xy 413.450866 -355.067612)
			(xy 413.401249 -355.090266) (xy 413.348913 -355.105628) (xy 413.294924 -355.113384) (xy 413.267652 -355.113844)
			(xy 412.404052 -355.113844) (xy 412.376784 -355.11339) (xy 412.322803 -355.105623) (xy 412.270476 -355.090252)
			(xy 412.22087 -355.067592) (xy 412.174993 -355.038104) (xy 412.133779 -355.002387) (xy 412.098067 -354.961169)
			(xy 412.068585 -354.915288) (xy 412.045931 -354.865679) (xy 412.030567 -354.81335) (xy 412.022806 -354.759368)
			(xy 403.52248 -354.759368) (xy 403.52248 -354.759371) (xy 403.514718 -354.813357) (xy 403.499352 -354.865689)
			(xy 403.476694 -354.915301) (xy 403.447206 -354.961183) (xy 403.411488 -355.002402) (xy 403.370267 -355.038118)
			(xy 403.324383 -355.067603) (xy 403.27477 -355.090259) (xy 403.222437 -355.105622) (xy 403.168451 -355.113382)
			(xy 403.14118 -355.113844) (xy 402.27758 -355.113844) (xy 402.25031 -355.113392) (xy 402.196326 -355.105628)
			(xy 402.143997 -355.09026) (xy 402.094387 -355.067602) (xy 402.048506 -355.038114) (xy 402.007289 -355.002397)
			(xy 401.971574 -354.961178) (xy 401.942089 -354.915296) (xy 401.919433 -354.865685) (xy 401.904068 -354.813354)
			(xy 401.896306 -354.75937) (xy 400.413458 -354.75937) (xy 400.405697 -354.813346) (xy 400.390333 -354.865672)
			(xy 400.36768 -354.915278) (xy 400.338197 -354.961156) (xy 400.302486 -355.002371) (xy 400.261272 -355.038085)
			(xy 400.215396 -355.06757) (xy 400.165791 -355.090226) (xy 400.113466 -355.105593) (xy 400.059487 -355.113356)
			(xy 400.03222 -355.113844) (xy 399.16862 -355.113844) (xy 399.141347 -355.113418) (xy 399.087355 -355.105658)
			(xy 399.035018 -355.090292) (xy 398.9854 -355.067635) (xy 398.939511 -355.038146) (xy 398.898287 -355.002427)
			(xy 398.862566 -354.961205) (xy 398.833075 -354.915318) (xy 398.810415 -354.865701) (xy 398.795047 -354.813364)
			(xy 398.787284 -354.759373) (xy 397.30458 -354.759373) (xy 397.296818 -354.813359) (xy 397.28145 -354.865693)
			(xy 397.258791 -354.915306) (xy 397.229301 -354.96119) (xy 397.193581 -355.002409) (xy 397.152358 -355.038125)
			(xy 397.106471 -355.06761) (xy 397.056855 -355.090264) (xy 397.00452 -355.105626) (xy 396.950532 -355.113383)
			(xy 396.92326 -355.113844) (xy 396.05966 -355.113844) (xy 396.032391 -355.113391) (xy 395.978409 -355.105624)
			(xy 395.926082 -355.090255) (xy 395.876475 -355.067595) (xy 395.830597 -355.038107) (xy 395.789382 -355.00239)
			(xy 395.753669 -354.961171) (xy 395.724186 -354.91529) (xy 395.701531 -354.86568) (xy 395.686167 -354.813351)
			(xy 395.678406 -354.759369) (xy 394.195558 -354.759369) (xy 394.187796 -354.813349) (xy 394.172432 -354.865676)
			(xy 394.149777 -354.915284) (xy 394.120292 -354.961163) (xy 394.084578 -355.002378) (xy 394.043363 -355.038092)
			(xy 393.997484 -355.067577) (xy 393.947876 -355.090232) (xy 393.895549 -355.105596) (xy 393.841568 -355.113358)
			(xy 393.8143 -355.113844) (xy 392.9507 -355.113844) (xy 392.923429 -355.113394) (xy 392.869443 -355.105631)
			(xy 392.817111 -355.090265) (xy 392.767499 -355.067608) (xy 392.721616 -355.038121) (xy 392.680396 -355.002404)
			(xy 392.644679 -354.961184) (xy 392.615192 -354.915301) (xy 392.592535 -354.865689) (xy 392.577169 -354.813357)
			(xy 392.569406 -354.759371) (xy 391.086557 -354.759371) (xy 391.078797 -354.813344) (xy 391.063435 -354.865668)
			(xy 391.040783 -354.915273) (xy 391.011302 -354.96115) (xy 390.975593 -355.002364) (xy 390.934382 -355.038078)
			(xy 390.888508 -355.067563) (xy 390.838905 -355.090221) (xy 390.786583 -355.105589) (xy 390.732606 -355.113355)
			(xy 390.70534 -355.113844) (xy 389.84174 -355.113844) (xy 389.814466 -355.113419) (xy 389.760472 -355.105661)
			(xy 389.708132 -355.090298) (xy 389.658512 -355.067641) (xy 389.612621 -355.038153) (xy 389.571394 -355.002434)
			(xy 389.535671 -354.961211) (xy 389.506178 -354.915324) (xy 389.483516 -354.865705) (xy 389.468147 -354.813367)
			(xy 389.460384 -354.759374) (xy 387.97768 -354.759374) (xy 387.969918 -354.813357) (xy 387.954552 -354.865689)
			(xy 387.931894 -354.915301) (xy 387.902406 -354.961183) (xy 387.866688 -355.002402) (xy 387.825467 -355.038118)
			(xy 387.779583 -355.067603) (xy 387.72997 -355.090259) (xy 387.677637 -355.105622) (xy 387.623651 -355.113382)
			(xy 387.59638 -355.113844) (xy 386.73278 -355.113844) (xy 386.70551 -355.113392) (xy 386.651526 -355.105628)
			(xy 386.599197 -355.09026) (xy 386.549587 -355.067602) (xy 386.503706 -355.038114) (xy 386.462489 -355.002397)
			(xy 386.426774 -354.961178) (xy 386.397289 -354.915296) (xy 386.374633 -354.865685) (xy 386.359268 -354.813354)
			(xy 386.351506 -354.75937) (xy 384.868658 -354.75937) (xy 384.860897 -354.813346) (xy 384.845533 -354.865672)
			(xy 384.82288 -354.915278) (xy 384.793397 -354.961156) (xy 384.757686 -355.002371) (xy 384.716472 -355.038085)
			(xy 384.670596 -355.06757) (xy 384.620991 -355.090226) (xy 384.568666 -355.105593) (xy 384.514687 -355.113356)
			(xy 384.48742 -355.113844) (xy 383.62382 -355.113844) (xy 383.596547 -355.113418) (xy 383.542555 -355.105658)
			(xy 383.490218 -355.090292) (xy 383.4406 -355.067635) (xy 383.394711 -355.038146) (xy 383.353487 -355.002427)
			(xy 383.317766 -354.961205) (xy 383.288275 -354.915318) (xy 383.265615 -354.865701) (xy 383.250247 -354.813364)
			(xy 383.242484 -354.759373) (xy 381.75978 -354.759373) (xy 381.752018 -354.813359) (xy 381.73665 -354.865693)
			(xy 381.713991 -354.915306) (xy 381.684501 -354.96119) (xy 381.648781 -355.002409) (xy 381.607558 -355.038125)
			(xy 381.561671 -355.06761) (xy 381.512055 -355.090264) (xy 381.45972 -355.105626) (xy 381.405732 -355.113383)
			(xy 381.37846 -355.113844) (xy 380.51486 -355.113844) (xy 380.487591 -355.113391) (xy 380.433609 -355.105624)
			(xy 380.381282 -355.090255) (xy 380.331675 -355.067595) (xy 380.285797 -355.038107) (xy 380.244582 -355.00239)
			(xy 380.208869 -354.961171) (xy 380.179386 -354.91529) (xy 380.156731 -354.86568) (xy 380.141367 -354.813351)
			(xy 380.133606 -354.759369) (xy 378.650758 -354.759369) (xy 378.642996 -354.813349) (xy 378.627632 -354.865676)
			(xy 378.604977 -354.915284) (xy 378.575492 -354.961163) (xy 378.539778 -355.002378) (xy 378.498563 -355.038092)
			(xy 378.452684 -355.067577) (xy 378.403076 -355.090232) (xy 378.350749 -355.105596) (xy 378.296768 -355.113358)
			(xy 378.2695 -355.113844) (xy 377.4059 -355.113844) (xy 377.378629 -355.113394) (xy 377.324643 -355.105631)
			(xy 377.272311 -355.090265) (xy 377.222699 -355.067608) (xy 377.176816 -355.038121) (xy 377.135596 -355.002404)
			(xy 377.099879 -354.961184) (xy 377.070392 -354.915301) (xy 377.047735 -354.865689) (xy 377.032369 -354.813357)
			(xy 377.024606 -354.759371) (xy 375.541757 -354.759371) (xy 375.533997 -354.813344) (xy 375.518635 -354.865668)
			(xy 375.495983 -354.915273) (xy 375.466502 -354.96115) (xy 375.430793 -355.002364) (xy 375.389582 -355.038078)
			(xy 375.343708 -355.067563) (xy 375.294105 -355.090221) (xy 375.241783 -355.105589) (xy 375.187806 -355.113355)
			(xy 375.16054 -355.113844) (xy 374.29694 -355.113844) (xy 374.269666 -355.113419) (xy 374.215672 -355.105661)
			(xy 374.163332 -355.090298) (xy 374.113712 -355.067641) (xy 374.067821 -355.038153) (xy 374.026594 -355.002434)
			(xy 373.990871 -354.961211) (xy 373.961378 -354.915324) (xy 373.938716 -354.865705) (xy 373.923347 -354.813367)
			(xy 373.915584 -354.759374) (xy 344.837257 -354.759374) (xy 344.829496 -354.813349) (xy 344.814132 -354.865675)
			(xy 344.791477 -354.915283) (xy 344.761993 -354.961161) (xy 344.72628 -355.002377) (xy 344.685065 -355.038091)
			(xy 344.639186 -355.067575) (xy 344.589579 -355.090231) (xy 344.537253 -355.105596) (xy 344.483272 -355.113357)
			(xy 344.456004 -355.113844) (xy 343.592404 -355.113844) (xy 343.565132 -355.113417) (xy 343.511142 -355.105655)
			(xy 343.458806 -355.090288) (xy 343.40919 -355.06763) (xy 343.363304 -355.038141) (xy 343.322081 -355.002422)
			(xy 343.286362 -354.961199) (xy 343.256872 -354.915313) (xy 343.234213 -354.865698) (xy 343.218846 -354.813362)
			(xy 343.211084 -354.759372) (xy 341.728257 -354.759372) (xy 341.720498 -354.813343) (xy 341.705135 -354.865667)
			(xy 341.682483 -354.915272) (xy 341.653003 -354.961148) (xy 341.617294 -355.002363) (xy 341.576084 -355.038076)
			(xy 341.53021 -355.067562) (xy 341.480608 -355.09022) (xy 341.428286 -355.105588) (xy 341.37431 -355.113355)
			(xy 341.347044 -355.113844) (xy 340.483444 -355.113844) (xy 340.45617 -355.113419) (xy 340.402175 -355.105662)
			(xy 340.349835 -355.090299) (xy 340.300214 -355.067643) (xy 340.254323 -355.038155) (xy 340.213095 -355.002436)
			(xy 340.177371 -354.961213) (xy 340.147878 -354.915325) (xy 340.125217 -354.865706) (xy 340.109847 -354.813368)
			(xy 340.102084 -354.759374) (xy 338.61938 -354.759374) (xy 338.611618 -354.813356) (xy 338.596252 -354.865688)
			(xy 338.573594 -354.9153) (xy 338.544107 -354.961182) (xy 338.508389 -355.0024) (xy 338.467169 -355.038116)
			(xy 338.421285 -355.067602) (xy 338.371673 -355.090258) (xy 338.319341 -355.105622) (xy 338.265354 -355.113382)
			(xy 338.238084 -355.113844) (xy 337.374484 -355.113844) (xy 337.347214 -355.113392) (xy 337.29323 -355.105629)
			(xy 337.2409 -355.090261) (xy 337.191289 -355.067603) (xy 337.145408 -355.038115) (xy 337.10419 -355.002398)
			(xy 337.068475 -354.961179) (xy 337.038989 -354.915297) (xy 337.016333 -354.865685) (xy 337.000968 -354.813355)
			(xy 336.993206 -354.75937) (xy 335.510358 -354.75937) (xy 335.502597 -354.813346) (xy 335.487234 -354.865671)
			(xy 335.46458 -354.915277) (xy 335.435098 -354.961155) (xy 335.399387 -355.00237) (xy 335.358174 -355.038084)
			(xy 335.312298 -355.067569) (xy 335.262694 -355.090225) (xy 335.210369 -355.105592) (xy 335.156391 -355.113356)
			(xy 335.129124 -355.113844) (xy 334.265524 -355.113844) (xy 334.238251 -355.113418) (xy 334.184259 -355.105658)
			(xy 334.131921 -355.090293) (xy 334.082302 -355.067636) (xy 334.036413 -355.038148) (xy 333.995188 -355.002429)
			(xy 333.959467 -354.961206) (xy 333.929975 -354.915319) (xy 333.907315 -354.865702) (xy 333.891947 -354.813365)
			(xy 333.884184 -354.759373) (xy 332.40148 -354.759373) (xy 332.393718 -354.813359) (xy 332.37835 -354.865692)
			(xy 332.355691 -354.915305) (xy 332.326202 -354.961188) (xy 332.290482 -355.002407) (xy 332.24926 -355.038123)
			(xy 332.203374 -355.067609) (xy 332.153758 -355.090263) (xy 332.101424 -355.105625) (xy 332.047435 -355.113383)
			(xy 332.020164 -355.113844) (xy 331.156564 -355.113844) (xy 331.129295 -355.113391) (xy 331.075313 -355.105625)
			(xy 331.022985 -355.090256) (xy 330.973377 -355.067596) (xy 330.927499 -355.038108) (xy 330.886283 -355.002391)
			(xy 330.85057 -354.961173) (xy 330.821086 -354.915291) (xy 330.798432 -354.865681) (xy 330.783067 -354.813352)
			(xy 330.775306 -354.759369) (xy 329.292458 -354.759369) (xy 329.284696 -354.813349) (xy 329.269332 -354.865675)
			(xy 329.246677 -354.915283) (xy 329.217193 -354.961161) (xy 329.18148 -355.002377) (xy 329.140265 -355.038091)
			(xy 329.094386 -355.067575) (xy 329.044779 -355.090231) (xy 328.992453 -355.105596) (xy 328.938472 -355.113357)
			(xy 328.911204 -355.113844) (xy 328.047604 -355.113844) (xy 328.020332 -355.113417) (xy 327.966342 -355.105655)
			(xy 327.914006 -355.090288) (xy 327.86439 -355.06763) (xy 327.818504 -355.038141) (xy 327.777281 -355.002422)
			(xy 327.741562 -354.961199) (xy 327.712072 -354.915313) (xy 327.689413 -354.865698) (xy 327.674046 -354.813362)
			(xy 327.666284 -354.759372) (xy 326.183457 -354.759372) (xy 326.175698 -354.813343) (xy 326.160335 -354.865667)
			(xy 326.137683 -354.915272) (xy 326.108203 -354.961148) (xy 326.072494 -355.002363) (xy 326.031284 -355.038076)
			(xy 325.98541 -355.067562) (xy 325.935808 -355.09022) (xy 325.883486 -355.105588) (xy 325.82951 -355.113355)
			(xy 325.802244 -355.113844) (xy 324.938644 -355.113844) (xy 324.91137 -355.113419) (xy 324.857375 -355.105662)
			(xy 324.805035 -355.090299) (xy 324.755414 -355.067643) (xy 324.709523 -355.038155) (xy 324.668295 -355.002436)
			(xy 324.632571 -354.961213) (xy 324.603078 -354.915325) (xy 324.580417 -354.865706) (xy 324.565047 -354.813368)
			(xy 324.557284 -354.759374) (xy 323.07458 -354.759374) (xy 323.066818 -354.813356) (xy 323.051452 -354.865688)
			(xy 323.028794 -354.9153) (xy 322.999307 -354.961182) (xy 322.963589 -355.0024) (xy 322.922369 -355.038116)
			(xy 322.876485 -355.067602) (xy 322.826873 -355.090258) (xy 322.774541 -355.105622) (xy 322.720554 -355.113382)
			(xy 322.693284 -355.113844) (xy 321.829684 -355.113844) (xy 321.802414 -355.113392) (xy 321.74843 -355.105629)
			(xy 321.6961 -355.090261) (xy 321.646489 -355.067603) (xy 321.600608 -355.038115) (xy 321.55939 -355.002398)
			(xy 321.523675 -354.961179) (xy 321.494189 -354.915297) (xy 321.471533 -354.865685) (xy 321.456168 -354.813355)
			(xy 321.448406 -354.75937) (xy 319.965558 -354.75937) (xy 319.957797 -354.813346) (xy 319.942434 -354.865671)
			(xy 319.91978 -354.915277) (xy 319.890298 -354.961155) (xy 319.854587 -355.00237) (xy 319.813374 -355.038084)
			(xy 319.767498 -355.067569) (xy 319.717894 -355.090225) (xy 319.665569 -355.105592) (xy 319.611591 -355.113356)
			(xy 319.584324 -355.113844) (xy 318.720724 -355.113844) (xy 318.693451 -355.113418) (xy 318.639459 -355.105658)
			(xy 318.587121 -355.090293) (xy 318.537502 -355.067636) (xy 318.491613 -355.038148) (xy 318.450388 -355.002429)
			(xy 318.414667 -354.961206) (xy 318.385175 -354.915319) (xy 318.362515 -354.865702) (xy 318.347147 -354.813365)
			(xy 318.339384 -354.759373) (xy 316.85668 -354.759373) (xy 316.848918 -354.813359) (xy 316.83355 -354.865692)
			(xy 316.810891 -354.915305) (xy 316.781402 -354.961188) (xy 316.745682 -355.002407) (xy 316.70446 -355.038123)
			(xy 316.658574 -355.067609) (xy 316.608958 -355.090263) (xy 316.556624 -355.105625) (xy 316.502635 -355.113383)
			(xy 316.475364 -355.113844) (xy 315.611764 -355.113844) (xy 315.584495 -355.113391) (xy 315.530513 -355.105625)
			(xy 315.478185 -355.090256) (xy 315.428577 -355.067596) (xy 315.382699 -355.038108) (xy 315.341483 -355.002391)
			(xy 315.30577 -354.961173) (xy 315.276286 -354.915291) (xy 315.253632 -354.865681) (xy 315.238267 -354.813352)
			(xy 315.230506 -354.759369) (xy 300.231558 -354.759369) (xy 300.223796 -354.813349) (xy 300.208432 -354.865676)
			(xy 300.185777 -354.915283) (xy 300.156293 -354.961162) (xy 300.120579 -355.002378) (xy 300.079364 -355.038091)
			(xy 300.033485 -355.067576) (xy 299.983878 -355.090231) (xy 299.931551 -355.105596) (xy 299.87757 -355.113357)
			(xy 299.850302 -355.113844) (xy 298.986702 -355.113844) (xy 298.95943 -355.113417) (xy 298.90544 -355.105654)
			(xy 298.853105 -355.090288) (xy 298.803489 -355.067629) (xy 298.757603 -355.03814) (xy 298.716381 -355.002421)
			(xy 298.680661 -354.961199) (xy 298.651172 -354.915313) (xy 298.628513 -354.865697) (xy 298.613146 -354.813362)
			(xy 298.605384 -354.759372) (xy 297.122557 -354.759372) (xy 297.114798 -354.813344) (xy 297.099435 -354.865667)
			(xy 297.076783 -354.915272) (xy 297.047302 -354.961149) (xy 297.011593 -355.002364) (xy 296.970383 -355.038077)
			(xy 296.924509 -355.067563) (xy 296.874907 -355.09022) (xy 296.822585 -355.105589) (xy 296.768608 -355.113355)
			(xy 296.741342 -355.113844) (xy 295.877742 -355.113844) (xy 295.850468 -355.113419) (xy 295.796474 -355.105662)
			(xy 295.744134 -355.090298) (xy 295.694513 -355.067642) (xy 295.648622 -355.038154) (xy 295.607395 -355.002435)
			(xy 295.571671 -354.961212) (xy 295.542178 -354.915324) (xy 295.519516 -354.865706) (xy 295.504147 -354.813367)
			(xy 295.496384 -354.759374) (xy 294.013681 -354.759374) (xy 294.005918 -354.813356) (xy 293.990552 -354.865688)
			(xy 293.967894 -354.9153) (xy 293.938406 -354.961182) (xy 293.902688 -355.002401) (xy 293.861468 -355.038117)
			(xy 293.815584 -355.067603) (xy 293.765971 -355.090258) (xy 293.713639 -355.105622) (xy 293.659653 -355.113382)
			(xy 293.632382 -355.113844) (xy 292.768782 -355.113844) (xy 292.741512 -355.113392) (xy 292.687528 -355.105628)
			(xy 292.635198 -355.090261) (xy 292.585588 -355.067602) (xy 292.539707 -355.038115) (xy 292.49849 -355.002398)
			(xy 292.462775 -354.961178) (xy 292.433289 -354.915296) (xy 292.410633 -354.865685) (xy 292.395268 -354.813354)
			(xy 292.387506 -354.75937) (xy 290.904658 -354.75937) (xy 290.896897 -354.813346) (xy 290.881533 -354.865672)
			(xy 290.85888 -354.915278) (xy 290.829397 -354.961156) (xy 290.793686 -355.002371) (xy 290.752473 -355.038084)
			(xy 290.706597 -355.067569) (xy 290.656992 -355.090226) (xy 290.604668 -355.105592) (xy 290.550689 -355.113356)
			(xy 290.523422 -355.113844) (xy 289.659822 -355.113844) (xy 289.632549 -355.113418) (xy 289.578557 -355.105658)
			(xy 289.526219 -355.090293) (xy 289.476601 -355.067636) (xy 289.430712 -355.038147) (xy 289.389488 -355.002428)
			(xy 289.353766 -354.961205) (xy 289.324275 -354.915318) (xy 289.301615 -354.865702) (xy 289.286247 -354.813365)
			(xy 289.278484 -354.759373) (xy 287.79578 -354.759373) (xy 287.788018 -354.813359) (xy 287.77265 -354.865692)
			(xy 287.749991 -354.915306) (xy 287.720501 -354.961189) (xy 287.684781 -355.002408) (xy 287.643559 -355.038124)
			(xy 287.597672 -355.067609) (xy 287.548057 -355.090264) (xy 287.495722 -355.105626) (xy 287.441733 -355.113383)
			(xy 287.414462 -355.113844) (xy 286.550862 -355.113844) (xy 286.523593 -355.113391) (xy 286.469611 -355.105625)
			(xy 286.417284 -355.090255) (xy 286.367676 -355.067596) (xy 286.321798 -355.038107) (xy 286.280583 -355.00239)
			(xy 286.24487 -354.961172) (xy 286.215386 -354.915291) (xy 286.192732 -354.865681) (xy 286.177367 -354.813352)
			(xy 286.169606 -354.759369) (xy 284.686758 -354.759369) (xy 284.678996 -354.813349) (xy 284.663632 -354.865676)
			(xy 284.640977 -354.915283) (xy 284.611493 -354.961162) (xy 284.575779 -355.002378) (xy 284.534564 -355.038091)
			(xy 284.488685 -355.067576) (xy 284.439078 -355.090231) (xy 284.386751 -355.105596) (xy 284.33277 -355.113357)
			(xy 284.305502 -355.113844) (xy 283.441902 -355.113844) (xy 283.41463 -355.113417) (xy 283.36064 -355.105654)
			(xy 283.308305 -355.090288) (xy 283.258689 -355.067629) (xy 283.212803 -355.03814) (xy 283.171581 -355.002421)
			(xy 283.135861 -354.961199) (xy 283.106372 -354.915313) (xy 283.083713 -354.865697) (xy 283.068346 -354.813362)
			(xy 283.060584 -354.759372) (xy 281.577757 -354.759372) (xy 281.569998 -354.813344) (xy 281.554635 -354.865667)
			(xy 281.531983 -354.915272) (xy 281.502502 -354.961149) (xy 281.466793 -355.002364) (xy 281.425583 -355.038077)
			(xy 281.379709 -355.067563) (xy 281.330107 -355.09022) (xy 281.277785 -355.105589) (xy 281.223808 -355.113355)
			(xy 281.196542 -355.113844) (xy 280.332942 -355.113844) (xy 280.305668 -355.113419) (xy 280.251674 -355.105662)
			(xy 280.199334 -355.090298) (xy 280.149713 -355.067642) (xy 280.103822 -355.038154) (xy 280.062595 -355.002435)
			(xy 280.026871 -354.961212) (xy 279.997378 -354.915324) (xy 279.974716 -354.865706) (xy 279.959347 -354.813367)
			(xy 279.951584 -354.759374) (xy 278.468881 -354.759374) (xy 278.461118 -354.813356) (xy 278.445752 -354.865688)
			(xy 278.423094 -354.9153) (xy 278.393606 -354.961182) (xy 278.357888 -355.002401) (xy 278.316668 -355.038117)
			(xy 278.270784 -355.067603) (xy 278.221171 -355.090258) (xy 278.168839 -355.105622) (xy 278.114853 -355.113382)
			(xy 278.087582 -355.113844) (xy 277.223982 -355.113844) (xy 277.196712 -355.113392) (xy 277.142728 -355.105628)
			(xy 277.090398 -355.090261) (xy 277.040788 -355.067602) (xy 276.994907 -355.038115) (xy 276.95369 -355.002398)
			(xy 276.917975 -354.961178) (xy 276.888489 -354.915296) (xy 276.865833 -354.865685) (xy 276.850468 -354.813354)
			(xy 276.842706 -354.75937) (xy 275.359858 -354.75937) (xy 275.352097 -354.813346) (xy 275.336733 -354.865672)
			(xy 275.31408 -354.915278) (xy 275.284597 -354.961156) (xy 275.248886 -355.002371) (xy 275.207673 -355.038084)
			(xy 275.161797 -355.067569) (xy 275.112192 -355.090226) (xy 275.059868 -355.105592) (xy 275.005889 -355.113356)
			(xy 274.978622 -355.113844) (xy 274.115022 -355.113844) (xy 274.087749 -355.113418) (xy 274.033757 -355.105658)
			(xy 273.981419 -355.090293) (xy 273.931801 -355.067636) (xy 273.885912 -355.038147) (xy 273.844688 -355.002428)
			(xy 273.808966 -354.961205) (xy 273.779475 -354.915318) (xy 273.756815 -354.865702) (xy 273.741447 -354.813365)
			(xy 273.733684 -354.759373) (xy 272.25098 -354.759373) (xy 272.243218 -354.813359) (xy 272.22785 -354.865692)
			(xy 272.205191 -354.915306) (xy 272.175701 -354.961189) (xy 272.139981 -355.002408) (xy 272.098759 -355.038124)
			(xy 272.052872 -355.067609) (xy 272.003257 -355.090264) (xy 271.950922 -355.105626) (xy 271.896933 -355.113383)
			(xy 271.869662 -355.113844) (xy 271.006062 -355.113844) (xy 270.978793 -355.113391) (xy 270.924811 -355.105625)
			(xy 270.872484 -355.090255) (xy 270.822876 -355.067596) (xy 270.776998 -355.038107) (xy 270.735783 -355.00239)
			(xy 270.70007 -354.961172) (xy 270.670586 -354.915291) (xy 270.647932 -354.865681) (xy 270.632567 -354.813352)
			(xy 270.624806 -354.759369) (xy 188.299268 -354.759369) (xy 188.294942 -354.78946) (xy 188.279575 -354.841794)
			(xy 188.256917 -354.891409) (xy 188.227428 -354.937294) (xy 188.191709 -354.978515) (xy 188.150487 -355.014233)
			(xy 188.104602 -355.04372) (xy 188.054987 -355.066378) (xy 188.002652 -355.081744) (xy 187.948664 -355.089505)
			(xy 187.921392 -355.089968) (xy 187.057792 -355.089968) (xy 187.030523 -355.089469) (xy 186.976542 -355.081707)
			(xy 186.924214 -355.066341) (xy 186.874605 -355.043684) (xy 186.828726 -355.014199) (xy 186.78751 -354.978484)
			(xy 186.751796 -354.937267) (xy 186.722312 -354.891388) (xy 186.699656 -354.841779) (xy 186.684292 -354.789451)
			(xy 186.67653 -354.735469) (xy 185.193682 -354.735469) (xy 185.185921 -354.78945) (xy 185.170557 -354.841778)
			(xy 185.147903 -354.891387) (xy 185.118419 -354.937267) (xy 185.082707 -354.978484) (xy 185.041492 -355.0142)
			(xy 184.995615 -355.043687) (xy 184.946008 -355.066346) (xy 184.893681 -355.081714) (xy 184.8397 -355.089479)
			(xy 184.812432 -355.089968) (xy 183.948832 -355.089968) (xy 183.92156 -355.089495) (xy 183.86757 -355.081736)
			(xy 183.815235 -355.066373) (xy 183.765618 -355.043718) (xy 183.719731 -355.014231) (xy 183.678508 -354.978515)
			(xy 183.642788 -354.937294) (xy 183.613298 -354.89141) (xy 183.590638 -354.841795) (xy 183.57527 -354.789461)
			(xy 183.567508 -354.735472) (xy 182.08478 -354.735472) (xy 182.08478 -354.759371) (xy 182.077018 -354.813358)
			(xy 182.061651 -354.86569) (xy 182.038992 -354.915303) (xy 182.009504 -354.961186) (xy 181.973785 -355.002405)
			(xy 181.932563 -355.03812) (xy 181.886678 -355.067606) (xy 181.837064 -355.090261) (xy 181.78473 -355.105624)
			(xy 181.730743 -355.113382) (xy 181.703472 -355.113844) (xy 180.839872 -355.113844) (xy 180.812603 -355.113392)
			(xy 180.75862 -355.105626) (xy 180.706291 -355.090258) (xy 180.656682 -355.067599) (xy 180.610802 -355.038111)
			(xy 180.569586 -355.002394) (xy 180.533872 -354.961175) (xy 180.504388 -354.915293) (xy 180.481732 -354.865683)
			(xy 180.466368 -354.813353) (xy 180.458606 -354.759369) (xy 178.975758 -354.759369) (xy 178.967997 -354.813348)
			(xy 178.952633 -354.865674) (xy 178.929978 -354.915281) (xy 178.900495 -354.961159) (xy 178.864783 -355.002374)
			(xy 178.823568 -355.038088) (xy 178.777691 -355.067573) (xy 178.728085 -355.090228) (xy 178.675759 -355.105594)
			(xy 178.62178 -355.113357) (xy 178.594512 -355.113844) (xy 177.730912 -355.113844) (xy 177.703639 -355.113417)
			(xy 177.649648 -355.105656) (xy 177.597312 -355.09029) (xy 177.547695 -355.067632) (xy 177.501808 -355.038144)
			(xy 177.460584 -355.002424) (xy 177.424864 -354.961202) (xy 177.395373 -354.915316) (xy 177.372714 -354.865699)
			(xy 177.357346 -354.813363) (xy 177.349584 -354.759373) (xy 175.86688 -354.759373) (xy 175.859117 -354.81336)
			(xy 175.843749 -354.865694) (xy 175.821089 -354.915309) (xy 175.791599 -354.961192) (xy 175.755878 -355.002412)
			(xy 175.714654 -355.038128) (xy 175.668766 -355.067612) (xy 175.619149 -355.090266) (xy 175.566813 -355.105628)
			(xy 175.512824 -355.113384) (xy 175.485552 -355.113844) (xy 174.621952 -355.113844) (xy 174.594684 -355.11339)
			(xy 174.540703 -355.105623) (xy 174.488376 -355.090252) (xy 174.43877 -355.067592) (xy 174.392893 -355.038104)
			(xy 174.351679 -355.002387) (xy 174.315967 -354.961169) (xy 174.286485 -354.915288) (xy 174.263831 -354.865679)
			(xy 174.248467 -354.81335) (xy 174.240706 -354.759368) (xy 172.757881 -354.759368) (xy 172.757881 -354.75937)
			(xy 172.750119 -354.813355) (xy 172.734753 -354.865686) (xy 172.712096 -354.915297) (xy 172.682609 -354.961179)
			(xy 172.646892 -355.002398) (xy 172.605673 -355.038113) (xy 172.55979 -355.067599) (xy 172.510178 -355.090255)
			(xy 172.457847 -355.10562) (xy 172.403862 -355.113381) (xy 172.376592 -355.113844) (xy 171.512992 -355.113844)
			(xy 171.485722 -355.113393) (xy 171.431736 -355.10563) (xy 171.379405 -355.090263) (xy 171.329794 -355.067606)
			(xy 171.283912 -355.038118) (xy 171.242693 -355.002401) (xy 171.206977 -354.961182) (xy 171.177491 -354.915299)
			(xy 171.154834 -354.865687) (xy 171.139468 -354.813356) (xy 171.131706 -354.75937) (xy 169.648858 -354.75937)
			(xy 169.641097 -354.813345) (xy 169.625734 -354.865669) (xy 169.603081 -354.915275) (xy 169.5736 -354.961152)
			(xy 169.53789 -355.002367) (xy 169.496678 -355.038081) (xy 169.450803 -355.067566) (xy 169.401199 -355.090223)
			(xy 169.348876 -355.10559) (xy 169.294899 -355.113355) (xy 169.267632 -355.113844) (xy 168.404032 -355.113844)
			(xy 168.376758 -355.113419) (xy 168.322765 -355.10566) (xy 168.270426 -355.090296) (xy 168.220807 -355.067639)
			(xy 168.174917 -355.038151) (xy 168.133691 -355.002432) (xy 168.097969 -354.961209) (xy 168.068477 -354.915321)
			(xy 168.045816 -354.865704) (xy 168.030447 -354.813366) (xy 168.022684 -354.759374) (xy 166.53998 -354.759374)
			(xy 166.532218 -354.813358) (xy 166.516851 -354.86569) (xy 166.494192 -354.915303) (xy 166.464704 -354.961186)
			(xy 166.428985 -355.002405) (xy 166.387763 -355.03812) (xy 166.341878 -355.067606) (xy 166.292264 -355.090261)
			(xy 166.23993 -355.105624) (xy 166.185943 -355.113382) (xy 166.158672 -355.113844) (xy 165.295072 -355.113844)
			(xy 165.267803 -355.113392) (xy 165.21382 -355.105626) (xy 165.161491 -355.090258) (xy 165.111882 -355.067599)
			(xy 165.066002 -355.038111) (xy 165.024786 -355.002394) (xy 164.989072 -354.961175) (xy 164.959588 -354.915293)
			(xy 164.936932 -354.865683) (xy 164.921568 -354.813353) (xy 164.913806 -354.759369) (xy 163.430958 -354.759369)
			(xy 163.423197 -354.813348) (xy 163.407833 -354.865674) (xy 163.385178 -354.915281) (xy 163.355695 -354.961159)
			(xy 163.319983 -355.002374) (xy 163.278768 -355.038088) (xy 163.232891 -355.067573) (xy 163.183285 -355.090228)
			(xy 163.130959 -355.105594) (xy 163.07698 -355.113357) (xy 163.049712 -355.113844) (xy 162.186112 -355.113844)
			(xy 162.158839 -355.113417) (xy 162.104848 -355.105656) (xy 162.052512 -355.09029) (xy 162.002895 -355.067632)
			(xy 161.957008 -355.038144) (xy 161.915784 -355.002424) (xy 161.880064 -354.961202) (xy 161.850573 -354.915316)
			(xy 161.827914 -354.865699) (xy 161.812546 -354.813363) (xy 161.804784 -354.759373) (xy 160.32208 -354.759373)
			(xy 160.314317 -354.81336) (xy 160.298949 -354.865694) (xy 160.276289 -354.915309) (xy 160.246799 -354.961192)
			(xy 160.211078 -355.002412) (xy 160.169854 -355.038128) (xy 160.123966 -355.067612) (xy 160.074349 -355.090266)
			(xy 160.022013 -355.105628) (xy 159.968024 -355.113384) (xy 159.940752 -355.113844) (xy 159.077152 -355.113844)
			(xy 159.049884 -355.11339) (xy 158.995903 -355.105623) (xy 158.943576 -355.090252) (xy 158.89397 -355.067592)
			(xy 158.848093 -355.038104) (xy 158.806879 -355.002387) (xy 158.771167 -354.961169) (xy 158.741685 -354.915288)
			(xy 158.719031 -354.865679) (xy 158.703667 -354.81335) (xy 158.695906 -354.759368) (xy 144.196558 -354.759368)
			(xy 144.188797 -354.813348) (xy 144.173432 -354.865675) (xy 144.150778 -354.915282) (xy 144.121294 -354.96116)
			(xy 144.085581 -355.002376) (xy 144.044367 -355.038089) (xy 143.998489 -355.067574) (xy 143.948882 -355.09023)
			(xy 143.896556 -355.105595) (xy 143.842576 -355.113357) (xy 143.815308 -355.113844) (xy 142.951708 -355.113844)
			(xy 142.924435 -355.113417) (xy 142.870445 -355.105655) (xy 142.818109 -355.090289) (xy 142.768492 -355.067631)
			(xy 142.722606 -355.038142) (xy 142.681383 -355.002423) (xy 142.645663 -354.961201) (xy 142.616173 -354.915315)
			(xy 142.593514 -354.865699) (xy 142.578146 -354.813363) (xy 142.570384 -354.759373) (xy 141.087557 -354.759373)
			(xy 141.079798 -354.813343) (xy 141.064436 -354.865666) (xy 141.041784 -354.915271) (xy 141.012304 -354.961147)
			(xy 140.976595 -355.002361) (xy 140.935386 -355.038075) (xy 140.889513 -355.067561) (xy 140.839911 -355.090219)
			(xy 140.78759 -355.105587) (xy 140.733614 -355.113354) (xy 140.706348 -355.113844) (xy 139.842748 -355.113844)
			(xy 139.815473 -355.11342) (xy 139.761479 -355.105663) (xy 139.709138 -355.0903) (xy 139.659516 -355.067644)
			(xy 139.613625 -355.038156) (xy 139.572397 -355.002437) (xy 139.536672 -354.961214) (xy 139.507179 -354.915326)
			(xy 139.484517 -354.865707) (xy 139.469147 -354.813368) (xy 139.461384 -354.759374) (xy 137.97868 -354.759374)
			(xy 137.970918 -354.813356) (xy 137.955552 -354.865687) (xy 137.932895 -354.915298) (xy 137.903408 -354.961181)
			(xy 137.867691 -355.002399) (xy 137.826471 -355.038115) (xy 137.780588 -355.067601) (xy 137.730976 -355.090256)
			(xy 137.678644 -355.105621) (xy 137.624658 -355.113381) (xy 137.597388 -355.113844) (xy 136.733788 -355.113844)
			(xy 136.706518 -355.113393) (xy 136.652533 -355.105629) (xy 136.600203 -355.090262) (xy 136.550591 -355.067604)
			(xy 136.50471 -355.038117) (xy 136.463492 -355.0024) (xy 136.427776 -354.96118) (xy 136.39829 -354.915298)
			(xy 136.375634 -354.865686) (xy 136.360268 -354.813355) (xy 136.352506 -354.75937) (xy 134.869658 -354.75937)
			(xy 134.861897 -354.813345) (xy 134.846534 -354.86567) (xy 134.823881 -354.915276) (xy 134.794399 -354.961154)
			(xy 134.758688 -355.002369) (xy 134.717476 -355.038082) (xy 134.671601 -355.067567) (xy 134.621997 -355.090224)
			(xy 134.569673 -355.105591) (xy 134.515695 -355.113356) (xy 134.488428 -355.113844) (xy 133.624828 -355.113844)
			(xy 133.597554 -355.113418) (xy 133.543562 -355.105659) (xy 133.491223 -355.090295) (xy 133.441604 -355.067638)
			(xy 133.395715 -355.038149) (xy 133.35449 -355.00243) (xy 133.318768 -354.961207) (xy 133.289276 -354.91532)
			(xy 133.266615 -354.865703) (xy 133.251247 -354.813365) (xy 133.243484 -354.759374) (xy 131.76078 -354.759374)
			(xy 131.753018 -354.813358) (xy 131.737651 -354.865691) (xy 131.714992 -354.915304) (xy 131.685503 -354.961187)
			(xy 131.649783 -355.002406) (xy 131.608561 -355.038122) (xy 131.562676 -355.067607) (xy 131.513061 -355.090262)
			(xy 131.460727 -355.105625) (xy 131.406739 -355.113383) (xy 131.379468 -355.113844) (xy 130.515868 -355.113844)
			(xy 130.488599 -355.113391) (xy 130.434616 -355.105626) (xy 130.382288 -355.090257) (xy 130.33268 -355.067598)
			(xy 130.2868 -355.03811) (xy 130.245585 -355.002393) (xy 130.209871 -354.961174) (xy 130.180387 -354.915292)
			(xy 130.157732 -354.865682) (xy 130.142368 -354.813353) (xy 130.134606 -354.759369) (xy 128.651758 -354.759369)
			(xy 128.643997 -354.813348) (xy 128.628632 -354.865675) (xy 128.605978 -354.915282) (xy 128.576494 -354.96116)
			(xy 128.540781 -355.002376) (xy 128.499567 -355.038089) (xy 128.453689 -355.067574) (xy 128.404082 -355.09023)
			(xy 128.351756 -355.105595) (xy 128.297776 -355.113357) (xy 128.270508 -355.113844) (xy 127.406908 -355.113844)
			(xy 127.379635 -355.113417) (xy 127.325645 -355.105655) (xy 127.273309 -355.090289) (xy 127.223692 -355.067631)
			(xy 127.177806 -355.038142) (xy 127.136583 -355.002423) (xy 127.100863 -354.961201) (xy 127.071373 -354.915315)
			(xy 127.048714 -354.865699) (xy 127.033346 -354.813363) (xy 127.025584 -354.759373) (xy 125.542757 -354.759373)
			(xy 125.534998 -354.813343) (xy 125.519636 -354.865666) (xy 125.496984 -354.915271) (xy 125.467504 -354.961147)
			(xy 125.431795 -355.002361) (xy 125.390586 -355.038075) (xy 125.344713 -355.067561) (xy 125.295111 -355.090219)
			(xy 125.24279 -355.105587) (xy 125.188814 -355.113354) (xy 125.161548 -355.113844) (xy 124.297948 -355.113844)
			(xy 124.270673 -355.11342) (xy 124.216679 -355.105663) (xy 124.164338 -355.0903) (xy 124.114716 -355.067644)
			(xy 124.068825 -355.038156) (xy 124.027597 -355.002437) (xy 123.991872 -354.961214) (xy 123.962379 -354.915326)
			(xy 123.939717 -354.865707) (xy 123.924347 -354.813368) (xy 123.916584 -354.759374) (xy 122.43388 -354.759374)
			(xy 122.426118 -354.813356) (xy 122.410752 -354.865687) (xy 122.388095 -354.915298) (xy 122.358608 -354.961181)
			(xy 122.322891 -355.002399) (xy 122.281671 -355.038115) (xy 122.235788 -355.067601) (xy 122.186176 -355.090256)
			(xy 122.133844 -355.105621) (xy 122.079858 -355.113381) (xy 122.052588 -355.113844) (xy 121.188988 -355.113844)
			(xy 121.161718 -355.113393) (xy 121.107733 -355.105629) (xy 121.055403 -355.090262) (xy 121.005791 -355.067604)
			(xy 120.95991 -355.038117) (xy 120.918692 -355.0024) (xy 120.882976 -354.96118) (xy 120.85349 -354.915298)
			(xy 120.830834 -354.865686) (xy 120.815468 -354.813355) (xy 120.807706 -354.75937) (xy 119.324858 -354.75937)
			(xy 119.317097 -354.813345) (xy 119.301734 -354.86567) (xy 119.279081 -354.915276) (xy 119.249599 -354.961154)
			(xy 119.213888 -355.002369) (xy 119.172676 -355.038082) (xy 119.126801 -355.067567) (xy 119.077197 -355.090224)
			(xy 119.024873 -355.105591) (xy 118.970895 -355.113356) (xy 118.943628 -355.113844) (xy 118.080028 -355.113844)
			(xy 118.052754 -355.113418) (xy 117.998762 -355.105659) (xy 117.946423 -355.090295) (xy 117.896804 -355.067638)
			(xy 117.850915 -355.038149) (xy 117.80969 -355.00243) (xy 117.773968 -354.961207) (xy 117.744476 -354.91532)
			(xy 117.721815 -354.865703) (xy 117.706447 -354.813365) (xy 117.698684 -354.759374) (xy 116.21598 -354.759374)
			(xy 116.208218 -354.813358) (xy 116.192851 -354.865691) (xy 116.170192 -354.915304) (xy 116.140703 -354.961187)
			(xy 116.104983 -355.002406) (xy 116.063761 -355.038122) (xy 116.017876 -355.067607) (xy 115.968261 -355.090262)
			(xy 115.915927 -355.105625) (xy 115.861939 -355.113383) (xy 115.834668 -355.113844) (xy 114.971068 -355.113844)
			(xy 114.943799 -355.113391) (xy 114.889816 -355.105626) (xy 114.837488 -355.090257) (xy 114.78788 -355.067598)
			(xy 114.742 -355.03811) (xy 114.700785 -355.002393) (xy 114.665071 -354.961174) (xy 114.635587 -354.915292)
			(xy 114.612932 -354.865682) (xy 114.597568 -354.813353) (xy 114.589806 -354.759369) (xy 93.706658 -354.759369)
			(xy 93.698898 -354.813344) (xy 93.683535 -354.865667) (xy 93.660883 -354.915272) (xy 93.631402 -354.961149)
			(xy 93.595693 -355.002364) (xy 93.554483 -355.038077) (xy 93.508609 -355.067563) (xy 93.459007 -355.09022)
			(xy 93.406685 -355.105589) (xy 93.352708 -355.113355) (xy 93.325442 -355.113844) (xy 92.461842 -355.113844)
			(xy 92.434568 -355.113419) (xy 92.380574 -355.105662) (xy 92.328234 -355.090298) (xy 92.278613 -355.067642)
			(xy 92.232722 -355.038154) (xy 92.191495 -355.002435) (xy 92.155771 -354.961212) (xy 92.126278 -354.915324)
			(xy 92.103616 -354.865706) (xy 92.088247 -354.813367) (xy 92.080484 -354.759374) (xy 90.597781 -354.759374)
			(xy 90.590018 -354.813356) (xy 90.574652 -354.865688) (xy 90.551994 -354.9153) (xy 90.522506 -354.961182)
			(xy 90.486788 -355.002401) (xy 90.445568 -355.038117) (xy 90.399684 -355.067603) (xy 90.350071 -355.090258)
			(xy 90.297739 -355.105622) (xy 90.243753 -355.113382) (xy 90.216482 -355.113844) (xy 89.352882 -355.113844)
			(xy 89.325612 -355.113392) (xy 89.271628 -355.105628) (xy 89.219298 -355.090261) (xy 89.169688 -355.067602)
			(xy 89.123807 -355.038115) (xy 89.08259 -355.002398) (xy 89.046875 -354.961178) (xy 89.017389 -354.915296)
			(xy 88.994733 -354.865685) (xy 88.979368 -354.813354) (xy 88.971606 -354.75937) (xy 87.488758 -354.75937)
			(xy 87.480997 -354.813346) (xy 87.465633 -354.865672) (xy 87.44298 -354.915278) (xy 87.413497 -354.961156)
			(xy 87.377786 -355.002371) (xy 87.336573 -355.038084) (xy 87.290697 -355.067569) (xy 87.241092 -355.090226)
			(xy 87.188768 -355.105592) (xy 87.134789 -355.113356) (xy 87.107522 -355.113844) (xy 86.243922 -355.113844)
			(xy 86.216649 -355.113418) (xy 86.162657 -355.105658) (xy 86.110319 -355.090293) (xy 86.060701 -355.067636)
			(xy 86.014812 -355.038147) (xy 85.973588 -355.002428) (xy 85.937866 -354.961205) (xy 85.908375 -354.915318)
			(xy 85.885715 -354.865702) (xy 85.870347 -354.813365) (xy 85.862584 -354.759373) (xy 84.37988 -354.759373)
			(xy 84.372118 -354.813359) (xy 84.35675 -354.865692) (xy 84.334091 -354.915306) (xy 84.304601 -354.961189)
			(xy 84.268881 -355.002408) (xy 84.227659 -355.038124) (xy 84.181772 -355.067609) (xy 84.132157 -355.090264)
			(xy 84.079822 -355.105626) (xy 84.025833 -355.113383) (xy 83.998562 -355.113844) (xy 83.134962 -355.113844)
			(xy 83.107693 -355.113391) (xy 83.053711 -355.105625) (xy 83.001384 -355.090255) (xy 82.951776 -355.067596)
			(xy 82.905898 -355.038107) (xy 82.864683 -355.00239) (xy 82.82897 -354.961172) (xy 82.799486 -354.915291)
			(xy 82.776832 -354.865681) (xy 82.761467 -354.813352) (xy 82.753706 -354.759369) (xy 81.270858 -354.759369)
			(xy 81.263096 -354.813349) (xy 81.247732 -354.865676) (xy 81.225077 -354.915283) (xy 81.195593 -354.961162)
			(xy 81.159879 -355.002378) (xy 81.118664 -355.038091) (xy 81.072785 -355.067576) (xy 81.023178 -355.090231)
			(xy 80.970851 -355.105596) (xy 80.91687 -355.113357) (xy 80.889602 -355.113844) (xy 80.026002 -355.113844)
			(xy 79.99873 -355.113417) (xy 79.94474 -355.105654) (xy 79.892405 -355.090288) (xy 79.842789 -355.067629)
			(xy 79.796903 -355.03814) (xy 79.755681 -355.002421) (xy 79.719961 -354.961199) (xy 79.690472 -354.915313)
			(xy 79.667813 -354.865697) (xy 79.652446 -354.813362) (xy 79.644684 -354.759372) (xy 78.161857 -354.759372)
			(xy 78.154098 -354.813344) (xy 78.138735 -354.865667) (xy 78.116083 -354.915272) (xy 78.086602 -354.961149)
			(xy 78.050893 -355.002364) (xy 78.009683 -355.038077) (xy 77.963809 -355.067563) (xy 77.914207 -355.09022)
			(xy 77.861885 -355.105589) (xy 77.807908 -355.113355) (xy 77.780642 -355.113844) (xy 76.917042 -355.113844)
			(xy 76.889768 -355.113419) (xy 76.835774 -355.105662) (xy 76.783434 -355.090298) (xy 76.733813 -355.067642)
			(xy 76.687922 -355.038154) (xy 76.646695 -355.002435) (xy 76.610971 -354.961212) (xy 76.581478 -354.915324)
			(xy 76.558816 -354.865706) (xy 76.543447 -354.813367) (xy 76.535684 -354.759374) (xy 75.052981 -354.759374)
			(xy 75.045218 -354.813356) (xy 75.029852 -354.865688) (xy 75.007194 -354.9153) (xy 74.977706 -354.961182)
			(xy 74.941988 -355.002401) (xy 74.900768 -355.038117) (xy 74.854884 -355.067603) (xy 74.805271 -355.090258)
			(xy 74.752939 -355.105622) (xy 74.698953 -355.113382) (xy 74.671682 -355.113844) (xy 73.808082 -355.113844)
			(xy 73.780812 -355.113392) (xy 73.726828 -355.105628) (xy 73.674498 -355.090261) (xy 73.624888 -355.067602)
			(xy 73.579007 -355.038115) (xy 73.53779 -355.002398) (xy 73.502075 -354.961178) (xy 73.472589 -354.915296)
			(xy 73.449933 -354.865685) (xy 73.434568 -354.813354) (xy 73.426806 -354.75937) (xy 71.943958 -354.75937)
			(xy 71.936197 -354.813346) (xy 71.920833 -354.865672) (xy 71.89818 -354.915278) (xy 71.868697 -354.961156)
			(xy 71.832986 -355.002371) (xy 71.791773 -355.038084) (xy 71.745897 -355.067569) (xy 71.696292 -355.090226)
			(xy 71.643968 -355.105592) (xy 71.589989 -355.113356) (xy 71.562722 -355.113844) (xy 70.699122 -355.113844)
			(xy 70.671849 -355.113418) (xy 70.617857 -355.105658) (xy 70.565519 -355.090293) (xy 70.515901 -355.067636)
			(xy 70.470012 -355.038147) (xy 70.428788 -355.002428) (xy 70.393066 -354.961205) (xy 70.363575 -354.915318)
			(xy 70.340915 -354.865702) (xy 70.325547 -354.813365) (xy 70.317784 -354.759373) (xy 68.83508 -354.759373)
			(xy 68.827318 -354.813359) (xy 68.81195 -354.865692) (xy 68.789291 -354.915306) (xy 68.759801 -354.961189)
			(xy 68.724081 -355.002408) (xy 68.682859 -355.038124) (xy 68.636972 -355.067609) (xy 68.587357 -355.090264)
			(xy 68.535022 -355.105626) (xy 68.481033 -355.113383) (xy 68.453762 -355.113844) (xy 67.590162 -355.113844)
			(xy 67.562893 -355.113391) (xy 67.508911 -355.105625) (xy 67.456584 -355.090255) (xy 67.406976 -355.067596)
			(xy 67.361098 -355.038107) (xy 67.319883 -355.00239) (xy 67.28417 -354.961172) (xy 67.254686 -354.915291)
			(xy 67.232032 -354.865681) (xy 67.216667 -354.813352) (xy 67.208906 -354.759369) (xy 65.726058 -354.759369)
			(xy 65.718296 -354.813349) (xy 65.702932 -354.865676) (xy 65.680277 -354.915283) (xy 65.650793 -354.961162)
			(xy 65.615079 -355.002378) (xy 65.573864 -355.038091) (xy 65.527985 -355.067576) (xy 65.478378 -355.090231)
			(xy 65.426051 -355.105596) (xy 65.37207 -355.113357) (xy 65.344802 -355.113844) (xy 64.481202 -355.113844)
			(xy 64.45393 -355.113417) (xy 64.39994 -355.105654) (xy 64.347605 -355.090288) (xy 64.297989 -355.067629)
			(xy 64.252103 -355.03814) (xy 64.210881 -355.002421) (xy 64.175161 -354.961199) (xy 64.145672 -354.915313)
			(xy 64.123013 -354.865697) (xy 64.107646 -354.813362) (xy 64.099884 -354.759372) (xy 51.666857 -354.759372)
			(xy 51.659098 -354.813343) (xy 51.643736 -354.865666) (xy 51.621084 -354.915271) (xy 51.591604 -354.961147)
			(xy 51.555895 -355.002361) (xy 51.514686 -355.038075) (xy 51.468813 -355.067561) (xy 51.419211 -355.090219)
			(xy 51.36689 -355.105587) (xy 51.312914 -355.113354) (xy 51.285648 -355.113844) (xy 50.422048 -355.113844)
			(xy 50.394773 -355.11342) (xy 50.340779 -355.105663) (xy 50.288438 -355.0903) (xy 50.238816 -355.067644)
			(xy 50.192925 -355.038156) (xy 50.151697 -355.002437) (xy 50.115972 -354.961214) (xy 50.086479 -354.915326)
			(xy 50.063817 -354.865707) (xy 50.048447 -354.813368) (xy 50.040684 -354.759374) (xy 48.55798 -354.759374)
			(xy 48.550218 -354.813356) (xy 48.534852 -354.865687) (xy 48.512195 -354.915298) (xy 48.482708 -354.961181)
			(xy 48.446991 -355.002399) (xy 48.405771 -355.038115) (xy 48.359888 -355.067601) (xy 48.310276 -355.090256)
			(xy 48.257944 -355.105621) (xy 48.203958 -355.113381) (xy 48.176688 -355.113844) (xy 47.313088 -355.113844)
			(xy 47.285818 -355.113393) (xy 47.231833 -355.105629) (xy 47.179503 -355.090262) (xy 47.129891 -355.067604)
			(xy 47.08401 -355.038117) (xy 47.042792 -355.0024) (xy 47.007076 -354.96118) (xy 46.97759 -354.915298)
			(xy 46.954934 -354.865686) (xy 46.939568 -354.813355) (xy 46.931806 -354.75937) (xy 45.448958 -354.75937)
			(xy 45.441197 -354.813345) (xy 45.425834 -354.86567) (xy 45.403181 -354.915276) (xy 45.373699 -354.961154)
			(xy 45.337988 -355.002369) (xy 45.296776 -355.038082) (xy 45.250901 -355.067567) (xy 45.201297 -355.090224)
			(xy 45.148973 -355.105591) (xy 45.094995 -355.113356) (xy 45.067728 -355.113844) (xy 44.204128 -355.113844)
			(xy 44.176854 -355.113418) (xy 44.122862 -355.105659) (xy 44.070523 -355.090295) (xy 44.020904 -355.067638)
			(xy 43.975015 -355.038149) (xy 43.93379 -355.00243) (xy 43.898068 -354.961207) (xy 43.868576 -354.91532)
			(xy 43.845915 -354.865703) (xy 43.830547 -354.813365) (xy 43.822784 -354.759374) (xy 42.34008 -354.759374)
			(xy 42.332318 -354.813358) (xy 42.316951 -354.865691) (xy 42.294292 -354.915304) (xy 42.264803 -354.961187)
			(xy 42.229083 -355.002406) (xy 42.187861 -355.038122) (xy 42.141976 -355.067607) (xy 42.092361 -355.090262)
			(xy 42.040027 -355.105625) (xy 41.986039 -355.113383) (xy 41.958768 -355.113844) (xy 41.095168 -355.113844)
			(xy 41.067899 -355.113391) (xy 41.013916 -355.105626) (xy 40.961588 -355.090257) (xy 40.91198 -355.067598)
			(xy 40.8661 -355.03811) (xy 40.824885 -355.002393) (xy 40.789171 -354.961174) (xy 40.759687 -354.915292)
			(xy 40.737032 -354.865682) (xy 40.721668 -354.813353) (xy 40.713906 -354.759369) (xy 39.231058 -354.759369)
			(xy 39.223297 -354.813348) (xy 39.207932 -354.865675) (xy 39.185278 -354.915282) (xy 39.155794 -354.96116)
			(xy 39.120081 -355.002376) (xy 39.078867 -355.038089) (xy 39.032989 -355.067574) (xy 38.983382 -355.09023)
			(xy 38.931056 -355.105595) (xy 38.877076 -355.113357) (xy 38.849808 -355.113844) (xy 37.986208 -355.113844)
			(xy 37.958935 -355.113417) (xy 37.904945 -355.105655) (xy 37.852609 -355.090289) (xy 37.802992 -355.067631)
			(xy 37.757106 -355.038142) (xy 37.715883 -355.002423) (xy 37.680163 -354.961201) (xy 37.650673 -354.915315)
			(xy 37.628014 -354.865699) (xy 37.612646 -354.813363) (xy 37.604884 -354.759373) (xy 36.122057 -354.759373)
			(xy 36.114298 -354.813343) (xy 36.098936 -354.865666) (xy 36.076284 -354.915271) (xy 36.046804 -354.961147)
			(xy 36.011095 -355.002361) (xy 35.969886 -355.038075) (xy 35.924013 -355.067561) (xy 35.874411 -355.090219)
			(xy 35.82209 -355.105587) (xy 35.768114 -355.113354) (xy 35.740848 -355.113844) (xy 34.877248 -355.113844)
			(xy 34.849973 -355.11342) (xy 34.795979 -355.105663) (xy 34.743638 -355.0903) (xy 34.694016 -355.067644)
			(xy 34.648125 -355.038156) (xy 34.606897 -355.002437) (xy 34.571172 -354.961214) (xy 34.541679 -354.915326)
			(xy 34.519017 -354.865707) (xy 34.503647 -354.813368) (xy 34.495884 -354.759374) (xy 33.01318 -354.759374)
			(xy 33.005418 -354.813356) (xy 32.990052 -354.865687) (xy 32.967395 -354.915298) (xy 32.937908 -354.961181)
			(xy 32.902191 -355.002399) (xy 32.860971 -355.038115) (xy 32.815088 -355.067601) (xy 32.765476 -355.090256)
			(xy 32.713144 -355.105621) (xy 32.659158 -355.113381) (xy 32.631888 -355.113844) (xy 31.768288 -355.113844)
			(xy 31.741018 -355.113393) (xy 31.687033 -355.105629) (xy 31.634703 -355.090262) (xy 31.585091 -355.067604)
			(xy 31.53921 -355.038117) (xy 31.497992 -355.0024) (xy 31.462276 -354.96118) (xy 31.43279 -354.915298)
			(xy 31.410134 -354.865686) (xy 31.394768 -354.813355) (xy 31.387006 -354.75937) (xy 29.904158 -354.75937)
			(xy 29.896397 -354.813345) (xy 29.881034 -354.86567) (xy 29.858381 -354.915276) (xy 29.828899 -354.961154)
			(xy 29.793188 -355.002369) (xy 29.751976 -355.038082) (xy 29.706101 -355.067567) (xy 29.656497 -355.090224)
			(xy 29.604173 -355.105591) (xy 29.550195 -355.113356) (xy 29.522928 -355.113844) (xy 28.659328 -355.113844)
			(xy 28.632054 -355.113418) (xy 28.578062 -355.105659) (xy 28.525723 -355.090295) (xy 28.476104 -355.067638)
			(xy 28.430215 -355.038149) (xy 28.38899 -355.00243) (xy 28.353268 -354.961207) (xy 28.323776 -354.91532)
			(xy 28.301115 -354.865703) (xy 28.285747 -354.813365) (xy 28.277984 -354.759374) (xy 26.79528 -354.759374)
			(xy 26.787518 -354.813358) (xy 26.772151 -354.865691) (xy 26.749492 -354.915304) (xy 26.720003 -354.961187)
			(xy 26.684283 -355.002406) (xy 26.643061 -355.038122) (xy 26.597176 -355.067607) (xy 26.547561 -355.090262)
			(xy 26.495227 -355.105625) (xy 26.441239 -355.113383) (xy 26.413968 -355.113844) (xy 25.550368 -355.113844)
			(xy 25.523099 -355.113391) (xy 25.469116 -355.105626) (xy 25.416788 -355.090257) (xy 25.36718 -355.067598)
			(xy 25.3213 -355.03811) (xy 25.280085 -355.002393) (xy 25.244371 -354.961174) (xy 25.214887 -354.915292)
			(xy 25.192232 -354.865682) (xy 25.176868 -354.813353) (xy 25.169106 -354.759369) (xy 23.686258 -354.759369)
			(xy 23.678497 -354.813348) (xy 23.663132 -354.865675) (xy 23.640478 -354.915282) (xy 23.610994 -354.96116)
			(xy 23.575281 -355.002376) (xy 23.534067 -355.038089) (xy 23.488189 -355.067574) (xy 23.438582 -355.09023)
			(xy 23.386256 -355.105595) (xy 23.332276 -355.113357) (xy 23.305008 -355.113844) (xy 22.441408 -355.113844)
			(xy 22.414135 -355.113417) (xy 22.360145 -355.105655) (xy 22.307809 -355.090289) (xy 22.258192 -355.067631)
			(xy 22.212306 -355.038142) (xy 22.171083 -355.002423) (xy 22.135363 -354.961201) (xy 22.105873 -354.915315)
			(xy 22.083214 -354.865699) (xy 22.067846 -354.813363) (xy 22.060084 -354.759373) (xy 1.524 -354.759373)
			(xy 1.524 -357.784969) (xy 22.060131 -357.784969) (xy 22.060131 -357.730431) (xy 22.067893 -357.676447)
			(xy 22.083259 -357.624118) (xy 22.105915 -357.574508) (xy 22.135401 -357.528628) (xy 22.171117 -357.487411)
			(xy 22.212334 -357.451696) (xy 22.258215 -357.422211) (xy 22.307826 -357.399556) (xy 22.360155 -357.384191)
			(xy 22.414139 -357.376431) (xy 22.441408 -357.375968) (xy 23.305008 -357.375968) (xy 23.332279 -357.376395)
			(xy 23.386266 -357.384158) (xy 23.438599 -357.399525) (xy 23.488212 -357.422184) (xy 23.534095 -357.451672)
			(xy 23.575315 -357.48739) (xy 23.611032 -357.528611) (xy 23.64052 -357.574495) (xy 23.663177 -357.624109)
			(xy 23.678543 -357.676442) (xy 23.686306 -357.730429) (xy 23.686306 -357.784966) (xy 25.169154 -357.784966)
			(xy 25.169154 -357.730434) (xy 25.176914 -357.676458) (xy 25.192277 -357.624135) (xy 25.214929 -357.574531)
			(xy 25.24441 -357.528655) (xy 25.280119 -357.487441) (xy 25.321329 -357.451729) (xy 25.367203 -357.422244)
			(xy 25.416805 -357.399588) (xy 25.469126 -357.384221) (xy 25.523102 -357.376457) (xy 25.550368 -357.375968)
			(xy 26.413968 -357.375968) (xy 26.441243 -357.376369) (xy 26.495237 -357.384128) (xy 26.547578 -357.399493)
			(xy 26.597199 -357.422151) (xy 26.64309 -357.45164) (xy 26.684317 -357.48736) (xy 26.720041 -357.528584)
			(xy 26.749534 -357.574473) (xy 26.772196 -357.624092) (xy 26.787565 -357.676431) (xy 26.795328 -357.730425)
			(xy 26.795328 -357.78497) (xy 28.278031 -357.78497) (xy 28.278032 -357.73043) (xy 28.285794 -357.676445)
			(xy 28.30116 -357.624114) (xy 28.323818 -357.574503) (xy 28.353306 -357.528621) (xy 28.389024 -357.487404)
			(xy 28.430244 -357.451689) (xy 28.476127 -357.422205) (xy 28.52574 -357.39955) (xy 28.578072 -357.384188)
			(xy 28.632058 -357.37643) (xy 28.659328 -357.375968) (xy 29.522928 -357.375968) (xy 29.550198 -357.376396)
			(xy 29.604183 -357.384162) (xy 29.656513 -357.399531) (xy 29.706124 -357.42219) (xy 29.752005 -357.451679)
			(xy 29.793222 -357.487397) (xy 29.828937 -357.528618) (xy 29.858423 -357.574501) (xy 29.881079 -357.624113)
			(xy 29.896444 -357.676444) (xy 29.904206 -357.73043) (xy 29.904206 -357.784967) (xy 31.387054 -357.784967)
			(xy 31.387054 -357.730433) (xy 31.394815 -357.676455) (xy 31.410179 -357.624131) (xy 31.432832 -357.574525)
			(xy 31.462315 -357.528648) (xy 31.498026 -357.487434) (xy 31.539239 -357.451722) (xy 31.585115 -357.422238)
			(xy 31.634719 -357.399583) (xy 31.687043 -357.384218) (xy 31.741021 -357.376455) (xy 31.768288 -357.375968)
			(xy 32.631888 -357.375968) (xy 32.659162 -357.376371) (xy 32.713154 -357.384132) (xy 32.765492 -357.399499)
			(xy 32.815111 -357.422157) (xy 32.861 -357.451647) (xy 32.902224 -357.487367) (xy 32.937946 -357.528591)
			(xy 32.967437 -357.574479) (xy 32.990097 -357.624096) (xy 33.005465 -357.676434) (xy 33.013228 -357.730426)
			(xy 33.013228 -357.784971) (xy 34.495932 -357.784971) (xy 34.495932 -357.730429) (xy 34.503694 -357.676442)
			(xy 34.519062 -357.62411) (xy 34.541721 -357.574497) (xy 34.571211 -357.528615) (xy 34.606931 -357.487397)
			(xy 34.648153 -357.451682) (xy 34.694039 -357.422198) (xy 34.743655 -357.399545) (xy 34.795989 -357.384184)
			(xy 34.849977 -357.376428) (xy 34.877248 -357.375968) (xy 35.740848 -357.375968) (xy 35.768117 -357.376398)
			(xy 35.8221 -357.384166) (xy 35.874428 -357.399536) (xy 35.924036 -357.422197) (xy 35.969914 -357.451687)
			(xy 36.011129 -357.487405) (xy 36.046842 -357.528624) (xy 36.076326 -357.574506) (xy 36.09898 -357.624117)
			(xy 36.114345 -357.676447) (xy 36.122106 -357.730431) (xy 36.122106 -357.784969) (xy 37.604931 -357.784969)
			(xy 37.604931 -357.730431) (xy 37.612693 -357.676447) (xy 37.628059 -357.624118) (xy 37.650715 -357.574508)
			(xy 37.680201 -357.528628) (xy 37.715917 -357.487411) (xy 37.757134 -357.451696) (xy 37.803015 -357.422211)
			(xy 37.852626 -357.399556) (xy 37.904955 -357.384191) (xy 37.958939 -357.376431) (xy 37.986208 -357.375968)
			(xy 38.849808 -357.375968) (xy 38.877079 -357.376395) (xy 38.931066 -357.384158) (xy 38.983399 -357.399525)
			(xy 39.033012 -357.422184) (xy 39.078895 -357.451672) (xy 39.120115 -357.48739) (xy 39.155832 -357.528611)
			(xy 39.18532 -357.574495) (xy 39.207977 -357.624109) (xy 39.223343 -357.676442) (xy 39.231106 -357.730429)
			(xy 39.231106 -357.784966) (xy 40.713954 -357.784966) (xy 40.713954 -357.730434) (xy 40.721714 -357.676458)
			(xy 40.737077 -357.624135) (xy 40.759729 -357.574531) (xy 40.78921 -357.528655) (xy 40.824919 -357.487441)
			(xy 40.866129 -357.451729) (xy 40.912003 -357.422244) (xy 40.961605 -357.399588) (xy 41.013926 -357.384221)
			(xy 41.067902 -357.376457) (xy 41.095168 -357.375968) (xy 41.958768 -357.375968) (xy 41.986043 -357.376369)
			(xy 42.040037 -357.384128) (xy 42.092378 -357.399493) (xy 42.141999 -357.422151) (xy 42.18789 -357.45164)
			(xy 42.229117 -357.48736) (xy 42.264841 -357.528584) (xy 42.294334 -357.574473) (xy 42.316996 -357.624092)
			(xy 42.332365 -357.676431) (xy 42.340128 -357.730425) (xy 42.340128 -357.78497) (xy 43.822831 -357.78497)
			(xy 43.822832 -357.73043) (xy 43.830594 -357.676445) (xy 43.84596 -357.624114) (xy 43.868618 -357.574503)
			(xy 43.898106 -357.528621) (xy 43.933824 -357.487404) (xy 43.975044 -357.451689) (xy 44.020927 -357.422205)
			(xy 44.07054 -357.39955) (xy 44.122872 -357.384188) (xy 44.176858 -357.37643) (xy 44.204128 -357.375968)
			(xy 45.067728 -357.375968) (xy 45.094998 -357.376396) (xy 45.148983 -357.384162) (xy 45.201313 -357.399531)
			(xy 45.250924 -357.42219) (xy 45.296805 -357.451679) (xy 45.338022 -357.487397) (xy 45.373737 -357.528618)
			(xy 45.403223 -357.574501) (xy 45.425879 -357.624113) (xy 45.441244 -357.676444) (xy 45.449006 -357.73043)
			(xy 45.449006 -357.784967) (xy 46.931854 -357.784967) (xy 46.931854 -357.730433) (xy 46.939615 -357.676455)
			(xy 46.954979 -357.624131) (xy 46.977632 -357.574525) (xy 47.007115 -357.528648) (xy 47.042826 -357.487434)
			(xy 47.084039 -357.451722) (xy 47.129915 -357.422238) (xy 47.179519 -357.399583) (xy 47.231843 -357.384218)
			(xy 47.285821 -357.376455) (xy 47.313088 -357.375968) (xy 48.176688 -357.375968) (xy 48.203962 -357.376371)
			(xy 48.257954 -357.384132) (xy 48.310292 -357.399499) (xy 48.359911 -357.422157) (xy 48.4058 -357.451647)
			(xy 48.447024 -357.487367) (xy 48.482746 -357.528591) (xy 48.512237 -357.574479) (xy 48.534897 -357.624096)
			(xy 48.550265 -357.676434) (xy 48.558028 -357.730426) (xy 48.558028 -357.784971) (xy 50.040732 -357.784971)
			(xy 50.040732 -357.730429) (xy 50.048494 -357.676442) (xy 50.063862 -357.62411) (xy 50.086521 -357.574497)
			(xy 50.116011 -357.528615) (xy 50.151731 -357.487397) (xy 50.192953 -357.451682) (xy 50.238839 -357.422198)
			(xy 50.288455 -357.399545) (xy 50.340789 -357.384184) (xy 50.394777 -357.376428) (xy 50.422048 -357.375968)
			(xy 51.285648 -357.375968) (xy 51.312917 -357.376398) (xy 51.3669 -357.384166) (xy 51.419228 -357.399536)
			(xy 51.468836 -357.422197) (xy 51.514714 -357.451687) (xy 51.555929 -357.487405) (xy 51.591642 -357.528624)
			(xy 51.621126 -357.574506) (xy 51.64378 -357.624117) (xy 51.659145 -357.676447) (xy 51.666906 -357.730431)
			(xy 51.666906 -357.784969) (xy 64.099931 -357.784969) (xy 64.099931 -357.730431) (xy 64.107693 -357.676448)
			(xy 64.123058 -357.62412) (xy 64.145714 -357.57451) (xy 64.1752 -357.52863) (xy 64.210914 -357.487413)
			(xy 64.252132 -357.451698) (xy 64.298012 -357.422213) (xy 64.347621 -357.399557) (xy 64.39995 -357.384193)
			(xy 64.453933 -357.376431) (xy 64.481202 -357.375968) (xy 65.344802 -357.375968) (xy 65.372073 -357.376395)
			(xy 65.426061 -357.384157) (xy 65.478394 -357.399524) (xy 65.528008 -357.422182) (xy 65.573893 -357.45167)
			(xy 65.615113 -357.487388) (xy 65.650831 -357.528609) (xy 65.680319 -357.574493) (xy 65.702977 -357.624107)
			(xy 65.718343 -357.676441) (xy 65.726106 -357.730429) (xy 65.726106 -357.784966) (xy 67.208954 -357.784966)
			(xy 67.208954 -357.730435) (xy 67.216714 -357.676458) (xy 67.232077 -357.624136) (xy 67.254728 -357.574532)
			(xy 67.284208 -357.528657) (xy 67.319917 -357.487443) (xy 67.361126 -357.451731) (xy 67.406999 -357.422246)
			(xy 67.4566 -357.39959) (xy 67.508921 -357.384222) (xy 67.562897 -357.376457) (xy 67.590162 -357.375968)
			(xy 68.453762 -357.375968) (xy 68.481037 -357.376369) (xy 68.535032 -357.384127) (xy 68.587373 -357.399491)
			(xy 68.636995 -357.422149) (xy 68.682887 -357.451638) (xy 68.724115 -357.487358) (xy 68.75984 -357.528582)
			(xy 68.789333 -357.574471) (xy 68.811995 -357.624091) (xy 68.827365 -357.676431) (xy 68.835128 -357.730425)
			(xy 68.835128 -357.78497) (xy 70.317831 -357.78497) (xy 70.317831 -357.73043) (xy 70.325594 -357.676446)
			(xy 70.34096 -357.624115) (xy 70.363617 -357.574505) (xy 70.393105 -357.528623) (xy 70.428822 -357.487406)
			(xy 70.470041 -357.451691) (xy 70.515924 -357.422207) (xy 70.565536 -357.399552) (xy 70.617867 -357.384189)
			(xy 70.671852 -357.37643) (xy 70.699122 -357.375968) (xy 71.562722 -357.375968) (xy 71.589992 -357.376396)
			(xy 71.643978 -357.384161) (xy 71.696309 -357.399529) (xy 71.74592 -357.422189) (xy 71.791802 -357.451677)
			(xy 71.83302 -357.487395) (xy 71.868736 -357.528616) (xy 71.898222 -357.574499) (xy 71.920878 -357.624112)
			(xy 71.936244 -357.676444) (xy 71.944006 -357.730429) (xy 71.944006 -357.784966) (xy 73.426854 -357.784966)
			(xy 73.426854 -357.730434) (xy 73.434615 -357.676456) (xy 73.449978 -357.624132) (xy 73.472631 -357.574527)
			(xy 73.502113 -357.52865) (xy 73.537824 -357.487436) (xy 73.579036 -357.451724) (xy 73.624911 -357.42224)
			(xy 73.674515 -357.399584) (xy 73.726838 -357.384219) (xy 73.780816 -357.376456) (xy 73.808082 -357.375968)
			(xy 74.671682 -357.375968) (xy 74.698956 -357.37637) (xy 74.752949 -357.384131) (xy 74.805288 -357.399497)
			(xy 74.854907 -357.422155) (xy 74.900797 -357.451645) (xy 74.942022 -357.487365) (xy 74.977744 -357.528589)
			(xy 75.007236 -357.574477) (xy 75.029897 -357.624095) (xy 75.045265 -357.676433) (xy 75.053028 -357.730426)
			(xy 75.053028 -357.784971) (xy 76.535732 -357.784971) (xy 76.535732 -357.730429) (xy 76.543494 -357.676443)
			(xy 76.558861 -357.624111) (xy 76.58152 -357.574499) (xy 76.611009 -357.528617) (xy 76.646729 -357.487399)
			(xy 76.687951 -357.451684) (xy 76.733836 -357.4222) (xy 76.78345 -357.399547) (xy 76.835784 -357.384185)
			(xy 76.889771 -357.376429) (xy 76.917042 -357.375968) (xy 77.780642 -357.375968) (xy 77.807912 -357.376397)
			(xy 77.861895 -357.384165) (xy 77.914223 -357.399535) (xy 77.963832 -357.422195) (xy 78.009711 -357.451684)
			(xy 78.050927 -357.487402) (xy 78.086641 -357.528622) (xy 78.116125 -357.574505) (xy 78.13878 -357.624116)
			(xy 78.154144 -357.676446) (xy 78.161906 -357.73043) (xy 78.161906 -357.784969) (xy 79.644731 -357.784969)
			(xy 79.644731 -357.730431) (xy 79.652493 -357.676448) (xy 79.667858 -357.62412) (xy 79.690514 -357.57451)
			(xy 79.72 -357.52863) (xy 79.755714 -357.487413) (xy 79.796932 -357.451698) (xy 79.842812 -357.422213)
			(xy 79.892421 -357.399557) (xy 79.94475 -357.384193) (xy 79.998733 -357.376431) (xy 80.026002 -357.375968)
			(xy 80.889602 -357.375968) (xy 80.916873 -357.376395) (xy 80.970861 -357.384157) (xy 81.023194 -357.399524)
			(xy 81.072808 -357.422182) (xy 81.118693 -357.45167) (xy 81.159913 -357.487388) (xy 81.195631 -357.528609)
			(xy 81.225119 -357.574493) (xy 81.247777 -357.624107) (xy 81.263143 -357.676441) (xy 81.270906 -357.730429)
			(xy 81.270906 -357.784966) (xy 82.753754 -357.784966) (xy 82.753754 -357.730435) (xy 82.761514 -357.676458)
			(xy 82.776877 -357.624136) (xy 82.799528 -357.574532) (xy 82.829008 -357.528657) (xy 82.864717 -357.487443)
			(xy 82.905926 -357.451731) (xy 82.951799 -357.422246) (xy 83.0014 -357.39959) (xy 83.053721 -357.384222)
			(xy 83.107697 -357.376457) (xy 83.134962 -357.375968) (xy 83.998562 -357.375968) (xy 84.025837 -357.376369)
			(xy 84.079832 -357.384127) (xy 84.132173 -357.399491) (xy 84.181795 -357.422149) (xy 84.227687 -357.451638)
			(xy 84.268915 -357.487358) (xy 84.30464 -357.528582) (xy 84.334133 -357.574471) (xy 84.356795 -357.624091)
			(xy 84.372165 -357.676431) (xy 84.379928 -357.730425) (xy 84.379928 -357.78497) (xy 85.862631 -357.78497)
			(xy 85.862631 -357.73043) (xy 85.870394 -357.676446) (xy 85.88576 -357.624115) (xy 85.908417 -357.574505)
			(xy 85.937905 -357.528623) (xy 85.973622 -357.487406) (xy 86.014841 -357.451691) (xy 86.060724 -357.422207)
			(xy 86.110336 -357.399552) (xy 86.162667 -357.384189) (xy 86.216652 -357.37643) (xy 86.243922 -357.375968)
			(xy 87.107522 -357.375968) (xy 87.134792 -357.376396) (xy 87.188778 -357.384161) (xy 87.241109 -357.399529)
			(xy 87.29072 -357.422189) (xy 87.336602 -357.451677) (xy 87.37782 -357.487395) (xy 87.413536 -357.528616)
			(xy 87.443022 -357.574499) (xy 87.465678 -357.624112) (xy 87.481044 -357.676444) (xy 87.488806 -357.730429)
			(xy 87.488806 -357.784966) (xy 88.971654 -357.784966) (xy 88.971654 -357.730434) (xy 88.979415 -357.676456)
			(xy 88.994778 -357.624132) (xy 89.017431 -357.574527) (xy 89.046913 -357.52865) (xy 89.082624 -357.487436)
			(xy 89.123836 -357.451724) (xy 89.169711 -357.42224) (xy 89.219315 -357.399584) (xy 89.271638 -357.384219)
			(xy 89.325616 -357.376456) (xy 89.352882 -357.375968) (xy 90.216482 -357.375968) (xy 90.243756 -357.37637)
			(xy 90.297749 -357.384131) (xy 90.350088 -357.399497) (xy 90.399707 -357.422155) (xy 90.445597 -357.451645)
			(xy 90.486822 -357.487365) (xy 90.522544 -357.528589) (xy 90.552036 -357.574477) (xy 90.574697 -357.624095)
			(xy 90.590065 -357.676433) (xy 90.597828 -357.730426) (xy 90.597828 -357.784971) (xy 92.080532 -357.784971)
			(xy 92.080532 -357.730429) (xy 92.088294 -357.676443) (xy 92.103661 -357.624111) (xy 92.12632 -357.574499)
			(xy 92.155809 -357.528617) (xy 92.191529 -357.487399) (xy 92.232751 -357.451684) (xy 92.278636 -357.4222)
			(xy 92.32825 -357.399547) (xy 92.380584 -357.384185) (xy 92.434571 -357.376429) (xy 92.461842 -357.375968)
			(xy 93.325442 -357.375968) (xy 93.352712 -357.376397) (xy 93.406695 -357.384165) (xy 93.459023 -357.399535)
			(xy 93.508632 -357.422195) (xy 93.554511 -357.451684) (xy 93.595727 -357.487402) (xy 93.631441 -357.528622)
			(xy 93.660925 -357.574505) (xy 93.68358 -357.624116) (xy 93.698944 -357.676446) (xy 93.706706 -357.73043)
			(xy 93.706706 -357.784966) (xy 114.589854 -357.784966) (xy 114.589854 -357.730434) (xy 114.597614 -357.676458)
			(xy 114.612977 -357.624135) (xy 114.635629 -357.574531) (xy 114.66511 -357.528655) (xy 114.700819 -357.487441)
			(xy 114.742029 -357.451729) (xy 114.787903 -357.422244) (xy 114.837505 -357.399588) (xy 114.889826 -357.384221)
			(xy 114.943802 -357.376457) (xy 114.971068 -357.375968) (xy 115.834668 -357.375968) (xy 115.861943 -357.376369)
			(xy 115.915937 -357.384128) (xy 115.968278 -357.399493) (xy 116.017899 -357.422151) (xy 116.06379 -357.45164)
			(xy 116.105017 -357.48736) (xy 116.140741 -357.528584) (xy 116.170234 -357.574473) (xy 116.192896 -357.624092)
			(xy 116.208265 -357.676431) (xy 116.216028 -357.730425) (xy 116.216028 -357.78497) (xy 117.698731 -357.78497)
			(xy 117.698732 -357.73043) (xy 117.706494 -357.676445) (xy 117.72186 -357.624114) (xy 117.744518 -357.574503)
			(xy 117.774006 -357.528621) (xy 117.809724 -357.487404) (xy 117.850944 -357.451689) (xy 117.896827 -357.422205)
			(xy 117.94644 -357.39955) (xy 117.998772 -357.384188) (xy 118.052758 -357.37643) (xy 118.080028 -357.375968)
			(xy 118.943628 -357.375968) (xy 118.970898 -357.376396) (xy 119.024883 -357.384162) (xy 119.077213 -357.399531)
			(xy 119.126824 -357.42219) (xy 119.172705 -357.451679) (xy 119.213922 -357.487397) (xy 119.249637 -357.528618)
			(xy 119.279123 -357.574501) (xy 119.301779 -357.624113) (xy 119.317144 -357.676444) (xy 119.324906 -357.73043)
			(xy 119.324906 -357.784967) (xy 120.807754 -357.784967) (xy 120.807754 -357.730433) (xy 120.815515 -357.676455)
			(xy 120.830879 -357.624131) (xy 120.853532 -357.574525) (xy 120.883015 -357.528648) (xy 120.918726 -357.487434)
			(xy 120.959939 -357.451722) (xy 121.005815 -357.422238) (xy 121.055419 -357.399583) (xy 121.107743 -357.384218)
			(xy 121.161721 -357.376455) (xy 121.188988 -357.375968) (xy 122.052588 -357.375968) (xy 122.079862 -357.376371)
			(xy 122.133854 -357.384132) (xy 122.186192 -357.399499) (xy 122.235811 -357.422157) (xy 122.2817 -357.451647)
			(xy 122.322924 -357.487367) (xy 122.358646 -357.528591) (xy 122.388137 -357.574479) (xy 122.410797 -357.624096)
			(xy 122.426165 -357.676434) (xy 122.433928 -357.730426) (xy 122.433928 -357.784971) (xy 123.916632 -357.784971)
			(xy 123.916632 -357.730429) (xy 123.924394 -357.676442) (xy 123.939762 -357.62411) (xy 123.962421 -357.574497)
			(xy 123.991911 -357.528615) (xy 124.027631 -357.487397) (xy 124.068853 -357.451682) (xy 124.114739 -357.422198)
			(xy 124.164355 -357.399545) (xy 124.216689 -357.384184) (xy 124.270677 -357.376428) (xy 124.297948 -357.375968)
			(xy 125.161548 -357.375968) (xy 125.188817 -357.376398) (xy 125.2428 -357.384166) (xy 125.295128 -357.399536)
			(xy 125.344736 -357.422197) (xy 125.390614 -357.451687) (xy 125.431829 -357.487405) (xy 125.467542 -357.528624)
			(xy 125.497026 -357.574506) (xy 125.51968 -357.624117) (xy 125.535045 -357.676447) (xy 125.542806 -357.730431)
			(xy 125.542806 -357.784969) (xy 127.025631 -357.784969) (xy 127.025631 -357.730431) (xy 127.033393 -357.676447)
			(xy 127.048759 -357.624118) (xy 127.071415 -357.574508) (xy 127.100901 -357.528628) (xy 127.136617 -357.487411)
			(xy 127.177834 -357.451696) (xy 127.223715 -357.422211) (xy 127.273326 -357.399556) (xy 127.325655 -357.384191)
			(xy 127.379639 -357.376431) (xy 127.406908 -357.375968) (xy 128.270508 -357.375968) (xy 128.297779 -357.376395)
			(xy 128.351766 -357.384158) (xy 128.404099 -357.399525) (xy 128.453712 -357.422184) (xy 128.499595 -357.451672)
			(xy 128.540815 -357.48739) (xy 128.576532 -357.528611) (xy 128.60602 -357.574495) (xy 128.628677 -357.624109)
			(xy 128.644043 -357.676442) (xy 128.651806 -357.730429) (xy 128.651806 -357.784966) (xy 130.134654 -357.784966)
			(xy 130.134654 -357.730434) (xy 130.142414 -357.676458) (xy 130.157777 -357.624135) (xy 130.180429 -357.574531)
			(xy 130.20991 -357.528655) (xy 130.245619 -357.487441) (xy 130.286829 -357.451729) (xy 130.332703 -357.422244)
			(xy 130.382305 -357.399588) (xy 130.434626 -357.384221) (xy 130.488602 -357.376457) (xy 130.515868 -357.375968)
			(xy 131.379468 -357.375968) (xy 131.406743 -357.376369) (xy 131.460737 -357.384128) (xy 131.513078 -357.399493)
			(xy 131.562699 -357.422151) (xy 131.60859 -357.45164) (xy 131.649817 -357.48736) (xy 131.685541 -357.528584)
			(xy 131.715034 -357.574473) (xy 131.737696 -357.624092) (xy 131.753065 -357.676431) (xy 131.760828 -357.730425)
			(xy 131.760828 -357.78497) (xy 133.243531 -357.78497) (xy 133.243532 -357.73043) (xy 133.251294 -357.676445)
			(xy 133.26666 -357.624114) (xy 133.289318 -357.574503) (xy 133.318806 -357.528621) (xy 133.354524 -357.487404)
			(xy 133.395744 -357.451689) (xy 133.441627 -357.422205) (xy 133.49124 -357.39955) (xy 133.543572 -357.384188)
			(xy 133.597558 -357.37643) (xy 133.624828 -357.375968) (xy 134.488428 -357.375968) (xy 134.515698 -357.376396)
			(xy 134.569683 -357.384162) (xy 134.622013 -357.399531) (xy 134.671624 -357.42219) (xy 134.717505 -357.451679)
			(xy 134.758722 -357.487397) (xy 134.794437 -357.528618) (xy 134.823923 -357.574501) (xy 134.846579 -357.624113)
			(xy 134.861944 -357.676444) (xy 134.869706 -357.73043) (xy 134.869706 -357.784967) (xy 136.352554 -357.784967)
			(xy 136.352554 -357.730433) (xy 136.360315 -357.676455) (xy 136.375679 -357.624131) (xy 136.398332 -357.574525)
			(xy 136.427815 -357.528648) (xy 136.463526 -357.487434) (xy 136.504739 -357.451722) (xy 136.550615 -357.422238)
			(xy 136.600219 -357.399583) (xy 136.652543 -357.384218) (xy 136.706521 -357.376455) (xy 136.733788 -357.375968)
			(xy 137.597388 -357.375968) (xy 137.624662 -357.376371) (xy 137.678654 -357.384132) (xy 137.730992 -357.399499)
			(xy 137.780611 -357.422157) (xy 137.8265 -357.451647) (xy 137.867724 -357.487367) (xy 137.903446 -357.528591)
			(xy 137.932937 -357.574479) (xy 137.955597 -357.624096) (xy 137.970965 -357.676434) (xy 137.978728 -357.730426)
			(xy 137.978728 -357.784971) (xy 139.461432 -357.784971) (xy 139.461432 -357.730429) (xy 139.469194 -357.676442)
			(xy 139.484562 -357.62411) (xy 139.507221 -357.574497) (xy 139.536711 -357.528615) (xy 139.572431 -357.487397)
			(xy 139.613653 -357.451682) (xy 139.659539 -357.422198) (xy 139.709155 -357.399545) (xy 139.761489 -357.384184)
			(xy 139.815477 -357.376428) (xy 139.842748 -357.375968) (xy 140.706348 -357.375968) (xy 140.733617 -357.376398)
			(xy 140.7876 -357.384166) (xy 140.839928 -357.399536) (xy 140.889536 -357.422197) (xy 140.935414 -357.451687)
			(xy 140.976629 -357.487405) (xy 141.012342 -357.528624) (xy 141.041826 -357.574506) (xy 141.06448 -357.624117)
			(xy 141.079845 -357.676447) (xy 141.087606 -357.730431) (xy 141.087606 -357.784969) (xy 142.570431 -357.784969)
			(xy 142.570431 -357.730431) (xy 142.578193 -357.676447) (xy 142.593559 -357.624118) (xy 142.616215 -357.574508)
			(xy 142.645701 -357.528628) (xy 142.681417 -357.487411) (xy 142.722634 -357.451696) (xy 142.768515 -357.422211)
			(xy 142.818126 -357.399556) (xy 142.870455 -357.384191) (xy 142.924439 -357.376431) (xy 142.951708 -357.375968)
			(xy 143.815308 -357.375968) (xy 143.842579 -357.376395) (xy 143.896566 -357.384158) (xy 143.948899 -357.399525)
			(xy 143.998512 -357.422184) (xy 144.044395 -357.451672) (xy 144.085615 -357.48739) (xy 144.121332 -357.528611)
			(xy 144.15082 -357.574495) (xy 144.173477 -357.624109) (xy 144.188843 -357.676442) (xy 144.196606 -357.730429)
			(xy 144.196606 -357.784965) (xy 158.695954 -357.784965) (xy 158.695954 -357.730435) (xy 158.703714 -357.67646)
			(xy 158.719076 -357.624138) (xy 158.741727 -357.574535) (xy 158.771206 -357.52866) (xy 158.806913 -357.487447)
			(xy 158.848122 -357.451735) (xy 158.893993 -357.42225) (xy 158.943593 -357.399593) (xy 158.995913 -357.384224)
			(xy 159.049887 -357.376458) (xy 159.077152 -357.375968) (xy 159.940752 -357.375968) (xy 159.968027 -357.376368)
			(xy 160.022024 -357.384125) (xy 160.074366 -357.399489) (xy 160.123989 -357.422145) (xy 160.169883 -357.451634)
			(xy 160.211112 -357.487354) (xy 160.246837 -357.528579) (xy 160.276332 -357.574468) (xy 160.298994 -357.624089)
			(xy 160.314364 -357.676429) (xy 160.322128 -357.730425) (xy 160.322128 -357.784969) (xy 161.804831 -357.784969)
			(xy 161.804831 -357.730431) (xy 161.812593 -357.676447) (xy 161.827959 -357.624117) (xy 161.850616 -357.574507)
			(xy 161.880102 -357.528627) (xy 161.915818 -357.487409) (xy 161.957036 -357.451695) (xy 162.002918 -357.42221)
			(xy 162.052529 -357.399555) (xy 162.104859 -357.384191) (xy 162.158843 -357.376431) (xy 162.186112 -357.375968)
			(xy 163.049712 -357.375968) (xy 163.076983 -357.376395) (xy 163.130969 -357.384159) (xy 163.183302 -357.399527)
			(xy 163.232914 -357.422185) (xy 163.278797 -357.451674) (xy 163.320017 -357.487392) (xy 163.355733 -357.528612)
			(xy 163.385221 -357.574496) (xy 163.407878 -357.62411) (xy 163.423244 -357.676442) (xy 163.431006 -357.730429)
			(xy 163.431006 -357.784966) (xy 164.913854 -357.784966) (xy 164.913854 -357.730434) (xy 164.921615 -357.676457)
			(xy 164.936977 -357.624134) (xy 164.95963 -357.57453) (xy 164.989111 -357.528654) (xy 165.02482 -357.48744)
			(xy 165.066031 -357.451727) (xy 165.111905 -357.422243) (xy 165.161508 -357.399587) (xy 165.21383 -357.384221)
			(xy 165.267806 -357.376456) (xy 165.295072 -357.375968) (xy 166.158672 -357.375968) (xy 166.185946 -357.37637)
			(xy 166.239941 -357.384129) (xy 166.292281 -357.399494) (xy 166.341901 -357.422152) (xy 166.387792 -357.451641)
			(xy 166.429019 -357.487361) (xy 166.464742 -357.528585) (xy 166.494235 -357.574474) (xy 166.516896 -357.624093)
			(xy 166.532265 -357.676432) (xy 166.540028 -357.730426) (xy 166.540028 -357.78497) (xy 168.022732 -357.78497)
			(xy 168.022732 -357.73043) (xy 168.030494 -357.676444) (xy 168.045861 -357.624113) (xy 168.068519 -357.574502)
			(xy 168.098007 -357.52862) (xy 168.133725 -357.487402) (xy 168.174946 -357.451688) (xy 168.22083 -357.422203)
			(xy 168.270443 -357.399549) (xy 168.322776 -357.384187) (xy 168.376762 -357.376429) (xy 168.404032 -357.375968)
			(xy 169.267632 -357.375968) (xy 169.294902 -357.376397) (xy 169.348886 -357.384163) (xy 169.401216 -357.399532)
			(xy 169.450826 -357.422192) (xy 169.496707 -357.451681) (xy 169.537924 -357.487399) (xy 169.573638 -357.528619)
			(xy 169.603124 -357.574502) (xy 169.625779 -357.624114) (xy 169.641144 -357.676445) (xy 169.648906 -357.73043)
			(xy 169.648906 -357.784967) (xy 171.131754 -357.784967) (xy 171.131754 -357.730433) (xy 171.139515 -357.676454)
			(xy 171.154879 -357.62413) (xy 171.177533 -357.574524) (xy 171.207016 -357.528647) (xy 171.242727 -357.487433)
			(xy 171.283941 -357.45172) (xy 171.329817 -357.422237) (xy 171.379422 -357.399582) (xy 171.431747 -357.384217)
			(xy 171.485725 -357.376455) (xy 171.512992 -357.375968) (xy 172.376592 -357.375968) (xy 172.403866 -357.376371)
			(xy 172.457857 -357.384133) (xy 172.510195 -357.3995) (xy 172.559813 -357.422159) (xy 172.605702 -357.451648)
			(xy 172.646926 -357.487368) (xy 172.682647 -357.528592) (xy 172.712138 -357.57448) (xy 172.734798 -357.624097)
			(xy 172.750165 -357.676435) (xy 172.757928 -357.730426) (xy 172.757928 -357.784965) (xy 174.240754 -357.784965)
			(xy 174.240754 -357.730435) (xy 174.248514 -357.67646) (xy 174.263876 -357.624138) (xy 174.286527 -357.574535)
			(xy 174.316006 -357.52866) (xy 174.351713 -357.487447) (xy 174.392922 -357.451735) (xy 174.438793 -357.42225)
			(xy 174.488393 -357.399593) (xy 174.540713 -357.384224) (xy 174.594687 -357.376458) (xy 174.621952 -357.375968)
			(xy 175.485552 -357.375968) (xy 175.512827 -357.376368) (xy 175.566824 -357.384125) (xy 175.619166 -357.399489)
			(xy 175.668789 -357.422145) (xy 175.714683 -357.451634) (xy 175.755912 -357.487354) (xy 175.791637 -357.528579)
			(xy 175.821132 -357.574468) (xy 175.843794 -357.624089) (xy 175.859164 -357.676429) (xy 175.866928 -357.730425)
			(xy 175.866928 -357.784969) (xy 177.349631 -357.784969) (xy 177.349631 -357.730431) (xy 177.357393 -357.676447)
			(xy 177.372759 -357.624117) (xy 177.395416 -357.574507) (xy 177.424902 -357.528627) (xy 177.460618 -357.487409)
			(xy 177.501836 -357.451695) (xy 177.547718 -357.42221) (xy 177.597329 -357.399555) (xy 177.649659 -357.384191)
			(xy 177.703643 -357.376431) (xy 177.730912 -357.375968) (xy 178.594512 -357.375968) (xy 178.621783 -357.376395)
			(xy 178.675769 -357.384159) (xy 178.728102 -357.399527) (xy 178.777714 -357.422185) (xy 178.823597 -357.451674)
			(xy 178.864817 -357.487392) (xy 178.900533 -357.528612) (xy 178.930021 -357.574496) (xy 178.952678 -357.62411)
			(xy 178.968044 -357.676442) (xy 178.975806 -357.730429) (xy 178.975806 -357.784966) (xy 180.458654 -357.784966)
			(xy 180.458654 -357.730434) (xy 180.466415 -357.676457) (xy 180.481777 -357.624134) (xy 180.50443 -357.57453)
			(xy 180.533911 -357.528654) (xy 180.56962 -357.48744) (xy 180.610831 -357.451727) (xy 180.656705 -357.422243)
			(xy 180.706308 -357.399587) (xy 180.75863 -357.384221) (xy 180.812606 -357.376456) (xy 180.839872 -357.375968)
			(xy 181.703472 -357.375968) (xy 181.730746 -357.37637) (xy 181.784741 -357.384129) (xy 181.837081 -357.399494)
			(xy 181.886701 -357.422152) (xy 181.932592 -357.451641) (xy 181.973819 -357.487361) (xy 182.009542 -357.528585)
			(xy 182.039035 -357.574474) (xy 182.061696 -357.624093) (xy 182.077065 -357.676432) (xy 182.084828 -357.730426)
			(xy 182.084828 -357.761176) (xy 183.567456 -357.761176) (xy 183.567456 -357.706624) (xy 183.57522 -357.652628)
			(xy 183.590589 -357.600287) (xy 183.613252 -357.550665) (xy 183.642746 -357.504775) (xy 183.678471 -357.463549)
			(xy 183.7197 -357.427827) (xy 183.765593 -357.398337) (xy 183.815217 -357.375678) (xy 183.867559 -357.360313)
			(xy 183.921556 -357.352553) (xy 183.948832 -357.352092) (xy 184.812432 -357.352092) (xy 184.839697 -357.352672)
			(xy 184.89367 -357.360437) (xy 184.94599 -357.375803) (xy 184.99559 -357.398458) (xy 185.041461 -357.427942)
			(xy 185.08267 -357.463653) (xy 185.118378 -357.504864) (xy 185.147857 -357.550738) (xy 185.170508 -357.60034)
			(xy 185.18587 -357.652661) (xy 185.19363 -357.706635) (xy 185.19363 -357.761165) (xy 185.193629 -357.761172)
			(xy 186.676479 -357.761172) (xy 186.676479 -357.706628) (xy 186.684241 -357.652638) (xy 186.699608 -357.600303)
			(xy 186.722266 -357.550688) (xy 186.751755 -357.504801) (xy 186.787473 -357.463579) (xy 186.828695 -357.42786)
			(xy 186.87458 -357.39837) (xy 186.924196 -357.37571) (xy 186.97653 -357.360343) (xy 187.03052 -357.352579)
			(xy 187.057792 -357.352092) (xy 187.921392 -357.352092) (xy 187.94866 -357.352647) (xy 188.002641 -357.360407)
			(xy 188.054969 -357.375771) (xy 188.104577 -357.398425) (xy 188.150456 -357.427909) (xy 188.191672 -357.463622)
			(xy 188.227386 -357.504838) (xy 188.256871 -357.550716) (xy 188.279526 -357.600324) (xy 188.294891 -357.652651)
			(xy 188.302653 -357.706632) (xy 188.302653 -357.761168) (xy 188.294891 -357.815149) (xy 188.279526 -357.867476)
			(xy 188.256871 -357.917084) (xy 188.227386 -357.962962) (xy 188.223925 -357.966956) (xy 245.50903 -357.966956)
			(xy 245.50903 -357.88226) (xy 245.517081 -357.797946) (xy 245.53311 -357.71478) (xy 245.556971 -357.633513)
			(xy 245.58845 -357.554883) (xy 245.627261 -357.479602) (xy 245.673051 -357.40835) (xy 245.725407 -357.341774)
			(xy 245.783855 -357.280476) (xy 245.847865 -357.225011) (xy 245.916857 -357.175882) (xy 245.990207 -357.133533)
			(xy 246.06725 -357.098349) (xy 246.147289 -357.070647) (xy 246.229598 -357.050679) (xy 246.313433 -357.038626)
			(xy 246.398034 -357.034596) (xy 246.482635 -357.038626) (xy 246.56647 -357.050679) (xy 246.648779 -357.070647)
			(xy 246.728818 -357.098349) (xy 246.805861 -357.133533) (xy 246.879211 -357.175882) (xy 246.948203 -357.225011)
			(xy 247.012213 -357.280476) (xy 247.070661 -357.341774) (xy 247.123017 -357.40835) (xy 247.168807 -357.479602)
			(xy 247.207618 -357.554883) (xy 247.239097 -357.633513) (xy 247.262958 -357.71478) (xy 247.276485 -357.784966)
			(xy 270.624854 -357.784966) (xy 270.624854 -357.730435) (xy 270.632614 -357.676458) (xy 270.647977 -357.624136)
			(xy 270.670628 -357.574532) (xy 270.700108 -357.528657) (xy 270.735817 -357.487443) (xy 270.777026 -357.451731)
			(xy 270.822899 -357.422246) (xy 270.8725 -357.39959) (xy 270.924821 -357.384222) (xy 270.978797 -357.376457)
			(xy 271.006062 -357.375968) (xy 271.869662 -357.375968) (xy 271.896937 -357.376369) (xy 271.950932 -357.384127)
			(xy 272.003273 -357.399491) (xy 272.052895 -357.422149) (xy 272.098787 -357.451638) (xy 272.140015 -357.487358)
			(xy 272.17574 -357.528582) (xy 272.205233 -357.574471) (xy 272.227895 -357.624091) (xy 272.243265 -357.676431)
			(xy 272.251028 -357.730425) (xy 272.251028 -357.78497) (xy 273.733731 -357.78497) (xy 273.733731 -357.73043)
			(xy 273.741494 -357.676446) (xy 273.75686 -357.624115) (xy 273.779517 -357.574505) (xy 273.809005 -357.528623)
			(xy 273.844722 -357.487406) (xy 273.885941 -357.451691) (xy 273.931824 -357.422207) (xy 273.981436 -357.399552)
			(xy 274.033767 -357.384189) (xy 274.087752 -357.37643) (xy 274.115022 -357.375968) (xy 274.978622 -357.375968)
			(xy 275.005892 -357.376396) (xy 275.059878 -357.384161) (xy 275.112209 -357.399529) (xy 275.16182 -357.422189)
			(xy 275.207702 -357.451677) (xy 275.24892 -357.487395) (xy 275.284636 -357.528616) (xy 275.314122 -357.574499)
			(xy 275.336778 -357.624112) (xy 275.352144 -357.676444) (xy 275.359906 -357.730429) (xy 275.359906 -357.784966)
			(xy 276.842754 -357.784966) (xy 276.842754 -357.730434) (xy 276.850515 -357.676456) (xy 276.865878 -357.624132)
			(xy 276.888531 -357.574527) (xy 276.918013 -357.52865) (xy 276.953724 -357.487436) (xy 276.994936 -357.451724)
			(xy 277.040811 -357.42224) (xy 277.090415 -357.399584) (xy 277.142738 -357.384219) (xy 277.196716 -357.376456)
			(xy 277.223982 -357.375968) (xy 278.087582 -357.375968) (xy 278.114856 -357.37637) (xy 278.168849 -357.384131)
			(xy 278.221188 -357.399497) (xy 278.270807 -357.422155) (xy 278.316697 -357.451645) (xy 278.357922 -357.487365)
			(xy 278.393644 -357.528589) (xy 278.423136 -357.574477) (xy 278.445797 -357.624095) (xy 278.461165 -357.676433)
			(xy 278.468928 -357.730426) (xy 278.468928 -357.784971) (xy 279.951632 -357.784971) (xy 279.951632 -357.730429)
			(xy 279.959394 -357.676443) (xy 279.974761 -357.624111) (xy 279.99742 -357.574499) (xy 280.026909 -357.528617)
			(xy 280.062629 -357.487399) (xy 280.103851 -357.451684) (xy 280.149736 -357.4222) (xy 280.19935 -357.399547)
			(xy 280.251684 -357.384185) (xy 280.305671 -357.376429) (xy 280.332942 -357.375968) (xy 281.196542 -357.375968)
			(xy 281.223812 -357.376397) (xy 281.277795 -357.384165) (xy 281.330123 -357.399535) (xy 281.379732 -357.422195)
			(xy 281.425611 -357.451684) (xy 281.466827 -357.487402) (xy 281.502541 -357.528622) (xy 281.532025 -357.574505)
			(xy 281.55468 -357.624116) (xy 281.570044 -357.676446) (xy 281.577806 -357.73043) (xy 281.577806 -357.784969)
			(xy 283.060631 -357.784969) (xy 283.060631 -357.730431) (xy 283.068393 -357.676448) (xy 283.083758 -357.62412)
			(xy 283.106414 -357.57451) (xy 283.1359 -357.52863) (xy 283.171614 -357.487413) (xy 283.212832 -357.451698)
			(xy 283.258712 -357.422213) (xy 283.308321 -357.399557) (xy 283.36065 -357.384193) (xy 283.414633 -357.376431)
			(xy 283.441902 -357.375968) (xy 284.305502 -357.375968) (xy 284.332773 -357.376395) (xy 284.386761 -357.384157)
			(xy 284.439094 -357.399524) (xy 284.488708 -357.422182) (xy 284.534593 -357.45167) (xy 284.575813 -357.487388)
			(xy 284.611531 -357.528609) (xy 284.641019 -357.574493) (xy 284.663677 -357.624107) (xy 284.679043 -357.676441)
			(xy 284.686806 -357.730429) (xy 284.686806 -357.784966) (xy 286.169654 -357.784966) (xy 286.169654 -357.730435)
			(xy 286.177414 -357.676458) (xy 286.192777 -357.624136) (xy 286.215428 -357.574532) (xy 286.244908 -357.528657)
			(xy 286.280617 -357.487443) (xy 286.321826 -357.451731) (xy 286.367699 -357.422246) (xy 286.4173 -357.39959)
			(xy 286.469621 -357.384222) (xy 286.523597 -357.376457) (xy 286.550862 -357.375968) (xy 287.414462 -357.375968)
			(xy 287.441737 -357.376369) (xy 287.495732 -357.384127) (xy 287.548073 -357.399491) (xy 287.597695 -357.422149)
			(xy 287.643587 -357.451638) (xy 287.684815 -357.487358) (xy 287.72054 -357.528582) (xy 287.750033 -357.574471)
			(xy 287.772695 -357.624091) (xy 287.788065 -357.676431) (xy 287.795828 -357.730425) (xy 287.795828 -357.78497)
			(xy 289.278531 -357.78497) (xy 289.278531 -357.73043) (xy 289.286294 -357.676446) (xy 289.30166 -357.624115)
			(xy 289.324317 -357.574505) (xy 289.353805 -357.528623) (xy 289.389522 -357.487406) (xy 289.430741 -357.451691)
			(xy 289.476624 -357.422207) (xy 289.526236 -357.399552) (xy 289.578567 -357.384189) (xy 289.632552 -357.37643)
			(xy 289.659822 -357.375968) (xy 290.523422 -357.375968) (xy 290.550692 -357.376396) (xy 290.604678 -357.384161)
			(xy 290.657009 -357.399529) (xy 290.70662 -357.422189) (xy 290.752502 -357.451677) (xy 290.79372 -357.487395)
			(xy 290.829436 -357.528616) (xy 290.858922 -357.574499) (xy 290.881578 -357.624112) (xy 290.896944 -357.676444)
			(xy 290.904706 -357.730429) (xy 290.904706 -357.784966) (xy 292.387554 -357.784966) (xy 292.387554 -357.730434)
			(xy 292.395315 -357.676456) (xy 292.410678 -357.624132) (xy 292.433331 -357.574527) (xy 292.462813 -357.52865)
			(xy 292.498524 -357.487436) (xy 292.539736 -357.451724) (xy 292.585611 -357.42224) (xy 292.635215 -357.399584)
			(xy 292.687538 -357.384219) (xy 292.741516 -357.376456) (xy 292.768782 -357.375968) (xy 293.632382 -357.375968)
			(xy 293.659656 -357.37637) (xy 293.713649 -357.384131) (xy 293.765988 -357.399497) (xy 293.815607 -357.422155)
			(xy 293.861497 -357.451645) (xy 293.902722 -357.487365) (xy 293.938444 -357.528589) (xy 293.967936 -357.574477)
			(xy 293.990597 -357.624095) (xy 294.005965 -357.676433) (xy 294.013728 -357.730426) (xy 294.013728 -357.784971)
			(xy 295.496432 -357.784971) (xy 295.496432 -357.730429) (xy 295.504194 -357.676443) (xy 295.519561 -357.624111)
			(xy 295.54222 -357.574499) (xy 295.571709 -357.528617) (xy 295.607429 -357.487399) (xy 295.648651 -357.451684)
			(xy 295.694536 -357.4222) (xy 295.74415 -357.399547) (xy 295.796484 -357.384185) (xy 295.850471 -357.376429)
			(xy 295.877742 -357.375968) (xy 296.741342 -357.375968) (xy 296.768612 -357.376397) (xy 296.822595 -357.384165)
			(xy 296.874923 -357.399535) (xy 296.924532 -357.422195) (xy 296.970411 -357.451684) (xy 297.011627 -357.487402)
			(xy 297.047341 -357.528622) (xy 297.076825 -357.574505) (xy 297.09948 -357.624116) (xy 297.114844 -357.676446)
			(xy 297.122606 -357.73043) (xy 297.122606 -357.784969) (xy 298.605431 -357.784969) (xy 298.605431 -357.730431)
			(xy 298.613193 -357.676448) (xy 298.628558 -357.62412) (xy 298.651214 -357.57451) (xy 298.6807 -357.52863)
			(xy 298.716414 -357.487413) (xy 298.757632 -357.451698) (xy 298.803512 -357.422213) (xy 298.853121 -357.399557)
			(xy 298.90545 -357.384193) (xy 298.959433 -357.376431) (xy 298.986702 -357.375968) (xy 299.850302 -357.375968)
			(xy 299.877573 -357.376395) (xy 299.931561 -357.384157) (xy 299.983894 -357.399524) (xy 300.033508 -357.422182)
			(xy 300.079393 -357.45167) (xy 300.120613 -357.487388) (xy 300.156331 -357.528609) (xy 300.185819 -357.574493)
			(xy 300.208477 -357.624107) (xy 300.223843 -357.676441) (xy 300.231606 -357.730429) (xy 300.231606 -357.784966)
			(xy 315.230554 -357.784966) (xy 315.230554 -357.730434) (xy 315.238314 -357.676458) (xy 315.253677 -357.624136)
			(xy 315.276328 -357.574532) (xy 315.305809 -357.528656) (xy 315.341517 -357.487443) (xy 315.382727 -357.45173)
			(xy 315.4286 -357.422246) (xy 315.478202 -357.399589) (xy 315.530523 -357.384222) (xy 315.584498 -357.376457)
			(xy 315.611764 -357.375968) (xy 316.475364 -357.375968) (xy 316.502639 -357.376369) (xy 316.556634 -357.384128)
			(xy 316.608975 -357.399492) (xy 316.658597 -357.422149) (xy 316.704488 -357.451638) (xy 316.745716 -357.487359)
			(xy 316.78144 -357.528583) (xy 316.810933 -357.574472) (xy 316.833595 -357.624091) (xy 316.848965 -357.676431)
			(xy 316.856728 -357.730425) (xy 316.856728 -357.78497) (xy 318.339431 -357.78497) (xy 318.339431 -357.73043)
			(xy 318.347194 -357.676445) (xy 318.36256 -357.624115) (xy 318.385217 -357.574504) (xy 318.414705 -357.528623)
			(xy 318.450422 -357.487405) (xy 318.491642 -357.451691) (xy 318.537525 -357.422206) (xy 318.587137 -357.399552)
			(xy 318.639469 -357.384189) (xy 318.693454 -357.37643) (xy 318.720724 -357.375968) (xy 319.584324 -357.375968)
			(xy 319.611594 -357.376396) (xy 319.66558 -357.384161) (xy 319.71791 -357.39953) (xy 319.767521 -357.422189)
			(xy 319.813403 -357.451678) (xy 319.854621 -357.487396) (xy 319.890336 -357.528616) (xy 319.919822 -357.5745)
			(xy 319.942479 -357.624112) (xy 319.957844 -357.676444) (xy 319.965606 -357.73043) (xy 319.965606 -357.784967)
			(xy 321.448454 -357.784967) (xy 321.448454 -357.730434) (xy 321.456215 -357.676456) (xy 321.471578 -357.624131)
			(xy 321.494232 -357.574526) (xy 321.523714 -357.52865) (xy 321.559424 -357.487436) (xy 321.600637 -357.451723)
			(xy 321.646512 -357.422239) (xy 321.696116 -357.399584) (xy 321.74844 -357.384218) (xy 321.802418 -357.376455)
			(xy 321.829684 -357.375968) (xy 322.693284 -357.375968) (xy 322.720558 -357.37637) (xy 322.774551 -357.384131)
			(xy 322.826889 -357.399497) (xy 322.876508 -357.422156) (xy 322.922398 -357.451645) (xy 322.963623 -357.487366)
			(xy 322.999345 -357.528589) (xy 323.028836 -357.574477) (xy 323.051497 -357.624096) (xy 323.066865 -357.676434)
			(xy 323.074628 -357.730426) (xy 323.074628 -357.784971) (xy 324.557332 -357.784971) (xy 324.557332 -357.730429)
			(xy 324.565094 -357.676443) (xy 324.580461 -357.624111) (xy 324.603121 -357.574498) (xy 324.63261 -357.528616)
			(xy 324.668329 -357.487398) (xy 324.709551 -357.451684) (xy 324.755437 -357.422199) (xy 324.805052 -357.399546)
			(xy 324.857386 -357.384185) (xy 324.911373 -357.376428) (xy 324.938644 -357.375968) (xy 325.802244 -357.375968)
			(xy 325.829513 -357.376398) (xy 325.883497 -357.384165) (xy 325.935825 -357.399535) (xy 325.985433 -357.422196)
			(xy 326.031312 -357.451685) (xy 326.072528 -357.487403) (xy 326.108241 -357.528623) (xy 326.137725 -357.574505)
			(xy 326.16038 -357.624116) (xy 326.175744 -357.676447) (xy 326.183506 -357.73043) (xy 326.183506 -357.784969)
			(xy 327.666331 -357.784969) (xy 327.666331 -357.730431) (xy 327.674093 -357.676448) (xy 327.689458 -357.624119)
			(xy 327.712114 -357.57451) (xy 327.7416 -357.528629) (xy 327.777315 -357.487412) (xy 327.818533 -357.451698)
			(xy 327.864413 -357.422212) (xy 327.914023 -357.399557) (xy 327.966352 -357.384192) (xy 328.020335 -357.376431)
			(xy 328.047604 -357.375968) (xy 328.911204 -357.375968) (xy 328.938475 -357.376395) (xy 328.992463 -357.384158)
			(xy 329.044796 -357.399524) (xy 329.094409 -357.422183) (xy 329.140293 -357.451671) (xy 329.181514 -357.487389)
			(xy 329.217231 -357.52861) (xy 329.246719 -357.574494) (xy 329.269377 -357.624108) (xy 329.284743 -357.676441)
			(xy 329.292506 -357.730429) (xy 329.292506 -357.784966) (xy 330.775354 -357.784966) (xy 330.775354 -357.730434)
			(xy 330.783114 -357.676458) (xy 330.798477 -357.624136) (xy 330.821128 -357.574532) (xy 330.850609 -357.528656)
			(xy 330.886317 -357.487443) (xy 330.927527 -357.45173) (xy 330.9734 -357.422246) (xy 331.023002 -357.399589)
			(xy 331.075323 -357.384222) (xy 331.129298 -357.376457) (xy 331.156564 -357.375968) (xy 332.020164 -357.375968)
			(xy 332.047439 -357.376369) (xy 332.101434 -357.384128) (xy 332.153775 -357.399492) (xy 332.203397 -357.422149)
			(xy 332.249288 -357.451638) (xy 332.290516 -357.487359) (xy 332.32624 -357.528583) (xy 332.355733 -357.574472)
			(xy 332.378395 -357.624091) (xy 332.393765 -357.676431) (xy 332.401528 -357.730425) (xy 332.401528 -357.78497)
			(xy 333.884231 -357.78497) (xy 333.884231 -357.73043) (xy 333.891994 -357.676445) (xy 333.90736 -357.624115)
			(xy 333.930017 -357.574504) (xy 333.959505 -357.528623) (xy 333.995222 -357.487405) (xy 334.036442 -357.451691)
			(xy 334.082325 -357.422206) (xy 334.131937 -357.399552) (xy 334.184269 -357.384189) (xy 334.238254 -357.37643)
			(xy 334.265524 -357.375968) (xy 335.129124 -357.375968) (xy 335.156394 -357.376396) (xy 335.21038 -357.384161)
			(xy 335.26271 -357.39953) (xy 335.312321 -357.422189) (xy 335.358203 -357.451678) (xy 335.399421 -357.487396)
			(xy 335.435136 -357.528616) (xy 335.464622 -357.5745) (xy 335.487279 -357.624112) (xy 335.502644 -357.676444)
			(xy 335.510406 -357.73043) (xy 335.510406 -357.784967) (xy 336.993254 -357.784967) (xy 336.993254 -357.730434)
			(xy 337.001015 -357.676456) (xy 337.016378 -357.624131) (xy 337.039032 -357.574526) (xy 337.068514 -357.52865)
			(xy 337.104224 -357.487436) (xy 337.145437 -357.451723) (xy 337.191312 -357.422239) (xy 337.240916 -357.399584)
			(xy 337.29324 -357.384218) (xy 337.347218 -357.376455) (xy 337.374484 -357.375968) (xy 338.238084 -357.375968)
			(xy 338.265358 -357.37637) (xy 338.319351 -357.384131) (xy 338.371689 -357.399497) (xy 338.421308 -357.422156)
			(xy 338.467198 -357.451645) (xy 338.508423 -357.487366) (xy 338.544145 -357.528589) (xy 338.573636 -357.574477)
			(xy 338.596297 -357.624096) (xy 338.611665 -357.676434) (xy 338.619428 -357.730426) (xy 338.619428 -357.784971)
			(xy 340.102132 -357.784971) (xy 340.102132 -357.730429) (xy 340.109894 -357.676443) (xy 340.125261 -357.624111)
			(xy 340.147921 -357.574498) (xy 340.17741 -357.528616) (xy 340.213129 -357.487398) (xy 340.254351 -357.451684)
			(xy 340.300237 -357.422199) (xy 340.349852 -357.399546) (xy 340.402186 -357.384185) (xy 340.456173 -357.376428)
			(xy 340.483444 -357.375968) (xy 341.347044 -357.375968) (xy 341.374313 -357.376398) (xy 341.428297 -357.384165)
			(xy 341.480625 -357.399535) (xy 341.530233 -357.422196) (xy 341.576112 -357.451685) (xy 341.617328 -357.487403)
			(xy 341.653041 -357.528623) (xy 341.682525 -357.574505) (xy 341.70518 -357.624116) (xy 341.720544 -357.676447)
			(xy 341.728306 -357.73043) (xy 341.728306 -357.784969) (xy 343.211131 -357.784969) (xy 343.211131 -357.730431)
			(xy 343.218893 -357.676448) (xy 343.234258 -357.624119) (xy 343.256914 -357.57451) (xy 343.2864 -357.528629)
			(xy 343.322115 -357.487412) (xy 343.363333 -357.451698) (xy 343.409213 -357.422212) (xy 343.458823 -357.399557)
			(xy 343.511152 -357.384192) (xy 343.565135 -357.376431) (xy 343.592404 -357.375968) (xy 344.456004 -357.375968)
			(xy 344.483275 -357.376395) (xy 344.537263 -357.384158) (xy 344.589596 -357.399524) (xy 344.639209 -357.422183)
			(xy 344.685093 -357.451671) (xy 344.726314 -357.487389) (xy 344.762031 -357.52861) (xy 344.791519 -357.574494)
			(xy 344.814177 -357.624108) (xy 344.829543 -357.676441) (xy 344.837306 -357.730429) (xy 344.837306 -357.784971)
			(xy 373.915632 -357.784971) (xy 373.915632 -357.730429) (xy 373.923394 -357.676443) (xy 373.938761 -357.624111)
			(xy 373.96142 -357.574499) (xy 373.990909 -357.528617) (xy 374.026628 -357.4874) (xy 374.06785 -357.451685)
			(xy 374.113735 -357.422201) (xy 374.163349 -357.399547) (xy 374.215682 -357.384186) (xy 374.269669 -357.376429)
			(xy 374.29694 -357.375968) (xy 375.16054 -357.375968) (xy 375.18781 -357.376397) (xy 375.241793 -357.384164)
			(xy 375.294122 -357.399534) (xy 375.343731 -357.422194) (xy 375.389611 -357.451684) (xy 375.430827 -357.487402)
			(xy 375.46654 -357.528622) (xy 375.496025 -357.574504) (xy 375.51868 -357.624116) (xy 375.534044 -357.676446)
			(xy 375.541806 -357.73043) (xy 375.541806 -357.784967) (xy 377.024654 -357.784967) (xy 377.024654 -357.730433)
			(xy 377.032415 -357.676453) (xy 377.04778 -357.624128) (xy 377.070434 -357.574522) (xy 377.099918 -357.528644)
			(xy 377.13563 -357.48743) (xy 377.176844 -357.451718) (xy 377.222722 -357.422234) (xy 377.272328 -357.39958)
			(xy 377.324653 -357.384215) (xy 377.378633 -357.376454) (xy 377.4059 -357.375968) (xy 378.2695 -357.375968)
			(xy 378.296772 -357.376395) (xy 378.350759 -357.384157) (xy 378.403093 -357.399523) (xy 378.452707 -357.422181)
			(xy 378.498592 -357.451669) (xy 378.539812 -357.487388) (xy 378.575531 -357.528608) (xy 378.605019 -357.574493)
			(xy 378.627677 -357.624107) (xy 378.643043 -357.676441) (xy 378.650805 -357.730428) (xy 378.650805 -357.784965)
			(xy 380.133654 -357.784965) (xy 380.133654 -357.730435) (xy 380.141414 -357.676459) (xy 380.156776 -357.624137)
			(xy 380.179428 -357.574533) (xy 380.208908 -357.528658) (xy 380.244616 -357.487444) (xy 380.285825 -357.451732)
			(xy 380.331698 -357.422247) (xy 380.381299 -357.39959) (xy 380.43362 -357.384223) (xy 380.487595 -357.376457)
			(xy 380.51486 -357.375968) (xy 381.37846 -357.375968) (xy 381.405735 -357.376369) (xy 381.45973 -357.384127)
			(xy 381.512072 -357.399491) (xy 381.561694 -357.422148) (xy 381.607586 -357.451637) (xy 381.648815 -357.487357)
			(xy 381.684539 -357.528582) (xy 381.714033 -357.574471) (xy 381.736695 -357.62409) (xy 381.752065 -357.67643)
			(xy 381.759828 -357.730425) (xy 381.759828 -357.78497) (xy 383.242531 -357.78497) (xy 383.242531 -357.73043)
			(xy 383.250294 -357.676446) (xy 383.26566 -357.624116) (xy 383.288317 -357.574505) (xy 383.317804 -357.528624)
			(xy 383.353521 -357.487407) (xy 383.39474 -357.451692) (xy 383.440623 -357.422207) (xy 383.490234 -357.399553)
			(xy 383.542565 -357.384189) (xy 383.59655 -357.37643) (xy 383.62382 -357.375968) (xy 384.48742 -357.375968)
			(xy 384.514691 -357.376396) (xy 384.568676 -357.38416) (xy 384.621007 -357.399529) (xy 384.670619 -357.422188)
			(xy 384.716501 -357.451677) (xy 384.75772 -357.487395) (xy 384.793435 -357.528615) (xy 384.822922 -357.574499)
			(xy 384.845578 -357.624111) (xy 384.860944 -357.676443) (xy 384.868706 -357.730429) (xy 384.868706 -357.784966)
			(xy 386.351554 -357.784966) (xy 386.351554 -357.730434) (xy 386.359315 -357.676456) (xy 386.374678 -357.624132)
			(xy 386.397331 -357.574527) (xy 386.426813 -357.528651) (xy 386.462523 -357.487437) (xy 386.503735 -357.451725)
			(xy 386.54961 -357.422241) (xy 386.599213 -357.399585) (xy 386.651537 -357.384219) (xy 386.705514 -357.376456)
			(xy 386.73278 -357.375968) (xy 387.59638 -357.375968) (xy 387.623654 -357.37637) (xy 387.677647 -357.384131)
			(xy 387.729987 -357.399496) (xy 387.779606 -357.422155) (xy 387.825496 -357.451644) (xy 387.866722 -357.487364)
			(xy 387.902444 -357.528588) (xy 387.931936 -357.574476) (xy 387.954597 -357.624095) (xy 387.969965 -357.676433)
			(xy 387.977728 -357.730426) (xy 387.977728 -357.784971) (xy 389.460432 -357.784971) (xy 389.460432 -357.730429)
			(xy 389.468194 -357.676443) (xy 389.483561 -357.624111) (xy 389.50622 -357.574499) (xy 389.535709 -357.528617)
			(xy 389.571428 -357.4874) (xy 389.61265 -357.451685) (xy 389.658535 -357.422201) (xy 389.708149 -357.399547)
			(xy 389.760482 -357.384186) (xy 389.814469 -357.376429) (xy 389.84174 -357.375968) (xy 390.70534 -357.375968)
			(xy 390.73261 -357.376397) (xy 390.786593 -357.384164) (xy 390.838922 -357.399534) (xy 390.888531 -357.422194)
			(xy 390.934411 -357.451684) (xy 390.975627 -357.487402) (xy 391.01134 -357.528622) (xy 391.040825 -357.574504)
			(xy 391.06348 -357.624116) (xy 391.078844 -357.676446) (xy 391.086606 -357.73043) (xy 391.086606 -357.784967)
			(xy 392.569454 -357.784967) (xy 392.569454 -357.730433) (xy 392.577215 -357.676453) (xy 392.59258 -357.624128)
			(xy 392.615234 -357.574522) (xy 392.644718 -357.528644) (xy 392.68043 -357.48743) (xy 392.721644 -357.451718)
			(xy 392.767522 -357.422234) (xy 392.817128 -357.39958) (xy 392.869453 -357.384215) (xy 392.923433 -357.376454)
			(xy 392.9507 -357.375968) (xy 393.8143 -357.375968) (xy 393.841572 -357.376395) (xy 393.895559 -357.384157)
			(xy 393.947893 -357.399523) (xy 393.997507 -357.422181) (xy 394.043392 -357.451669) (xy 394.084612 -357.487388)
			(xy 394.120331 -357.528608) (xy 394.149819 -357.574493) (xy 394.172477 -357.624107) (xy 394.187843 -357.676441)
			(xy 394.195605 -357.730428) (xy 394.195605 -357.784965) (xy 395.678454 -357.784965) (xy 395.678454 -357.730435)
			(xy 395.686214 -357.676459) (xy 395.701576 -357.624137) (xy 395.724228 -357.574533) (xy 395.753708 -357.528658)
			(xy 395.789416 -357.487444) (xy 395.830625 -357.451732) (xy 395.876498 -357.422247) (xy 395.926099 -357.39959)
			(xy 395.97842 -357.384223) (xy 396.032395 -357.376457) (xy 396.05966 -357.375968) (xy 396.92326 -357.375968)
			(xy 396.950535 -357.376369) (xy 397.00453 -357.384127) (xy 397.056872 -357.399491) (xy 397.106494 -357.422148)
			(xy 397.152386 -357.451637) (xy 397.193615 -357.487357) (xy 397.229339 -357.528582) (xy 397.258833 -357.574471)
			(xy 397.281495 -357.62409) (xy 397.296865 -357.67643) (xy 397.304628 -357.730425) (xy 397.304628 -357.78497)
			(xy 398.787331 -357.78497) (xy 398.787331 -357.73043) (xy 398.795094 -357.676446) (xy 398.81046 -357.624116)
			(xy 398.833117 -357.574505) (xy 398.862604 -357.528624) (xy 398.898321 -357.487407) (xy 398.93954 -357.451692)
			(xy 398.985423 -357.422207) (xy 399.035034 -357.399553) (xy 399.087365 -357.384189) (xy 399.14135 -357.37643)
			(xy 399.16862 -357.375968) (xy 400.03222 -357.375968) (xy 400.059491 -357.376396) (xy 400.113476 -357.38416)
			(xy 400.165807 -357.399529) (xy 400.215419 -357.422188) (xy 400.261301 -357.451677) (xy 400.30252 -357.487395)
			(xy 400.338235 -357.528615) (xy 400.367722 -357.574499) (xy 400.390378 -357.624111) (xy 400.405744 -357.676443)
			(xy 400.413506 -357.730429) (xy 400.413506 -357.784966) (xy 401.896354 -357.784966) (xy 401.896354 -357.730434)
			(xy 401.904115 -357.676456) (xy 401.919478 -357.624132) (xy 401.942131 -357.574527) (xy 401.971613 -357.528651)
			(xy 402.007323 -357.487437) (xy 402.048535 -357.451725) (xy 402.09441 -357.422241) (xy 402.144013 -357.399585)
			(xy 402.196337 -357.384219) (xy 402.250314 -357.376456) (xy 402.27758 -357.375968) (xy 403.14118 -357.375968)
			(xy 403.168454 -357.37637) (xy 403.222447 -357.384131) (xy 403.274787 -357.399496) (xy 403.324406 -357.422155)
			(xy 403.370296 -357.451644) (xy 403.411522 -357.487364) (xy 403.447244 -357.528588) (xy 403.476736 -357.574476)
			(xy 403.499397 -357.624095) (xy 403.514765 -357.676433) (xy 403.522528 -357.730426) (xy 403.522528 -357.784965)
			(xy 412.022854 -357.784965) (xy 412.022854 -357.730435) (xy 412.030614 -357.67646) (xy 412.045976 -357.624138)
			(xy 412.068627 -357.574535) (xy 412.098106 -357.52866) (xy 412.133813 -357.487447) (xy 412.175022 -357.451735)
			(xy 412.220893 -357.42225) (xy 412.270493 -357.399593) (xy 412.322813 -357.384224) (xy 412.376787 -357.376458)
			(xy 412.404052 -357.375968) (xy 413.267652 -357.375968) (xy 413.294927 -357.376368) (xy 413.348924 -357.384125)
			(xy 413.401266 -357.399489) (xy 413.450889 -357.422145) (xy 413.496783 -357.451634) (xy 413.538012 -357.487354)
			(xy 413.573737 -357.528579) (xy 413.603232 -357.574468) (xy 413.625894 -357.624089) (xy 413.641264 -357.676429)
			(xy 413.649028 -357.730425) (xy 413.649028 -357.784969) (xy 415.131731 -357.784969) (xy 415.131731 -357.730431)
			(xy 415.139493 -357.676447) (xy 415.154859 -357.624117) (xy 415.177516 -357.574507) (xy 415.207002 -357.528627)
			(xy 415.242718 -357.487409) (xy 415.283936 -357.451695) (xy 415.329818 -357.42221) (xy 415.379429 -357.399555)
			(xy 415.431759 -357.384191) (xy 415.485743 -357.376431) (xy 415.513012 -357.375968) (xy 416.376612 -357.375968)
			(xy 416.403883 -357.376395) (xy 416.457869 -357.384159) (xy 416.510202 -357.399527) (xy 416.559814 -357.422185)
			(xy 416.605697 -357.451674) (xy 416.646917 -357.487392) (xy 416.682633 -357.528612) (xy 416.712121 -357.574496)
			(xy 416.734778 -357.62411) (xy 416.750144 -357.676442) (xy 416.757906 -357.730429) (xy 416.757906 -357.784966)
			(xy 418.240754 -357.784966) (xy 418.240754 -357.730434) (xy 418.248515 -357.676457) (xy 418.263877 -357.624134)
			(xy 418.28653 -357.57453) (xy 418.316011 -357.528654) (xy 418.35172 -357.48744) (xy 418.392931 -357.451727)
			(xy 418.438805 -357.422243) (xy 418.488408 -357.399587) (xy 418.54073 -357.384221) (xy 418.594706 -357.376456)
			(xy 418.621972 -357.375968) (xy 419.485572 -357.375968) (xy 419.512846 -357.37637) (xy 419.566841 -357.384129)
			(xy 419.619181 -357.399494) (xy 419.668801 -357.422152) (xy 419.714692 -357.451641) (xy 419.755919 -357.487361)
			(xy 419.791642 -357.528585) (xy 419.821135 -357.574474) (xy 419.843796 -357.624093) (xy 419.859165 -357.676432)
			(xy 419.866928 -357.730426) (xy 419.866928 -357.78497) (xy 421.349632 -357.78497) (xy 421.349632 -357.73043)
			(xy 421.357394 -357.676444) (xy 421.372761 -357.624113) (xy 421.395419 -357.574502) (xy 421.424907 -357.52862)
			(xy 421.460625 -357.487402) (xy 421.501846 -357.451688) (xy 421.54773 -357.422203) (xy 421.597343 -357.399549)
			(xy 421.649676 -357.384187) (xy 421.703662 -357.376429) (xy 421.730932 -357.375968) (xy 422.594532 -357.375968)
			(xy 422.621802 -357.376397) (xy 422.675786 -357.384163) (xy 422.728116 -357.399532) (xy 422.777726 -357.422192)
			(xy 422.823607 -357.451681) (xy 422.864824 -357.487399) (xy 422.900538 -357.528619) (xy 422.930024 -357.574502)
			(xy 422.952679 -357.624114) (xy 422.968044 -357.676445) (xy 422.975806 -357.73043) (xy 422.975806 -357.784967)
			(xy 424.458654 -357.784967) (xy 424.458654 -357.730433) (xy 424.466415 -357.676454) (xy 424.481779 -357.62413)
			(xy 424.504433 -357.574524) (xy 424.533916 -357.528647) (xy 424.569627 -357.487433) (xy 424.610841 -357.45172)
			(xy 424.656717 -357.422237) (xy 424.706322 -357.399582) (xy 424.758647 -357.384217) (xy 424.812625 -357.376455)
			(xy 424.839892 -357.375968) (xy 425.703492 -357.375968) (xy 425.730766 -357.376371) (xy 425.784757 -357.384133)
			(xy 425.837095 -357.3995) (xy 425.886713 -357.422159) (xy 425.932602 -357.451648) (xy 425.973826 -357.487368)
			(xy 426.009547 -357.528592) (xy 426.039038 -357.57448) (xy 426.061698 -357.624097) (xy 426.077065 -357.676435)
			(xy 426.084828 -357.730426) (xy 426.084828 -357.784965) (xy 427.567654 -357.784965) (xy 427.567654 -357.730435)
			(xy 427.575414 -357.67646) (xy 427.590776 -357.624138) (xy 427.613427 -357.574535) (xy 427.642906 -357.52866)
			(xy 427.678613 -357.487447) (xy 427.719822 -357.451735) (xy 427.765693 -357.42225) (xy 427.815293 -357.399593)
			(xy 427.867613 -357.384224) (xy 427.921587 -357.376458) (xy 427.948852 -357.375968) (xy 428.812452 -357.375968)
			(xy 428.839727 -357.376368) (xy 428.893724 -357.384125) (xy 428.946066 -357.399489) (xy 428.995689 -357.422145)
			(xy 429.041583 -357.451634) (xy 429.082812 -357.487354) (xy 429.118537 -357.528579) (xy 429.148032 -357.574468)
			(xy 429.170694 -357.624089) (xy 429.186064 -357.676429) (xy 429.193828 -357.730425) (xy 429.193828 -357.784969)
			(xy 430.676531 -357.784969) (xy 430.676531 -357.730431) (xy 430.684293 -357.676447) (xy 430.699659 -357.624117)
			(xy 430.722316 -357.574507) (xy 430.751802 -357.528627) (xy 430.787518 -357.487409) (xy 430.828736 -357.451695)
			(xy 430.874618 -357.42221) (xy 430.924229 -357.399555) (xy 430.976559 -357.384191) (xy 431.030543 -357.376431)
			(xy 431.057812 -357.375968) (xy 431.921412 -357.375968) (xy 431.948683 -357.376395) (xy 432.002669 -357.384159)
			(xy 432.055002 -357.399527) (xy 432.104614 -357.422185) (xy 432.150497 -357.451674) (xy 432.191717 -357.487392)
			(xy 432.227433 -357.528612) (xy 432.256921 -357.574496) (xy 432.279578 -357.62411) (xy 432.294944 -357.676442)
			(xy 432.302706 -357.730429) (xy 432.302706 -357.784966) (xy 433.785554 -357.784966) (xy 433.785554 -357.730434)
			(xy 433.793315 -357.676457) (xy 433.808677 -357.624134) (xy 433.83133 -357.57453) (xy 433.860811 -357.528654)
			(xy 433.89652 -357.48744) (xy 433.937731 -357.451727) (xy 433.983605 -357.422243) (xy 434.033208 -357.399587)
			(xy 434.08553 -357.384221) (xy 434.139506 -357.376456) (xy 434.166772 -357.375968) (xy 435.030372 -357.375968)
			(xy 435.057646 -357.37637) (xy 435.111641 -357.384129) (xy 435.163981 -357.399494) (xy 435.213601 -357.422152)
			(xy 435.259492 -357.451641) (xy 435.300719 -357.487361) (xy 435.336442 -357.528585) (xy 435.365935 -357.574474)
			(xy 435.388596 -357.624093) (xy 435.403965 -357.676432) (xy 435.411728 -357.730426) (xy 435.411728 -357.78497)
			(xy 436.894432 -357.78497) (xy 436.894432 -357.73043) (xy 436.902194 -357.676444) (xy 436.917561 -357.624113)
			(xy 436.940219 -357.574502) (xy 436.969707 -357.52862) (xy 437.005425 -357.487402) (xy 437.046646 -357.451688)
			(xy 437.09253 -357.422203) (xy 437.142143 -357.399549) (xy 437.194476 -357.384187) (xy 437.248462 -357.376429)
			(xy 437.275732 -357.375968) (xy 438.139332 -357.375968) (xy 438.166602 -357.376397) (xy 438.220586 -357.384163)
			(xy 438.272916 -357.399532) (xy 438.322526 -357.422192) (xy 438.368407 -357.451681) (xy 438.409624 -357.487399)
			(xy 438.445338 -357.528619) (xy 438.474824 -357.574502) (xy 438.497479 -357.624114) (xy 438.512844 -357.676445)
			(xy 438.520606 -357.73043) (xy 438.520606 -357.784967) (xy 440.003454 -357.784967) (xy 440.003454 -357.730433)
			(xy 440.011215 -357.676454) (xy 440.026579 -357.62413) (xy 440.049233 -357.574524) (xy 440.078716 -357.528647)
			(xy 440.114427 -357.487433) (xy 440.155641 -357.45172) (xy 440.201517 -357.422237) (xy 440.251122 -357.399582)
			(xy 440.303447 -357.384217) (xy 440.357425 -357.376455) (xy 440.384692 -357.375968) (xy 441.248292 -357.375968)
			(xy 441.275566 -357.376371) (xy 441.329557 -357.384133) (xy 441.381895 -357.3995) (xy 441.431513 -357.422159)
			(xy 441.477402 -357.451648) (xy 441.518626 -357.487368) (xy 441.554347 -357.528592) (xy 441.583838 -357.57448)
			(xy 441.606498 -357.624097) (xy 441.621865 -357.676435) (xy 441.629628 -357.730426) (xy 441.629628 -357.784974)
			(xy 441.621865 -357.838965) (xy 441.606498 -357.891303) (xy 441.583838 -357.94092) (xy 441.554347 -357.986808)
			(xy 441.518626 -358.028032) (xy 441.477402 -358.063752) (xy 441.431513 -358.093241) (xy 441.381895 -358.1159)
			(xy 441.329557 -358.131267) (xy 441.275566 -358.139029) (xy 441.248292 -358.139492) (xy 440.384692 -358.139492)
			(xy 440.357425 -358.138945) (xy 440.303447 -358.131183) (xy 440.251122 -358.115818) (xy 440.201517 -358.093163)
			(xy 440.155641 -358.06368) (xy 440.114427 -358.027967) (xy 440.078716 -357.986753) (xy 440.049233 -357.940876)
			(xy 440.026579 -357.89127) (xy 440.011215 -357.838946) (xy 440.003454 -357.784967) (xy 438.520606 -357.784967)
			(xy 438.520606 -357.78497) (xy 438.512844 -357.838955) (xy 438.497479 -357.891286) (xy 438.474824 -357.940898)
			(xy 438.445338 -357.986781) (xy 438.409624 -358.028001) (xy 438.368407 -358.063719) (xy 438.322526 -358.093208)
			(xy 438.272916 -358.115868) (xy 438.220586 -358.131237) (xy 438.166602 -358.139003) (xy 438.139332 -358.139492)
			(xy 437.275732 -358.139492) (xy 437.248462 -358.138971) (xy 437.194476 -358.131213) (xy 437.142143 -358.115851)
			(xy 437.09253 -358.093197) (xy 437.046646 -358.063712) (xy 437.005425 -358.027998) (xy 436.969707 -357.98678)
			(xy 436.940219 -357.940898) (xy 436.917561 -357.891287) (xy 436.902194 -357.838956) (xy 436.894432 -357.78497)
			(xy 435.411728 -357.78497) (xy 435.411728 -357.784974) (xy 435.403965 -357.838968) (xy 435.388596 -357.891307)
			(xy 435.365935 -357.940926) (xy 435.336442 -357.986815) (xy 435.300719 -358.028039) (xy 435.259492 -358.063759)
			(xy 435.213601 -358.093248) (xy 435.163981 -358.115906) (xy 435.111641 -358.131271) (xy 435.057646 -358.13903)
			(xy 435.030372 -358.139492) (xy 434.166772 -358.139492) (xy 434.139506 -358.138944) (xy 434.08553 -358.131179)
			(xy 434.033208 -358.115813) (xy 433.983605 -358.093157) (xy 433.937731 -358.063673) (xy 433.89652 -358.02796)
			(xy 433.860811 -357.986746) (xy 433.83133 -357.94087) (xy 433.808677 -357.891266) (xy 433.793315 -357.838943)
			(xy 433.785554 -357.784966) (xy 432.302706 -357.784966) (xy 432.302706 -357.784971) (xy 432.294944 -357.838958)
			(xy 432.279578 -357.89129) (xy 432.256921 -357.940904) (xy 432.227433 -357.986788) (xy 432.191717 -358.028008)
			(xy 432.150497 -358.063726) (xy 432.104614 -358.093215) (xy 432.055002 -358.115873) (xy 432.002669 -358.131241)
			(xy 431.948683 -358.139005) (xy 431.921412 -358.139492) (xy 431.057812 -358.139492) (xy 431.030543 -358.138969)
			(xy 430.976559 -358.131209) (xy 430.924229 -358.115845) (xy 430.874618 -358.09319) (xy 430.828736 -358.063705)
			(xy 430.787518 -358.027991) (xy 430.751802 -357.986773) (xy 430.722316 -357.940893) (xy 430.699659 -357.891283)
			(xy 430.684293 -357.838953) (xy 430.676531 -357.784969) (xy 429.193828 -357.784969) (xy 429.193828 -357.784975)
			(xy 429.186064 -357.838971) (xy 429.170694 -357.891311) (xy 429.148032 -357.940932) (xy 429.118537 -357.986821)
			(xy 429.082812 -358.028046) (xy 429.041583 -358.063766) (xy 428.995689 -358.093255) (xy 428.946066 -358.115911)
			(xy 428.893724 -358.131275) (xy 428.839727 -358.139032) (xy 428.812452 -358.139492) (xy 427.948852 -358.139492)
			(xy 427.921587 -358.138942) (xy 427.867613 -358.131176) (xy 427.815293 -358.115807) (xy 427.765693 -358.09315)
			(xy 427.719822 -358.063665) (xy 427.678613 -358.027953) (xy 427.642906 -357.98674) (xy 427.613427 -357.940865)
			(xy 427.590776 -357.891262) (xy 427.575414 -357.83894) (xy 427.567654 -357.784965) (xy 426.084828 -357.784965)
			(xy 426.084828 -357.784974) (xy 426.077065 -357.838965) (xy 426.061698 -357.891303) (xy 426.039038 -357.94092)
			(xy 426.009547 -357.986808) (xy 425.973826 -358.028032) (xy 425.932602 -358.063752) (xy 425.886713 -358.093241)
			(xy 425.837095 -358.1159) (xy 425.784757 -358.131267) (xy 425.730766 -358.139029) (xy 425.703492 -358.139492)
			(xy 424.839892 -358.139492) (xy 424.812625 -358.138945) (xy 424.758647 -358.131183) (xy 424.706322 -358.115818)
			(xy 424.656717 -358.093163) (xy 424.610841 -358.06368) (xy 424.569627 -358.027967) (xy 424.533916 -357.986753)
			(xy 424.504433 -357.940876) (xy 424.481779 -357.89127) (xy 424.466415 -357.838946) (xy 424.458654 -357.784967)
			(xy 422.975806 -357.784967) (xy 422.975806 -357.78497) (xy 422.968044 -357.838955) (xy 422.952679 -357.891286)
			(xy 422.930024 -357.940898) (xy 422.900538 -357.986781) (xy 422.864824 -358.028001) (xy 422.823607 -358.063719)
			(xy 422.777726 -358.093208) (xy 422.728116 -358.115868) (xy 422.675786 -358.131237) (xy 422.621802 -358.139003)
			(xy 422.594532 -358.139492) (xy 421.730932 -358.139492) (xy 421.703662 -358.138971) (xy 421.649676 -358.131213)
			(xy 421.597343 -358.115851) (xy 421.54773 -358.093197) (xy 421.501846 -358.063712) (xy 421.460625 -358.027998)
			(xy 421.424907 -357.98678) (xy 421.395419 -357.940898) (xy 421.372761 -357.891287) (xy 421.357394 -357.838956)
			(xy 421.349632 -357.78497) (xy 419.866928 -357.78497) (xy 419.866928 -357.784974) (xy 419.859165 -357.838968)
			(xy 419.843796 -357.891307) (xy 419.821135 -357.940926) (xy 419.791642 -357.986815) (xy 419.755919 -358.028039)
			(xy 419.714692 -358.063759) (xy 419.668801 -358.093248) (xy 419.619181 -358.115906) (xy 419.566841 -358.131271)
			(xy 419.512846 -358.13903) (xy 419.485572 -358.139492) (xy 418.621972 -358.139492) (xy 418.594706 -358.138944)
			(xy 418.54073 -358.131179) (xy 418.488408 -358.115813) (xy 418.438805 -358.093157) (xy 418.392931 -358.063673)
			(xy 418.35172 -358.02796) (xy 418.316011 -357.986746) (xy 418.28653 -357.94087) (xy 418.263877 -357.891266)
			(xy 418.248515 -357.838943) (xy 418.240754 -357.784966) (xy 416.757906 -357.784966) (xy 416.757906 -357.784971)
			(xy 416.750144 -357.838958) (xy 416.734778 -357.89129) (xy 416.712121 -357.940904) (xy 416.682633 -357.986788)
			(xy 416.646917 -358.028008) (xy 416.605697 -358.063726) (xy 416.559814 -358.093215) (xy 416.510202 -358.115873)
			(xy 416.457869 -358.131241) (xy 416.403883 -358.139005) (xy 416.376612 -358.139492) (xy 415.513012 -358.139492)
			(xy 415.485743 -358.138969) (xy 415.431759 -358.131209) (xy 415.379429 -358.115845) (xy 415.329818 -358.09319)
			(xy 415.283936 -358.063705) (xy 415.242718 -358.027991) (xy 415.207002 -357.986773) (xy 415.177516 -357.940893)
			(xy 415.154859 -357.891283) (xy 415.139493 -357.838953) (xy 415.131731 -357.784969) (xy 413.649028 -357.784969)
			(xy 413.649028 -357.784975) (xy 413.641264 -357.838971) (xy 413.625894 -357.891311) (xy 413.603232 -357.940932)
			(xy 413.573737 -357.986821) (xy 413.538012 -358.028046) (xy 413.496783 -358.063766) (xy 413.450889 -358.093255)
			(xy 413.401266 -358.115911) (xy 413.348924 -358.131275) (xy 413.294927 -358.139032) (xy 413.267652 -358.139492)
			(xy 412.404052 -358.139492) (xy 412.376787 -358.138942) (xy 412.322813 -358.131176) (xy 412.270493 -358.115807)
			(xy 412.220893 -358.09315) (xy 412.175022 -358.063665) (xy 412.133813 -358.027953) (xy 412.098106 -357.98674)
			(xy 412.068627 -357.940865) (xy 412.045976 -357.891262) (xy 412.030614 -357.83894) (xy 412.022854 -357.784965)
			(xy 403.522528 -357.784965) (xy 403.522528 -357.784974) (xy 403.514765 -357.838967) (xy 403.499397 -357.891305)
			(xy 403.476736 -357.940924) (xy 403.447244 -357.986812) (xy 403.411522 -358.028036) (xy 403.370296 -358.063756)
			(xy 403.324406 -358.093245) (xy 403.274787 -358.115904) (xy 403.222447 -358.131269) (xy 403.168454 -358.13903)
			(xy 403.14118 -358.139492) (xy 402.27758 -358.139492) (xy 402.250314 -358.138944) (xy 402.196337 -358.131181)
			(xy 402.144013 -358.115815) (xy 402.09441 -358.093159) (xy 402.048535 -358.063675) (xy 402.007323 -358.027963)
			(xy 401.971613 -357.986749) (xy 401.942131 -357.940873) (xy 401.919478 -357.891268) (xy 401.904115 -357.838944)
			(xy 401.896354 -357.784966) (xy 400.413506 -357.784966) (xy 400.413506 -357.784971) (xy 400.405744 -357.838957)
			(xy 400.390378 -357.891289) (xy 400.367722 -357.940901) (xy 400.338235 -357.986785) (xy 400.30252 -358.028005)
			(xy 400.261301 -358.063723) (xy 400.215419 -358.093212) (xy 400.165807 -358.115871) (xy 400.113476 -358.13124)
			(xy 400.059491 -358.139004) (xy 400.03222 -358.139492) (xy 399.16862 -358.139492) (xy 399.14135 -358.13897)
			(xy 399.087365 -358.131211) (xy 399.035034 -358.115847) (xy 398.985423 -358.093193) (xy 398.93954 -358.063708)
			(xy 398.898321 -358.027993) (xy 398.862604 -357.986776) (xy 398.833117 -357.940895) (xy 398.81046 -357.891284)
			(xy 398.795094 -357.838954) (xy 398.787331 -357.78497) (xy 397.304628 -357.78497) (xy 397.304628 -357.784975)
			(xy 397.296865 -357.83897) (xy 397.281495 -357.89131) (xy 397.258833 -357.940929) (xy 397.229339 -357.986818)
			(xy 397.193615 -358.028043) (xy 397.152386 -358.063763) (xy 397.106494 -358.093252) (xy 397.056872 -358.115909)
			(xy 397.00453 -358.131273) (xy 396.950535 -358.139031) (xy 396.92326 -358.139492) (xy 396.05966 -358.139492)
			(xy 396.032395 -358.138943) (xy 395.97842 -358.131177) (xy 395.926099 -358.11581) (xy 395.876498 -358.093153)
			(xy 395.830625 -358.063668) (xy 395.789416 -358.027956) (xy 395.753708 -357.986742) (xy 395.724228 -357.940867)
			(xy 395.701576 -357.891263) (xy 395.686214 -357.838941) (xy 395.678454 -357.784965) (xy 394.195605 -357.784965)
			(xy 394.195605 -357.784972) (xy 394.187843 -357.838959) (xy 394.172477 -357.891293) (xy 394.149819 -357.940907)
			(xy 394.120331 -357.986792) (xy 394.084612 -358.028012) (xy 394.043392 -358.063731) (xy 393.997507 -358.093219)
			(xy 393.947893 -358.115877) (xy 393.895559 -358.131243) (xy 393.841572 -358.139005) (xy 393.8143 -358.139492)
			(xy 392.9507 -358.139492) (xy 392.923433 -358.138946) (xy 392.869453 -358.131185) (xy 392.817128 -358.11582)
			(xy 392.767522 -358.093166) (xy 392.721644 -358.063682) (xy 392.68043 -358.02797) (xy 392.644718 -357.986756)
			(xy 392.615234 -357.940878) (xy 392.59258 -357.891272) (xy 392.577215 -357.838947) (xy 392.569454 -357.784967)
			(xy 391.086606 -357.784967) (xy 391.086606 -357.78497) (xy 391.078844 -357.838954) (xy 391.06348 -357.891284)
			(xy 391.040825 -357.940896) (xy 391.01134 -357.986778) (xy 390.975627 -358.027998) (xy 390.934411 -358.063716)
			(xy 390.888531 -358.093206) (xy 390.838922 -358.115866) (xy 390.786593 -358.131236) (xy 390.73261 -358.139003)
			(xy 390.70534 -358.139492) (xy 389.84174 -358.139492) (xy 389.814469 -358.138971) (xy 389.760482 -358.131214)
			(xy 389.708149 -358.115853) (xy 389.658535 -358.093199) (xy 389.61265 -358.063715) (xy 389.571428 -358.028)
			(xy 389.535709 -357.986783) (xy 389.50622 -357.940901) (xy 389.483561 -357.891289) (xy 389.468194 -357.838957)
			(xy 389.460432 -357.784971) (xy 387.977728 -357.784971) (xy 387.977728 -357.784974) (xy 387.969965 -357.838967)
			(xy 387.954597 -357.891305) (xy 387.931936 -357.940924) (xy 387.902444 -357.986812) (xy 387.866722 -358.028036)
			(xy 387.825496 -358.063756) (xy 387.779606 -358.093245) (xy 387.729987 -358.115904) (xy 387.677647 -358.131269)
			(xy 387.623654 -358.13903) (xy 387.59638 -358.139492) (xy 386.73278 -358.139492) (xy 386.705514 -358.138944)
			(xy 386.651537 -358.131181) (xy 386.599213 -358.115815) (xy 386.54961 -358.093159) (xy 386.503735 -358.063675)
			(xy 386.462523 -358.027963) (xy 386.426813 -357.986749) (xy 386.397331 -357.940873) (xy 386.374678 -357.891268)
			(xy 386.359315 -357.838944) (xy 386.351554 -357.784966) (xy 384.868706 -357.784966) (xy 384.868706 -357.784971)
			(xy 384.860944 -357.838957) (xy 384.845578 -357.891289) (xy 384.822922 -357.940901) (xy 384.793435 -357.986785)
			(xy 384.75772 -358.028005) (xy 384.716501 -358.063723) (xy 384.670619 -358.093212) (xy 384.621007 -358.115871)
			(xy 384.568676 -358.13124) (xy 384.514691 -358.139004) (xy 384.48742 -358.139492) (xy 383.62382 -358.139492)
			(xy 383.59655 -358.13897) (xy 383.542565 -358.131211) (xy 383.490234 -358.115847) (xy 383.440623 -358.093193)
			(xy 383.39474 -358.063708) (xy 383.353521 -358.027993) (xy 383.317804 -357.986776) (xy 383.288317 -357.940895)
			(xy 383.26566 -357.891284) (xy 383.250294 -357.838954) (xy 383.242531 -357.78497) (xy 381.759828 -357.78497)
			(xy 381.759828 -357.784975) (xy 381.752065 -357.83897) (xy 381.736695 -357.89131) (xy 381.714033 -357.940929)
			(xy 381.684539 -357.986818) (xy 381.648815 -358.028043) (xy 381.607586 -358.063763) (xy 381.561694 -358.093252)
			(xy 381.512072 -358.115909) (xy 381.45973 -358.131273) (xy 381.405735 -358.139031) (xy 381.37846 -358.139492)
			(xy 380.51486 -358.139492) (xy 380.487595 -358.138943) (xy 380.43362 -358.131177) (xy 380.381299 -358.11581)
			(xy 380.331698 -358.093153) (xy 380.285825 -358.063668) (xy 380.244616 -358.027956) (xy 380.208908 -357.986742)
			(xy 380.179428 -357.940867) (xy 380.156776 -357.891263) (xy 380.141414 -357.838941) (xy 380.133654 -357.784965)
			(xy 378.650805 -357.784965) (xy 378.650805 -357.784972) (xy 378.643043 -357.838959) (xy 378.627677 -357.891293)
			(xy 378.605019 -357.940907) (xy 378.575531 -357.986792) (xy 378.539812 -358.028012) (xy 378.498592 -358.063731)
			(xy 378.452707 -358.093219) (xy 378.403093 -358.115877) (xy 378.350759 -358.131243) (xy 378.296772 -358.139005)
			(xy 378.2695 -358.139492) (xy 377.4059 -358.139492) (xy 377.378633 -358.138946) (xy 377.324653 -358.131185)
			(xy 377.272328 -358.11582) (xy 377.222722 -358.093166) (xy 377.176844 -358.063682) (xy 377.13563 -358.02797)
			(xy 377.099918 -357.986756) (xy 377.070434 -357.940878) (xy 377.04778 -357.891272) (xy 377.032415 -357.838947)
			(xy 377.024654 -357.784967) (xy 375.541806 -357.784967) (xy 375.541806 -357.78497) (xy 375.534044 -357.838954)
			(xy 375.51868 -357.891284) (xy 375.496025 -357.940896) (xy 375.46654 -357.986778) (xy 375.430827 -358.027998)
			(xy 375.389611 -358.063716) (xy 375.343731 -358.093206) (xy 375.294122 -358.115866) (xy 375.241793 -358.131236)
			(xy 375.18781 -358.139003) (xy 375.16054 -358.139492) (xy 374.29694 -358.139492) (xy 374.269669 -358.138971)
			(xy 374.215682 -358.131214) (xy 374.163349 -358.115853) (xy 374.113735 -358.093199) (xy 374.06785 -358.063715)
			(xy 374.026628 -358.028) (xy 373.990909 -357.986783) (xy 373.96142 -357.940901) (xy 373.938761 -357.891289)
			(xy 373.923394 -357.838957) (xy 373.915632 -357.784971) (xy 344.837306 -357.784971) (xy 344.829543 -357.838959)
			(xy 344.814177 -357.891292) (xy 344.791519 -357.940906) (xy 344.762031 -357.98679) (xy 344.726314 -358.028011)
			(xy 344.685093 -358.063729) (xy 344.639209 -358.093217) (xy 344.589596 -358.115876) (xy 344.537263 -358.131242)
			(xy 344.483275 -358.139005) (xy 344.456004 -358.139492) (xy 343.592404 -358.139492) (xy 343.565135 -358.138969)
			(xy 343.511152 -358.131208) (xy 343.458823 -358.115843) (xy 343.409213 -358.093188) (xy 343.363333 -358.063702)
			(xy 343.322115 -358.027988) (xy 343.2864 -357.986771) (xy 343.256914 -357.94089) (xy 343.234258 -357.891281)
			(xy 343.218893 -357.838952) (xy 343.211131 -357.784969) (xy 341.728306 -357.784969) (xy 341.728306 -357.78497)
			(xy 341.720544 -357.838953) (xy 341.70518 -357.891284) (xy 341.682525 -357.940895) (xy 341.653041 -357.986777)
			(xy 341.617328 -358.027997) (xy 341.576112 -358.063715) (xy 341.530233 -358.093204) (xy 341.480625 -358.115865)
			(xy 341.428297 -358.131235) (xy 341.374313 -358.139002) (xy 341.347044 -358.139492) (xy 340.483444 -358.139492)
			(xy 340.456173 -358.138972) (xy 340.402186 -358.131215) (xy 340.349852 -358.115854) (xy 340.300237 -358.093201)
			(xy 340.254351 -358.063716) (xy 340.213129 -358.028002) (xy 340.17741 -357.986784) (xy 340.147921 -357.940902)
			(xy 340.125261 -357.891289) (xy 340.109894 -357.838957) (xy 340.102132 -357.784971) (xy 338.619428 -357.784971)
			(xy 338.619428 -357.784974) (xy 338.611665 -357.838966) (xy 338.596297 -357.891304) (xy 338.573636 -357.940923)
			(xy 338.544145 -357.986811) (xy 338.508423 -358.028034) (xy 338.467198 -358.063755) (xy 338.421308 -358.093244)
			(xy 338.371689 -358.115903) (xy 338.319351 -358.131269) (xy 338.265358 -358.13903) (xy 338.238084 -358.139492)
			(xy 337.374484 -358.139492) (xy 337.347218 -358.138945) (xy 337.29324 -358.131182) (xy 337.240916 -358.115816)
			(xy 337.191312 -358.093161) (xy 337.145437 -358.063677) (xy 337.104224 -358.027964) (xy 337.068514 -357.98675)
			(xy 337.039032 -357.940874) (xy 337.016378 -357.891269) (xy 337.001015 -357.838944) (xy 336.993254 -357.784967)
			(xy 335.510406 -357.784967) (xy 335.510406 -357.78497) (xy 335.502644 -357.838956) (xy 335.487279 -357.891288)
			(xy 335.464622 -357.9409) (xy 335.435136 -357.986784) (xy 335.399421 -358.028004) (xy 335.358203 -358.063722)
			(xy 335.312321 -358.093211) (xy 335.26271 -358.11587) (xy 335.21038 -358.131239) (xy 335.156394 -358.139004)
			(xy 335.129124 -358.139492) (xy 334.265524 -358.139492) (xy 334.238254 -358.13897) (xy 334.184269 -358.131211)
			(xy 334.131937 -358.115848) (xy 334.082325 -358.093194) (xy 334.036442 -358.063709) (xy 333.995222 -358.027995)
			(xy 333.959505 -357.986777) (xy 333.930017 -357.940896) (xy 333.90736 -357.891285) (xy 333.891994 -357.838955)
			(xy 333.884231 -357.78497) (xy 332.401528 -357.78497) (xy 332.401528 -357.784975) (xy 332.393765 -357.838969)
			(xy 332.378395 -357.891309) (xy 332.355733 -357.940928) (xy 332.32624 -357.986817) (xy 332.290516 -358.028041)
			(xy 332.249288 -358.063762) (xy 332.203397 -358.093251) (xy 332.153775 -358.115908) (xy 332.101434 -358.131272)
			(xy 332.047439 -358.139031) (xy 332.020164 -358.139492) (xy 331.156564 -358.139492) (xy 331.129298 -358.138943)
			(xy 331.075323 -358.131178) (xy 331.023002 -358.115811) (xy 330.9734 -358.093154) (xy 330.927527 -358.06367)
			(xy 330.886317 -358.027957) (xy 330.850609 -357.986744) (xy 330.821128 -357.940868) (xy 330.798477 -357.891264)
			(xy 330.783114 -357.838942) (xy 330.775354 -357.784966) (xy 329.292506 -357.784966) (xy 329.292506 -357.784971)
			(xy 329.284743 -357.838959) (xy 329.269377 -357.891292) (xy 329.246719 -357.940906) (xy 329.217231 -357.98679)
			(xy 329.181514 -358.028011) (xy 329.140293 -358.063729) (xy 329.094409 -358.093217) (xy 329.044796 -358.115876)
			(xy 328.992463 -358.131242) (xy 328.938475 -358.139005) (xy 328.911204 -358.139492) (xy 328.047604 -358.139492)
			(xy 328.020335 -358.138969) (xy 327.966352 -358.131208) (xy 327.914023 -358.115843) (xy 327.864413 -358.093188)
			(xy 327.818533 -358.063702) (xy 327.777315 -358.027988) (xy 327.7416 -357.986771) (xy 327.712114 -357.94089)
			(xy 327.689458 -357.891281) (xy 327.674093 -357.838952) (xy 327.666331 -357.784969) (xy 326.183506 -357.784969)
			(xy 326.183506 -357.78497) (xy 326.175744 -357.838953) (xy 326.16038 -357.891284) (xy 326.137725 -357.940895)
			(xy 326.108241 -357.986777) (xy 326.072528 -358.027997) (xy 326.031312 -358.063715) (xy 325.985433 -358.093204)
			(xy 325.935825 -358.115865) (xy 325.883497 -358.131235) (xy 325.829513 -358.139002) (xy 325.802244 -358.139492)
			(xy 324.938644 -358.139492) (xy 324.911373 -358.138972) (xy 324.857386 -358.131215) (xy 324.805052 -358.115854)
			(xy 324.755437 -358.093201) (xy 324.709551 -358.063716) (xy 324.668329 -358.028002) (xy 324.63261 -357.986784)
			(xy 324.603121 -357.940902) (xy 324.580461 -357.891289) (xy 324.565094 -357.838957) (xy 324.557332 -357.784971)
			(xy 323.074628 -357.784971) (xy 323.074628 -357.784974) (xy 323.066865 -357.838966) (xy 323.051497 -357.891304)
			(xy 323.028836 -357.940923) (xy 322.999345 -357.986811) (xy 322.963623 -358.028034) (xy 322.922398 -358.063755)
			(xy 322.876508 -358.093244) (xy 322.826889 -358.115903) (xy 322.774551 -358.131269) (xy 322.720558 -358.13903)
			(xy 322.693284 -358.139492) (xy 321.829684 -358.139492) (xy 321.802418 -358.138945) (xy 321.74844 -358.131182)
			(xy 321.696116 -358.115816) (xy 321.646512 -358.093161) (xy 321.600637 -358.063677) (xy 321.559424 -358.027964)
			(xy 321.523714 -357.98675) (xy 321.494232 -357.940874) (xy 321.471578 -357.891269) (xy 321.456215 -357.838944)
			(xy 321.448454 -357.784967) (xy 319.965606 -357.784967) (xy 319.965606 -357.78497) (xy 319.957844 -357.838956)
			(xy 319.942479 -357.891288) (xy 319.919822 -357.9409) (xy 319.890336 -357.986784) (xy 319.854621 -358.028004)
			(xy 319.813403 -358.063722) (xy 319.767521 -358.093211) (xy 319.71791 -358.11587) (xy 319.66558 -358.131239)
			(xy 319.611594 -358.139004) (xy 319.584324 -358.139492) (xy 318.720724 -358.139492) (xy 318.693454 -358.13897)
			(xy 318.639469 -358.131211) (xy 318.587137 -358.115848) (xy 318.537525 -358.093194) (xy 318.491642 -358.063709)
			(xy 318.450422 -358.027995) (xy 318.414705 -357.986777) (xy 318.385217 -357.940896) (xy 318.36256 -357.891285)
			(xy 318.347194 -357.838955) (xy 318.339431 -357.78497) (xy 316.856728 -357.78497) (xy 316.856728 -357.784975)
			(xy 316.848965 -357.838969) (xy 316.833595 -357.891309) (xy 316.810933 -357.940928) (xy 316.78144 -357.986817)
			(xy 316.745716 -358.028041) (xy 316.704488 -358.063762) (xy 316.658597 -358.093251) (xy 316.608975 -358.115908)
			(xy 316.556634 -358.131272) (xy 316.502639 -358.139031) (xy 316.475364 -358.139492) (xy 315.611764 -358.139492)
			(xy 315.584498 -358.138943) (xy 315.530523 -358.131178) (xy 315.478202 -358.115811) (xy 315.4286 -358.093154)
			(xy 315.382727 -358.06367) (xy 315.341517 -358.027957) (xy 315.305809 -357.986744) (xy 315.276328 -357.940868)
			(xy 315.253677 -357.891264) (xy 315.238314 -357.838942) (xy 315.230554 -357.784966) (xy 300.231606 -357.784966)
			(xy 300.231606 -357.784971) (xy 300.223843 -357.838959) (xy 300.208477 -357.891293) (xy 300.185819 -357.940907)
			(xy 300.156331 -357.986791) (xy 300.120613 -358.028012) (xy 300.079393 -358.06373) (xy 300.033508 -358.093218)
			(xy 299.983894 -358.115876) (xy 299.931561 -358.131243) (xy 299.877573 -358.139005) (xy 299.850302 -358.139492)
			(xy 298.986702 -358.139492) (xy 298.959433 -358.138969) (xy 298.90545 -358.131207) (xy 298.853121 -358.115843)
			(xy 298.803512 -358.093187) (xy 298.757632 -358.063702) (xy 298.716414 -358.027987) (xy 298.6807 -357.98677)
			(xy 298.651214 -357.94089) (xy 298.628558 -357.89128) (xy 298.613193 -357.838952) (xy 298.605431 -357.784969)
			(xy 297.122606 -357.784969) (xy 297.122606 -357.78497) (xy 297.114844 -357.838954) (xy 297.09948 -357.891284)
			(xy 297.076825 -357.940895) (xy 297.047341 -357.986778) (xy 297.011627 -358.027998) (xy 296.970411 -358.063716)
			(xy 296.924532 -358.093205) (xy 296.874923 -358.115865) (xy 296.822595 -358.131235) (xy 296.768612 -358.139003)
			(xy 296.741342 -358.139492) (xy 295.877742 -358.139492) (xy 295.850471 -358.138971) (xy 295.796484 -358.131215)
			(xy 295.74415 -358.115853) (xy 295.694536 -358.0932) (xy 295.64865 -358.063716) (xy 295.607429 -358.028001)
			(xy 295.571709 -357.986783) (xy 295.54222 -357.940901) (xy 295.519561 -357.891289) (xy 295.504194 -357.838957)
			(xy 295.496432 -357.784971) (xy 294.013728 -357.784971) (xy 294.013728 -357.784974) (xy 294.005965 -357.838967)
			(xy 293.990597 -357.891305) (xy 293.967936 -357.940923) (xy 293.938444 -357.986811) (xy 293.902722 -358.028035)
			(xy 293.861497 -358.063755) (xy 293.815607 -358.093245) (xy 293.765988 -358.115903) (xy 293.713649 -358.131269)
			(xy 293.659656 -358.13903) (xy 293.632382 -358.139492) (xy 292.768782 -358.139492) (xy 292.741516 -358.138944)
			(xy 292.687538 -358.131181) (xy 292.635215 -358.115816) (xy 292.585611 -358.09316) (xy 292.539736 -358.063676)
			(xy 292.498524 -358.027964) (xy 292.462813 -357.98675) (xy 292.433331 -357.940873) (xy 292.410678 -357.891268)
			(xy 292.395315 -357.838944) (xy 292.387554 -357.784966) (xy 290.904706 -357.784966) (xy 290.904706 -357.784971)
			(xy 290.896944 -357.838956) (xy 290.881578 -357.891288) (xy 290.858922 -357.940901) (xy 290.829436 -357.986784)
			(xy 290.79372 -358.028005) (xy 290.752502 -358.063723) (xy 290.70662 -358.093211) (xy 290.657009 -358.115871)
			(xy 290.604678 -358.131239) (xy 290.550692 -358.139004) (xy 290.523422 -358.139492) (xy 289.659822 -358.139492)
			(xy 289.632552 -358.13897) (xy 289.578567 -358.131211) (xy 289.526236 -358.115848) (xy 289.476624 -358.093193)
			(xy 289.430741 -358.063709) (xy 289.389522 -358.027994) (xy 289.353805 -357.986777) (xy 289.324317 -357.940895)
			(xy 289.30166 -357.891285) (xy 289.286294 -357.838954) (xy 289.278531 -357.78497) (xy 287.795828 -357.78497)
			(xy 287.795828 -357.784975) (xy 287.788065 -357.838969) (xy 287.772695 -357.891309) (xy 287.750033 -357.940929)
			(xy 287.72054 -357.986818) (xy 287.684815 -358.028042) (xy 287.643587 -358.063762) (xy 287.597695 -358.093251)
			(xy 287.548073 -358.115908) (xy 287.495732 -358.131273) (xy 287.441737 -358.139031) (xy 287.414462 -358.139492)
			(xy 286.550862 -358.139492) (xy 286.523597 -358.138943) (xy 286.469621 -358.131178) (xy 286.4173 -358.11581)
			(xy 286.367699 -358.093154) (xy 286.321826 -358.063669) (xy 286.280617 -358.027957) (xy 286.244908 -357.986743)
			(xy 286.215428 -357.940868) (xy 286.192777 -357.891264) (xy 286.177414 -357.838942) (xy 286.169654 -357.784966)
			(xy 284.686806 -357.784966) (xy 284.686806 -357.784971) (xy 284.679043 -357.838959) (xy 284.663677 -357.891293)
			(xy 284.641019 -357.940907) (xy 284.611531 -357.986791) (xy 284.575813 -358.028012) (xy 284.534593 -358.06373)
			(xy 284.488708 -358.093218) (xy 284.439094 -358.115876) (xy 284.386761 -358.131243) (xy 284.332773 -358.139005)
			(xy 284.305502 -358.139492) (xy 283.441902 -358.139492) (xy 283.414633 -358.138969) (xy 283.36065 -358.131207)
			(xy 283.308321 -358.115843) (xy 283.258712 -358.093187) (xy 283.212832 -358.063702) (xy 283.171614 -358.027987)
			(xy 283.1359 -357.98677) (xy 283.106414 -357.94089) (xy 283.083758 -357.89128) (xy 283.068393 -357.838952)
			(xy 283.060631 -357.784969) (xy 281.577806 -357.784969) (xy 281.577806 -357.78497) (xy 281.570044 -357.838954)
			(xy 281.55468 -357.891284) (xy 281.532025 -357.940895) (xy 281.502541 -357.986778) (xy 281.466827 -358.027998)
			(xy 281.425611 -358.063716) (xy 281.379732 -358.093205) (xy 281.330123 -358.115865) (xy 281.277795 -358.131235)
			(xy 281.223812 -358.139003) (xy 281.196542 -358.139492) (xy 280.332942 -358.139492) (xy 280.305671 -358.138971)
			(xy 280.251684 -358.131215) (xy 280.19935 -358.115853) (xy 280.149736 -358.0932) (xy 280.10385 -358.063716)
			(xy 280.062629 -358.028001) (xy 280.026909 -357.986783) (xy 279.99742 -357.940901) (xy 279.974761 -357.891289)
			(xy 279.959394 -357.838957) (xy 279.951632 -357.784971) (xy 278.468928 -357.784971) (xy 278.468928 -357.784974)
			(xy 278.461165 -357.838967) (xy 278.445797 -357.891305) (xy 278.423136 -357.940923) (xy 278.393644 -357.986811)
			(xy 278.357922 -358.028035) (xy 278.316697 -358.063755) (xy 278.270807 -358.093245) (xy 278.221188 -358.115903)
			(xy 278.168849 -358.131269) (xy 278.114856 -358.13903) (xy 278.087582 -358.139492) (xy 277.223982 -358.139492)
			(xy 277.196716 -358.138944) (xy 277.142738 -358.131181) (xy 277.090415 -358.115816) (xy 277.040811 -358.09316)
			(xy 276.994936 -358.063676) (xy 276.953724 -358.027964) (xy 276.918013 -357.98675) (xy 276.888531 -357.940873)
			(xy 276.865878 -357.891268) (xy 276.850515 -357.838944) (xy 276.842754 -357.784966) (xy 275.359906 -357.784966)
			(xy 275.359906 -357.784971) (xy 275.352144 -357.838956) (xy 275.336778 -357.891288) (xy 275.314122 -357.940901)
			(xy 275.284636 -357.986784) (xy 275.24892 -358.028005) (xy 275.207702 -358.063723) (xy 275.16182 -358.093211)
			(xy 275.112209 -358.115871) (xy 275.059878 -358.131239) (xy 275.005892 -358.139004) (xy 274.978622 -358.139492)
			(xy 274.115022 -358.139492) (xy 274.087752 -358.13897) (xy 274.033767 -358.131211) (xy 273.981436 -358.115848)
			(xy 273.931824 -358.093193) (xy 273.885941 -358.063709) (xy 273.844722 -358.027994) (xy 273.809005 -357.986777)
			(xy 273.779517 -357.940895) (xy 273.75686 -357.891285) (xy 273.741494 -357.838954) (xy 273.733731 -357.78497)
			(xy 272.251028 -357.78497) (xy 272.251028 -357.784975) (xy 272.243265 -357.838969) (xy 272.227895 -357.891309)
			(xy 272.205233 -357.940929) (xy 272.17574 -357.986818) (xy 272.140015 -358.028042) (xy 272.098787 -358.063762)
			(xy 272.052895 -358.093251) (xy 272.003273 -358.115908) (xy 271.950932 -358.131273) (xy 271.896937 -358.139031)
			(xy 271.869662 -358.139492) (xy 271.006062 -358.139492) (xy 270.978797 -358.138943) (xy 270.924821 -358.131178)
			(xy 270.8725 -358.11581) (xy 270.822899 -358.093154) (xy 270.777026 -358.063669) (xy 270.735817 -358.027957)
			(xy 270.700108 -357.986743) (xy 270.670628 -357.940868) (xy 270.647977 -357.891264) (xy 270.632614 -357.838942)
			(xy 270.624854 -357.784966) (xy 247.276485 -357.784966) (xy 247.278987 -357.797946) (xy 247.287038 -357.88226)
			(xy 247.287542 -357.924608) (xy 247.287038 -357.966956) (xy 247.278987 -358.05127) (xy 247.262958 -358.134436)
			(xy 247.239097 -358.215703) (xy 247.207618 -358.294333) (xy 247.168807 -358.369614) (xy 247.123017 -358.440866)
			(xy 247.070661 -358.507442) (xy 247.012213 -358.56874) (xy 246.948203 -358.624205) (xy 246.879211 -358.673334)
			(xy 246.805861 -358.715683) (xy 246.728818 -358.750867) (xy 246.648779 -358.778569) (xy 246.56647 -358.798537)
			(xy 246.482635 -358.81059) (xy 246.398034 -358.814621) (xy 246.313433 -358.81059) (xy 246.229598 -358.798537)
			(xy 246.147289 -358.778569) (xy 246.06725 -358.750867) (xy 245.990207 -358.715683) (xy 245.916857 -358.673334)
			(xy 245.847865 -358.624205) (xy 245.783855 -358.56874) (xy 245.725407 -358.507442) (xy 245.673051 -358.440866)
			(xy 245.627261 -358.369614) (xy 245.58845 -358.294333) (xy 245.556971 -358.215703) (xy 245.53311 -358.134436)
			(xy 245.517081 -358.05127) (xy 245.50903 -357.966956) (xy 188.223925 -357.966956) (xy 188.191672 -358.004178)
			(xy 188.150456 -358.039891) (xy 188.104577 -358.069375) (xy 188.054969 -358.092029) (xy 188.002641 -358.107393)
			(xy 187.94866 -358.115153) (xy 187.921392 -358.115616) (xy 187.057792 -358.115616) (xy 187.03052 -358.115221)
			(xy 186.97653 -358.107457) (xy 186.924196 -358.092089) (xy 186.87458 -358.06943) (xy 186.828695 -358.03994)
			(xy 186.787473 -358.004221) (xy 186.751755 -357.962999) (xy 186.722266 -357.917112) (xy 186.699608 -357.867497)
			(xy 186.684241 -357.815162) (xy 186.676479 -357.761172) (xy 185.193629 -357.761172) (xy 185.18587 -357.815139)
			(xy 185.170508 -357.86746) (xy 185.147857 -357.917062) (xy 185.118378 -357.962936) (xy 185.08267 -358.004147)
			(xy 185.041461 -358.039858) (xy 184.99559 -358.069342) (xy 184.94599 -358.091997) (xy 184.89367 -358.107363)
			(xy 184.839697 -358.115128) (xy 184.812432 -358.115616) (xy 183.948832 -358.115616) (xy 183.921556 -358.115247)
			(xy 183.867559 -358.107487) (xy 183.815217 -358.092122) (xy 183.765593 -358.069463) (xy 183.7197 -358.039973)
			(xy 183.678471 -358.004251) (xy 183.642746 -357.963025) (xy 183.613252 -357.917135) (xy 183.590589 -357.867513)
			(xy 183.57522 -357.815172) (xy 183.567456 -357.761176) (xy 182.084828 -357.761176) (xy 182.084828 -357.784974)
			(xy 182.077065 -357.838968) (xy 182.061696 -357.891307) (xy 182.039035 -357.940926) (xy 182.009542 -357.986815)
			(xy 181.973819 -358.028039) (xy 181.932592 -358.063759) (xy 181.886701 -358.093248) (xy 181.837081 -358.115906)
			(xy 181.784741 -358.131271) (xy 181.730746 -358.13903) (xy 181.703472 -358.139492) (xy 180.839872 -358.139492)
			(xy 180.812606 -358.138944) (xy 180.75863 -358.131179) (xy 180.706308 -358.115813) (xy 180.656705 -358.093157)
			(xy 180.610831 -358.063673) (xy 180.56962 -358.02796) (xy 180.533911 -357.986746) (xy 180.50443 -357.94087)
			(xy 180.481777 -357.891266) (xy 180.466415 -357.838943) (xy 180.458654 -357.784966) (xy 178.975806 -357.784966)
			(xy 178.975806 -357.784971) (xy 178.968044 -357.838958) (xy 178.952678 -357.89129) (xy 178.930021 -357.940904)
			(xy 178.900533 -357.986788) (xy 178.864817 -358.028008) (xy 178.823597 -358.063726) (xy 178.777714 -358.093215)
			(xy 178.728102 -358.115873) (xy 178.675769 -358.131241) (xy 178.621783 -358.139005) (xy 178.594512 -358.139492)
			(xy 177.730912 -358.139492) (xy 177.703643 -358.138969) (xy 177.649659 -358.131209) (xy 177.597329 -358.115845)
			(xy 177.547718 -358.09319) (xy 177.501836 -358.063705) (xy 177.460618 -358.027991) (xy 177.424902 -357.986773)
			(xy 177.395416 -357.940893) (xy 177.372759 -357.891283) (xy 177.357393 -357.838953) (xy 177.349631 -357.784969)
			(xy 175.866928 -357.784969) (xy 175.866928 -357.784975) (xy 175.859164 -357.838971) (xy 175.843794 -357.891311)
			(xy 175.821132 -357.940932) (xy 175.791637 -357.986821) (xy 175.755912 -358.028046) (xy 175.714683 -358.063766)
			(xy 175.668789 -358.093255) (xy 175.619166 -358.115911) (xy 175.566824 -358.131275) (xy 175.512827 -358.139032)
			(xy 175.485552 -358.139492) (xy 174.621952 -358.139492) (xy 174.594687 -358.138942) (xy 174.540713 -358.131176)
			(xy 174.488393 -358.115807) (xy 174.438793 -358.09315) (xy 174.392922 -358.063665) (xy 174.351713 -358.027953)
			(xy 174.316006 -357.98674) (xy 174.286527 -357.940865) (xy 174.263876 -357.891262) (xy 174.248514 -357.83894)
			(xy 174.240754 -357.784965) (xy 172.757928 -357.784965) (xy 172.757928 -357.784974) (xy 172.750165 -357.838965)
			(xy 172.734798 -357.891303) (xy 172.712138 -357.94092) (xy 172.682647 -357.986808) (xy 172.646926 -358.028032)
			(xy 172.605702 -358.063752) (xy 172.559813 -358.093241) (xy 172.510195 -358.1159) (xy 172.457857 -358.131267)
			(xy 172.403866 -358.139029) (xy 172.376592 -358.139492) (xy 171.512992 -358.139492) (xy 171.485725 -358.138945)
			(xy 171.431747 -358.131183) (xy 171.379422 -358.115818) (xy 171.329817 -358.093163) (xy 171.283941 -358.06368)
			(xy 171.242727 -358.027967) (xy 171.207016 -357.986753) (xy 171.177533 -357.940876) (xy 171.154879 -357.89127)
			(xy 171.139515 -357.838946) (xy 171.131754 -357.784967) (xy 169.648906 -357.784967) (xy 169.648906 -357.78497)
			(xy 169.641144 -357.838955) (xy 169.625779 -357.891286) (xy 169.603124 -357.940898) (xy 169.573638 -357.986781)
			(xy 169.537924 -358.028001) (xy 169.496707 -358.063719) (xy 169.450826 -358.093208) (xy 169.401216 -358.115868)
			(xy 169.348886 -358.131237) (xy 169.294902 -358.139003) (xy 169.267632 -358.139492) (xy 168.404032 -358.139492)
			(xy 168.376762 -358.138971) (xy 168.322776 -358.131213) (xy 168.270443 -358.115851) (xy 168.22083 -358.093197)
			(xy 168.174946 -358.063712) (xy 168.133725 -358.027998) (xy 168.098007 -357.98678) (xy 168.068519 -357.940898)
			(xy 168.045861 -357.891287) (xy 168.030494 -357.838956) (xy 168.022732 -357.78497) (xy 166.540028 -357.78497)
			(xy 166.540028 -357.784974) (xy 166.532265 -357.838968) (xy 166.516896 -357.891307) (xy 166.494235 -357.940926)
			(xy 166.464742 -357.986815) (xy 166.429019 -358.028039) (xy 166.387792 -358.063759) (xy 166.341901 -358.093248)
			(xy 166.292281 -358.115906) (xy 166.239941 -358.131271) (xy 166.185946 -358.13903) (xy 166.158672 -358.139492)
			(xy 165.295072 -358.139492) (xy 165.267806 -358.138944) (xy 165.21383 -358.131179) (xy 165.161508 -358.115813)
			(xy 165.111905 -358.093157) (xy 165.066031 -358.063673) (xy 165.02482 -358.02796) (xy 164.989111 -357.986746)
			(xy 164.95963 -357.94087) (xy 164.936977 -357.891266) (xy 164.921615 -357.838943) (xy 164.913854 -357.784966)
			(xy 163.431006 -357.784966) (xy 163.431006 -357.784971) (xy 163.423244 -357.838958) (xy 163.407878 -357.89129)
			(xy 163.385221 -357.940904) (xy 163.355733 -357.986788) (xy 163.320017 -358.028008) (xy 163.278797 -358.063726)
			(xy 163.232914 -358.093215) (xy 163.183302 -358.115873) (xy 163.130969 -358.131241) (xy 163.076983 -358.139005)
			(xy 163.049712 -358.139492) (xy 162.186112 -358.139492) (xy 162.158843 -358.138969) (xy 162.104859 -358.131209)
			(xy 162.052529 -358.115845) (xy 162.002918 -358.09319) (xy 161.957036 -358.063705) (xy 161.915818 -358.027991)
			(xy 161.880102 -357.986773) (xy 161.850616 -357.940893) (xy 161.827959 -357.891283) (xy 161.812593 -357.838953)
			(xy 161.804831 -357.784969) (xy 160.322128 -357.784969) (xy 160.322128 -357.784975) (xy 160.314364 -357.838971)
			(xy 160.298994 -357.891311) (xy 160.276332 -357.940932) (xy 160.246837 -357.986821) (xy 160.211112 -358.028046)
			(xy 160.169883 -358.063766) (xy 160.123989 -358.093255) (xy 160.074366 -358.115911) (xy 160.022024 -358.131275)
			(xy 159.968027 -358.139032) (xy 159.940752 -358.139492) (xy 159.077152 -358.139492) (xy 159.049887 -358.138942)
			(xy 158.995913 -358.131176) (xy 158.943593 -358.115807) (xy 158.893993 -358.09315) (xy 158.848122 -358.063665)
			(xy 158.806913 -358.027953) (xy 158.771206 -357.98674) (xy 158.741727 -357.940865) (xy 158.719076 -357.891262)
			(xy 158.703714 -357.83894) (xy 158.695954 -357.784965) (xy 144.196606 -357.784965) (xy 144.196606 -357.784971)
			(xy 144.188843 -357.838958) (xy 144.173477 -357.891291) (xy 144.15082 -357.940905) (xy 144.121332 -357.986789)
			(xy 144.085615 -358.02801) (xy 144.044395 -358.063728) (xy 143.998512 -358.093216) (xy 143.948899 -358.115875)
			(xy 143.896566 -358.131242) (xy 143.842579 -358.139005) (xy 143.815308 -358.139492) (xy 142.951708 -358.139492)
			(xy 142.924439 -358.138969) (xy 142.870455 -358.131209) (xy 142.818126 -358.115844) (xy 142.768515 -358.093189)
			(xy 142.722634 -358.063704) (xy 142.681417 -358.027989) (xy 142.645701 -357.986772) (xy 142.616215 -357.940892)
			(xy 142.593559 -357.891282) (xy 142.578193 -357.838953) (xy 142.570431 -357.784969) (xy 141.087606 -357.784969)
			(xy 141.079845 -357.838953) (xy 141.06448 -357.891283) (xy 141.041826 -357.940894) (xy 141.012342 -357.986776)
			(xy 140.976629 -358.027995) (xy 140.935414 -358.063713) (xy 140.889536 -358.093203) (xy 140.839928 -358.115864)
			(xy 140.7876 -358.131234) (xy 140.733617 -358.139002) (xy 140.706348 -358.139492) (xy 139.842748 -358.139492)
			(xy 139.815477 -358.138972) (xy 139.761489 -358.131216) (xy 139.709155 -358.115855) (xy 139.659539 -358.093202)
			(xy 139.613653 -358.063718) (xy 139.572431 -358.028003) (xy 139.536711 -357.986785) (xy 139.507221 -357.940903)
			(xy 139.484562 -357.89129) (xy 139.469194 -357.838958) (xy 139.461432 -357.784971) (xy 137.978728 -357.784971)
			(xy 137.978728 -357.784974) (xy 137.970965 -357.838966) (xy 137.955597 -357.891304) (xy 137.932937 -357.940921)
			(xy 137.903446 -357.986809) (xy 137.867724 -358.028033) (xy 137.8265 -358.063753) (xy 137.780611 -358.093243)
			(xy 137.730992 -358.115901) (xy 137.678654 -358.131268) (xy 137.624662 -358.139029) (xy 137.597388 -358.139492)
			(xy 136.733788 -358.139492) (xy 136.706521 -358.138945) (xy 136.652543 -358.131182) (xy 136.600219 -358.115817)
			(xy 136.550615 -358.093162) (xy 136.504739 -358.063678) (xy 136.463526 -358.027966) (xy 136.427815 -357.986752)
			(xy 136.398332 -357.940875) (xy 136.375679 -357.891269) (xy 136.360315 -357.838945) (xy 136.352554 -357.784967)
			(xy 134.869706 -357.784967) (xy 134.869706 -357.78497) (xy 134.861944 -357.838956) (xy 134.846579 -357.891287)
			(xy 134.823923 -357.940899) (xy 134.794437 -357.986782) (xy 134.758722 -358.028003) (xy 134.717505 -358.063721)
			(xy 134.671624 -358.09321) (xy 134.622013 -358.115869) (xy 134.569683 -358.131238) (xy 134.515698 -358.139004)
			(xy 134.488428 -358.139492) (xy 133.624828 -358.139492) (xy 133.597558 -358.13897) (xy 133.543572 -358.131212)
			(xy 133.49124 -358.11585) (xy 133.441627 -358.093195) (xy 133.395744 -358.063711) (xy 133.354524 -358.027996)
			(xy 133.318806 -357.986779) (xy 133.289318 -357.940897) (xy 133.26666 -357.891286) (xy 133.251294 -357.838955)
			(xy 133.243531 -357.78497) (xy 131.760828 -357.78497) (xy 131.760828 -357.784975) (xy 131.753065 -357.838969)
			(xy 131.737696 -357.891308) (xy 131.715034 -357.940927) (xy 131.685541 -357.986816) (xy 131.649817 -358.02804)
			(xy 131.60859 -358.06376) (xy 131.562699 -358.093249) (xy 131.513078 -358.115907) (xy 131.460737 -358.131272)
			(xy 131.406743 -358.139031) (xy 131.379468 -358.139492) (xy 130.515868 -358.139492) (xy 130.488602 -358.138943)
			(xy 130.434626 -358.131179) (xy 130.382305 -358.115812) (xy 130.332703 -358.093156) (xy 130.286829 -358.063671)
			(xy 130.245619 -358.027959) (xy 130.20991 -357.986745) (xy 130.180429 -357.940869) (xy 130.157777 -357.891265)
			(xy 130.142414 -357.838942) (xy 130.134654 -357.784966) (xy 128.651806 -357.784966) (xy 128.651806 -357.784971)
			(xy 128.644043 -357.838958) (xy 128.628677 -357.891291) (xy 128.60602 -357.940905) (xy 128.576532 -357.986789)
			(xy 128.540815 -358.02801) (xy 128.499595 -358.063728) (xy 128.453712 -358.093216) (xy 128.404099 -358.115875)
			(xy 128.351766 -358.131242) (xy 128.297779 -358.139005) (xy 128.270508 -358.139492) (xy 127.406908 -358.139492)
			(xy 127.379639 -358.138969) (xy 127.325655 -358.131209) (xy 127.273326 -358.115844) (xy 127.223715 -358.093189)
			(xy 127.177834 -358.063704) (xy 127.136617 -358.027989) (xy 127.100901 -357.986772) (xy 127.071415 -357.940892)
			(xy 127.048759 -357.891282) (xy 127.033393 -357.838953) (xy 127.025631 -357.784969) (xy 125.542806 -357.784969)
			(xy 125.535045 -357.838953) (xy 125.51968 -357.891283) (xy 125.497026 -357.940894) (xy 125.467542 -357.986776)
			(xy 125.431829 -358.027995) (xy 125.390614 -358.063713) (xy 125.344736 -358.093203) (xy 125.295128 -358.115864)
			(xy 125.2428 -358.131234) (xy 125.188817 -358.139002) (xy 125.161548 -358.139492) (xy 124.297948 -358.139492)
			(xy 124.270677 -358.138972) (xy 124.216689 -358.131216) (xy 124.164355 -358.115855) (xy 124.114739 -358.093202)
			(xy 124.068853 -358.063718) (xy 124.027631 -358.028003) (xy 123.991911 -357.986785) (xy 123.962421 -357.940903)
			(xy 123.939762 -357.89129) (xy 123.924394 -357.838958) (xy 123.916632 -357.784971) (xy 122.433928 -357.784971)
			(xy 122.433928 -357.784974) (xy 122.426165 -357.838966) (xy 122.410797 -357.891304) (xy 122.388137 -357.940921)
			(xy 122.358646 -357.986809) (xy 122.322924 -358.028033) (xy 122.2817 -358.063753) (xy 122.235811 -358.093243)
			(xy 122.186192 -358.115901) (xy 122.133854 -358.131268) (xy 122.079862 -358.139029) (xy 122.052588 -358.139492)
			(xy 121.188988 -358.139492) (xy 121.161721 -358.138945) (xy 121.107743 -358.131182) (xy 121.055419 -358.115817)
			(xy 121.005815 -358.093162) (xy 120.959939 -358.063678) (xy 120.918726 -358.027966) (xy 120.883015 -357.986752)
			(xy 120.853532 -357.940875) (xy 120.830879 -357.891269) (xy 120.815515 -357.838945) (xy 120.807754 -357.784967)
			(xy 119.324906 -357.784967) (xy 119.324906 -357.78497) (xy 119.317144 -357.838956) (xy 119.301779 -357.891287)
			(xy 119.279123 -357.940899) (xy 119.249637 -357.986782) (xy 119.213922 -358.028003) (xy 119.172705 -358.063721)
			(xy 119.126824 -358.09321) (xy 119.077213 -358.115869) (xy 119.024883 -358.131238) (xy 118.970898 -358.139004)
			(xy 118.943628 -358.139492) (xy 118.080028 -358.139492) (xy 118.052758 -358.13897) (xy 117.998772 -358.131212)
			(xy 117.94644 -358.11585) (xy 117.896827 -358.093195) (xy 117.850944 -358.063711) (xy 117.809724 -358.027996)
			(xy 117.774006 -357.986779) (xy 117.744518 -357.940897) (xy 117.72186 -357.891286) (xy 117.706494 -357.838955)
			(xy 117.698731 -357.78497) (xy 116.216028 -357.78497) (xy 116.216028 -357.784975) (xy 116.208265 -357.838969)
			(xy 116.192896 -357.891308) (xy 116.170234 -357.940927) (xy 116.140741 -357.986816) (xy 116.105017 -358.02804)
			(xy 116.06379 -358.06376) (xy 116.017899 -358.093249) (xy 115.968278 -358.115907) (xy 115.915937 -358.131272)
			(xy 115.861943 -358.139031) (xy 115.834668 -358.139492) (xy 114.971068 -358.139492) (xy 114.943802 -358.138943)
			(xy 114.889826 -358.131179) (xy 114.837505 -358.115812) (xy 114.787903 -358.093156) (xy 114.742029 -358.063671)
			(xy 114.700819 -358.027959) (xy 114.66511 -357.986745) (xy 114.635629 -357.940869) (xy 114.612977 -357.891265)
			(xy 114.597614 -357.838942) (xy 114.589854 -357.784966) (xy 93.706706 -357.784966) (xy 93.706706 -357.78497)
			(xy 93.698944 -357.838954) (xy 93.68358 -357.891284) (xy 93.660925 -357.940895) (xy 93.631441 -357.986778)
			(xy 93.595727 -358.027998) (xy 93.554511 -358.063716) (xy 93.508632 -358.093205) (xy 93.459023 -358.115865)
			(xy 93.406695 -358.131235) (xy 93.352712 -358.139003) (xy 93.325442 -358.139492) (xy 92.461842 -358.139492)
			(xy 92.434571 -358.138971) (xy 92.380584 -358.131215) (xy 92.32825 -358.115853) (xy 92.278636 -358.0932)
			(xy 92.23275 -358.063716) (xy 92.191529 -358.028001) (xy 92.155809 -357.986783) (xy 92.12632 -357.940901)
			(xy 92.103661 -357.891289) (xy 92.088294 -357.838957) (xy 92.080532 -357.784971) (xy 90.597828 -357.784971)
			(xy 90.597828 -357.784974) (xy 90.590065 -357.838967) (xy 90.574697 -357.891305) (xy 90.552036 -357.940923)
			(xy 90.522544 -357.986811) (xy 90.486822 -358.028035) (xy 90.445597 -358.063755) (xy 90.399707 -358.093245)
			(xy 90.350088 -358.115903) (xy 90.297749 -358.131269) (xy 90.243756 -358.13903) (xy 90.216482 -358.139492)
			(xy 89.352882 -358.139492) (xy 89.325616 -358.138944) (xy 89.271638 -358.131181) (xy 89.219315 -358.115816)
			(xy 89.169711 -358.09316) (xy 89.123836 -358.063676) (xy 89.082624 -358.027964) (xy 89.046913 -357.98675)
			(xy 89.017431 -357.940873) (xy 88.994778 -357.891268) (xy 88.979415 -357.838944) (xy 88.971654 -357.784966)
			(xy 87.488806 -357.784966) (xy 87.488806 -357.784971) (xy 87.481044 -357.838956) (xy 87.465678 -357.891288)
			(xy 87.443022 -357.940901) (xy 87.413536 -357.986784) (xy 87.37782 -358.028005) (xy 87.336602 -358.063723)
			(xy 87.29072 -358.093211) (xy 87.241109 -358.115871) (xy 87.188778 -358.131239) (xy 87.134792 -358.139004)
			(xy 87.107522 -358.139492) (xy 86.243922 -358.139492) (xy 86.216652 -358.13897) (xy 86.162667 -358.131211)
			(xy 86.110336 -358.115848) (xy 86.060724 -358.093193) (xy 86.014841 -358.063709) (xy 85.973622 -358.027994)
			(xy 85.937905 -357.986777) (xy 85.908417 -357.940895) (xy 85.88576 -357.891285) (xy 85.870394 -357.838954)
			(xy 85.862631 -357.78497) (xy 84.379928 -357.78497) (xy 84.379928 -357.784975) (xy 84.372165 -357.838969)
			(xy 84.356795 -357.891309) (xy 84.334133 -357.940929) (xy 84.30464 -357.986818) (xy 84.268915 -358.028042)
			(xy 84.227687 -358.063762) (xy 84.181795 -358.093251) (xy 84.132173 -358.115908) (xy 84.079832 -358.131273)
			(xy 84.025837 -358.139031) (xy 83.998562 -358.139492) (xy 83.134962 -358.139492) (xy 83.107697 -358.138943)
			(xy 83.053721 -358.131178) (xy 83.0014 -358.11581) (xy 82.951799 -358.093154) (xy 82.905926 -358.063669)
			(xy 82.864717 -358.027957) (xy 82.829008 -357.986743) (xy 82.799528 -357.940868) (xy 82.776877 -357.891264)
			(xy 82.761514 -357.838942) (xy 82.753754 -357.784966) (xy 81.270906 -357.784966) (xy 81.270906 -357.784971)
			(xy 81.263143 -357.838959) (xy 81.247777 -357.891293) (xy 81.225119 -357.940907) (xy 81.195631 -357.986791)
			(xy 81.159913 -358.028012) (xy 81.118693 -358.06373) (xy 81.072808 -358.093218) (xy 81.023194 -358.115876)
			(xy 80.970861 -358.131243) (xy 80.916873 -358.139005) (xy 80.889602 -358.139492) (xy 80.026002 -358.139492)
			(xy 79.998733 -358.138969) (xy 79.94475 -358.131207) (xy 79.892421 -358.115843) (xy 79.842812 -358.093187)
			(xy 79.796932 -358.063702) (xy 79.755714 -358.027987) (xy 79.72 -357.98677) (xy 79.690514 -357.94089)
			(xy 79.667858 -357.89128) (xy 79.652493 -357.838952) (xy 79.644731 -357.784969) (xy 78.161906 -357.784969)
			(xy 78.161906 -357.78497) (xy 78.154144 -357.838954) (xy 78.13878 -357.891284) (xy 78.116125 -357.940895)
			(xy 78.086641 -357.986778) (xy 78.050927 -358.027998) (xy 78.009711 -358.063716) (xy 77.963832 -358.093205)
			(xy 77.914223 -358.115865) (xy 77.861895 -358.131235) (xy 77.807912 -358.139003) (xy 77.780642 -358.139492)
			(xy 76.917042 -358.139492) (xy 76.889771 -358.138971) (xy 76.835784 -358.131215) (xy 76.78345 -358.115853)
			(xy 76.733836 -358.0932) (xy 76.68795 -358.063716) (xy 76.646729 -358.028001) (xy 76.611009 -357.986783)
			(xy 76.58152 -357.940901) (xy 76.558861 -357.891289) (xy 76.543494 -357.838957) (xy 76.535732 -357.784971)
			(xy 75.053028 -357.784971) (xy 75.053028 -357.784974) (xy 75.045265 -357.838967) (xy 75.029897 -357.891305)
			(xy 75.007236 -357.940923) (xy 74.977744 -357.986811) (xy 74.942022 -358.028035) (xy 74.900797 -358.063755)
			(xy 74.854907 -358.093245) (xy 74.805288 -358.115903) (xy 74.752949 -358.131269) (xy 74.698956 -358.13903)
			(xy 74.671682 -358.139492) (xy 73.808082 -358.139492) (xy 73.780816 -358.138944) (xy 73.726838 -358.131181)
			(xy 73.674515 -358.115816) (xy 73.624911 -358.09316) (xy 73.579036 -358.063676) (xy 73.537824 -358.027964)
			(xy 73.502113 -357.98675) (xy 73.472631 -357.940873) (xy 73.449978 -357.891268) (xy 73.434615 -357.838944)
			(xy 73.426854 -357.784966) (xy 71.944006 -357.784966) (xy 71.944006 -357.784971) (xy 71.936244 -357.838956)
			(xy 71.920878 -357.891288) (xy 71.898222 -357.940901) (xy 71.868736 -357.986784) (xy 71.83302 -358.028005)
			(xy 71.791802 -358.063723) (xy 71.74592 -358.093211) (xy 71.696309 -358.115871) (xy 71.643978 -358.131239)
			(xy 71.589992 -358.139004) (xy 71.562722 -358.139492) (xy 70.699122 -358.139492) (xy 70.671852 -358.13897)
			(xy 70.617867 -358.131211) (xy 70.565536 -358.115848) (xy 70.515924 -358.093193) (xy 70.470041 -358.063709)
			(xy 70.428822 -358.027994) (xy 70.393105 -357.986777) (xy 70.363617 -357.940895) (xy 70.34096 -357.891285)
			(xy 70.325594 -357.838954) (xy 70.317831 -357.78497) (xy 68.835128 -357.78497) (xy 68.835128 -357.784975)
			(xy 68.827365 -357.838969) (xy 68.811995 -357.891309) (xy 68.789333 -357.940929) (xy 68.75984 -357.986818)
			(xy 68.724115 -358.028042) (xy 68.682887 -358.063762) (xy 68.636995 -358.093251) (xy 68.587373 -358.115908)
			(xy 68.535032 -358.131273) (xy 68.481037 -358.139031) (xy 68.453762 -358.139492) (xy 67.590162 -358.139492)
			(xy 67.562897 -358.138943) (xy 67.508921 -358.131178) (xy 67.4566 -358.11581) (xy 67.406999 -358.093154)
			(xy 67.361126 -358.063669) (xy 67.319917 -358.027957) (xy 67.284208 -357.986743) (xy 67.254728 -357.940868)
			(xy 67.232077 -357.891264) (xy 67.216714 -357.838942) (xy 67.208954 -357.784966) (xy 65.726106 -357.784966)
			(xy 65.726106 -357.784971) (xy 65.718343 -357.838959) (xy 65.702977 -357.891293) (xy 65.680319 -357.940907)
			(xy 65.650831 -357.986791) (xy 65.615113 -358.028012) (xy 65.573893 -358.06373) (xy 65.528008 -358.093218)
			(xy 65.478394 -358.115876) (xy 65.426061 -358.131243) (xy 65.372073 -358.139005) (xy 65.344802 -358.139492)
			(xy 64.481202 -358.139492) (xy 64.453933 -358.138969) (xy 64.39995 -358.131207) (xy 64.347621 -358.115843)
			(xy 64.298012 -358.093187) (xy 64.252132 -358.063702) (xy 64.210914 -358.027987) (xy 64.1752 -357.98677)
			(xy 64.145714 -357.94089) (xy 64.123058 -357.89128) (xy 64.107693 -357.838952) (xy 64.099931 -357.784969)
			(xy 51.666906 -357.784969) (xy 51.659145 -357.838953) (xy 51.64378 -357.891283) (xy 51.621126 -357.940894)
			(xy 51.591642 -357.986776) (xy 51.555929 -358.027995) (xy 51.514714 -358.063713) (xy 51.468836 -358.093203)
			(xy 51.419228 -358.115864) (xy 51.3669 -358.131234) (xy 51.312917 -358.139002) (xy 51.285648 -358.139492)
			(xy 50.422048 -358.139492) (xy 50.394777 -358.138972) (xy 50.340789 -358.131216) (xy 50.288455 -358.115855)
			(xy 50.238839 -358.093202) (xy 50.192953 -358.063718) (xy 50.151731 -358.028003) (xy 50.116011 -357.986785)
			(xy 50.086521 -357.940903) (xy 50.063862 -357.89129) (xy 50.048494 -357.838958) (xy 50.040732 -357.784971)
			(xy 48.558028 -357.784971) (xy 48.558028 -357.784974) (xy 48.550265 -357.838966) (xy 48.534897 -357.891304)
			(xy 48.512237 -357.940921) (xy 48.482746 -357.986809) (xy 48.447024 -358.028033) (xy 48.4058 -358.063753)
			(xy 48.359911 -358.093243) (xy 48.310292 -358.115901) (xy 48.257954 -358.131268) (xy 48.203962 -358.139029)
			(xy 48.176688 -358.139492) (xy 47.313088 -358.139492) (xy 47.285821 -358.138945) (xy 47.231843 -358.131182)
			(xy 47.179519 -358.115817) (xy 47.129915 -358.093162) (xy 47.084039 -358.063678) (xy 47.042826 -358.027966)
			(xy 47.007115 -357.986752) (xy 46.977632 -357.940875) (xy 46.954979 -357.891269) (xy 46.939615 -357.838945)
			(xy 46.931854 -357.784967) (xy 45.449006 -357.784967) (xy 45.449006 -357.78497) (xy 45.441244 -357.838956)
			(xy 45.425879 -357.891287) (xy 45.403223 -357.940899) (xy 45.373737 -357.986782) (xy 45.338022 -358.028003)
			(xy 45.296805 -358.063721) (xy 45.250924 -358.09321) (xy 45.201313 -358.115869) (xy 45.148983 -358.131238)
			(xy 45.094998 -358.139004) (xy 45.067728 -358.139492) (xy 44.204128 -358.139492) (xy 44.176858 -358.13897)
			(xy 44.122872 -358.131212) (xy 44.07054 -358.11585) (xy 44.020927 -358.093195) (xy 43.975044 -358.063711)
			(xy 43.933824 -358.027996) (xy 43.898106 -357.986779) (xy 43.868618 -357.940897) (xy 43.84596 -357.891286)
			(xy 43.830594 -357.838955) (xy 43.822831 -357.78497) (xy 42.340128 -357.78497) (xy 42.340128 -357.784975)
			(xy 42.332365 -357.838969) (xy 42.316996 -357.891308) (xy 42.294334 -357.940927) (xy 42.264841 -357.986816)
			(xy 42.229117 -358.02804) (xy 42.18789 -358.06376) (xy 42.141999 -358.093249) (xy 42.092378 -358.115907)
			(xy 42.040037 -358.131272) (xy 41.986043 -358.139031) (xy 41.958768 -358.139492) (xy 41.095168 -358.139492)
			(xy 41.067902 -358.138943) (xy 41.013926 -358.131179) (xy 40.961605 -358.115812) (xy 40.912003 -358.093156)
			(xy 40.866129 -358.063671) (xy 40.824919 -358.027959) (xy 40.78921 -357.986745) (xy 40.759729 -357.940869)
			(xy 40.737077 -357.891265) (xy 40.721714 -357.838942) (xy 40.713954 -357.784966) (xy 39.231106 -357.784966)
			(xy 39.231106 -357.784971) (xy 39.223343 -357.838958) (xy 39.207977 -357.891291) (xy 39.18532 -357.940905)
			(xy 39.155832 -357.986789) (xy 39.120115 -358.02801) (xy 39.078895 -358.063728) (xy 39.033012 -358.093216)
			(xy 38.983399 -358.115875) (xy 38.931066 -358.131242) (xy 38.877079 -358.139005) (xy 38.849808 -358.139492)
			(xy 37.986208 -358.139492) (xy 37.958939 -358.138969) (xy 37.904955 -358.131209) (xy 37.852626 -358.115844)
			(xy 37.803015 -358.093189) (xy 37.757134 -358.063704) (xy 37.715917 -358.027989) (xy 37.680201 -357.986772)
			(xy 37.650715 -357.940892) (xy 37.628059 -357.891282) (xy 37.612693 -357.838953) (xy 37.604931 -357.784969)
			(xy 36.122106 -357.784969) (xy 36.114345 -357.838953) (xy 36.09898 -357.891283) (xy 36.076326 -357.940894)
			(xy 36.046842 -357.986776) (xy 36.011129 -358.027995) (xy 35.969914 -358.063713) (xy 35.924036 -358.093203)
			(xy 35.874428 -358.115864) (xy 35.8221 -358.131234) (xy 35.768117 -358.139002) (xy 35.740848 -358.139492)
			(xy 34.877248 -358.139492) (xy 34.849977 -358.138972) (xy 34.795989 -358.131216) (xy 34.743655 -358.115855)
			(xy 34.694039 -358.093202) (xy 34.648153 -358.063718) (xy 34.606931 -358.028003) (xy 34.571211 -357.986785)
			(xy 34.541721 -357.940903) (xy 34.519062 -357.89129) (xy 34.503694 -357.838958) (xy 34.495932 -357.784971)
			(xy 33.013228 -357.784971) (xy 33.013228 -357.784974) (xy 33.005465 -357.838966) (xy 32.990097 -357.891304)
			(xy 32.967437 -357.940921) (xy 32.937946 -357.986809) (xy 32.902224 -358.028033) (xy 32.861 -358.063753)
			(xy 32.815111 -358.093243) (xy 32.765492 -358.115901) (xy 32.713154 -358.131268) (xy 32.659162 -358.139029)
			(xy 32.631888 -358.139492) (xy 31.768288 -358.139492) (xy 31.741021 -358.138945) (xy 31.687043 -358.131182)
			(xy 31.634719 -358.115817) (xy 31.585115 -358.093162) (xy 31.539239 -358.063678) (xy 31.498026 -358.027966)
			(xy 31.462315 -357.986752) (xy 31.432832 -357.940875) (xy 31.410179 -357.891269) (xy 31.394815 -357.838945)
			(xy 31.387054 -357.784967) (xy 29.904206 -357.784967) (xy 29.904206 -357.78497) (xy 29.896444 -357.838956)
			(xy 29.881079 -357.891287) (xy 29.858423 -357.940899) (xy 29.828937 -357.986782) (xy 29.793222 -358.028003)
			(xy 29.752005 -358.063721) (xy 29.706124 -358.09321) (xy 29.656513 -358.115869) (xy 29.604183 -358.131238)
			(xy 29.550198 -358.139004) (xy 29.522928 -358.139492) (xy 28.659328 -358.139492) (xy 28.632058 -358.13897)
			(xy 28.578072 -358.131212) (xy 28.52574 -358.11585) (xy 28.476127 -358.093195) (xy 28.430244 -358.063711)
			(xy 28.389024 -358.027996) (xy 28.353306 -357.986779) (xy 28.323818 -357.940897) (xy 28.30116 -357.891286)
			(xy 28.285794 -357.838955) (xy 28.278031 -357.78497) (xy 26.795328 -357.78497) (xy 26.795328 -357.784975)
			(xy 26.787565 -357.838969) (xy 26.772196 -357.891308) (xy 26.749534 -357.940927) (xy 26.720041 -357.986816)
			(xy 26.684317 -358.02804) (xy 26.64309 -358.06376) (xy 26.597199 -358.093249) (xy 26.547578 -358.115907)
			(xy 26.495237 -358.131272) (xy 26.441243 -358.139031) (xy 26.413968 -358.139492) (xy 25.550368 -358.139492)
			(xy 25.523102 -358.138943) (xy 25.469126 -358.131179) (xy 25.416805 -358.115812) (xy 25.367203 -358.093156)
			(xy 25.321329 -358.063671) (xy 25.280119 -358.027959) (xy 25.24441 -357.986745) (xy 25.214929 -357.940869)
			(xy 25.192277 -357.891265) (xy 25.176914 -357.838942) (xy 25.169154 -357.784966) (xy 23.686306 -357.784966)
			(xy 23.686306 -357.784971) (xy 23.678543 -357.838958) (xy 23.663177 -357.891291) (xy 23.64052 -357.940905)
			(xy 23.611032 -357.986789) (xy 23.575315 -358.02801) (xy 23.534095 -358.063728) (xy 23.488212 -358.093216)
			(xy 23.438599 -358.115875) (xy 23.386266 -358.131242) (xy 23.332279 -358.139005) (xy 23.305008 -358.139492)
			(xy 22.441408 -358.139492) (xy 22.414139 -358.138969) (xy 22.360155 -358.131209) (xy 22.307826 -358.115844)
			(xy 22.258215 -358.093189) (xy 22.212334 -358.063704) (xy 22.171117 -358.027989) (xy 22.135401 -357.986772)
			(xy 22.105915 -357.940892) (xy 22.083259 -357.891282) (xy 22.067893 -357.838953) (xy 22.060131 -357.784969)
			(xy 1.524 -357.784969) (xy 1.524 -360.017783) (xy 101.774757 -360.017783) (xy 101.774757 -359.957817)
			(xy 101.782584 -359.898365) (xy 101.798104 -359.840443) (xy 101.821052 -359.785042) (xy 101.851035 -359.733111)
			(xy 101.88754 -359.685538) (xy 101.929942 -359.643136) (xy 101.977516 -359.606632) (xy 102.029448 -359.57665)
			(xy 102.084849 -359.553703) (xy 102.142771 -359.538183) (xy 102.202223 -359.530357) (xy 102.232206 -359.529888)
			(xy 103.095806 -359.529888) (xy 103.125793 -359.530279) (xy 103.185255 -359.538108) (xy 103.243186 -359.553631)
			(xy 103.298595 -359.576583) (xy 103.350534 -359.60657) (xy 103.398115 -359.643081) (xy 103.440523 -359.68549)
			(xy 103.477033 -359.733071) (xy 103.50702 -359.785011) (xy 103.529971 -359.84042) (xy 103.545494 -359.898351)
			(xy 103.553322 -359.957813) (xy 103.553322 -360.017787) (xy 103.545494 -360.077249) (xy 103.529971 -360.13518)
			(xy 103.50702 -360.190589) (xy 103.477033 -360.242529) (xy 103.440523 -360.29011) (xy 103.398115 -360.332519)
			(xy 103.350534 -360.36903) (xy 103.298595 -360.399017) (xy 103.243186 -360.421969) (xy 103.185255 -360.437492)
			(xy 103.125793 -360.445321) (xy 103.095806 -360.445812) (xy 102.232206 -360.445812) (xy 102.202223 -360.445243)
			(xy 102.142771 -360.437417) (xy 102.084849 -360.421897) (xy 102.029448 -360.39895) (xy 101.977516 -360.368968)
			(xy 101.929942 -360.332464) (xy 101.88754 -360.290062) (xy 101.851035 -360.242489) (xy 101.821052 -360.190558)
			(xy 101.798104 -360.135157) (xy 101.782584 -360.077235) (xy 101.774757 -360.017783) (xy 1.524 -360.017783)
			(xy 1.524 -363.334808) (xy 54.890416 -363.334808) (xy 54.890416 -362.471208) (xy 54.890906 -362.441224)
			(xy 54.898734 -362.381768) (xy 54.914255 -362.323843) (xy 54.937204 -362.268439) (xy 54.967188 -362.216505)
			(xy 55.003694 -362.168929) (xy 55.046099 -362.126524) (xy 55.093675 -362.090018) (xy 55.145609 -362.060034)
			(xy 55.201013 -362.037085) (xy 55.258938 -362.021564) (xy 55.318394 -362.013736) (xy 55.378362 -362.013736)
			(xy 55.437818 -362.021564) (xy 55.495743 -362.037085) (xy 55.551147 -362.060034) (xy 55.603081 -362.090018)
			(xy 55.650657 -362.126524) (xy 55.693062 -362.168929) (xy 55.729568 -362.216505) (xy 55.759552 -362.268439)
			(xy 55.782501 -362.323843) (xy 55.798022 -362.381768) (xy 55.80585 -362.441224) (xy 55.80634 -362.471208)
			(xy 55.80634 -363.334808) (xy 55.80585 -363.364792) (xy 55.798022 -363.424248) (xy 55.782501 -363.482173)
			(xy 55.759552 -363.537577) (xy 55.729568 -363.589511) (xy 55.693062 -363.637087) (xy 55.650657 -363.679492)
			(xy 55.603081 -363.715998) (xy 55.551147 -363.745982) (xy 55.495743 -363.768931) (xy 55.437818 -363.784452)
			(xy 55.378362 -363.79228) (xy 55.318394 -363.79228) (xy 55.258938 -363.784452) (xy 55.201013 -363.768931)
			(xy 55.145609 -363.745982) (xy 55.093675 -363.715998) (xy 55.046099 -363.679492) (xy 55.003694 -363.637087)
			(xy 54.967188 -363.589511) (xy 54.937204 -363.537577) (xy 54.914255 -363.482173) (xy 54.898734 -363.424248)
			(xy 54.890906 -363.364792) (xy 54.890416 -363.334808) (xy 1.524 -363.334808) (xy 1.524 -365.797384)
			(xy 54.438294 -365.797384) (xy 54.438294 -365.737416) (xy 54.446121 -365.67796) (xy 54.461641 -365.620034)
			(xy 54.484589 -365.564629) (xy 54.514571 -365.512694) (xy 54.551076 -365.465115) (xy 54.593478 -365.422709)
			(xy 54.641052 -365.386199) (xy 54.692984 -365.356211) (xy 54.748387 -365.333257) (xy 54.806311 -365.317731)
			(xy 54.865766 -365.309897) (xy 54.89575 -365.309404) (xy 55.75935 -365.309404) (xy 55.789336 -365.309938)
			(xy 55.848794 -365.31776) (xy 55.906723 -365.333276) (xy 55.962131 -365.356222) (xy 56.01407 -365.386203)
			(xy 56.06165 -365.422708) (xy 56.104059 -365.465112) (xy 56.140569 -365.512689) (xy 56.170556 -365.564624)
			(xy 56.193508 -365.620029) (xy 56.20903 -365.677957) (xy 56.216859 -365.737414) (xy 56.216859 -365.797386)
			(xy 56.20903 -365.856843) (xy 56.193508 -365.914771) (xy 56.170556 -365.970176) (xy 56.140569 -366.022112)
			(xy 56.104059 -366.069688) (xy 56.06165 -366.112092) (xy 56.01407 -366.148597) (xy 55.962131 -366.178578)
			(xy 55.906723 -366.201524) (xy 55.848794 -366.21704) (xy 55.789336 -366.224862) (xy 55.75935 -366.225328)
			(xy 54.89575 -366.225328) (xy 54.865766 -366.224903) (xy 54.806311 -366.217069) (xy 54.748386 -366.201543)
			(xy 54.692984 -366.178589) (xy 54.641052 -366.148601) (xy 54.593478 -366.112091) (xy 54.551076 -366.069685)
			(xy 54.514571 -366.022106) (xy 54.484589 -365.970171) (xy 54.461641 -365.914766) (xy 54.446121 -365.85684)
			(xy 54.438294 -365.797384) (xy 1.524 -365.797384) (xy 1.524 -367.89868) (xy 1.524416 -367.908704)
			(xy 1.532082 -367.927228) (xy 1.546255 -367.941406) (xy 1.564776 -367.94908) (xy 1.5748 -367.94948)
			(xy 5.720842 -367.94948) (xy 5.7531 -367.937796) (xy 5.775978 -367.919717) (xy 5.82614 -367.889994)
			(xy 5.880243 -367.868254) (xy 5.937025 -367.855004) (xy 5.995162 -367.850553) (xy 6.053299 -367.855004)
			(xy 6.110081 -367.868254) (xy 6.164184 -367.889994) (xy 6.214346 -367.919717) (xy 6.237224 -367.937796)
			(xy 6.269482 -367.94948) (xy 53.915564 -367.94948) (xy 53.925589 -367.949066) (xy 53.944114 -367.941402)
			(xy 53.958293 -367.927228) (xy 53.965963 -367.908704) (xy 53.966364 -367.89868) (xy 53.966364 -367.653062)
			(xy 53.96685 -367.625793) (xy 53.974612 -367.571809) (xy 53.989977 -367.519479) (xy 54.012634 -367.469869)
			(xy 54.04212 -367.423988) (xy 54.077835 -367.382771) (xy 54.119052 -367.347056) (xy 54.164933 -367.31757)
			(xy 54.214543 -367.294913) (xy 54.266873 -367.279548) (xy 54.320857 -367.271786) (xy 54.375395 -367.271786)
			(xy 54.429379 -367.279548) (xy 54.481709 -367.294913) (xy 54.531319 -367.31757) (xy 54.5772 -367.347056)
			(xy 54.618417 -367.382771) (xy 54.654132 -367.423988) (xy 54.683618 -367.469869) (xy 54.706275 -367.519479)
			(xy 54.72164 -367.571809) (xy 54.729402 -367.625793) (xy 54.729888 -367.653062) (xy 54.729888 -367.89868)
			(xy 54.730304 -367.908705) (xy 54.73797 -367.927231) (xy 54.752142 -367.941412) (xy 54.770663 -367.94909)
			(xy 54.780688 -367.94948) (xy 57.288684 -367.94948) (xy 57.298706 -367.949063) (xy 57.317225 -367.941395)
			(xy 57.331397 -367.927221) (xy 57.339063 -367.908702) (xy 57.339484 -367.89868) (xy 57.339484 -367.653062)
			(xy 57.33997 -367.625793) (xy 57.347732 -367.571809) (xy 57.363097 -367.519479) (xy 57.385754 -367.469869)
			(xy 57.41524 -367.423988) (xy 57.450955 -367.382771) (xy 57.492172 -367.347056) (xy 57.538053 -367.31757)
			(xy 57.587663 -367.294913) (xy 57.639993 -367.279548) (xy 57.693977 -367.271786) (xy 57.748515 -367.271786)
			(xy 57.802499 -367.279548) (xy 57.854829 -367.294913) (xy 57.904439 -367.31757) (xy 57.95032 -367.347056)
			(xy 57.991537 -367.382771) (xy 58.027252 -367.423988) (xy 58.056738 -367.469869) (xy 58.079395 -367.519479)
			(xy 58.09476 -367.571809) (xy 58.102522 -367.625793) (xy 58.103008 -367.653062) (xy 58.103008 -367.89868)
			(xy 58.103424 -367.908703) (xy 58.111091 -367.927226) (xy 58.125264 -367.941402) (xy 58.143785 -367.949074)
			(xy 58.153808 -367.94948) (xy 100.418392 -367.94948) (xy 100.426774 -367.946432) (xy 100.457938 -367.935988)
			(xy 100.522691 -367.924755) (xy 100.555552 -367.92408) (xy 100.58841 -367.924772) (xy 100.653157 -367.936019)
			(xy 100.68433 -367.946432) (xy 100.692712 -367.94948) (xy 103.35514 -367.94948) (xy 103.386636 -367.938304)
			(xy 103.40928 -367.920932) (xy 103.458706 -367.892403) (xy 103.511831 -367.871556) (xy 103.56747 -367.85886)
			(xy 103.62438 -367.854596) (xy 103.68129 -367.85886) (xy 103.736929 -367.871556) (xy 103.790054 -367.892403)
			(xy 103.83948 -367.920932) (xy 103.862124 -367.938304) (xy 103.89362 -367.94948) (xy 202.57135 -367.94948)
			(xy 202.580783 -367.948986) (xy 202.598343 -367.94207) (xy 202.612234 -367.929294) (xy 202.616816 -367.921032)
			(xy 202.616816 -367.920778) (xy 202.628817 -367.896844) (xy 202.658526 -367.852301) (xy 202.694175 -367.812353)
			(xy 202.735062 -367.777786) (xy 202.780383 -367.749279) (xy 202.829247 -367.727393) (xy 202.880693 -367.712558)
			(xy 202.933707 -367.705068) (xy 202.987249 -367.705068) (xy 203.040263 -367.712558) (xy 203.091709 -367.727393)
			(xy 203.140573 -367.749279) (xy 203.185894 -367.777786) (xy 203.226781 -367.812353) (xy 203.26243 -367.852301)
			(xy 203.292139 -367.896844) (xy 203.30414 -367.920778) (xy 203.30414 -367.921032) (xy 203.308629 -367.929365)
			(xy 203.322531 -367.94219) (xy 203.340149 -367.949074) (xy 203.349606 -367.94948) (xy 203.58735 -367.94948)
			(xy 203.596783 -367.948986) (xy 203.614343 -367.94207) (xy 203.628234 -367.929294) (xy 203.632816 -367.921032)
			(xy 203.632816 -367.920778) (xy 203.644817 -367.896844) (xy 203.674527 -367.852302) (xy 203.710177 -367.812354)
			(xy 203.751064 -367.777786) (xy 203.796385 -367.749279) (xy 203.845248 -367.727391) (xy 203.896693 -367.712555)
			(xy 203.949707 -367.705062) (xy 203.976478 -367.704624) (xy 203.985876 -367.704624) (xy 203.996036 -367.704878)
			(xy 204.015086 -367.697512) (xy 204.074776 -367.6396) (xy 204.081725 -367.632175) (xy 204.089587 -367.613439)
			(xy 204.090016 -367.603278) (xy 204.090016 -367.26876) (xy 204.0905 -367.243808) (xy 204.098296 -367.194518)
			(xy 204.113706 -367.147053) (xy 204.13635 -367.102583) (xy 204.16567 -367.062201) (xy 204.18298 -367.044224)
			(xy 204.446632 -366.780572) (xy 204.464629 -366.763285) (xy 204.50501 -366.733969) (xy 204.549476 -366.711323)
			(xy 204.596934 -366.695902) (xy 204.646218 -366.688086) (xy 204.671168 -366.687608) (xy 208.09839 -366.687608)
			(xy 208.123342 -366.688071) (xy 208.17263 -366.695876) (xy 208.220091 -366.711296) (xy 208.264556 -366.733951)
			(xy 208.304928 -366.763283) (xy 208.322926 -366.780572) (xy 208.566512 -367.024158) (xy 208.583794 -367.042158)
			(xy 208.613098 -367.082542) (xy 208.635735 -367.127008) (xy 208.651147 -367.174465) (xy 208.658958 -367.223746)
			(xy 208.659476 -367.248694) (xy 208.659476 -369.788186) (xy 208.659961 -369.798197) (xy 208.667617 -369.816698)
			(xy 208.68177 -369.830861) (xy 208.700265 -369.838531) (xy 208.710276 -369.838986) (xy 208.785968 -369.838986)
			(xy 208.810918 -369.839473) (xy 208.860205 -369.847274) (xy 208.907665 -369.862689) (xy 208.95213 -369.885339)
			(xy 208.992503 -369.914666) (xy 209.010504 -369.93195) (xy 209.67573 -370.597176) (xy 209.683129 -370.60402)
			(xy 209.701727 -370.611748) (xy 209.711798 -370.612162) (xy 210.06562 -370.612162) (xy 210.090572 -370.612645)
			(xy 210.139863 -370.620439) (xy 210.187329 -370.635848) (xy 210.231799 -370.658493) (xy 210.27218 -370.687815)
			(xy 210.290156 -370.705126) (xy 210.516978 -370.931948) (xy 210.534262 -370.949947) (xy 210.563571 -370.99033)
			(xy 210.586211 -371.034796) (xy 210.601627 -371.082253) (xy 210.60944 -371.131535) (xy 210.609942 -371.156484)
			(xy 210.609942 -371.380512) (xy 210.610364 -371.390529) (xy 210.618038 -371.409034) (xy 210.632211 -371.423192)
			(xy 210.650725 -371.430846) (xy 210.660742 -371.431312) (xy 216.45245 -371.431312) (xy 216.462516 -371.43088)
			(xy 216.481109 -371.423154) (xy 216.488518 -371.416326) (xy 217.302334 -370.60251) (xy 217.309189 -370.595115)
			(xy 217.316938 -370.576517) (xy 217.31732 -370.566442) (xy 217.31732 -367.318036) (xy 217.317806 -367.293085)
			(xy 217.325606 -367.243796) (xy 217.341018 -367.196334) (xy 217.363664 -367.151867) (xy 217.392987 -367.111488)
			(xy 217.410284 -367.0935) (xy 217.733118 -366.770666) (xy 217.751115 -366.753378) (xy 217.791496 -366.724062)
			(xy 217.835962 -366.701414) (xy 217.883419 -366.685991) (xy 217.932704 -366.678172) (xy 217.957654 -366.677702)
			(xy 221.342458 -366.677702) (xy 221.367411 -366.678163) (xy 221.416702 -366.685963) (xy 221.464166 -366.701379)
			(xy 221.508634 -366.724031) (xy 221.549011 -366.753361) (xy 221.566994 -366.770666) (xy 221.81058 -367.014252)
			(xy 221.827864 -367.032251) (xy 221.857172 -367.072634) (xy 221.879811 -367.1171) (xy 221.895227 -367.164557)
			(xy 221.903039 -367.213839) (xy 221.903544 -367.238788) (xy 221.903544 -370.592604) (xy 221.903969 -370.602673)
			(xy 221.91169 -370.621272) (xy 221.91853 -370.628672) (xy 222.004382 -370.714524) (xy 222.021667 -370.732522)
			(xy 222.050979 -370.772905) (xy 222.073622 -370.817371) (xy 222.089041 -370.864828) (xy 222.096858 -370.914111)
			(xy 222.097346 -370.93906) (xy 222.097346 -373.42191) (xy 222.097772 -373.431978) (xy 222.105494 -373.450576)
			(xy 222.112332 -373.457978) (xy 223.764602 -375.110248) (xy 223.771998 -375.1171) (xy 223.790597 -375.124842)
			(xy 223.80067 -375.125234) (xy 225.416872 -375.125234) (xy 225.426935 -375.124796) (xy 225.445514 -375.117056)
			(xy 225.45294 -375.110248) (xy 226.51339 -374.049798) (xy 226.520237 -374.0424) (xy 226.527972 -374.023802)
			(xy 226.528376 -374.01373) (xy 226.528376 -372.656862) (xy 226.528835 -372.631909) (xy 226.536633 -372.582615)
			(xy 226.552045 -372.535148) (xy 226.574694 -372.490677) (xy 226.60402 -372.450296) (xy 226.62134 -372.432326)
			(xy 227.816156 -371.23751) (xy 227.823009 -371.230114) (xy 227.830754 -371.211516) (xy 227.831142 -371.201442)
			(xy 227.831142 -370.936012) (xy 227.83163 -370.911062) (xy 227.839433 -370.861776) (xy 227.854849 -370.814316)
			(xy 227.877499 -370.769853) (xy 227.906824 -370.729479) (xy 227.924106 -370.711476) (xy 228.003608 -370.631974)
			(xy 228.010449 -370.624574) (xy 228.018173 -370.605976) (xy 228.018594 -370.595906) (xy 228.018594 -367.245138)
			(xy 228.019055 -367.220185) (xy 228.026856 -367.170894) (xy 228.042272 -367.12343) (xy 228.064924 -367.078962)
			(xy 228.094253 -367.038585) (xy 228.111558 -367.020602) (xy 228.364796 -366.767364) (xy 228.382793 -366.750075)
			(xy 228.423173 -366.720756) (xy 228.467638 -366.698105) (xy 228.515096 -366.682679) (xy 228.564381 -366.674857)
			(xy 228.589332 -366.6744) (xy 232.007156 -366.6744) (xy 232.032109 -366.67486) (xy 232.0814 -366.682661)
			(xy 232.128865 -366.698077) (xy 232.173333 -366.720728) (xy 232.213711 -366.750057) (xy 232.231692 -366.767364)
			(xy 232.48493 -367.020602) (xy 232.502219 -367.038599) (xy 232.531538 -367.078979) (xy 232.554188 -367.123444)
			(xy 232.569613 -367.170902) (xy 232.577435 -367.220187) (xy 232.577894 -367.245138) (xy 232.577894 -370.60251)
			(xy 232.578319 -370.61258) (xy 232.586035 -370.631182) (xy 232.59288 -370.638578) (xy 232.652824 -370.698522)
			(xy 232.670112 -370.716519) (xy 232.699429 -370.7569) (xy 232.722077 -370.801365) (xy 232.737499 -370.848823)
			(xy 232.745318 -370.898108) (xy 232.745788 -370.923058) (xy 232.745788 -371.05971) (xy 232.746212 -371.06978)
			(xy 232.753928 -371.088383) (xy 232.760774 -371.095778) (xy 233.402886 -371.73789) (xy 233.420167 -371.75589)
			(xy 233.44947 -371.796274) (xy 233.472104 -371.840741) (xy 233.487513 -371.888197) (xy 233.495319 -371.937478)
			(xy 233.49585 -371.962426) (xy 233.49585 -375.346214) (xy 233.496277 -375.356282) (xy 233.504001 -375.374878)
			(xy 233.510836 -375.382282) (xy 237.245652 -379.117098) (xy 237.253053 -379.123937) (xy 237.271651 -379.131652)
			(xy 237.28172 -379.132084) (xy 239.621314 -379.132084) (xy 239.631383 -379.131658) (xy 239.649982 -379.123938)
			(xy 239.657382 -379.117098) (xy 240.207292 -378.567188) (xy 240.225293 -378.549908) (xy 240.265678 -378.520608)
			(xy 240.310144 -378.497976) (xy 240.3576 -378.482569) (xy 240.406881 -378.474763) (xy 240.431828 -378.474224)
			(xy 262.084058 -378.474224) (xy 262.109009 -378.47471) (xy 262.158298 -378.482508) (xy 262.205761 -378.49792)
			(xy 262.250229 -378.520566) (xy 262.290608 -378.549888) (xy 262.308594 -378.567188) (xy 262.441436 -378.70003)
			(xy 266.644636 -378.70003) (xy 266.648637 -378.494991) (xy 266.660635 -378.290263) (xy 266.680612 -378.08616)
			(xy 266.708537 -377.882992) (xy 266.744367 -377.681068) (xy 266.788049 -377.480695) (xy 266.839515 -377.28218)
			(xy 266.898687 -377.085823) (xy 266.965475 -376.891925) (xy 267.039777 -376.70078) (xy 267.12148 -376.51268)
			(xy 267.210461 -376.327911) (xy 267.306582 -376.146754) (xy 267.409698 -375.969485) (xy 267.519652 -375.796375)
			(xy 267.636277 -375.627686) (xy 267.759394 -375.463676) (xy 267.888817 -375.304594) (xy 268.024347 -375.150683)
			(xy 268.16578 -375.002177) (xy 268.312899 -374.859302) (xy 268.46548 -374.722277) (xy 268.623292 -374.591308)
			(xy 268.786093 -374.466597) (xy 268.953636 -374.348332) (xy 269.125665 -374.236694) (xy 269.30192 -374.131853)
			(xy 269.48213 -374.033969) (xy 269.666022 -373.94319) (xy 269.853317 -373.859656) (xy 270.043727 -373.783492)
			(xy 270.236965 -373.714815) (xy 270.432735 -373.65373) (xy 270.630739 -373.60033) (xy 270.830675 -373.554696)
			(xy 271.03224 -373.516897) (xy 271.235126 -373.486991) (xy 271.439025 -373.465024) (xy 271.643625 -373.451029)
			(xy 271.848616 -373.445028) (xy 272.053685 -373.447028) (xy 272.258519 -373.457029) (xy 272.462807 -373.475013)
			(xy 272.666239 -373.500955) (xy 272.868503 -373.534813) (xy 273.069292 -373.576538) (xy 273.2683 -373.626064)
			(xy 273.465224 -373.683318) (xy 273.659765 -373.748211) (xy 273.851626 -373.820645) (xy 274.040514 -373.900509)
			(xy 274.226143 -373.987683) (xy 274.408229 -374.082032) (xy 274.586495 -374.183414) (xy 274.76067 -374.291674)
			(xy 274.930489 -374.406647) (xy 274.953921 -374.423882) (xy 286.928731 -374.423882) (xy 286.928735 -374.356454)
			(xy 286.936815 -374.289512) (xy 286.952857 -374.22402) (xy 286.976628 -374.160921) (xy 287.007787 -374.101124)
			(xy 287.045884 -374.04549) (xy 287.067752 -374.019826) (xy 287.073569 -374.012695) (xy 287.08007 -373.995494)
			(xy 287.080452 -373.986298) (xy 287.080452 -373.828818) (xy 287.080942 -373.818691) (xy 287.088666 -373.799968)
			(xy 287.102951 -373.785611) (xy 287.121636 -373.777793) (xy 287.13176 -373.777256) (xy 287.84804 -373.777256)
			(xy 287.858191 -373.777688) (xy 287.876936 -373.785489) (xy 287.891256 -373.799881) (xy 287.898963 -373.818665)
			(xy 287.899348 -373.828818) (xy 287.899348 -373.986298) (xy 287.899771 -373.995484) (xy 287.906277 -374.012667)
			(xy 287.912048 -374.019826) (xy 287.933873 -374.045524) (xy 287.971966 -374.101153) (xy 288.003121 -374.160944)
			(xy 288.02689 -374.224037) (xy 288.04293 -374.289522) (xy 288.05101 -374.356458) (xy 288.051014 -374.423823)
			(xy 291.32905 -374.423823) (xy 291.329054 -374.356514) (xy 291.337102 -374.289689) (xy 291.35308 -374.224304)
			(xy 291.376757 -374.161298) (xy 291.407796 -374.101573) (xy 291.44575 -374.045986) (xy 291.46754 -374.020334)
			(xy 291.473352 -374.0132) (xy 291.479857 -373.996001) (xy 291.48024 -373.986806) (xy 291.48024 -373.828818)
			(xy 291.480678 -373.818647) (xy 291.488458 -373.799853) (xy 291.502839 -373.785467) (xy 291.521631 -373.777682)
			(xy 291.531802 -373.777256) (xy 292.248082 -373.777256) (xy 292.258255 -373.777679) (xy 292.277053 -373.785461)
			(xy 292.291439 -373.799847) (xy 292.299221 -373.818645) (xy 292.299644 -373.828818) (xy 292.299644 -373.986806)
			(xy 292.300064 -373.995992) (xy 292.306572 -374.013176) (xy 292.312344 -374.020334) (xy 292.334091 -374.04602)
			(xy 292.372042 -374.101601) (xy 292.403078 -374.16132) (xy 292.426754 -374.22432) (xy 292.44273 -374.289698)
			(xy 292.450778 -374.356517) (xy 292.450782 -374.423819) (xy 292.450774 -374.423882) (xy 295.728819 -374.423882)
			(xy 295.728822 -374.356455) (xy 295.736903 -374.289513) (xy 295.752944 -374.224021) (xy 295.776715 -374.160922)
			(xy 295.807872 -374.101125) (xy 295.845968 -374.045491) (xy 295.867836 -374.019826) (xy 295.873651 -374.012694)
			(xy 295.880154 -373.995493) (xy 295.880536 -373.986298) (xy 295.880536 -373.828818) (xy 295.881041 -373.818693)
			(xy 295.888762 -373.799973) (xy 295.903043 -373.785616) (xy 295.921722 -373.777796) (xy 295.931844 -373.777256)
			(xy 296.648124 -373.777256) (xy 296.658274 -373.777701) (xy 296.677019 -373.785496) (xy 296.69134 -373.799885)
			(xy 296.699046 -373.818666) (xy 296.699432 -373.828818) (xy 296.699432 -373.986298) (xy 296.699858 -373.995483)
			(xy 296.706362 -374.012667) (xy 296.712132 -374.019826) (xy 296.733954 -374.045526) (xy 296.772041 -374.101156)
			(xy 296.803192 -374.160948) (xy 296.826957 -374.22404) (xy 296.842995 -374.289525) (xy 296.851073 -374.356459)
			(xy 296.851077 -374.423878) (xy 296.851077 -374.423882) (xy 300.12861 -374.423882) (xy 300.128613 -374.356455)
			(xy 300.136694 -374.289513) (xy 300.152734 -374.224021) (xy 300.176504 -374.160923) (xy 300.207661 -374.101126)
			(xy 300.245757 -374.045491) (xy 300.267624 -374.019826) (xy 300.273437 -374.012693) (xy 300.279941 -373.995493)
			(xy 300.280324 -373.986298) (xy 300.280324 -373.828818) (xy 300.280841 -373.818694) (xy 300.28856 -373.799977)
			(xy 300.302837 -373.78562) (xy 300.321511 -373.777798) (xy 300.331632 -373.777256) (xy 301.047912 -373.777256)
			(xy 301.058061 -373.777711) (xy 301.076806 -373.785502) (xy 301.091127 -373.799888) (xy 301.098834 -373.818667)
			(xy 301.09922 -373.828818) (xy 301.09922 -373.986298) (xy 301.099627 -373.995486) (xy 301.106142 -374.01267)
			(xy 301.11192 -374.019826) (xy 301.133742 -374.045526) (xy 301.171831 -374.101156) (xy 301.202982 -374.160947)
			(xy 301.226748 -374.22404) (xy 301.242785 -374.289524) (xy 301.250864 -374.356458) (xy 301.250868 -374.423823)
			(xy 330.929168 -374.423823) (xy 330.929172 -374.356514) (xy 330.937221 -374.289688) (xy 330.953199 -374.224303)
			(xy 330.976878 -374.161297) (xy 331.007917 -374.101572) (xy 331.045873 -374.045986) (xy 331.067664 -374.020334)
			(xy 331.073479 -374.013202) (xy 331.079981 -373.996001) (xy 331.080364 -373.986806) (xy 331.080364 -373.828818)
			(xy 331.080779 -373.818644) (xy 331.088563 -373.799845) (xy 331.102952 -373.785458) (xy 331.121752 -373.777677)
			(xy 331.131926 -373.777256) (xy 331.848206 -373.777256) (xy 331.85838 -373.777659) (xy 331.877178 -373.78545)
			(xy 331.891564 -373.799842) (xy 331.899345 -373.818644) (xy 331.899768 -373.828818) (xy 331.899768 -373.986806)
			(xy 331.900182 -373.995993) (xy 331.906694 -374.013177) (xy 331.912468 -374.020334) (xy 331.934214 -374.04602)
			(xy 331.972164 -374.101602) (xy 332.003198 -374.161321) (xy 332.026873 -374.224321) (xy 332.042849 -374.289699)
			(xy 332.050896 -374.356518) (xy 332.0509 -374.423819) (xy 332.050892 -374.423882) (xy 335.328961 -374.423882)
			(xy 335.328965 -374.356455) (xy 335.337045 -374.289515) (xy 335.353083 -374.224024) (xy 335.37685 -374.160926)
			(xy 335.408004 -374.101128) (xy 335.446095 -374.045492) (xy 335.46796 -374.019826) (xy 335.473778 -374.012696)
			(xy 335.480278 -373.995494) (xy 335.48066 -373.986298) (xy 335.48066 -373.828818) (xy 335.481142 -373.81869)
			(xy 335.488867 -373.799965) (xy 335.503156 -373.785608) (xy 335.521842 -373.777791) (xy 335.531968 -373.777256)
			(xy 336.248248 -373.777256) (xy 336.2584 -373.777682) (xy 336.277145 -373.785485) (xy 336.291465 -373.799879)
			(xy 336.299171 -373.818664) (xy 336.299556 -373.828818) (xy 336.299556 -373.986298) (xy 336.299977 -373.995484)
			(xy 336.306484 -374.012668) (xy 336.312256 -374.019826) (xy 336.33408 -374.045525) (xy 336.372173 -374.101153)
			(xy 336.403328 -374.160944) (xy 336.427097 -374.224037) (xy 336.443136 -374.289523) (xy 336.451216 -374.356458)
			(xy 336.45122 -374.423823) (xy 339.729256 -374.423823) (xy 339.72926 -374.356514) (xy 339.737309 -374.289689)
			(xy 339.753286 -374.224304) (xy 339.776964 -374.161298) (xy 339.808003 -374.101573) (xy 339.845957 -374.045986)
			(xy 339.867748 -374.020334) (xy 339.873561 -374.013201) (xy 339.880065 -373.996001) (xy 339.880448 -373.986806)
			(xy 339.880448 -373.828818) (xy 339.880879 -373.818646) (xy 339.88866 -373.79985) (xy 339.903043 -373.785464)
			(xy 339.921838 -373.77768) (xy 339.93201 -373.777256) (xy 340.64829 -373.777256) (xy 340.658463 -373.777672)
			(xy 340.677261 -373.785457) (xy 340.691647 -373.799846) (xy 340.699429 -373.818645) (xy 340.699852 -373.828818)
			(xy 340.699852 -373.986806) (xy 340.70027 -373.995992) (xy 340.706779 -374.013176) (xy 340.712552 -374.020334)
			(xy 340.734299 -374.04602) (xy 340.772249 -374.101601) (xy 340.803285 -374.16132) (xy 340.82696 -374.22432)
			(xy 340.842936 -374.289699) (xy 340.850984 -374.356517) (xy 340.850988 -374.423819) (xy 340.850988 -374.423823)
			(xy 344.129047 -374.423823) (xy 344.129051 -374.356514) (xy 344.137099 -374.289689) (xy 344.153077 -374.224304)
			(xy 344.176754 -374.161298) (xy 344.207792 -374.101573) (xy 344.245746 -374.045986) (xy 344.267536 -374.020334)
			(xy 344.273348 -374.0132) (xy 344.279852 -373.996001) (xy 344.280236 -373.986806) (xy 344.280236 -373.828818)
			(xy 344.280678 -373.818648) (xy 344.288457 -373.799854) (xy 344.302837 -373.785468) (xy 344.321628 -373.777682)
			(xy 344.331798 -373.777256) (xy 345.048078 -373.777256) (xy 345.05825 -373.777683) (xy 345.077048 -373.785464)
			(xy 345.091434 -373.799849) (xy 345.099217 -373.818646) (xy 345.09964 -373.828818) (xy 345.09964 -373.986806)
			(xy 345.100061 -373.995992) (xy 345.106569 -374.013175) (xy 345.11234 -374.020334) (xy 345.134087 -374.04602)
			(xy 345.172038 -374.101601) (xy 345.203075 -374.16132) (xy 345.226751 -374.22432) (xy 345.242727 -374.289698)
			(xy 345.250775 -374.356517) (xy 345.250779 -374.423819) (xy 345.250779 -374.423823) (xy 374.929078 -374.423823)
			(xy 374.929081 -374.356514) (xy 374.93713 -374.289688) (xy 374.953109 -374.224303) (xy 374.976788 -374.161296)
			(xy 375.007828 -374.101572) (xy 375.045784 -374.045985) (xy 375.067576 -374.020334) (xy 375.07338 -374.013194)
			(xy 375.079891 -373.996) (xy 375.080276 -373.986806) (xy 375.080276 -373.828818) (xy 375.080679 -373.818643)
			(xy 375.088465 -373.799841) (xy 375.102858 -373.785454) (xy 375.121663 -373.777675) (xy 375.131838 -373.777256)
			(xy 375.848118 -373.777256) (xy 375.858279 -373.777719) (xy 375.877052 -373.785503) (xy 375.891418 -373.799878)
			(xy 375.899188 -373.818656) (xy 375.89968 -373.828818) (xy 375.89968 -373.986806) (xy 375.900092 -373.995993)
			(xy 375.906605 -374.013177) (xy 375.91238 -374.020334) (xy 375.934126 -374.046021) (xy 375.972074 -374.101603)
			(xy 376.003108 -374.161322) (xy 376.026783 -374.224321) (xy 376.042758 -374.289699) (xy 376.050805 -374.356518)
			(xy 376.050809 -374.423819) (xy 376.050801 -374.423882) (xy 379.32887 -374.423882) (xy 379.328874 -374.356455)
			(xy 379.336954 -374.289515) (xy 379.352993 -374.224024) (xy 379.376761 -374.160925) (xy 379.407915 -374.101127)
			(xy 379.446007 -374.045492) (xy 379.467872 -374.019826) (xy 379.473691 -374.012697) (xy 379.48019 -373.995494)
			(xy 379.480572 -373.986298) (xy 379.480572 -373.828818) (xy 379.481042 -373.818688) (xy 379.48877 -373.799962)
			(xy 379.503062 -373.785604) (xy 379.521753 -373.777789) (xy 379.53188 -373.777256) (xy 380.24816 -373.777256)
			(xy 380.258306 -373.777754) (xy 380.277049 -373.785528) (xy 380.291372 -373.799901) (xy 380.299081 -373.818671)
			(xy 380.299468 -373.828818) (xy 380.299468 -373.986298) (xy 380.299886 -373.995484) (xy 380.306395 -374.012668)
			(xy 380.312168 -374.019826) (xy 380.333992 -374.045525) (xy 380.372084 -374.101154) (xy 380.403238 -374.160945)
			(xy 380.427006 -374.224038) (xy 380.443046 -374.289523) (xy 380.451125 -374.356458) (xy 380.451129 -374.423823)
			(xy 383.729165 -374.423823) (xy 383.729169 -374.356514) (xy 383.737218 -374.289688) (xy 383.753196 -374.224303)
			(xy 383.776874 -374.161297) (xy 383.807914 -374.101572) (xy 383.845869 -374.045986) (xy 383.86766 -374.020334)
			(xy 383.873474 -374.013202) (xy 383.879977 -373.996001) (xy 383.88036 -373.986806) (xy 383.88036 -373.828818)
			(xy 383.880779 -373.818645) (xy 383.888562 -373.799846) (xy 383.90295 -373.78546) (xy 383.921749 -373.777678)
			(xy 383.931922 -373.777256) (xy 384.648202 -373.777256) (xy 384.658376 -373.777663) (xy 384.677174 -373.785452)
			(xy 384.69156 -373.799843) (xy 384.699341 -373.818644) (xy 384.699764 -373.828818) (xy 384.699764 -373.986806)
			(xy 384.700179 -373.995992) (xy 384.70669 -374.013176) (xy 384.712464 -374.020334) (xy 384.73421 -374.04602)
			(xy 384.77216 -374.101602) (xy 384.803195 -374.161321) (xy 384.82687 -374.224321) (xy 384.842846 -374.289699)
			(xy 384.850893 -374.356518) (xy 384.850897 -374.423819) (xy 384.850897 -374.423823) (xy 388.128956 -374.423823)
			(xy 388.12896 -374.356514) (xy 388.137009 -374.289689) (xy 388.152986 -374.224304) (xy 388.176664 -374.161298)
			(xy 388.207703 -374.101573) (xy 388.245657 -374.045986) (xy 388.267448 -374.020334) (xy 388.273261 -374.013201)
			(xy 388.279765 -373.996001) (xy 388.280148 -373.986806) (xy 388.280148 -373.828818) (xy 388.280579 -373.818646)
			(xy 388.28836 -373.79985) (xy 388.302743 -373.785464) (xy 388.321538 -373.77768) (xy 388.33171 -373.777256)
			(xy 389.04799 -373.777256) (xy 389.058163 -373.777672) (xy 389.076961 -373.785457) (xy 389.091347 -373.799846)
			(xy 389.099129 -373.818645) (xy 389.099552 -373.828818) (xy 389.099552 -373.986806) (xy 389.09997 -373.995992)
			(xy 389.106479 -374.013176) (xy 389.112252 -374.020334) (xy 389.133999 -374.04602) (xy 389.171949 -374.101601)
			(xy 389.202985 -374.16132) (xy 389.22666 -374.22432) (xy 389.242636 -374.289699) (xy 389.250684 -374.356517)
			(xy 389.250688 -374.423819) (xy 389.250688 -374.423823) (xy 418.928987 -374.423823) (xy 418.928991 -374.356514)
			(xy 418.93704 -374.289688) (xy 418.953019 -374.224302) (xy 418.976698 -374.161296) (xy 419.007739 -374.101572)
			(xy 419.045696 -374.045986) (xy 419.067488 -374.020334) (xy 419.073294 -374.013195) (xy 419.079803 -373.996)
			(xy 419.080188 -373.986806) (xy 419.080188 -373.828818) (xy 419.08058 -373.818641) (xy 419.088368 -373.799837)
			(xy 419.102764 -373.78545) (xy 419.121573 -373.777673) (xy 419.13175 -373.777256) (xy 419.84803 -373.777256)
			(xy 419.858192 -373.777709) (xy 419.876965 -373.785497) (xy 419.89133 -373.799875) (xy 419.8991 -373.818656)
			(xy 419.899592 -373.828818) (xy 419.899592 -373.986806) (xy 419.900001 -373.995993) (xy 419.906516 -374.013177)
			(xy 419.912292 -374.020334) (xy 419.934038 -374.04602) (xy 419.971986 -374.101603) (xy 420.003019 -374.161322)
			(xy 420.026693 -374.224322) (xy 420.042668 -374.2897) (xy 420.050715 -374.356518) (xy 420.050719 -374.423819)
			(xy 420.050711 -374.423882) (xy 423.328779 -374.423882) (xy 423.328783 -374.356455) (xy 423.336863 -374.289514)
			(xy 423.352903 -374.224023) (xy 423.376671 -374.160925) (xy 423.407825 -374.101127) (xy 423.445918 -374.045492)
			(xy 423.467784 -374.019826) (xy 423.473593 -374.012689) (xy 423.480101 -373.995492) (xy 423.480484 -373.986298)
			(xy 423.480484 -373.828818) (xy 423.480942 -373.818687) (xy 423.488672 -373.799958) (xy 423.502968 -373.785599)
			(xy 423.521663 -373.777787) (xy 423.531792 -373.777256) (xy 424.248072 -373.777256) (xy 424.258219 -373.777743)
			(xy 424.276962 -373.785522) (xy 424.291285 -373.799898) (xy 424.298994 -373.81867) (xy 424.29938 -373.828818)
			(xy 424.29938 -373.986298) (xy 424.299795 -373.995485) (xy 424.306306 -374.012669) (xy 424.31208 -374.019826)
			(xy 424.333903 -374.045525) (xy 424.371995 -374.101154) (xy 424.403148 -374.160946) (xy 424.426916 -374.224038)
			(xy 424.442955 -374.289523) (xy 424.451034 -374.356458) (xy 424.451038 -374.423823) (xy 427.729074 -374.423823)
			(xy 427.729078 -374.356514) (xy 427.737127 -374.289688) (xy 427.753106 -374.224303) (xy 427.776784 -374.161296)
			(xy 427.807824 -374.101572) (xy 427.84578 -374.045986) (xy 427.867572 -374.020334) (xy 427.873388 -374.013203)
			(xy 427.879889 -373.996001) (xy 427.880272 -373.986806) (xy 427.880272 -373.828818) (xy 427.880679 -373.818643)
			(xy 427.888465 -373.799842) (xy 427.902856 -373.785456) (xy 427.921659 -373.777676) (xy 427.931834 -373.777256)
			(xy 428.648114 -373.777256) (xy 428.658289 -373.777653) (xy 428.677087 -373.785446) (xy 428.691472 -373.79984)
			(xy 428.699253 -373.818643) (xy 428.699676 -373.828818) (xy 428.699676 -373.986806) (xy 428.700088 -373.995993)
			(xy 428.706601 -374.013177) (xy 428.712376 -374.020334) (xy 428.734122 -374.04602) (xy 428.772071 -374.101602)
			(xy 428.803105 -374.161321) (xy 428.82678 -374.224321) (xy 428.842755 -374.289699) (xy 428.850802 -374.356518)
			(xy 428.850806 -374.423819) (xy 428.850806 -374.423823) (xy 432.128865 -374.423823) (xy 432.128869 -374.356514)
			(xy 432.136918 -374.289688) (xy 432.152896 -374.224303) (xy 432.176574 -374.161297) (xy 432.207614 -374.101572)
			(xy 432.245569 -374.045986) (xy 432.26736 -374.020334) (xy 432.273174 -374.013202) (xy 432.279677 -373.996001)
			(xy 432.28006 -373.986806) (xy 432.28006 -373.828818) (xy 432.280479 -373.818645) (xy 432.288262 -373.799846)
			(xy 432.30265 -373.78546) (xy 432.321449 -373.777678) (xy 432.331622 -373.777256) (xy 433.047902 -373.777256)
			(xy 433.058076 -373.777663) (xy 433.076874 -373.785452) (xy 433.09126 -373.799843) (xy 433.099041 -373.818644)
			(xy 433.099464 -373.828818) (xy 433.099464 -373.986806) (xy 433.099879 -373.995992) (xy 433.10639 -374.013176)
			(xy 433.112164 -374.020334) (xy 433.13391 -374.04602) (xy 433.17186 -374.101602) (xy 433.202895 -374.161321)
			(xy 433.22657 -374.224321) (xy 433.242546 -374.289699) (xy 433.250593 -374.356518) (xy 433.250597 -374.423819)
			(xy 433.242557 -374.490639) (xy 433.226589 -374.556019) (xy 433.202921 -374.619021) (xy 433.171892 -374.678744)
			(xy 433.133949 -374.73433) (xy 433.112164 -374.759982) (xy 433.106346 -374.767112) (xy 433.099845 -374.784314)
			(xy 433.099464 -374.79351) (xy 433.099464 -375.286778) (xy 433.099893 -375.295963) (xy 433.106394 -375.313147)
			(xy 433.112164 -375.320306) (xy 433.133981 -375.345934) (xy 433.171929 -375.401524) (xy 433.202961 -375.461251)
			(xy 433.226632 -375.524259) (xy 433.242603 -375.589644) (xy 433.250644 -375.656469) (xy 433.250642 -375.723776)
			(xy 433.242594 -375.790601) (xy 433.226618 -375.855985) (xy 433.202942 -375.91899) (xy 433.171906 -375.978715)
			(xy 433.133954 -376.034302) (xy 433.112164 -376.059954) (xy 433.106357 -376.067092) (xy 433.09985 -376.084288)
			(xy 433.099464 -376.093482) (xy 433.099464 -376.25147) (xy 433.099011 -376.261639) (xy 433.091237 -376.280433)
			(xy 433.07686 -376.294819) (xy 433.058071 -376.302605) (xy 433.047902 -376.303032) (xy 432.331622 -376.303032)
			(xy 432.321448 -376.302617) (xy 432.302648 -376.294834) (xy 432.288262 -376.280445) (xy 432.280481 -376.261644)
			(xy 432.28006 -376.25147) (xy 432.28006 -376.093482) (xy 432.279645 -376.084296) (xy 432.273133 -376.067112)
			(xy 432.26736 -376.059954) (xy 432.245601 -376.034278) (xy 432.20765 -375.978695) (xy 432.176614 -375.918975)
			(xy 432.152939 -375.855974) (xy 432.136963 -375.790594) (xy 432.128917 -375.723774) (xy 432.128914 -375.656471)
			(xy 432.136955 -375.58965) (xy 432.152926 -375.524269) (xy 432.176596 -375.461266) (xy 432.207627 -375.401543)
			(xy 432.245574 -375.345958) (xy 432.26736 -375.320306) (xy 432.273144 -375.313152) (xy 432.279664 -375.295968)
			(xy 432.28006 -375.286778) (xy 432.28006 -374.79351) (xy 432.279632 -374.784325) (xy 432.273129 -374.767141)
			(xy 432.26736 -374.759982) (xy 432.24553 -374.734364) (xy 432.207581 -374.678773) (xy 432.176549 -374.619045)
			(xy 432.152877 -374.556036) (xy 432.136907 -374.49065) (xy 432.128865 -374.423823) (xy 428.850806 -374.423823)
			(xy 428.842766 -374.490639) (xy 428.826798 -374.556018) (xy 428.803131 -374.619021) (xy 428.772103 -374.678743)
			(xy 428.73416 -374.734329) (xy 428.712376 -374.759982) (xy 428.706559 -374.767113) (xy 428.700057 -374.784314)
			(xy 428.699676 -374.79351) (xy 428.699676 -375.286778) (xy 428.700102 -375.295963) (xy 428.706605 -375.313148)
			(xy 428.712376 -375.320306) (xy 428.734193 -375.345934) (xy 428.77214 -375.401524) (xy 428.803171 -375.461251)
			(xy 428.826841 -375.524259) (xy 428.842812 -375.589644) (xy 428.850853 -375.656469) (xy 428.850851 -375.723776)
			(xy 428.842804 -375.790601) (xy 428.826828 -375.855984) (xy 428.803152 -375.91899) (xy 428.772117 -375.978714)
			(xy 428.734165 -376.034302) (xy 428.712376 -376.059954) (xy 428.706571 -376.067093) (xy 428.700062 -376.084288)
			(xy 428.699676 -376.093482) (xy 428.699676 -376.25147) (xy 428.699212 -376.261638) (xy 428.691439 -376.280429)
			(xy 428.677066 -376.294815) (xy 428.658282 -376.302603) (xy 428.648114 -376.303032) (xy 427.931834 -376.303032)
			(xy 427.921661 -376.302607) (xy 427.902861 -376.294828) (xy 427.888474 -376.280442) (xy 427.880693 -376.261643)
			(xy 427.880272 -376.25147) (xy 427.880272 -376.093482) (xy 427.879877 -376.084293) (xy 427.873353 -376.067109)
			(xy 427.867572 -376.059954) (xy 427.845813 -376.034278) (xy 427.807861 -375.978696) (xy 427.776825 -375.918976)
			(xy 427.753149 -375.855974) (xy 427.737173 -375.790595) (xy 427.729126 -375.723774) (xy 427.729123 -375.656471)
			(xy 427.737165 -375.58965) (xy 427.753135 -375.524269) (xy 427.776806 -375.461266) (xy 427.807838 -375.401543)
			(xy 427.845785 -375.345958) (xy 427.867572 -375.320306) (xy 427.873357 -375.313153) (xy 427.879877 -375.295968)
			(xy 427.880272 -375.286778) (xy 427.880272 -374.79351) (xy 427.879863 -374.784323) (xy 427.873349 -374.767138)
			(xy 427.867572 -374.759982) (xy 427.845742 -374.734364) (xy 427.807792 -374.678774) (xy 427.776759 -374.619046)
			(xy 427.753087 -374.556037) (xy 427.737116 -374.49065) (xy 427.729074 -374.423823) (xy 424.451038 -374.423823)
			(xy 424.451038 -374.423879) (xy 424.442966 -374.490815) (xy 424.426934 -374.556302) (xy 424.403174 -374.619397)
			(xy 424.372027 -374.679192) (xy 424.333942 -374.734825) (xy 424.31208 -374.76049) (xy 424.30626 -374.767619)
			(xy 424.29976 -374.784822) (xy 424.29938 -374.794018) (xy 424.29938 -375.28627) (xy 424.299809 -375.295455)
			(xy 424.30631 -375.312639) (xy 424.31208 -375.319798) (xy 424.333974 -375.345439) (xy 424.372063 -375.401076)
			(xy 424.403214 -375.460876) (xy 424.426977 -375.523976) (xy 424.443011 -375.589468) (xy 424.451085 -375.656409)
			(xy 424.451082 -375.723836) (xy 424.443003 -375.790776) (xy 424.426964 -375.856267) (xy 424.403195 -375.919366)
			(xy 424.37204 -375.979163) (xy 424.333946 -376.034797) (xy 424.31208 -376.060462) (xy 424.306272 -376.067599)
			(xy 424.299765 -376.084796) (xy 424.29938 -376.09399) (xy 424.29938 -376.25147) (xy 424.29885 -376.261592)
			(xy 424.291135 -376.280309) (xy 424.276863 -376.294666) (xy 424.258191 -376.30249) (xy 424.248072 -376.303032)
			(xy 423.531792 -376.303032) (xy 423.521641 -376.302585) (xy 423.502895 -376.294793) (xy 423.488573 -376.280405)
			(xy 423.480868 -376.261622) (xy 423.480484 -376.25147) (xy 423.480484 -376.09399) (xy 423.480082 -376.084802)
			(xy 423.473563 -376.067617) (xy 423.467784 -376.060462) (xy 423.44595 -376.034772) (xy 423.407862 -375.979141)
			(xy 423.37671 -375.919348) (xy 423.352945 -375.856254) (xy 423.336908 -375.790768) (xy 423.32883 -375.723833)
			(xy 423.328827 -375.656412) (xy 423.3369 -375.589476) (xy 423.352932 -375.523989) (xy 423.376692 -375.460893)
			(xy 423.407838 -375.401098) (xy 423.445922 -375.345463) (xy 423.467784 -375.319798) (xy 423.473562 -375.31264)
			(xy 423.480088 -375.295459) (xy 423.480484 -375.28627) (xy 423.480484 -374.794018) (xy 423.480069 -374.784831)
			(xy 423.473559 -374.767647) (xy 423.467784 -374.76049) (xy 423.445879 -374.734859) (xy 423.407793 -374.679219)
			(xy 423.376645 -374.619418) (xy 423.352884 -374.556317) (xy 423.336852 -374.490824) (xy 423.328779 -374.423882)
			(xy 420.050711 -374.423882) (xy 420.042679 -374.490638) (xy 420.026712 -374.556018) (xy 420.003045 -374.61902)
			(xy 419.972018 -374.678743) (xy 419.934076 -374.73433) (xy 419.912292 -374.759982) (xy 419.906477 -374.767114)
			(xy 419.899974 -374.784315) (xy 419.899592 -374.79351) (xy 419.899592 -375.286778) (xy 419.900015 -375.295964)
			(xy 419.90652 -375.313148) (xy 419.912292 -375.320306) (xy 419.934108 -375.345934) (xy 419.972054 -375.401525)
			(xy 420.003084 -375.461252) (xy 420.026754 -375.52426) (xy 420.042724 -375.589644) (xy 420.050765 -375.656469)
			(xy 420.050763 -375.723776) (xy 420.042716 -375.7906) (xy 420.026741 -375.855984) (xy 420.003066 -375.918989)
			(xy 419.972031 -375.978714) (xy 419.934081 -376.034301) (xy 419.912292 -376.059954) (xy 419.906489 -376.067095)
			(xy 419.899978 -376.084289) (xy 419.899592 -376.093482) (xy 419.899592 -376.25147) (xy 419.899043 -376.261622)
			(xy 419.891284 -376.280385) (xy 419.876935 -376.29475) (xy 419.858182 -376.302531) (xy 419.84803 -376.303032)
			(xy 419.13175 -376.303032) (xy 419.121578 -376.302595) (xy 419.102779 -376.29482) (xy 419.088391 -376.280438)
			(xy 419.080609 -376.261642) (xy 419.080188 -376.25147) (xy 419.080188 -376.093482) (xy 419.079789 -376.084294)
			(xy 419.073268 -376.067109) (xy 419.067488 -376.059954) (xy 419.045728 -376.034278) (xy 419.007775 -375.978696)
			(xy 418.976738 -375.918976) (xy 418.953061 -375.855975) (xy 418.937085 -375.790595) (xy 418.929038 -375.723774)
			(xy 418.929035 -375.656471) (xy 418.937077 -375.589649) (xy 418.953048 -375.524268) (xy 418.97672 -375.461265)
			(xy 419.007752 -375.401542) (xy 419.045701 -375.345957) (xy 419.067488 -375.320306) (xy 419.073263 -375.313145)
			(xy 419.079791 -375.295967) (xy 419.080188 -375.286778) (xy 419.080188 -374.79351) (xy 419.079776 -374.784323)
			(xy 419.073264 -374.767138) (xy 419.067488 -374.759982) (xy 419.045658 -374.734364) (xy 419.007707 -374.678774)
			(xy 418.976673 -374.619046) (xy 418.953 -374.556037) (xy 418.937029 -374.49065) (xy 418.928987 -374.423823)
			(xy 389.250688 -374.423823) (xy 389.242648 -374.490639) (xy 389.226679 -374.556019) (xy 389.203011 -374.619022)
			(xy 389.171982 -374.678744) (xy 389.134037 -374.73433) (xy 389.112252 -374.759982) (xy 389.106432 -374.76711)
			(xy 389.099933 -374.784314) (xy 389.099552 -374.79351) (xy 389.099552 -375.286778) (xy 389.099983 -375.295963)
			(xy 389.106483 -375.313147) (xy 389.112252 -375.320306) (xy 389.13407 -375.345934) (xy 389.172018 -375.401523)
			(xy 389.203051 -375.46125) (xy 389.226722 -375.524258) (xy 389.242693 -375.589643) (xy 389.250735 -375.656469)
			(xy 389.250732 -375.723776) (xy 389.242685 -375.790601) (xy 389.226709 -375.855985) (xy 389.203032 -375.918991)
			(xy 389.171995 -375.978715) (xy 389.134042 -376.034302) (xy 389.112252 -376.059954) (xy 389.106444 -376.067091)
			(xy 389.099937 -376.084288) (xy 389.099552 -376.093482) (xy 389.099552 -376.25147) (xy 389.099111 -376.261641)
			(xy 389.091334 -376.280437) (xy 389.076954 -376.294823) (xy 389.058161 -376.302607) (xy 389.04799 -376.303032)
			(xy 388.33171 -376.303032) (xy 388.321535 -376.302627) (xy 388.302735 -376.29484) (xy 388.288349 -376.280448)
			(xy 388.280569 -376.261645) (xy 388.280148 -376.25147) (xy 388.280148 -376.093482) (xy 388.279736 -376.084295)
			(xy 388.273222 -376.067111) (xy 388.267448 -376.059954) (xy 388.24569 -376.034278) (xy 388.207739 -375.978695)
			(xy 388.176704 -375.918975) (xy 388.153029 -375.855973) (xy 388.137054 -375.790594) (xy 388.129007 -375.723774)
			(xy 388.129005 -375.656471) (xy 388.137046 -375.58965) (xy 388.153016 -375.52427) (xy 388.176686 -375.461267)
			(xy 388.207716 -375.401544) (xy 388.245662 -375.345958) (xy 388.267448 -375.320306) (xy 388.273231 -375.313151)
			(xy 388.279752 -375.295968) (xy 388.280148 -375.286778) (xy 388.280148 -374.79351) (xy 388.279722 -374.784325)
			(xy 388.273218 -374.767141) (xy 388.267448 -374.759982) (xy 388.245619 -374.734364) (xy 388.20767 -374.678773)
			(xy 388.176638 -374.619045) (xy 388.152968 -374.556036) (xy 388.136997 -374.490649) (xy 388.128956 -374.423823)
			(xy 384.850897 -374.423823) (xy 384.842857 -374.490639) (xy 384.826889 -374.556019) (xy 384.803221 -374.619021)
			(xy 384.772192 -374.678744) (xy 384.734249 -374.73433) (xy 384.712464 -374.759982) (xy 384.706646 -374.767112)
			(xy 384.700145 -374.784314) (xy 384.699764 -374.79351) (xy 384.699764 -375.286778) (xy 384.700193 -375.295963)
			(xy 384.706694 -375.313147) (xy 384.712464 -375.320306) (xy 384.734281 -375.345934) (xy 384.772229 -375.401524)
			(xy 384.803261 -375.461251) (xy 384.826932 -375.524259) (xy 384.842903 -375.589644) (xy 384.850944 -375.656469)
			(xy 384.850942 -375.723776) (xy 384.842894 -375.790601) (xy 384.826918 -375.855985) (xy 384.803242 -375.91899)
			(xy 384.772206 -375.978715) (xy 384.734254 -376.034302) (xy 384.712464 -376.059954) (xy 384.706657 -376.067092)
			(xy 384.70015 -376.084288) (xy 384.699764 -376.093482) (xy 384.699764 -376.25147) (xy 384.699311 -376.261639)
			(xy 384.691537 -376.280433) (xy 384.67716 -376.294819) (xy 384.658371 -376.302605) (xy 384.648202 -376.303032)
			(xy 383.931922 -376.303032) (xy 383.921748 -376.302617) (xy 383.902948 -376.294834) (xy 383.888562 -376.280445)
			(xy 383.880781 -376.261644) (xy 383.88036 -376.25147) (xy 383.88036 -376.093482) (xy 383.879945 -376.084296)
			(xy 383.873433 -376.067112) (xy 383.86766 -376.059954) (xy 383.845901 -376.034278) (xy 383.80795 -375.978695)
			(xy 383.776914 -375.918975) (xy 383.753239 -375.855974) (xy 383.737263 -375.790594) (xy 383.729217 -375.723774)
			(xy 383.729214 -375.656471) (xy 383.737255 -375.58965) (xy 383.753226 -375.524269) (xy 383.776896 -375.461266)
			(xy 383.807927 -375.401543) (xy 383.845874 -375.345958) (xy 383.86766 -375.320306) (xy 383.873444 -375.313152)
			(xy 383.879964 -375.295968) (xy 383.88036 -375.286778) (xy 383.88036 -374.79351) (xy 383.879932 -374.784325)
			(xy 383.873429 -374.767141) (xy 383.86766 -374.759982) (xy 383.84583 -374.734364) (xy 383.807881 -374.678773)
			(xy 383.776849 -374.619045) (xy 383.753177 -374.556036) (xy 383.737207 -374.49065) (xy 383.729165 -374.423823)
			(xy 380.451129 -374.423823) (xy 380.451129 -374.423879) (xy 380.443057 -374.490815) (xy 380.427025 -374.556302)
			(xy 380.403264 -374.619397) (xy 380.372116 -374.679192) (xy 380.334031 -374.734825) (xy 380.312168 -374.76049)
			(xy 380.306347 -374.767617) (xy 380.299847 -374.784822) (xy 380.299468 -374.794018) (xy 380.299468 -375.28627)
			(xy 380.2999 -375.295455) (xy 380.306399 -375.312639) (xy 380.312168 -375.319798) (xy 380.334063 -375.345438)
			(xy 380.372152 -375.401076) (xy 380.403304 -375.460875) (xy 380.427068 -375.523975) (xy 380.443102 -375.589468)
			(xy 380.451176 -375.656409) (xy 380.451173 -375.723836) (xy 380.443094 -375.790777) (xy 380.427054 -375.856268)
			(xy 380.403285 -375.919366) (xy 380.372129 -375.979163) (xy 380.334035 -376.034797) (xy 380.312168 -376.060462)
			(xy 380.306358 -376.067598) (xy 380.299852 -376.084796) (xy 380.299468 -376.09399) (xy 380.299468 -376.25147)
			(xy 380.298949 -376.261594) (xy 380.291233 -376.280313) (xy 380.276956 -376.29467) (xy 380.258281 -376.302492)
			(xy 380.24816 -376.303032) (xy 379.53188 -376.303032) (xy 379.521729 -376.302596) (xy 379.502982 -376.294799)
			(xy 379.48866 -376.280408) (xy 379.480955 -376.261623) (xy 379.480572 -376.25147) (xy 379.480572 -376.09399)
			(xy 379.480173 -376.084802) (xy 379.473652 -376.067617) (xy 379.467872 -376.060462) (xy 379.446038 -376.034772)
			(xy 379.407951 -375.97914) (xy 379.3768 -375.919347) (xy 379.353036 -375.856254) (xy 379.336999 -375.790768)
			(xy 379.328921 -375.723833) (xy 379.328918 -375.656412) (xy 379.336991 -375.589476) (xy 379.353022 -375.523989)
			(xy 379.376782 -375.460894) (xy 379.407928 -375.401098) (xy 379.446011 -375.345464) (xy 379.467872 -375.319798)
			(xy 379.473661 -375.312648) (xy 379.480178 -375.295461) (xy 379.480572 -375.28627) (xy 379.480572 -374.794018)
			(xy 379.48016 -374.784831) (xy 379.473648 -374.767646) (xy 379.467872 -374.76049) (xy 379.445968 -374.734858)
			(xy 379.407882 -374.679218) (xy 379.376735 -374.619417) (xy 379.352974 -374.556316) (xy 379.336943 -374.490823)
			(xy 379.32887 -374.423882) (xy 376.050801 -374.423882) (xy 376.042769 -374.490638) (xy 376.026801 -374.556018)
			(xy 376.003134 -374.619021) (xy 375.972107 -374.678743) (xy 375.934164 -374.734329) (xy 375.91238 -374.759982)
			(xy 375.906564 -374.767113) (xy 375.900062 -374.784315) (xy 375.89968 -374.79351) (xy 375.89968 -375.286778)
			(xy 375.900105 -375.295963) (xy 375.906609 -375.313148) (xy 375.91238 -375.320306) (xy 375.934197 -375.345934)
			(xy 375.972143 -375.401524) (xy 376.003174 -375.461252) (xy 376.026845 -375.524259) (xy 376.042815 -375.589644)
			(xy 376.050856 -375.656469) (xy 376.050854 -375.723776) (xy 376.042807 -375.7906) (xy 376.026831 -375.855984)
			(xy 376.003156 -375.91899) (xy 375.97212 -375.978714) (xy 375.934169 -376.034302) (xy 375.91238 -376.059954)
			(xy 375.906576 -376.067094) (xy 375.900066 -376.084288) (xy 375.89968 -376.093482) (xy 375.89968 -376.25147)
			(xy 375.899212 -376.261637) (xy 375.89144 -376.280428) (xy 375.877068 -376.294813) (xy 375.858285 -376.302602)
			(xy 375.848118 -376.303032) (xy 375.131838 -376.303032) (xy 375.121665 -376.302604) (xy 375.102866 -376.294826)
			(xy 375.088478 -376.280441) (xy 375.080697 -376.261643) (xy 375.080276 -376.25147) (xy 375.080276 -376.093482)
			(xy 375.07988 -376.084293) (xy 375.073357 -376.067109) (xy 375.067576 -376.059954) (xy 375.045817 -376.034278)
			(xy 375.007865 -375.978696) (xy 374.976828 -375.918976) (xy 374.953152 -375.855974) (xy 374.937176 -375.790595)
			(xy 374.929129 -375.723774) (xy 374.929126 -375.656471) (xy 374.937168 -375.58965) (xy 374.953138 -375.524269)
			(xy 374.97681 -375.461265) (xy 375.007841 -375.401543) (xy 375.045789 -375.345958) (xy 375.067576 -375.320306)
			(xy 375.07335 -375.313144) (xy 375.079879 -375.295967) (xy 375.080276 -375.286778) (xy 375.080276 -374.79351)
			(xy 375.079866 -374.784323) (xy 375.073353 -374.767138) (xy 375.067576 -374.759982) (xy 375.045746 -374.734365)
			(xy 375.007796 -374.678774) (xy 374.976762 -374.619046) (xy 374.95309 -374.556037) (xy 374.937119 -374.49065)
			(xy 374.929078 -374.423823) (xy 345.250779 -374.423823) (xy 345.242739 -374.49064) (xy 345.226769 -374.55602)
			(xy 345.2031 -374.619022) (xy 345.172071 -374.678745) (xy 345.134126 -374.73433) (xy 345.11234 -374.759982)
			(xy 345.106519 -374.767109) (xy 345.10002 -374.784314) (xy 345.09964 -374.79351) (xy 345.09964 -375.286778)
			(xy 345.100074 -375.295962) (xy 345.106573 -375.313146) (xy 345.11234 -375.320306) (xy 345.134158 -375.345933)
			(xy 345.172107 -375.401523) (xy 345.203141 -375.46125) (xy 345.226813 -375.524258) (xy 345.242784 -375.589643)
			(xy 345.250826 -375.656469) (xy 345.250823 -375.723776) (xy 345.242776 -375.790602) (xy 345.226799 -375.855986)
			(xy 345.203122 -375.918992) (xy 345.172084 -375.978716) (xy 345.13413 -376.034302) (xy 345.11234 -376.059954)
			(xy 345.106531 -376.06709) (xy 345.100025 -376.084288) (xy 345.09964 -376.093482) (xy 345.09964 -376.25147)
			(xy 345.099211 -376.261642) (xy 345.091432 -376.280441) (xy 345.077047 -376.294827) (xy 345.05825 -376.302609)
			(xy 345.048078 -376.303032) (xy 344.331798 -376.303032) (xy 344.321623 -376.302637) (xy 344.302822 -376.294846)
			(xy 344.288436 -376.280451) (xy 344.280657 -376.261646) (xy 344.280236 -376.25147) (xy 344.280236 -376.093482)
			(xy 344.279826 -376.084295) (xy 344.273311 -376.067111) (xy 344.267536 -376.059954) (xy 344.245778 -376.034277)
			(xy 344.207829 -375.978694) (xy 344.176794 -375.918974) (xy 344.15312 -375.855973) (xy 344.137145 -375.790594)
			(xy 344.129098 -375.723774) (xy 344.129096 -375.656471) (xy 344.137137 -375.589651) (xy 344.153106 -375.52427)
			(xy 344.176776 -375.461267) (xy 344.207805 -375.401544) (xy 344.24575 -375.345958) (xy 344.267536 -375.320306)
			(xy 344.273317 -375.31315) (xy 344.27984 -375.295968) (xy 344.280236 -375.286778) (xy 344.280236 -374.79351)
			(xy 344.279813 -374.784324) (xy 344.273308 -374.76714) (xy 344.267536 -374.759982) (xy 344.245707 -374.734364)
			(xy 344.20776 -374.678772) (xy 344.176728 -374.619044) (xy 344.153058 -374.556035) (xy 344.137088 -374.490649)
			(xy 344.129047 -374.423823) (xy 340.850988 -374.423823) (xy 340.842948 -374.490639) (xy 340.826979 -374.556019)
			(xy 340.803311 -374.619022) (xy 340.772282 -374.678744) (xy 340.734337 -374.73433) (xy 340.712552 -374.759982)
			(xy 340.706732 -374.76711) (xy 340.700233 -374.784314) (xy 340.699852 -374.79351) (xy 340.699852 -375.286778)
			(xy 340.700283 -375.295963) (xy 340.706783 -375.313147) (xy 340.712552 -375.320306) (xy 340.73437 -375.345934)
			(xy 340.772318 -375.401523) (xy 340.803351 -375.46125) (xy 340.827022 -375.524258) (xy 340.842993 -375.589643)
			(xy 340.851035 -375.656469) (xy 340.851032 -375.723776) (xy 340.842985 -375.790601) (xy 340.827009 -375.855985)
			(xy 340.803332 -375.918991) (xy 340.772295 -375.978715) (xy 340.734342 -376.034302) (xy 340.712552 -376.059954)
			(xy 340.706744 -376.067091) (xy 340.700237 -376.084288) (xy 340.699852 -376.093482) (xy 340.699852 -376.25147)
			(xy 340.699411 -376.261641) (xy 340.691634 -376.280437) (xy 340.677254 -376.294823) (xy 340.658461 -376.302607)
			(xy 340.64829 -376.303032) (xy 339.93201 -376.303032) (xy 339.921835 -376.302627) (xy 339.903035 -376.29484)
			(xy 339.888649 -376.280448) (xy 339.880869 -376.261645) (xy 339.880448 -376.25147) (xy 339.880448 -376.093482)
			(xy 339.880036 -376.084295) (xy 339.873522 -376.067111) (xy 339.867748 -376.059954) (xy 339.84599 -376.034278)
			(xy 339.808039 -375.978695) (xy 339.777004 -375.918975) (xy 339.753329 -375.855973) (xy 339.737354 -375.790594)
			(xy 339.729307 -375.723774) (xy 339.729305 -375.656471) (xy 339.737346 -375.58965) (xy 339.753316 -375.52427)
			(xy 339.776986 -375.461267) (xy 339.808016 -375.401544) (xy 339.845962 -375.345958) (xy 339.867748 -375.320306)
			(xy 339.873531 -375.313151) (xy 339.880052 -375.295968) (xy 339.880448 -375.286778) (xy 339.880448 -374.79351)
			(xy 339.880022 -374.784325) (xy 339.873518 -374.767141) (xy 339.867748 -374.759982) (xy 339.845919 -374.734364)
			(xy 339.80797 -374.678773) (xy 339.776938 -374.619045) (xy 339.753268 -374.556036) (xy 339.737297 -374.490649)
			(xy 339.729256 -374.423823) (xy 336.45122 -374.423823) (xy 336.45122 -374.423879) (xy 336.443148 -374.490815)
			(xy 336.427115 -374.556303) (xy 336.403354 -374.619398) (xy 336.372206 -374.679193) (xy 336.334119 -374.734826)
			(xy 336.312256 -374.76049) (xy 336.306433 -374.767616) (xy 336.299935 -374.784821) (xy 336.299556 -374.794018)
			(xy 336.299556 -375.28627) (xy 336.29999 -375.295454) (xy 336.306488 -375.312639) (xy 336.312256 -375.319798)
			(xy 336.334151 -375.345438) (xy 336.372242 -375.401075) (xy 336.403394 -375.460875) (xy 336.427158 -375.523975)
			(xy 336.443193 -375.589467) (xy 336.451267 -375.656409) (xy 336.451264 -375.723836) (xy 336.443185 -375.790777)
			(xy 336.427145 -375.856268) (xy 336.403375 -375.919367) (xy 336.372218 -375.979163) (xy 336.334123 -376.034797)
			(xy 336.312256 -376.060462) (xy 336.306445 -376.067597) (xy 336.29994 -376.084795) (xy 336.299556 -376.09399)
			(xy 336.299556 -376.25147) (xy 336.299049 -376.261595) (xy 336.29133 -376.280317) (xy 336.27705 -376.294674)
			(xy 336.258371 -376.302494) (xy 336.248248 -376.303032) (xy 335.531968 -376.303032) (xy 335.521816 -376.302605)
			(xy 335.503069 -376.294805) (xy 335.488748 -376.280411) (xy 335.481043 -376.261624) (xy 335.48066 -376.25147)
			(xy 335.48066 -376.09399) (xy 335.480241 -376.084804) (xy 335.473732 -376.06762) (xy 335.46796 -376.060462)
			(xy 335.446127 -376.034772) (xy 335.40804 -375.97914) (xy 335.37689 -375.919347) (xy 335.353126 -375.856253)
			(xy 335.33709 -375.790768) (xy 335.329012 -375.723833) (xy 335.329009 -375.656412) (xy 335.337082 -375.589477)
			(xy 335.353113 -375.52399) (xy 335.376872 -375.460894) (xy 335.408017 -375.401099) (xy 335.446099 -375.345464)
			(xy 335.46796 -375.319798) (xy 335.473747 -375.312647) (xy 335.480266 -375.295461) (xy 335.48066 -375.28627)
			(xy 335.48066 -374.794018) (xy 335.480228 -374.784833) (xy 335.473728 -374.76765) (xy 335.46796 -374.76049)
			(xy 335.446056 -374.734858) (xy 335.407971 -374.679218) (xy 335.376825 -374.619417) (xy 335.353065 -374.556316)
			(xy 335.337033 -374.490823) (xy 335.328961 -374.423882) (xy 332.050892 -374.423882) (xy 332.04286 -374.490639)
			(xy 332.026892 -374.556019) (xy 332.003224 -374.619021) (xy 331.972196 -374.678744) (xy 331.934253 -374.73433)
			(xy 331.912468 -374.759982) (xy 331.90665 -374.767112) (xy 331.900149 -374.784314) (xy 331.899768 -374.79351)
			(xy 331.899768 -375.286778) (xy 331.900196 -375.295963) (xy 331.906698 -375.313147) (xy 331.912468 -375.320306)
			(xy 331.934285 -375.345934) (xy 331.972233 -375.401524) (xy 332.003264 -375.461251) (xy 332.026935 -375.524259)
			(xy 332.042906 -375.589644) (xy 332.050947 -375.656469) (xy 332.050945 -375.723776) (xy 332.042898 -375.790601)
			(xy 332.026922 -375.855985) (xy 332.003246 -375.91899) (xy 331.972209 -375.978715) (xy 331.934257 -376.034302)
			(xy 331.912468 -376.059954) (xy 331.906662 -376.067092) (xy 331.900154 -376.084288) (xy 331.899768 -376.093482)
			(xy 331.899768 -376.25147) (xy 331.899312 -376.261639) (xy 331.891538 -376.280432) (xy 331.877162 -376.294817)
			(xy 331.858375 -376.302604) (xy 331.848206 -376.303032) (xy 331.131926 -376.303032) (xy 331.121752 -376.302614)
			(xy 331.102953 -376.294832) (xy 331.088566 -376.280444) (xy 331.080785 -376.261644) (xy 331.080364 -376.25147)
			(xy 331.080364 -376.093482) (xy 331.079948 -376.084296) (xy 331.073437 -376.067112) (xy 331.067664 -376.059954)
			(xy 331.045905 -376.034278) (xy 331.007954 -375.978695) (xy 330.976918 -375.918975) (xy 330.953242 -375.855974)
			(xy 330.937266 -375.790594) (xy 330.92922 -375.723774) (xy 330.929217 -375.656471) (xy 330.937258 -375.58965)
			(xy 330.953229 -375.524269) (xy 330.976899 -375.461266) (xy 331.007931 -375.401543) (xy 331.045877 -375.345958)
			(xy 331.067664 -375.320306) (xy 331.073448 -375.313152) (xy 331.079969 -375.295968) (xy 331.080364 -375.286778)
			(xy 331.080364 -374.79351) (xy 331.079935 -374.784325) (xy 331.073433 -374.767141) (xy 331.067664 -374.759982)
			(xy 331.045834 -374.734364) (xy 331.007885 -374.678773) (xy 330.976852 -374.619045) (xy 330.95318 -374.556036)
			(xy 330.93721 -374.49065) (xy 330.929168 -374.423823) (xy 301.250868 -374.423823) (xy 301.250868 -374.423878)
			(xy 301.242797 -374.490814) (xy 301.226766 -374.5563) (xy 301.203008 -374.619395) (xy 301.171863 -374.67919)
			(xy 301.133781 -374.734824) (xy 301.11192 -374.76049) (xy 301.106105 -374.767622) (xy 301.099601 -374.784823)
			(xy 301.09922 -374.794018) (xy 301.09922 -375.28627) (xy 301.09964 -375.295456) (xy 301.106146 -375.312641)
			(xy 301.11192 -375.319798) (xy 301.133813 -375.345439) (xy 301.171899 -375.401078) (xy 301.203048 -375.460877)
			(xy 301.226809 -375.523977) (xy 301.242842 -375.589469) (xy 301.250915 -375.65641) (xy 301.250912 -375.723835)
			(xy 301.242834 -375.790775) (xy 301.226796 -375.856266) (xy 301.203029 -375.919364) (xy 301.171876 -375.979161)
			(xy 301.133785 -376.034796) (xy 301.11192 -376.060462) (xy 301.106117 -376.067603) (xy 301.099605 -376.084797)
			(xy 301.09922 -376.09399) (xy 301.09922 -376.25147) (xy 301.098748 -376.2616) (xy 301.091023 -376.280328)
			(xy 301.076731 -376.294687) (xy 301.058039 -376.3025) (xy 301.047912 -376.303032) (xy 300.331632 -376.303032)
			(xy 300.321484 -376.302553) (xy 300.302738 -376.294774) (xy 300.288415 -376.280395) (xy 300.280708 -376.26162)
			(xy 300.280324 -376.25147) (xy 300.280324 -376.09399) (xy 300.279913 -376.084803) (xy 300.2734 -376.067619)
			(xy 300.267624 -376.060462) (xy 300.245789 -376.034773) (xy 300.207697 -375.979142) (xy 300.176544 -375.91935)
			(xy 300.152777 -375.856256) (xy 300.136739 -375.790769) (xy 300.12866 -375.723833) (xy 300.128658 -375.656412)
			(xy 300.136731 -375.589475) (xy 300.152764 -375.523987) (xy 300.176526 -375.460892) (xy 300.207674 -375.401096)
			(xy 300.245761 -375.345463) (xy 300.267624 -375.319798) (xy 300.273407 -375.312643) (xy 300.279929 -375.29546)
			(xy 300.280324 -375.28627) (xy 300.280324 -374.794018) (xy 300.2799 -374.784832) (xy 300.273395 -374.767648)
			(xy 300.267624 -374.76049) (xy 300.245718 -374.734859) (xy 300.207629 -374.67922) (xy 300.176479 -374.61942)
			(xy 300.152716 -374.556318) (xy 300.136683 -374.490825) (xy 300.12861 -374.423882) (xy 296.851077 -374.423882)
			(xy 296.843006 -374.490813) (xy 296.826976 -374.556299) (xy 296.803218 -374.619394) (xy 296.772074 -374.67919)
			(xy 296.733992 -374.734824) (xy 296.712132 -374.76049) (xy 296.706306 -374.767614) (xy 296.699811 -374.784821)
			(xy 296.699432 -374.794018) (xy 296.699432 -375.28627) (xy 296.699872 -375.295454) (xy 296.706366 -375.312638)
			(xy 296.712132 -375.319798) (xy 296.734024 -375.345439) (xy 296.77211 -375.401078) (xy 296.803258 -375.460878)
			(xy 296.827019 -375.523978) (xy 296.843051 -375.589469) (xy 296.851124 -375.65641) (xy 296.851121 -375.723835)
			(xy 296.843043 -375.790775) (xy 296.827005 -375.856265) (xy 296.803239 -375.919363) (xy 296.772087 -375.979161)
			(xy 296.733997 -376.034796) (xy 296.712132 -376.060462) (xy 296.706318 -376.067595) (xy 296.699816 -376.084795)
			(xy 296.699432 -376.09399) (xy 296.699432 -376.25147) (xy 296.698948 -376.261598) (xy 296.691225 -376.280324)
			(xy 296.676937 -376.294683) (xy 296.65825 -376.302498) (xy 296.648124 -376.303032) (xy 295.931844 -376.303032)
			(xy 295.921697 -376.302543) (xy 295.902951 -376.294768) (xy 295.888628 -376.280392) (xy 295.880921 -376.261619)
			(xy 295.880536 -376.25147) (xy 295.880536 -376.09399) (xy 295.880123 -376.084803) (xy 295.87361 -376.067619)
			(xy 295.867836 -376.060462) (xy 295.846 -376.034773) (xy 295.807908 -375.979143) (xy 295.776754 -375.91935)
			(xy 295.752987 -375.856256) (xy 295.736948 -375.79077) (xy 295.728869 -375.723834) (xy 295.728867 -375.656412)
			(xy 295.73694 -375.589475) (xy 295.752973 -375.523987) (xy 295.776736 -375.460891) (xy 295.807885 -375.401096)
			(xy 295.845973 -375.345463) (xy 295.867836 -375.319798) (xy 295.873621 -375.312644) (xy 295.880142 -375.29546)
			(xy 295.880536 -375.28627) (xy 295.880536 -374.794018) (xy 295.880109 -374.784833) (xy 295.873606 -374.767649)
			(xy 295.867836 -374.76049) (xy 295.84593 -374.734859) (xy 295.80784 -374.679221) (xy 295.776689 -374.61942)
			(xy 295.752925 -374.556319) (xy 295.736892 -374.490825) (xy 295.728819 -374.423882) (xy 292.450774 -374.423882)
			(xy 292.442742 -374.490639) (xy 292.426773 -374.55602) (xy 292.403104 -374.619022) (xy 292.372075 -374.678745)
			(xy 292.33413 -374.73433) (xy 292.312344 -374.759982) (xy 292.306523 -374.76711) (xy 292.300025 -374.784314)
			(xy 292.299644 -374.79351) (xy 292.299644 -375.286778) (xy 292.300077 -375.295962) (xy 292.306576 -375.313146)
			(xy 292.312344 -375.320306) (xy 292.334162 -375.345934) (xy 292.372111 -375.401523) (xy 292.403144 -375.46125)
			(xy 292.426816 -375.524258) (xy 292.442787 -375.589643) (xy 292.450829 -375.656469) (xy 292.450826 -375.723776)
			(xy 292.442779 -375.790601) (xy 292.426802 -375.855985) (xy 292.403125 -375.918991) (xy 292.372088 -375.978716)
			(xy 292.334134 -376.034302) (xy 292.312344 -376.059954) (xy 292.306535 -376.06709) (xy 292.300029 -376.084288)
			(xy 292.299644 -376.093482) (xy 292.299644 -376.25147) (xy 292.299211 -376.261642) (xy 292.291433 -376.280439)
			(xy 292.277049 -376.294826) (xy 292.258254 -376.302609) (xy 292.248082 -376.303032) (xy 291.531802 -376.303032)
			(xy 291.521627 -376.302634) (xy 291.502826 -376.294844) (xy 291.48844 -376.28045) (xy 291.480661 -376.261645)
			(xy 291.48024 -376.25147) (xy 291.48024 -376.093482) (xy 291.47983 -376.084295) (xy 291.473315 -376.067111)
			(xy 291.46754 -376.059954) (xy 291.445782 -376.034277) (xy 291.407832 -375.978695) (xy 291.376798 -375.918974)
			(xy 291.353123 -375.855973) (xy 291.337148 -375.790594) (xy 291.329101 -375.723774) (xy 291.329099 -375.656471)
			(xy 291.33714 -375.589651) (xy 291.35311 -375.52427) (xy 291.376779 -375.461267) (xy 291.407809 -375.401544)
			(xy 291.445754 -375.345958) (xy 291.46754 -375.320306) (xy 291.473322 -375.31315) (xy 291.479844 -375.295968)
			(xy 291.48024 -375.286778) (xy 291.48024 -374.79351) (xy 291.479816 -374.784324) (xy 291.473311 -374.76714)
			(xy 291.46754 -374.759982) (xy 291.445711 -374.734364) (xy 291.407763 -374.678773) (xy 291.376732 -374.619044)
			(xy 291.353061 -374.556035) (xy 291.337091 -374.490649) (xy 291.32905 -374.423823) (xy 288.051014 -374.423823)
			(xy 288.051014 -374.423879) (xy 288.042941 -374.490816) (xy 288.026909 -374.556303) (xy 288.003147 -374.619398)
			(xy 287.971998 -374.679193) (xy 287.933911 -374.734826) (xy 287.912048 -374.76049) (xy 287.906224 -374.767616)
			(xy 287.899727 -374.784821) (xy 287.899348 -374.794018) (xy 287.899348 -375.28627) (xy 287.899784 -375.295454)
			(xy 287.906281 -375.312638) (xy 287.912048 -375.319798) (xy 287.933943 -375.345438) (xy 287.972035 -375.401075)
			(xy 288.003187 -375.460874) (xy 288.026952 -375.523974) (xy 288.042987 -375.589467) (xy 288.051061 -375.656409)
			(xy 288.051058 -375.723836) (xy 288.042978 -375.790777) (xy 288.026938 -375.856269) (xy 288.003168 -375.919367)
			(xy 287.972011 -375.979164) (xy 287.933916 -376.034798) (xy 287.912048 -376.060462) (xy 287.906236 -376.067596)
			(xy 287.899732 -376.084795) (xy 287.899348 -376.09399) (xy 287.899348 -376.25147) (xy 287.898849 -376.261596)
			(xy 287.891129 -376.280319) (xy 287.876846 -376.294677) (xy 287.858164 -376.302495) (xy 287.84804 -376.303032)
			(xy 287.13176 -376.303032) (xy 287.121607 -376.302612) (xy 287.10286 -376.294809) (xy 287.088539 -376.280413)
			(xy 287.080835 -376.261625) (xy 287.080452 -376.25147) (xy 287.080452 -376.09399) (xy 287.080035 -376.084804)
			(xy 287.073525 -376.06762) (xy 287.067752 -376.060462) (xy 287.045916 -376.034773) (xy 287.007823 -375.979143)
			(xy 286.976668 -375.919351) (xy 286.9529 -375.856257) (xy 286.93686 -375.79077) (xy 286.928781 -375.723834)
			(xy 286.928779 -375.656411) (xy 286.936852 -375.589474) (xy 286.952886 -375.523986) (xy 286.976649 -375.46089)
			(xy 287.007799 -375.401095) (xy 287.045888 -375.345462) (xy 287.067752 -375.319798) (xy 287.073538 -375.312646)
			(xy 287.080058 -375.29546) (xy 287.080452 -375.28627) (xy 287.080452 -374.794018) (xy 287.080022 -374.784833)
			(xy 287.073521 -374.767649) (xy 287.067752 -374.76049) (xy 287.045845 -374.73486) (xy 287.007754 -374.679221)
			(xy 286.976602 -374.619421) (xy 286.952838 -374.556319) (xy 286.936804 -374.490825) (xy 286.928731 -374.423882)
			(xy 274.953921 -374.423882) (xy 275.095692 -374.528158) (xy 275.256029 -374.656022) (xy 275.411255 -374.790045)
			(xy 275.561134 -374.930022) (xy 275.705437 -375.07574) (xy 275.843945 -375.226977) (xy 275.976447 -375.383504)
			(xy 276.102741 -375.54508) (xy 276.222634 -375.711461) (xy 276.335945 -375.882393) (xy 276.442501 -376.057616)
			(xy 276.542138 -376.236863) (xy 276.634707 -376.419861) (xy 276.720065 -376.606332) (xy 276.798083 -376.79599)
			(xy 276.808294 -376.823856) (xy 289.128922 -376.823856) (xy 289.128922 -376.75655) (xy 289.136967 -376.689727)
			(xy 289.152941 -376.624344) (xy 289.176615 -376.56134) (xy 289.207651 -376.501617) (xy 289.245603 -376.446031)
			(xy 289.267392 -376.42038) (xy 289.273179 -376.413228) (xy 289.2797 -376.396043) (xy 289.280092 -376.386852)
			(xy 289.280092 -375.893584) (xy 289.279691 -375.884396) (xy 289.273171 -375.867212) (xy 289.267392 -375.860056)
			(xy 289.245634 -375.834379) (xy 289.207681 -375.778797) (xy 289.176643 -375.719078) (xy 289.152966 -375.656076)
			(xy 289.13699 -375.590696) (xy 289.128942 -375.523876) (xy 289.128939 -375.456572) (xy 289.136981 -375.389751)
			(xy 289.152952 -375.32437) (xy 289.176624 -375.261367) (xy 289.207656 -375.201644) (xy 289.245605 -375.146059)
			(xy 289.267392 -375.120408) (xy 289.273167 -375.113247) (xy 289.279695 -375.096069) (xy 289.280092 -375.08688)
			(xy 289.280092 -374.928638) (xy 289.280664 -374.918488) (xy 289.288417 -374.899729) (xy 289.302758 -374.885364)
			(xy 289.321505 -374.87758) (xy 289.331654 -374.877076) (xy 290.047934 -374.877076) (xy 290.058113 -374.877437)
			(xy 290.076915 -374.88524) (xy 290.0913 -374.899645) (xy 290.099077 -374.918459) (xy 290.099496 -374.928638)
			(xy 290.099496 -375.08688) (xy 290.099917 -375.096066) (xy 290.106423 -375.11325) (xy 290.112196 -375.120408)
			(xy 290.134014 -375.146035) (xy 290.17196 -375.201626) (xy 290.20299 -375.261353) (xy 290.226659 -375.324361)
			(xy 290.242629 -375.389746) (xy 290.25067 -375.456571) (xy 290.250667 -375.523878) (xy 290.24262 -375.590702)
			(xy 290.226645 -375.656085) (xy 290.20297 -375.719091) (xy 290.171935 -375.778816) (xy 290.133985 -375.834403)
			(xy 290.112196 -375.860056) (xy 290.106393 -375.867196) (xy 290.099882 -375.884391) (xy 290.099496 -375.893584)
			(xy 290.099496 -376.386852) (xy 290.09993 -376.396037) (xy 290.106427 -376.413221) (xy 290.112196 -376.42038)
			(xy 290.133987 -376.446029) (xy 290.171933 -376.501617) (xy 290.202964 -376.561341) (xy 290.226635 -376.624346)
			(xy 290.242607 -376.689728) (xy 290.25065 -376.756551) (xy 290.25065 -376.823855) (xy 290.250643 -376.823915)
			(xy 293.528715 -376.823915) (xy 293.528715 -376.756491) (xy 293.53679 -376.689554) (xy 293.552824 -376.624065)
			(xy 293.576588 -376.560968) (xy 293.607737 -376.501172) (xy 293.645825 -376.445537) (xy 293.667688 -376.419872)
			(xy 293.673478 -376.412722) (xy 293.679997 -376.395535) (xy 293.680388 -376.386344) (xy 293.680388 -375.894092)
			(xy 293.679984 -375.884904) (xy 293.673466 -375.86772) (xy 293.667688 -375.860564) (xy 293.645856 -375.834873)
			(xy 293.607767 -375.779242) (xy 293.576616 -375.719449) (xy 293.55285 -375.656355) (xy 293.536813 -375.59087)
			(xy 293.528735 -375.523934) (xy 293.528732 -375.456514) (xy 293.536804 -375.389578) (xy 293.552836 -375.324091)
			(xy 293.576596 -375.260995) (xy 293.607742 -375.2012) (xy 293.645826 -375.145565) (xy 293.667688 -375.1199)
			(xy 293.673466 -375.112741) (xy 293.679992 -375.095561) (xy 293.680388 -375.086372) (xy 293.680388 -374.928638)
			(xy 293.680956 -374.91852) (xy 293.688662 -374.89981) (xy 293.702923 -374.885454) (xy 293.721582 -374.877624)
			(xy 293.731696 -374.877076) (xy 294.447976 -374.877076) (xy 294.458126 -374.877541) (xy 294.476873 -374.885324)
			(xy 294.491196 -374.899707) (xy 294.498901 -374.918487) (xy 294.499284 -374.928638) (xy 294.499284 -375.086372)
			(xy 294.499711 -375.095557) (xy 294.506214 -375.112742) (xy 294.511984 -375.1199) (xy 294.53388 -375.145539)
			(xy 294.571969 -375.201177) (xy 294.603119 -375.260977) (xy 294.626882 -375.324077) (xy 294.642916 -375.389569)
			(xy 294.650989 -375.456511) (xy 294.650986 -375.523937) (xy 294.642907 -375.590878) (xy 294.626868 -375.656369)
			(xy 294.603099 -375.719467) (xy 294.571944 -375.779264) (xy 294.53385 -375.834899) (xy 294.511984 -375.860564)
			(xy 294.506176 -375.867701) (xy 294.499669 -375.884898) (xy 294.499284 -375.894092) (xy 294.499284 -376.386344)
			(xy 294.499677 -376.395533) (xy 294.506203 -376.412717) (xy 294.511984 -376.419872) (xy 294.533852 -376.445534)
			(xy 294.571942 -376.501168) (xy 294.603094 -376.560965) (xy 294.626858 -376.624062) (xy 294.642894 -376.689552)
			(xy 294.65097 -376.756491) (xy 294.650969 -376.823856) (xy 297.92901 -376.823856) (xy 297.92901 -376.75655)
			(xy 297.937054 -376.689727) (xy 297.953028 -376.624345) (xy 297.976702 -376.56134) (xy 298.007737 -376.501617)
			(xy 298.045687 -376.446032) (xy 298.067476 -376.42038) (xy 298.073261 -376.413226) (xy 298.079783 -376.396042)
			(xy 298.080176 -376.386852) (xy 298.080176 -375.893584) (xy 298.079779 -375.884395) (xy 298.073257 -375.867211)
			(xy 298.067476 -375.860056) (xy 298.045719 -375.834378) (xy 298.007766 -375.778797) (xy 297.97673 -375.719077)
			(xy 297.953054 -375.656076) (xy 297.937077 -375.590696) (xy 297.92903 -375.523876) (xy 297.929027 -375.456572)
			(xy 297.937069 -375.389751) (xy 297.953039 -375.324371) (xy 297.97671 -375.261367) (xy 298.007742 -375.201645)
			(xy 298.045689 -375.14606) (xy 298.067476 -375.120408) (xy 298.073249 -375.113246) (xy 298.079778 -375.096068)
			(xy 298.080176 -375.08688) (xy 298.080176 -374.928638) (xy 298.080596 -374.918464) (xy 298.088376 -374.899663)
			(xy 298.102763 -374.885276) (xy 298.121564 -374.877496) (xy 298.131738 -374.877076) (xy 298.848018 -374.877076)
			(xy 298.858195 -374.87745) (xy 298.876998 -374.885248) (xy 298.891383 -374.899649) (xy 298.899161 -374.91846)
			(xy 298.89958 -374.928638) (xy 298.89958 -375.08688) (xy 298.900004 -375.096066) (xy 298.906509 -375.11325)
			(xy 298.91228 -375.120408) (xy 298.934099 -375.146035) (xy 298.972045 -375.201625) (xy 299.003076 -375.261352)
			(xy 299.026746 -375.32436) (xy 299.042716 -375.389745) (xy 299.050758 -375.45657) (xy 299.050755 -375.523878)
			(xy 299.042708 -375.590702) (xy 299.026732 -375.656086) (xy 299.003056 -375.719092) (xy 298.972021 -375.778816)
			(xy 298.934069 -375.834404) (xy 298.91228 -375.860056) (xy 298.906475 -375.867195) (xy 298.899966 -375.88439)
			(xy 298.89958 -375.893584) (xy 298.89958 -376.386852) (xy 298.900018 -376.396036) (xy 298.906513 -376.413221)
			(xy 298.91228 -376.42038) (xy 298.934071 -376.446029) (xy 298.972019 -376.501616) (xy 299.003051 -376.561341)
			(xy 299.026722 -376.624345) (xy 299.042695 -376.689728) (xy 299.050731 -376.756492) (xy 302.328802 -376.756492)
			(xy 302.336877 -376.689554) (xy 302.352912 -376.624066) (xy 302.376674 -376.560969) (xy 302.407823 -376.501173)
			(xy 302.445909 -376.445538) (xy 302.467772 -376.419872) (xy 302.473572 -376.412729) (xy 302.480082 -376.395537)
			(xy 302.480472 -376.386344) (xy 302.480472 -375.894092) (xy 302.480072 -375.884904) (xy 302.473552 -375.867719)
			(xy 302.467772 -375.860564) (xy 302.44594 -375.834872) (xy 302.407853 -375.779241) (xy 302.376702 -375.719448)
			(xy 302.352937 -375.656355) (xy 302.336901 -375.590869) (xy 302.328823 -375.523934) (xy 302.32882 -375.456514)
			(xy 302.336892 -375.389578) (xy 302.352923 -375.324091) (xy 302.376682 -375.260996) (xy 302.407828 -375.2012)
			(xy 302.445911 -375.145566) (xy 302.467772 -375.1199) (xy 302.47356 -375.112749) (xy 302.480078 -375.095563)
			(xy 302.480472 -375.086372) (xy 302.480472 -374.928638) (xy 302.480959 -374.91851) (xy 302.48868 -374.899784)
			(xy 302.502967 -374.885425) (xy 302.521654 -374.87761) (xy 302.53178 -374.877076) (xy 303.24806 -374.877076)
			(xy 303.258209 -374.877554) (xy 303.276955 -374.885332) (xy 303.291279 -374.899711) (xy 303.298985 -374.918488)
			(xy 303.299368 -374.928638) (xy 303.299368 -375.086372) (xy 303.299799 -375.095557) (xy 303.306299 -375.112741)
			(xy 303.312068 -375.1199) (xy 303.333965 -375.145539) (xy 303.372054 -375.201176) (xy 303.403205 -375.260976)
			(xy 303.426969 -375.324076) (xy 303.443004 -375.389569) (xy 303.451077 -375.456511) (xy 303.451074 -375.523937)
			(xy 303.442995 -375.590878) (xy 303.426955 -375.65637) (xy 303.403186 -375.719468) (xy 303.37203 -375.779265)
			(xy 303.333935 -375.834899) (xy 303.312068 -375.860564) (xy 303.306258 -375.867699) (xy 303.299752 -375.884898)
			(xy 303.299368 -375.894092) (xy 303.299368 -376.386344) (xy 303.299764 -376.395533) (xy 303.306288 -376.412716)
			(xy 303.312068 -376.419872) (xy 303.333937 -376.445533) (xy 303.372028 -376.501168) (xy 303.40318 -376.560964)
			(xy 303.426945 -376.624062) (xy 303.442982 -376.689551) (xy 303.451058 -376.756491) (xy 303.451057 -376.823915)
			(xy 333.128833 -376.823915) (xy 333.128833 -376.756491) (xy 333.136908 -376.689553) (xy 333.152944 -376.624064)
			(xy 333.176708 -376.560967) (xy 333.207859 -376.501171) (xy 333.245948 -376.445537) (xy 333.267812 -376.419872)
			(xy 333.273604 -376.412724) (xy 333.280121 -376.395536) (xy 333.280512 -376.386344) (xy 333.280512 -375.894092)
			(xy 333.280103 -375.884905) (xy 333.273588 -375.86772) (xy 333.267812 -375.860564) (xy 333.245979 -375.834873)
			(xy 333.207889 -375.779242) (xy 333.176736 -375.71945) (xy 333.152969 -375.656356) (xy 333.136931 -375.59087)
			(xy 333.128853 -375.523935) (xy 333.12885 -375.456513) (xy 333.136923 -375.389577) (xy 333.152955 -375.32409)
			(xy 333.176716 -375.260994) (xy 333.207864 -375.201199) (xy 333.24595 -375.145565) (xy 333.267812 -375.1199)
			(xy 333.273592 -375.112743) (xy 333.280116 -375.095562) (xy 333.280512 -375.086372) (xy 333.280512 -374.928638)
			(xy 333.281057 -374.918517) (xy 333.288767 -374.899802) (xy 333.303035 -374.885446) (xy 333.321702 -374.87762)
			(xy 333.33182 -374.877076) (xy 334.0481 -374.877076) (xy 334.058251 -374.877521) (xy 334.076999 -374.885312)
			(xy 334.091321 -374.899701) (xy 334.099025 -374.918485) (xy 334.099408 -374.928638) (xy 334.099408 -375.086372)
			(xy 334.09983 -375.095558) (xy 334.106335 -375.112743) (xy 334.112108 -375.1199) (xy 334.134003 -375.145539)
			(xy 334.17209 -375.201178) (xy 334.203239 -375.260978) (xy 334.227001 -375.324078) (xy 334.243034 -375.38957)
			(xy 334.251107 -375.456511) (xy 334.251105 -375.523937) (xy 334.243026 -375.590877) (xy 334.226987 -375.656368)
			(xy 334.20322 -375.719466) (xy 334.172066 -375.779263) (xy 334.133974 -375.834899) (xy 334.112108 -375.860564)
			(xy 334.106303 -375.867703) (xy 334.099793 -375.884898) (xy 334.099408 -375.894092) (xy 334.099408 -376.386344)
			(xy 334.099795 -376.395534) (xy 334.106324 -376.412718) (xy 334.112108 -376.419872) (xy 334.133976 -376.445534)
			(xy 334.172064 -376.501169) (xy 334.203214 -376.560966) (xy 334.226977 -376.624063) (xy 334.243012 -376.689553)
			(xy 334.251088 -376.756491) (xy 334.251087 -376.823855) (xy 337.529152 -376.823855) (xy 337.529152 -376.756551)
			(xy 337.537195 -376.689729) (xy 337.553167 -376.624348) (xy 337.576837 -376.561344) (xy 337.607868 -376.50162)
			(xy 337.645814 -376.446033) (xy 337.6676 -376.42038) (xy 337.673388 -376.413228) (xy 337.679908 -376.396043)
			(xy 337.6803 -376.386852) (xy 337.6803 -375.893584) (xy 337.679897 -375.884396) (xy 337.673378 -375.867212)
			(xy 337.6676 -375.860056) (xy 337.645845 -375.834377) (xy 337.607898 -375.778794) (xy 337.576865 -375.719074)
			(xy 337.553192 -375.656073) (xy 337.537218 -375.590694) (xy 337.529172 -375.523875) (xy 337.529169 -375.456573)
			(xy 337.53721 -375.389753) (xy 337.553178 -375.324373) (xy 337.576846 -375.26137) (xy 337.607873 -375.201647)
			(xy 337.645815 -375.146061) (xy 337.6676 -375.120408) (xy 337.673376 -375.113248) (xy 337.679903 -375.096069)
			(xy 337.6803 -375.08688) (xy 337.6803 -374.928638) (xy 337.680864 -374.918487) (xy 337.688619 -374.899726)
			(xy 337.702963 -374.885361) (xy 337.721712 -374.877579) (xy 337.731862 -374.877076) (xy 338.448142 -374.877076)
			(xy 338.458307 -374.8775) (xy 338.477085 -374.885295) (xy 338.49145 -374.899683) (xy 338.499216 -374.918472)
			(xy 338.499704 -374.928638) (xy 338.499704 -375.08688) (xy 338.500123 -375.096066) (xy 338.50663 -375.113251)
			(xy 338.512404 -375.120408) (xy 338.534222 -375.146035) (xy 338.572167 -375.201626) (xy 338.603196 -375.261353)
			(xy 338.626865 -375.324361) (xy 338.642835 -375.389746) (xy 338.650876 -375.456571) (xy 338.650873 -375.523877)
			(xy 338.642826 -375.590701) (xy 338.626851 -375.656085) (xy 338.603177 -375.719091) (xy 338.572142 -375.778815)
			(xy 338.534192 -375.834403) (xy 338.512404 -375.860056) (xy 338.506602 -375.867197) (xy 338.50009 -375.884391)
			(xy 338.499704 -375.893584) (xy 338.499704 -376.386852) (xy 338.500136 -376.396037) (xy 338.506634 -376.413222)
			(xy 338.512404 -376.42038) (xy 338.534194 -376.44603) (xy 338.57214 -376.501617) (xy 338.603171 -376.561342)
			(xy 338.626842 -376.624346) (xy 338.642813 -376.689729) (xy 338.650856 -376.756551) (xy 338.650856 -376.823855)
			(xy 338.650849 -376.823915) (xy 341.928921 -376.823915) (xy 341.928921 -376.756491) (xy 341.936996 -376.689553)
			(xy 341.953031 -376.624065) (xy 341.976794 -376.560968) (xy 342.007944 -376.501172) (xy 342.046032 -376.445537)
			(xy 342.067896 -376.419872) (xy 342.073686 -376.412722) (xy 342.080205 -376.395535) (xy 342.080596 -376.386344)
			(xy 342.080596 -375.894092) (xy 342.08019 -375.884904) (xy 342.073674 -375.86772) (xy 342.067896 -375.860564)
			(xy 342.046064 -375.834873) (xy 342.007974 -375.779242) (xy 341.976822 -375.719449) (xy 341.953057 -375.656356)
			(xy 341.937019 -375.59087) (xy 341.928941 -375.523935) (xy 341.928938 -375.456513) (xy 341.93701 -375.389577)
			(xy 341.953042 -375.32409) (xy 341.976803 -375.260995) (xy 342.007949 -375.201199) (xy 342.046034 -375.145565)
			(xy 342.067896 -375.1199) (xy 342.073675 -375.112742) (xy 342.0802 -375.095561) (xy 342.080596 -375.086372)
			(xy 342.080596 -374.928638) (xy 342.081157 -374.918519) (xy 342.088864 -374.899807) (xy 342.103127 -374.885451)
			(xy 342.121789 -374.877623) (xy 342.131904 -374.877076) (xy 342.848184 -374.877076) (xy 342.858334 -374.877534)
			(xy 342.877082 -374.88532) (xy 342.891405 -374.899705) (xy 342.899109 -374.918486) (xy 342.899492 -374.928638)
			(xy 342.899492 -375.086372) (xy 342.899917 -375.095558) (xy 342.906421 -375.112742) (xy 342.912192 -375.1199)
			(xy 342.934088 -375.145539) (xy 342.972176 -375.201177) (xy 343.003326 -375.260977) (xy 343.027088 -375.324077)
			(xy 343.043122 -375.38957) (xy 343.051195 -375.456511) (xy 343.051193 -375.523937) (xy 343.043113 -375.590878)
			(xy 343.027074 -375.656369) (xy 343.003306 -375.719467) (xy 342.972151 -375.779264) (xy 342.934058 -375.834899)
			(xy 342.912192 -375.860564) (xy 342.906385 -375.867702) (xy 342.899877 -375.884898) (xy 342.899492 -375.894092)
			(xy 342.899492 -376.386344) (xy 342.899883 -376.395533) (xy 342.90641 -376.412717) (xy 342.912192 -376.419872)
			(xy 342.93406 -376.445534) (xy 342.972149 -376.501169) (xy 343.0033 -376.560965) (xy 343.027065 -376.624063)
			(xy 343.0431 -376.689552) (xy 343.051176 -376.756491) (xy 343.051175 -376.823856) (xy 346.329216 -376.823856)
			(xy 346.329216 -376.75655) (xy 346.33726 -376.689727) (xy 346.353234 -376.624345) (xy 346.376909 -376.56134)
			(xy 346.407944 -376.501617) (xy 346.445895 -376.446032) (xy 346.467684 -376.42038) (xy 346.47347 -376.413227)
			(xy 346.479991 -376.396043) (xy 346.480384 -376.386852) (xy 346.480384 -375.893584) (xy 346.479985 -375.884396)
			(xy 346.473464 -375.867211) (xy 346.467684 -375.860056) (xy 346.445926 -375.834379) (xy 346.407974 -375.778797)
			(xy 346.376937 -375.719077) (xy 346.35326 -375.656076) (xy 346.337283 -375.590696) (xy 346.329236 -375.523876)
			(xy 346.329233 -375.456572) (xy 346.337275 -375.389751) (xy 346.353246 -375.32437) (xy 346.376917 -375.261367)
			(xy 346.407949 -375.201645) (xy 346.445897 -375.14606) (xy 346.467684 -375.120408) (xy 346.473458 -375.113247)
			(xy 346.479987 -375.096069) (xy 346.480384 -375.08688) (xy 346.480384 -374.928638) (xy 346.480796 -374.918463)
			(xy 346.488577 -374.899661) (xy 346.502967 -374.885273) (xy 346.521771 -374.877495) (xy 346.531946 -374.877076)
			(xy 347.248226 -374.877076) (xy 347.258404 -374.877443) (xy 347.277207 -374.885244) (xy 347.291592 -374.899647)
			(xy 347.299369 -374.918459) (xy 347.299788 -374.928638) (xy 347.299788 -375.08688) (xy 347.300211 -375.096066)
			(xy 347.306716 -375.11325) (xy 347.312488 -375.120408) (xy 347.334306 -375.146035) (xy 347.372252 -375.201625)
			(xy 347.403283 -375.261353) (xy 347.426953 -375.324361) (xy 347.442923 -375.389746) (xy 347.450964 -375.456571)
			(xy 347.450961 -375.523878) (xy 347.442914 -375.590702) (xy 347.426938 -375.656086) (xy 347.403263 -375.719091)
			(xy 347.372228 -375.778816) (xy 347.334277 -375.834403) (xy 347.312488 -375.860056) (xy 347.306684 -375.867196)
			(xy 347.300174 -375.88439) (xy 347.299788 -375.893584) (xy 347.299788 -376.386852) (xy 347.300224 -376.396036)
			(xy 347.30672 -376.413221) (xy 347.312488 -376.42038) (xy 347.334279 -376.446029) (xy 347.372226 -376.501617)
			(xy 347.403257 -376.561341) (xy 347.426929 -376.624346) (xy 347.442901 -376.689728) (xy 347.450944 -376.756551)
			(xy 347.450944 -376.823855) (xy 347.450937 -376.823915) (xy 377.128742 -376.823915) (xy 377.128742 -376.756491)
			(xy 377.136817 -376.689553) (xy 377.152853 -376.624064) (xy 377.176618 -376.560967) (xy 377.20777 -376.501171)
			(xy 377.245859 -376.445537) (xy 377.267724 -376.419872) (xy 377.273518 -376.412725) (xy 377.280033 -376.395536)
			(xy 377.280424 -376.386344) (xy 377.280424 -375.894092) (xy 377.280012 -375.884905) (xy 377.273499 -375.867721)
			(xy 377.267724 -375.860564) (xy 377.245891 -375.834873) (xy 377.207799 -375.779243) (xy 377.176646 -375.71945)
			(xy 377.152879 -375.656357) (xy 377.136841 -375.590871) (xy 377.128762 -375.523935) (xy 377.128759 -375.456513)
			(xy 377.136832 -375.389577) (xy 377.152865 -375.324089) (xy 377.176626 -375.260993) (xy 377.207775 -375.201198)
			(xy 377.245861 -375.145565) (xy 377.267724 -375.1199) (xy 377.273506 -375.112744) (xy 377.280029 -375.095562)
			(xy 377.280424 -375.086372) (xy 377.280424 -374.928638) (xy 377.280957 -374.918516) (xy 377.28867 -374.899799)
			(xy 377.302942 -374.885442) (xy 377.321613 -374.877618) (xy 377.331732 -374.877076) (xy 378.048012 -374.877076)
			(xy 378.058164 -374.877511) (xy 378.076912 -374.885306) (xy 378.091234 -374.899698) (xy 378.098938 -374.918484)
			(xy 378.09932 -374.928638) (xy 378.09932 -375.086372) (xy 378.099739 -375.095558) (xy 378.106246 -375.112743)
			(xy 378.11202 -375.1199) (xy 378.133915 -375.14554) (xy 378.172001 -375.201178) (xy 378.203149 -375.260978)
			(xy 378.226911 -375.324078) (xy 378.242943 -375.38957) (xy 378.251016 -375.456511) (xy 378.251014 -375.523937)
			(xy 378.242935 -375.590877) (xy 378.226897 -375.656368) (xy 378.20313 -375.719466) (xy 378.171976 -375.779263)
			(xy 378.133885 -375.834898) (xy 378.11202 -375.860564) (xy 378.106216 -375.867704) (xy 378.099705 -375.884898)
			(xy 378.09932 -375.894092) (xy 378.09932 -376.386344) (xy 378.099704 -376.395534) (xy 378.106235 -376.412718)
			(xy 378.11202 -376.419872) (xy 378.133887 -376.445534) (xy 378.171974 -376.50117) (xy 378.203124 -376.560967)
			(xy 378.226887 -376.624064) (xy 378.242922 -376.689553) (xy 378.250997 -376.756491) (xy 378.250997 -376.756551)
			(xy 381.529061 -376.756551) (xy 381.537105 -376.689729) (xy 381.553076 -376.624347) (xy 381.576747 -376.561343)
			(xy 381.607779 -376.501619) (xy 381.645725 -376.446032) (xy 381.667512 -376.42038) (xy 381.673301 -376.413229)
			(xy 381.67982 -376.396043) (xy 381.680212 -376.386852) (xy 381.680212 -375.893584) (xy 381.679807 -375.884396)
			(xy 381.67329 -375.867212) (xy 381.667512 -375.860056) (xy 381.645756 -375.834378) (xy 381.607808 -375.778794)
			(xy 381.576775 -375.719074) (xy 381.553102 -375.656073) (xy 381.537127 -375.590694) (xy 381.529081 -375.523875)
			(xy 381.529078 -375.456573) (xy 381.537119 -375.389753) (xy 381.553088 -375.324373) (xy 381.576756 -375.26137)
			(xy 381.607784 -375.201647) (xy 381.645727 -375.14606) (xy 381.667512 -375.120408) (xy 381.673289 -375.113249)
			(xy 381.679815 -375.096069) (xy 381.680212 -375.08688) (xy 381.680212 -374.928638) (xy 381.680694 -374.918472)
			(xy 381.688462 -374.899683) (xy 381.702829 -374.885298) (xy 381.721609 -374.877507) (xy 381.731774 -374.877076)
			(xy 382.448054 -374.877076) (xy 382.458227 -374.877502) (xy 382.477028 -374.885279) (xy 382.491416 -374.899665)
			(xy 382.499196 -374.918465) (xy 382.499616 -374.928638) (xy 382.499616 -375.08688) (xy 382.500032 -375.096067)
			(xy 382.506541 -375.113251) (xy 382.512316 -375.120408) (xy 382.534136 -375.146034) (xy 382.572087 -375.201623)
			(xy 382.603122 -375.26135) (xy 382.626795 -375.324358) (xy 382.642767 -375.389744) (xy 382.650809 -375.45657)
			(xy 382.650806 -375.523878) (xy 382.642758 -375.590704) (xy 382.62678 -375.656088) (xy 382.603102 -375.719094)
			(xy 382.572063 -375.778818) (xy 382.534107 -375.834404) (xy 382.512316 -375.860056) (xy 382.506515 -375.867198)
			(xy 382.500002 -375.884391) (xy 382.499616 -375.893584) (xy 382.499616 -376.386852) (xy 382.500045 -376.396037)
			(xy 382.506545 -376.413222) (xy 382.512316 -376.42038) (xy 382.534109 -376.446028) (xy 382.572061 -376.501614)
			(xy 382.603096 -376.561338) (xy 382.626771 -376.624343) (xy 382.642745 -376.689726) (xy 382.650789 -376.75655)
			(xy 382.650789 -376.823856) (xy 382.650782 -376.823915) (xy 385.92883 -376.823915) (xy 385.92883 -376.756491)
			(xy 385.936905 -376.689553) (xy 385.95294 -376.624064) (xy 385.976705 -376.560967) (xy 386.007855 -376.501171)
			(xy 386.045944 -376.445537) (xy 386.067808 -376.419872) (xy 386.0736 -376.412724) (xy 386.080117 -376.395535)
			(xy 386.080508 -376.386344) (xy 386.080508 -375.894092) (xy 386.0801 -375.884905) (xy 386.073584 -375.867721)
			(xy 386.067808 -375.860564) (xy 386.045975 -375.834873) (xy 386.007885 -375.779242) (xy 385.976732 -375.71945)
			(xy 385.952966 -375.656356) (xy 385.936928 -375.59087) (xy 385.92885 -375.523935) (xy 385.928847 -375.456513)
			(xy 385.93692 -375.389577) (xy 385.952952 -375.32409) (xy 385.976713 -375.260994) (xy 386.00786 -375.201199)
			(xy 386.045946 -375.145565) (xy 386.067808 -375.1199) (xy 386.073588 -375.112743) (xy 386.080112 -375.095562)
			(xy 386.080508 -375.086372) (xy 386.080508 -374.928638) (xy 386.081057 -374.918518) (xy 386.088766 -374.899804)
			(xy 386.103033 -374.885447) (xy 386.121699 -374.877621) (xy 386.131816 -374.877076) (xy 386.848096 -374.877076)
			(xy 386.858247 -374.877524) (xy 386.876995 -374.885314) (xy 386.891317 -374.899702) (xy 386.899021 -374.918485)
			(xy 386.899404 -374.928638) (xy 386.899404 -375.086372) (xy 386.899827 -375.095558) (xy 386.906332 -375.112742)
			(xy 386.912104 -375.1199) (xy 386.933999 -375.145539) (xy 386.972087 -375.201178) (xy 387.003236 -375.260978)
			(xy 387.026998 -375.324078) (xy 387.043031 -375.38957) (xy 387.051104 -375.456511) (xy 387.051102 -375.523937)
			(xy 387.043023 -375.590877) (xy 387.026984 -375.656368) (xy 387.003216 -375.719466) (xy 386.972062 -375.779264)
			(xy 386.93397 -375.834899) (xy 386.912104 -375.860564) (xy 386.906298 -375.867703) (xy 386.899789 -375.884898)
			(xy 386.899404 -375.894092) (xy 386.899404 -376.386344) (xy 386.899792 -376.395534) (xy 386.906321 -376.412718)
			(xy 386.912104 -376.419872) (xy 386.933972 -376.445534) (xy 386.97206 -376.501169) (xy 387.00321 -376.560966)
			(xy 387.026974 -376.624063) (xy 387.043009 -376.689552) (xy 387.051085 -376.756491) (xy 387.051084 -376.823855)
			(xy 390.329149 -376.823855) (xy 390.329149 -376.756551) (xy 390.337192 -376.689729) (xy 390.353163 -376.624348)
			(xy 390.376834 -376.561344) (xy 390.407864 -376.50162) (xy 390.44581 -376.446033) (xy 390.467596 -376.42038)
			(xy 390.473383 -376.413228) (xy 390.479904 -376.396043) (xy 390.480296 -376.386852) (xy 390.480296 -375.893584)
			(xy 390.479894 -375.884396) (xy 390.473375 -375.867212) (xy 390.467596 -375.860056) (xy 390.445841 -375.834377)
			(xy 390.407894 -375.778794) (xy 390.376862 -375.719073) (xy 390.353189 -375.656072) (xy 390.337215 -375.590694)
			(xy 390.329169 -375.523875) (xy 390.329166 -375.456573) (xy 390.337207 -375.389754) (xy 390.353175 -375.324374)
			(xy 390.376842 -375.261371) (xy 390.407869 -375.201648) (xy 390.445812 -375.146061) (xy 390.467596 -375.120408)
			(xy 390.473371 -375.113248) (xy 390.479899 -375.096069) (xy 390.480296 -375.08688) (xy 390.480296 -374.928638)
			(xy 390.480864 -374.918488) (xy 390.488618 -374.899728) (xy 390.502961 -374.885363) (xy 390.521709 -374.877579)
			(xy 390.531858 -374.877076) (xy 391.248138 -374.877076) (xy 391.258303 -374.877503) (xy 391.27708 -374.885297)
			(xy 391.291445 -374.899684) (xy 391.299212 -374.918472) (xy 391.2997 -374.928638) (xy 391.2997 -375.08688)
			(xy 391.30012 -375.096066) (xy 391.306627 -375.113251) (xy 391.3124 -375.120408) (xy 391.334218 -375.146035)
			(xy 391.372163 -375.201626) (xy 391.403193 -375.261353) (xy 391.426862 -375.324361) (xy 391.442832 -375.389746)
			(xy 391.450873 -375.456571) (xy 391.45087 -375.523877) (xy 391.442823 -375.590702) (xy 391.426848 -375.656085)
			(xy 391.403173 -375.719091) (xy 391.372139 -375.778816) (xy 391.334188 -375.834403) (xy 391.3124 -375.860056)
			(xy 391.306597 -375.867197) (xy 391.300086 -375.884391) (xy 391.2997 -375.893584) (xy 391.2997 -376.386852)
			(xy 391.300133 -376.396037) (xy 391.306631 -376.413221) (xy 391.3124 -376.42038) (xy 391.33419 -376.446029)
			(xy 391.372137 -376.501617) (xy 391.403168 -376.561342) (xy 391.426838 -376.624346) (xy 391.44281 -376.689728)
			(xy 391.450853 -376.756551) (xy 391.450853 -376.823855) (xy 391.450846 -376.823915) (xy 421.128651 -376.823915)
			(xy 421.128651 -376.756491) (xy 421.136727 -376.689552) (xy 421.152763 -376.624063) (xy 421.176528 -376.560966)
			(xy 421.20768 -376.50117) (xy 421.245771 -376.445537) (xy 421.267636 -376.419872) (xy 421.273432 -376.412726)
			(xy 421.279946 -376.395536) (xy 421.280336 -376.386344) (xy 421.280336 -375.894092) (xy 421.279922 -375.884905)
			(xy 421.27341 -375.867721) (xy 421.267636 -375.860564) (xy 421.245802 -375.834873) (xy 421.20771 -375.779243)
			(xy 421.176556 -375.719451) (xy 421.152788 -375.656357) (xy 421.13675 -375.590871) (xy 421.128671 -375.523935)
			(xy 421.128668 -375.456513) (xy 421.136741 -375.389576) (xy 421.152774 -375.324089) (xy 421.176536 -375.260993)
			(xy 421.207685 -375.201198) (xy 421.245773 -375.145565) (xy 421.267636 -375.1199) (xy 421.27342 -375.112746)
			(xy 421.279941 -375.095562) (xy 421.280336 -375.086372) (xy 421.280336 -374.928638) (xy 421.280858 -374.918514)
			(xy 421.288572 -374.899795) (xy 421.302848 -374.885437) (xy 421.321523 -374.877616) (xy 421.331644 -374.877076)
			(xy 422.047924 -374.877076) (xy 422.058077 -374.877501) (xy 422.076825 -374.8853) (xy 422.091147 -374.899695)
			(xy 422.09885 -374.918483) (xy 422.099232 -374.928638) (xy 422.099232 -375.086372) (xy 422.099671 -375.095556)
			(xy 422.106166 -375.11274) (xy 422.111932 -375.1199) (xy 422.133826 -375.14554) (xy 422.171912 -375.201179)
			(xy 422.203059 -375.260979) (xy 422.22682 -375.324079) (xy 422.242853 -375.389571) (xy 422.250926 -375.456511)
			(xy 422.250923 -375.523937) (xy 422.242844 -375.590877) (xy 422.226806 -375.656367) (xy 422.20304 -375.719465)
			(xy 422.171887 -375.779263) (xy 422.133797 -375.834898) (xy 422.111932 -375.860564) (xy 422.106117 -375.867696)
			(xy 422.099615 -375.884897) (xy 422.099232 -375.894092) (xy 422.099232 -376.386344) (xy 422.099636 -376.395532)
			(xy 422.106156 -376.412715) (xy 422.111932 -376.419872) (xy 422.133799 -376.445535) (xy 422.171885 -376.50117)
			(xy 422.203034 -376.560967) (xy 422.226797 -376.624064) (xy 422.242831 -376.689553) (xy 422.250906 -376.756491)
			(xy 422.250906 -376.756551) (xy 425.52897 -376.756551) (xy 425.537014 -376.689729) (xy 425.552986 -376.624347)
			(xy 425.576658 -376.561343) (xy 425.607689 -376.501619) (xy 425.645637 -376.446032) (xy 425.667424 -376.42038)
			(xy 425.673214 -376.413231) (xy 425.679732 -376.396043) (xy 425.680124 -376.386852) (xy 425.680124 -375.893584)
			(xy 425.679716 -375.884397) (xy 425.6732 -375.867213) (xy 425.667424 -375.860056) (xy 425.645668 -375.834378)
			(xy 425.60772 -375.778795) (xy 425.576686 -375.719074) (xy 425.553012 -375.656073) (xy 425.537037 -375.590695)
			(xy 425.528991 -375.523875) (xy 425.528988 -375.456573) (xy 425.537029 -375.389753) (xy 425.552998 -375.324373)
			(xy 425.576666 -375.26137) (xy 425.607695 -375.201647) (xy 425.645639 -375.146061) (xy 425.667424 -375.120408)
			(xy 425.673202 -375.11325) (xy 425.679727 -375.096069) (xy 425.680124 -375.08688) (xy 425.680124 -374.928638)
			(xy 425.680595 -374.918471) (xy 425.688365 -374.899679) (xy 425.702736 -374.885294) (xy 425.721519 -374.877505)
			(xy 425.731686 -374.877076) (xy 426.447966 -374.877076) (xy 426.45814 -374.877493) (xy 426.476941 -374.885274)
			(xy 426.491329 -374.899662) (xy 426.499108 -374.918464) (xy 426.499528 -374.928638) (xy 426.499528 -375.08688)
			(xy 426.499941 -375.096067) (xy 426.506452 -375.113252) (xy 426.512228 -375.120408) (xy 426.534048 -375.146034)
			(xy 426.571998 -375.201623) (xy 426.603032 -375.26135) (xy 426.626705 -375.324358) (xy 426.642676 -375.389744)
			(xy 426.650718 -375.45657) (xy 426.650716 -375.523878) (xy 426.642668 -375.590704) (xy 426.62669 -375.656088)
			(xy 426.603013 -375.719094) (xy 426.571974 -375.778818) (xy 426.534019 -375.834404) (xy 426.512228 -375.860056)
			(xy 426.506416 -375.86719) (xy 426.499913 -375.884389) (xy 426.499528 -375.893584) (xy 426.499528 -376.386852)
			(xy 426.499955 -376.396037) (xy 426.506456 -376.413222) (xy 426.512228 -376.42038) (xy 426.534021 -376.446029)
			(xy 426.571971 -376.501615) (xy 426.603006 -376.561338) (xy 426.62668 -376.624344) (xy 426.642654 -376.689727)
			(xy 426.650698 -376.75655) (xy 426.650698 -376.823856) (xy 426.650691 -376.823915) (xy 429.928739 -376.823915)
			(xy 429.928739 -376.756491) (xy 429.936814 -376.689553) (xy 429.95285 -376.624064) (xy 429.976615 -376.560967)
			(xy 430.007766 -376.501171) (xy 430.045856 -376.445537) (xy 430.06772 -376.419872) (xy 430.073513 -376.412725)
			(xy 430.080029 -376.395536) (xy 430.08042 -376.386344) (xy 430.08042 -375.894092) (xy 430.080009 -375.884905)
			(xy 430.073496 -375.867721) (xy 430.06772 -375.860564) (xy 430.045887 -375.834873) (xy 430.007796 -375.779243)
			(xy 429.976643 -375.71945) (xy 429.952876 -375.656357) (xy 429.936837 -375.590871) (xy 429.928759 -375.523935)
			(xy 429.928756 -375.456513) (xy 429.936829 -375.389577) (xy 429.952861 -375.324089) (xy 429.976623 -375.260994)
			(xy 430.007771 -375.201199) (xy 430.045857 -375.145565) (xy 430.06772 -375.1199) (xy 430.073501 -375.112744)
			(xy 430.080024 -375.095562) (xy 430.08042 -375.086372) (xy 430.08042 -374.928638) (xy 430.080957 -374.918516)
			(xy 430.088669 -374.8998) (xy 430.10294 -374.885443) (xy 430.121609 -374.877619) (xy 430.131728 -374.877076)
			(xy 430.848008 -374.877076) (xy 430.85816 -374.877515) (xy 430.876907 -374.885308) (xy 430.89123 -374.899699)
			(xy 430.898933 -374.918484) (xy 430.899316 -374.928638) (xy 430.899316 -375.086372) (xy 430.899736 -375.095558)
			(xy 430.906242 -375.112743) (xy 430.912016 -375.1199) (xy 430.933911 -375.14554) (xy 430.971998 -375.201178)
			(xy 431.003146 -375.260978) (xy 431.026908 -375.324078) (xy 431.04294 -375.38957) (xy 431.051013 -375.456511)
			(xy 431.051011 -375.523937) (xy 431.042932 -375.590877) (xy 431.026893 -375.656368) (xy 431.003126 -375.719466)
			(xy 430.971973 -375.779263) (xy 430.933881 -375.834898) (xy 430.912016 -375.860564) (xy 430.906212 -375.867704)
			(xy 430.899701 -375.884898) (xy 430.899316 -375.894092) (xy 430.899316 -376.386344) (xy 430.899701 -376.395534)
			(xy 430.906232 -376.412718) (xy 430.912016 -376.419872) (xy 430.933883 -376.445534) (xy 430.971971 -376.50117)
			(xy 431.003121 -376.560966) (xy 431.026884 -376.624064) (xy 431.042918 -376.689553) (xy 431.050994 -376.756491)
			(xy 431.050994 -376.756551) (xy 434.329058 -376.756551) (xy 434.337101 -376.689729) (xy 434.353073 -376.624348)
			(xy 434.376744 -376.561343) (xy 434.407775 -376.50162) (xy 434.445721 -376.446033) (xy 434.467508 -376.42038)
			(xy 434.473296 -376.413229) (xy 434.479816 -376.396043) (xy 434.480208 -376.386852) (xy 434.480208 -375.893584)
			(xy 434.479804 -375.884396) (xy 434.473286 -375.867212) (xy 434.467508 -375.860056) (xy 434.445753 -375.834378)
			(xy 434.407805 -375.778794) (xy 434.376772 -375.719074) (xy 434.353099 -375.656073) (xy 434.337124 -375.590694)
			(xy 434.329078 -375.523875) (xy 434.329075 -375.456573) (xy 434.337116 -375.389753) (xy 434.353084 -375.324373)
			(xy 434.376752 -375.26137) (xy 434.40778 -375.201647) (xy 434.445723 -375.146061) (xy 434.467508 -375.120408)
			(xy 434.473285 -375.113249) (xy 434.479811 -375.096069) (xy 434.480208 -375.08688) (xy 434.480208 -374.928638)
			(xy 434.480694 -374.918473) (xy 434.488461 -374.899684) (xy 434.502827 -374.885299) (xy 434.521605 -374.877508)
			(xy 434.53177 -374.877076) (xy 435.24805 -374.877076) (xy 435.258223 -374.877506) (xy 435.277024 -374.885281)
			(xy 435.291412 -374.899666) (xy 435.299192 -374.918465) (xy 435.299612 -374.928638) (xy 435.299612 -375.08688)
			(xy 435.300029 -375.096067) (xy 435.306538 -375.113251) (xy 435.312312 -375.120408) (xy 435.334133 -375.146034)
			(xy 435.372084 -375.201623) (xy 435.403118 -375.26135) (xy 435.426791 -375.324358) (xy 435.442764 -375.389744)
			(xy 435.450806 -375.45657) (xy 435.450803 -375.523878) (xy 435.442755 -375.590704) (xy 435.426777 -375.656088)
			(xy 435.403099 -375.719094) (xy 435.372059 -375.778819) (xy 435.334103 -375.834404) (xy 435.312312 -375.860056)
			(xy 435.306511 -375.867198) (xy 435.299998 -375.884391) (xy 435.299612 -375.893584) (xy 435.299612 -376.386852)
			(xy 435.300042 -376.396037) (xy 435.306542 -376.413222) (xy 435.312312 -376.42038) (xy 435.334105 -376.446028)
			(xy 435.372057 -376.501614) (xy 435.403093 -376.561338) (xy 435.426768 -376.624343) (xy 435.442742 -376.689726)
			(xy 435.450786 -376.75655) (xy 435.450786 -376.823856) (xy 435.442741 -376.89068) (xy 435.426766 -376.956063)
			(xy 435.40309 -377.019068) (xy 435.372054 -377.078791) (xy 435.334101 -377.134376) (xy 435.312312 -377.160028)
			(xy 435.306522 -377.167178) (xy 435.300003 -377.184365) (xy 435.299612 -377.193556) (xy 435.299612 -377.35129)
			(xy 435.299227 -377.361467) (xy 435.291436 -377.380271) (xy 435.277038 -377.394658) (xy 435.258228 -377.402435)
			(xy 435.24805 -377.402852) (xy 434.53177 -377.402852) (xy 434.521609 -377.402391) (xy 434.502837 -377.394605)
			(xy 434.488473 -377.380229) (xy 434.480701 -377.361451) (xy 434.480208 -377.35129) (xy 434.480208 -377.193556)
			(xy 434.479817 -377.184367) (xy 434.47329 -377.167183) (xy 434.467508 -377.160028) (xy 434.445725 -377.134372)
			(xy 434.407778 -377.078786) (xy 434.376746 -377.019062) (xy 434.353075 -376.956058) (xy 434.337103 -376.890677)
			(xy 434.329059 -376.823855) (xy 434.329058 -376.756551) (xy 431.050994 -376.756551) (xy 431.050993 -376.823915)
			(xy 431.042917 -376.890853) (xy 431.026882 -376.956342) (xy 431.003118 -377.019439) (xy 430.971968 -377.079236)
			(xy 430.93388 -377.13487) (xy 430.912016 -377.160536) (xy 430.906223 -377.167684) (xy 430.899706 -377.184872)
			(xy 430.899316 -377.194064) (xy 430.899316 -377.35129) (xy 430.898864 -377.361421) (xy 430.891131 -377.380151)
			(xy 430.876834 -377.394509) (xy 430.858137 -377.402321) (xy 430.848008 -377.402852) (xy 430.131728 -377.402852)
			(xy 430.121582 -377.402357) (xy 430.10284 -377.39458) (xy 430.088518 -377.380207) (xy 430.080808 -377.361437)
			(xy 430.08042 -377.35129) (xy 430.08042 -377.194064) (xy 430.080023 -377.184876) (xy 430.0735 -377.167692)
			(xy 430.06772 -377.160536) (xy 430.045859 -377.134868) (xy 430.007769 -377.079234) (xy 429.976617 -377.019439)
			(xy 429.952852 -376.956342) (xy 429.936815 -376.890853) (xy 429.928739 -376.823915) (xy 426.650691 -376.823915)
			(xy 426.642653 -376.890679) (xy 426.626679 -376.956062) (xy 426.603004 -377.019067) (xy 426.571968 -377.07879)
			(xy 426.534017 -377.134376) (xy 426.512228 -377.160028) (xy 426.506428 -377.167171) (xy 426.499918 -377.184363)
			(xy 426.499528 -377.193556) (xy 426.499528 -377.35129) (xy 426.499127 -377.361465) (xy 426.491339 -377.380266)
			(xy 426.476946 -377.394653) (xy 426.458141 -377.402432) (xy 426.447966 -377.402852) (xy 425.731686 -377.402852)
			(xy 425.721526 -377.402378) (xy 425.702755 -377.394597) (xy 425.68839 -377.380225) (xy 425.680618 -377.36145)
			(xy 425.680124 -377.35129) (xy 425.680124 -377.193556) (xy 425.67973 -377.184367) (xy 425.673204 -377.167183)
			(xy 425.667424 -377.160028) (xy 425.645641 -377.134372) (xy 425.607693 -377.078786) (xy 425.57666 -377.019063)
			(xy 425.552988 -376.956059) (xy 425.537015 -376.890677) (xy 425.528971 -376.823855) (xy 425.52897 -376.756551)
			(xy 422.250906 -376.756551) (xy 422.250905 -376.823915) (xy 422.24283 -376.890853) (xy 422.226795 -376.956342)
			(xy 422.203032 -377.019438) (xy 422.171882 -377.079235) (xy 422.133795 -377.13487) (xy 422.111932 -377.160536)
			(xy 422.106129 -377.167677) (xy 422.09962 -377.184871) (xy 422.099232 -377.194064) (xy 422.099232 -377.35129)
			(xy 422.098764 -377.36142) (xy 422.091035 -377.380146) (xy 422.076742 -377.394503) (xy 422.058051 -377.402318)
			(xy 422.047924 -377.402852) (xy 421.331644 -377.402852) (xy 421.321499 -377.402343) (xy 421.302758 -377.394572)
			(xy 421.288435 -377.380202) (xy 421.280724 -377.361436) (xy 421.280336 -377.35129) (xy 421.280336 -377.194064)
			(xy 421.279935 -377.184876) (xy 421.273414 -377.167692) (xy 421.267636 -377.160536) (xy 421.245775 -377.134868)
			(xy 421.207684 -377.079235) (xy 421.176531 -377.019439) (xy 421.152765 -376.956343) (xy 421.136728 -376.890854)
			(xy 421.128651 -376.823915) (xy 391.450846 -376.823915) (xy 391.442809 -376.890678) (xy 391.426837 -376.956059)
			(xy 391.403165 -377.019064) (xy 391.372134 -377.078788) (xy 391.334187 -377.134375) (xy 391.3124 -377.160028)
			(xy 391.306609 -377.167177) (xy 391.300091 -377.184365) (xy 391.2997 -377.193556) (xy 391.2997 -377.35129)
			(xy 391.299159 -377.361442) (xy 391.291395 -377.380204) (xy 391.277044 -377.394568) (xy 391.25829 -377.40235)
			(xy 391.248138 -377.402852) (xy 390.531858 -377.402852) (xy 390.521696 -377.402401) (xy 390.502924 -377.394611)
			(xy 390.48856 -377.380232) (xy 390.480789 -377.361452) (xy 390.480296 -377.35129) (xy 390.480296 -377.193556)
			(xy 390.479908 -377.184366) (xy 390.473379 -377.167182) (xy 390.467596 -377.160028) (xy 390.445814 -377.134372)
			(xy 390.407867 -377.078785) (xy 390.376836 -377.019062) (xy 390.353165 -376.956058) (xy 390.337193 -376.890676)
			(xy 390.329149 -376.823855) (xy 387.051084 -376.823855) (xy 387.051084 -376.823915) (xy 387.043008 -376.890853)
			(xy 387.026972 -376.956343) (xy 387.003208 -377.01944) (xy 386.972057 -377.079236) (xy 386.933968 -377.134871)
			(xy 386.912104 -377.160536) (xy 386.90631 -377.167683) (xy 386.899794 -377.184872) (xy 386.899404 -377.194064)
			(xy 386.899404 -377.35129) (xy 386.898867 -377.361411) (xy 386.89115 -377.380123) (xy 386.87688 -377.394478)
			(xy 386.858214 -377.402306) (xy 386.848096 -377.402852) (xy 386.131816 -377.402852) (xy 386.121669 -377.402366)
			(xy 386.102927 -377.394586) (xy 386.088605 -377.380209) (xy 386.080896 -377.361438) (xy 386.080508 -377.35129)
			(xy 386.080508 -377.194064) (xy 386.080114 -377.184875) (xy 386.073589 -377.167691) (xy 386.067808 -377.160536)
			(xy 386.045948 -377.134868) (xy 386.007858 -377.079234) (xy 385.976707 -377.019438) (xy 385.952942 -376.956342)
			(xy 385.936906 -376.890853) (xy 385.92883 -376.823915) (xy 382.650782 -376.823915) (xy 382.642744 -376.89068)
			(xy 382.626769 -376.956063) (xy 382.603094 -377.019068) (xy 382.572058 -377.078791) (xy 382.534105 -377.134376)
			(xy 382.512316 -377.160028) (xy 382.506527 -377.167179) (xy 382.500007 -377.184365) (xy 382.499616 -377.193556)
			(xy 382.499616 -377.35129) (xy 382.499227 -377.361467) (xy 382.491437 -377.38027) (xy 382.47704 -377.394657)
			(xy 382.458231 -377.402434) (xy 382.448054 -377.402852) (xy 381.731774 -377.402852) (xy 381.721613 -377.402388)
			(xy 381.702842 -377.394603) (xy 381.688477 -377.380228) (xy 381.680705 -377.361451) (xy 381.680212 -377.35129)
			(xy 381.680212 -377.193556) (xy 381.67982 -377.184367) (xy 381.673294 -377.167183) (xy 381.667512 -377.160028)
			(xy 381.645729 -377.134372) (xy 381.607782 -377.078786) (xy 381.57675 -377.019062) (xy 381.553078 -376.956058)
			(xy 381.537106 -376.890677) (xy 381.529062 -376.823855) (xy 381.529061 -376.756551) (xy 378.250997 -376.756551)
			(xy 378.250996 -376.823915) (xy 378.24292 -376.890853) (xy 378.226885 -376.956342) (xy 378.203121 -377.019439)
			(xy 378.171971 -377.079235) (xy 378.133884 -377.13487) (xy 378.11202 -377.160536) (xy 378.106228 -377.167685)
			(xy 378.09971 -377.184872) (xy 378.09932 -377.194064) (xy 378.09932 -377.35129) (xy 378.098864 -377.361421)
			(xy 378.091132 -377.38015) (xy 378.076836 -377.394508) (xy 378.058141 -377.40232) (xy 378.048012 -377.402852)
			(xy 377.331732 -377.402852) (xy 377.321586 -377.402353) (xy 377.302845 -377.394578) (xy 377.288522 -377.380206)
			(xy 377.280812 -377.361437) (xy 377.280424 -377.35129) (xy 377.280424 -377.194064) (xy 377.280026 -377.184876)
			(xy 377.273503 -377.167692) (xy 377.267724 -377.160536) (xy 377.245863 -377.134868) (xy 377.207773 -377.079234)
			(xy 377.17662 -377.019439) (xy 377.152855 -376.956342) (xy 377.136819 -376.890853) (xy 377.128742 -376.823915)
			(xy 347.450937 -376.823915) (xy 347.4429 -376.890678) (xy 347.426927 -376.95606) (xy 347.403255 -377.019065)
			(xy 347.372223 -377.078788) (xy 347.334275 -377.134376) (xy 347.312488 -377.160028) (xy 347.306696 -377.167176)
			(xy 347.300179 -377.184364) (xy 347.299788 -377.193556) (xy 347.299788 -377.35129) (xy 347.299259 -377.361444)
			(xy 347.291493 -377.380208) (xy 347.277138 -377.394573) (xy 347.25838 -377.402352) (xy 347.248226 -377.402852)
			(xy 346.531946 -377.402852) (xy 346.521776 -377.402398) (xy 346.502981 -377.394627) (xy 346.488594 -377.38025)
			(xy 346.480809 -377.36146) (xy 346.480384 -377.35129) (xy 346.480384 -377.193556) (xy 346.479999 -377.184366)
			(xy 346.473468 -377.167182) (xy 346.467684 -377.160028) (xy 346.445899 -377.134373) (xy 346.407947 -377.078788)
			(xy 346.376911 -377.019065) (xy 346.353236 -376.956061) (xy 346.337262 -376.890679) (xy 346.329216 -376.823856)
			(xy 343.051175 -376.823856) (xy 343.051175 -376.823915) (xy 343.043099 -376.890854) (xy 343.027063 -376.956343)
			(xy 343.003298 -377.01944) (xy 342.972146 -377.079236) (xy 342.934056 -377.134871) (xy 342.912192 -377.160536)
			(xy 342.906397 -377.167682) (xy 342.899882 -377.184872) (xy 342.899492 -377.194064) (xy 342.899492 -377.35129)
			(xy 342.898966 -377.361412) (xy 342.891248 -377.380127) (xy 342.876974 -377.394483) (xy 342.858303 -377.402308)
			(xy 342.848184 -377.402852) (xy 342.131904 -377.402852) (xy 342.121757 -377.402376) (xy 342.103014 -377.394592)
			(xy 342.088693 -377.380212) (xy 342.080984 -377.361439) (xy 342.080596 -377.35129) (xy 342.080596 -377.194064)
			(xy 342.080204 -377.184875) (xy 342.073678 -377.167691) (xy 342.067896 -377.160536) (xy 342.046036 -377.134867)
			(xy 342.007948 -377.079233) (xy 341.976797 -377.019438) (xy 341.953033 -376.956341) (xy 341.936997 -376.890852)
			(xy 341.928921 -376.823915) (xy 338.650849 -376.823915) (xy 338.642812 -376.890677) (xy 338.62684 -376.956059)
			(xy 338.603168 -377.019064) (xy 338.572137 -377.078788) (xy 338.534191 -377.134375) (xy 338.512404 -377.160028)
			(xy 338.506614 -377.167178) (xy 338.500095 -377.184365) (xy 338.499704 -377.193556) (xy 338.499704 -377.35129)
			(xy 338.49916 -377.361442) (xy 338.491396 -377.380203) (xy 338.477047 -377.394567) (xy 338.458293 -377.402349)
			(xy 338.448142 -377.402852) (xy 337.731862 -377.402852) (xy 337.721701 -377.402397) (xy 337.702929 -377.394609)
			(xy 337.688564 -377.380231) (xy 337.680793 -377.361452) (xy 337.6803 -377.35129) (xy 337.6803 -377.193556)
			(xy 337.679911 -377.184367) (xy 337.673383 -377.167182) (xy 337.6676 -377.160028) (xy 337.645817 -377.134372)
			(xy 337.607871 -377.078785) (xy 337.57684 -377.019062) (xy 337.553168 -376.956058) (xy 337.537196 -376.890677)
			(xy 337.529152 -376.823855) (xy 334.251087 -376.823855) (xy 334.251087 -376.823915) (xy 334.243011 -376.890853)
			(xy 334.226976 -376.956342) (xy 334.203211 -377.019439) (xy 334.172061 -377.079236) (xy 334.133972 -377.134871)
			(xy 334.112108 -377.160536) (xy 334.106315 -377.167684) (xy 334.099798 -377.184872) (xy 334.099408 -377.194064)
			(xy 334.099408 -377.35129) (xy 334.098867 -377.36141) (xy 334.091151 -377.380122) (xy 334.076882 -377.394477)
			(xy 334.058217 -377.402305) (xy 334.0481 -377.402852) (xy 333.33182 -377.402852) (xy 333.321674 -377.402363)
			(xy 333.302932 -377.394584) (xy 333.288609 -377.380209) (xy 333.2809 -377.361438) (xy 333.280512 -377.35129)
			(xy 333.280512 -377.194064) (xy 333.280117 -377.184875) (xy 333.273592 -377.167691) (xy 333.267812 -377.160536)
			(xy 333.245952 -377.134868) (xy 333.207862 -377.079234) (xy 333.17671 -377.019438) (xy 333.152945 -376.956342)
			(xy 333.136909 -376.890853) (xy 333.128833 -376.823915) (xy 303.451057 -376.823915) (xy 303.44298 -376.890854)
			(xy 303.426944 -376.956344) (xy 303.403178 -377.019441) (xy 303.372025 -377.079237) (xy 303.333933 -377.134871)
			(xy 303.312068 -377.160536) (xy 303.30627 -377.16768) (xy 303.299757 -377.184871) (xy 303.299368 -377.194064)
			(xy 303.299368 -377.35129) (xy 303.298865 -377.361415) (xy 303.291142 -377.380135) (xy 303.276861 -377.394491)
			(xy 303.258182 -377.402312) (xy 303.24806 -377.402852) (xy 302.53178 -377.402852) (xy 302.521631 -377.402396)
			(xy 302.502888 -377.394604) (xy 302.488567 -377.380218) (xy 302.480859 -377.361441) (xy 302.480472 -377.35129)
			(xy 302.480472 -377.194064) (xy 302.480085 -377.184874) (xy 302.473556 -377.16769) (xy 302.467772 -377.160536)
			(xy 302.445913 -377.134867) (xy 302.407826 -377.079232) (xy 302.376677 -377.019436) (xy 302.352913 -376.95634)
			(xy 302.336879 -376.890852) (xy 302.328803 -376.823914) (xy 302.328802 -376.756492) (xy 299.050731 -376.756492)
			(xy 299.050738 -376.756551) (xy 299.050738 -376.823856) (xy 299.042693 -376.890678) (xy 299.026721 -376.95606)
			(xy 299.003048 -377.019065) (xy 298.972016 -377.078789) (xy 298.934067 -377.134376) (xy 298.91228 -377.160028)
			(xy 298.906487 -377.167175) (xy 298.899971 -377.184364) (xy 298.89958 -377.193556) (xy 298.89958 -377.35129)
			(xy 298.899059 -377.361445) (xy 298.891291 -377.38021) (xy 298.876934 -377.394575) (xy 298.858173 -377.402353)
			(xy 298.848018 -377.402852) (xy 298.131738 -377.402852) (xy 298.121568 -377.402405) (xy 298.102772 -377.39463)
			(xy 298.088385 -377.380252) (xy 298.080601 -377.36146) (xy 298.080176 -377.35129) (xy 298.080176 -377.193556)
			(xy 298.079792 -377.184366) (xy 298.073261 -377.167182) (xy 298.067476 -377.160028) (xy 298.045691 -377.134373)
			(xy 298.00774 -377.078788) (xy 297.976704 -377.019065) (xy 297.95303 -376.956061) (xy 297.937055 -376.890679)
			(xy 297.92901 -376.823856) (xy 294.650969 -376.823856) (xy 294.650969 -376.823915) (xy 294.642893 -376.890854)
			(xy 294.626856 -376.956343) (xy 294.603091 -377.019441) (xy 294.571939 -377.079237) (xy 294.533849 -377.134871)
			(xy 294.511984 -377.160536) (xy 294.506188 -377.167681) (xy 294.499673 -377.184872) (xy 294.499284 -377.194064)
			(xy 294.499284 -377.35129) (xy 294.498766 -377.361413) (xy 294.491046 -377.38013) (xy 294.47677 -377.394485)
			(xy 294.458096 -377.402309) (xy 294.447976 -377.402852) (xy 293.731696 -377.402852) (xy 293.721548 -377.402383)
			(xy 293.702806 -377.394595) (xy 293.688484 -377.380214) (xy 293.680776 -377.36144) (xy 293.680388 -377.35129)
			(xy 293.680388 -377.194064) (xy 293.679998 -377.184875) (xy 293.673471 -377.16769) (xy 293.667688 -377.160536)
			(xy 293.645828 -377.134867) (xy 293.60774 -377.079233) (xy 293.57659 -377.019437) (xy 293.552826 -376.956341)
			(xy 293.536791 -376.890852) (xy 293.528715 -376.823915) (xy 290.250643 -376.823915) (xy 290.242606 -376.890678)
			(xy 290.226633 -376.95606) (xy 290.202962 -377.019064) (xy 290.17193 -377.078788) (xy 290.133983 -377.134375)
			(xy 290.112196 -377.160028) (xy 290.106405 -377.167177) (xy 290.099887 -377.184365) (xy 290.099496 -377.193556)
			(xy 290.099496 -377.35129) (xy 290.098959 -377.361443) (xy 290.091194 -377.380205) (xy 290.076842 -377.39457)
			(xy 290.058087 -377.402351) (xy 290.047934 -377.402852) (xy 289.331654 -377.402852) (xy 289.321492 -377.402404)
			(xy 289.30272 -377.394613) (xy 289.288356 -377.380233) (xy 289.280585 -377.361452) (xy 289.280092 -377.35129)
			(xy 289.280092 -377.193556) (xy 289.279705 -377.184366) (xy 289.273176 -377.167182) (xy 289.267392 -377.160028)
			(xy 289.245607 -377.134373) (xy 289.207654 -377.078788) (xy 289.176618 -377.019066) (xy 289.152942 -376.956061)
			(xy 289.136968 -376.890679) (xy 289.128922 -376.823856) (xy 276.808294 -376.823856) (xy 276.868641 -376.988548)
			(xy 276.931633 -377.183713) (xy 276.986963 -377.381187) (xy 277.034546 -377.580669) (xy 277.074309 -377.781855)
			(xy 277.106193 -377.98444) (xy 277.130148 -378.188114) (xy 277.14076 -378.323794) (xy 286.928742 -378.323794)
			(xy 286.928744 -378.256367) (xy 286.936824 -378.189426) (xy 286.952863 -378.123935) (xy 286.976633 -378.060837)
			(xy 287.007789 -378.00104) (xy 287.045885 -377.945406) (xy 287.067752 -377.919742) (xy 287.073562 -377.912607)
			(xy 287.080067 -377.895408) (xy 287.080452 -377.886214) (xy 287.080452 -377.728734) (xy 287.080955 -377.718608)
			(xy 287.088674 -377.699885) (xy 287.102955 -377.685528) (xy 287.121637 -377.677709) (xy 287.13176 -377.677172)
			(xy 287.84804 -377.677172) (xy 287.858193 -377.677588) (xy 287.876941 -377.685392) (xy 287.891262 -377.699789)
			(xy 287.898965 -377.718579) (xy 287.899348 -377.728734) (xy 287.899348 -377.886214) (xy 287.899763 -377.8954)
			(xy 287.906275 -377.912584) (xy 287.912048 -377.919742) (xy 287.933888 -377.945427) (xy 287.971981 -378.001058)
			(xy 288.003136 -378.060851) (xy 288.026904 -378.123945) (xy 288.042943 -378.189432) (xy 288.051021 -378.256369)
			(xy 288.051024 -378.323734) (xy 291.329062 -378.323734) (xy 291.329064 -378.256427) (xy 291.337111 -378.189602)
			(xy 291.353086 -378.124219) (xy 291.376762 -378.061213) (xy 291.407799 -378.001489) (xy 291.445751 -377.945902)
			(xy 291.46754 -377.92025) (xy 291.473345 -377.913111) (xy 291.479854 -377.895916) (xy 291.48024 -377.886722)
			(xy 291.48024 -377.728734) (xy 291.480692 -377.718564) (xy 291.488466 -377.69977) (xy 291.502843 -377.685384)
			(xy 291.521633 -377.677598) (xy 291.531802 -377.677172) (xy 292.248082 -377.677172) (xy 292.258257 -377.677579)
			(xy 292.277058 -377.685365) (xy 292.291444 -377.699756) (xy 292.299224 -377.718559) (xy 292.299644 -377.728734)
			(xy 292.299644 -377.886722) (xy 292.300056 -377.895909) (xy 292.30657 -377.913092) (xy 292.312344 -377.92025)
			(xy 292.334107 -377.945923) (xy 292.372057 -378.001506) (xy 292.403093 -378.061227) (xy 292.426768 -378.124228)
			(xy 292.442743 -378.189608) (xy 292.450789 -378.256429) (xy 292.450792 -378.323732) (xy 292.450785 -378.323794)
			(xy 295.72883 -378.323794) (xy 295.728832 -378.256367) (xy 295.736911 -378.189427) (xy 295.752951 -378.123936)
			(xy 295.776719 -378.060837) (xy 295.807875 -378.001041) (xy 295.845969 -377.945407) (xy 295.867836 -377.919742)
			(xy 295.873644 -377.912605) (xy 295.880151 -377.895408) (xy 295.880536 -377.886214) (xy 295.880536 -377.728734)
			(xy 295.881055 -377.71861) (xy 295.88877 -377.69989) (xy 295.903047 -377.685533) (xy 295.921723 -377.677712)
			(xy 295.931844 -377.677172) (xy 296.648124 -377.677172) (xy 296.658276 -377.677601) (xy 296.677024 -377.6854)
			(xy 296.691345 -377.699793) (xy 296.699049 -377.71858) (xy 296.699432 -377.728734) (xy 296.699432 -377.886214)
			(xy 296.699851 -377.8954) (xy 296.70636 -377.912584) (xy 296.712132 -377.919742) (xy 296.733969 -377.945429)
			(xy 296.772057 -378.001061) (xy 296.803207 -378.060855) (xy 296.826971 -378.123949) (xy 296.843007 -378.189435)
			(xy 296.851085 -378.25637) (xy 296.851087 -378.323791) (xy 296.851087 -378.323794) (xy 300.128621 -378.323794)
			(xy 300.128623 -378.256367) (xy 300.136702 -378.189427) (xy 300.152741 -378.123936) (xy 300.176509 -378.060838)
			(xy 300.207664 -378.001041) (xy 300.245758 -377.945407) (xy 300.267624 -377.919742) (xy 300.27343 -377.912604)
			(xy 300.279938 -377.895408) (xy 300.280324 -377.886214) (xy 300.280324 -377.728734) (xy 300.280854 -377.718611)
			(xy 300.288568 -377.699894) (xy 300.302841 -377.685537) (xy 300.321512 -377.677714) (xy 300.331632 -377.677172)
			(xy 301.047912 -377.677172) (xy 301.058063 -377.677611) (xy 301.076811 -377.685405) (xy 301.091133 -377.699796)
			(xy 301.098837 -377.718581) (xy 301.09922 -377.728734) (xy 301.09922 -377.886214) (xy 301.099619 -377.895402)
			(xy 301.10614 -377.912587) (xy 301.11192 -377.919742) (xy 301.133758 -377.945429) (xy 301.171846 -378.001061)
			(xy 301.202997 -378.060854) (xy 301.226761 -378.123948) (xy 301.242798 -378.189434) (xy 301.250876 -378.25637)
			(xy 301.250878 -378.323734) (xy 330.92918 -378.323734) (xy 330.929182 -378.256427) (xy 330.937229 -378.189602)
			(xy 330.953206 -378.124218) (xy 330.976882 -378.061212) (xy 331.00792 -378.001488) (xy 331.045874 -377.945902)
			(xy 331.067664 -377.92025) (xy 331.073472 -377.913113) (xy 331.079978 -377.895916) (xy 331.080364 -377.886722)
			(xy 331.080364 -377.728734) (xy 331.080792 -377.718561) (xy 331.088571 -377.699763) (xy 331.102956 -377.685376)
			(xy 331.121753 -377.677594) (xy 331.131926 -377.677172) (xy 331.848206 -377.677172) (xy 331.858382 -377.67756)
			(xy 331.877184 -377.685353) (xy 331.891569 -377.69975) (xy 331.899348 -377.718557) (xy 331.899768 -377.728734)
			(xy 331.899768 -377.886722) (xy 331.900175 -377.895909) (xy 331.906692 -377.913093) (xy 331.912468 -377.92025)
			(xy 331.93423 -377.945923) (xy 331.972179 -378.001507) (xy 332.003213 -378.061228) (xy 332.026887 -378.124229)
			(xy 332.042861 -378.189609) (xy 332.050907 -378.256429) (xy 332.05091 -378.323732) (xy 332.050903 -378.323793)
			(xy 335.328973 -378.323793) (xy 335.328975 -378.256368) (xy 335.337053 -378.189429) (xy 335.35309 -378.123939)
			(xy 335.376855 -378.060841) (xy 335.408007 -378.001044) (xy 335.446096 -377.945408) (xy 335.46796 -377.919742)
			(xy 335.473771 -377.912607) (xy 335.480275 -377.895409) (xy 335.48066 -377.886214) (xy 335.48066 -377.728734)
			(xy 335.481155 -377.718607) (xy 335.488875 -377.699883) (xy 335.50316 -377.685525) (xy 335.521844 -377.677708)
			(xy 335.531968 -377.677172) (xy 336.248248 -377.677172) (xy 336.258402 -377.677582) (xy 336.27715 -377.685388)
			(xy 336.29147 -377.699787) (xy 336.299173 -377.718578) (xy 336.299556 -377.728734) (xy 336.299556 -377.886214)
			(xy 336.299969 -377.895401) (xy 336.306482 -377.912585) (xy 336.312256 -377.919742) (xy 336.334096 -377.945428)
			(xy 336.372188 -378.001058) (xy 336.403343 -378.060851) (xy 336.42711 -378.123945) (xy 336.443149 -378.189433)
			(xy 336.451227 -378.256369) (xy 336.45123 -378.323734) (xy 339.729268 -378.323734) (xy 339.72927 -378.256427)
			(xy 339.737317 -378.189602) (xy 339.753293 -378.124218) (xy 339.776969 -378.061213) (xy 339.808006 -378.001489)
			(xy 339.845958 -377.945902) (xy 339.867748 -377.92025) (xy 339.873554 -377.913112) (xy 339.880062 -377.895916)
			(xy 339.880448 -377.886722) (xy 339.880448 -377.728734) (xy 339.880892 -377.718563) (xy 339.888668 -377.699768)
			(xy 339.903047 -377.685381) (xy 339.92184 -377.677597) (xy 339.93201 -377.677172) (xy 340.64829 -377.677172)
			(xy 340.658465 -377.677573) (xy 340.677266 -377.685361) (xy 340.691653 -377.699754) (xy 340.699432 -377.718559)
			(xy 340.699852 -377.728734) (xy 340.699852 -377.886722) (xy 340.700262 -377.895909) (xy 340.706777 -377.913093)
			(xy 340.712552 -377.92025) (xy 340.734314 -377.945923) (xy 340.772264 -378.001506) (xy 340.803299 -378.061227)
			(xy 340.826974 -378.124229) (xy 340.842949 -378.189608) (xy 340.850995 -378.256429) (xy 340.850998 -378.323732)
			(xy 340.850998 -378.323734) (xy 344.129059 -378.323734) (xy 344.129061 -378.256427) (xy 344.137108 -378.189603)
			(xy 344.153083 -378.124219) (xy 344.176759 -378.061213) (xy 344.207795 -378.001489) (xy 344.245747 -377.945902)
			(xy 344.267536 -377.92025) (xy 344.273341 -377.913111) (xy 344.27985 -377.895916) (xy 344.280236 -377.886722)
			(xy 344.280236 -377.728734) (xy 344.280692 -377.718565) (xy 344.288465 -377.699771) (xy 344.302841 -377.685385)
			(xy 344.321629 -377.677599) (xy 344.331798 -377.677172) (xy 345.048078 -377.677172) (xy 345.058252 -377.677583)
			(xy 345.077053 -377.685367) (xy 345.09144 -377.699757) (xy 345.099219 -377.71856) (xy 345.09964 -377.728734)
			(xy 345.09964 -377.886722) (xy 345.100053 -377.895909) (xy 345.106566 -377.913092) (xy 345.11234 -377.92025)
			(xy 345.134103 -377.945923) (xy 345.172054 -378.001506) (xy 345.203089 -378.061226) (xy 345.226764 -378.124228)
			(xy 345.24274 -378.189608) (xy 345.250786 -378.256429) (xy 345.250789 -378.323732) (xy 345.250789 -378.323734)
			(xy 374.929089 -378.323734) (xy 374.929092 -378.256427) (xy 374.937139 -378.189602) (xy 374.953116 -378.124218)
			(xy 374.976793 -378.061212) (xy 375.007831 -378.001488) (xy 375.045786 -377.945902) (xy 375.067576 -377.92025)
			(xy 375.073374 -377.913105) (xy 375.079888 -377.895915) (xy 375.080276 -377.886722) (xy 375.080276 -377.728734)
			(xy 375.080693 -377.71856) (xy 375.088474 -377.699759) (xy 375.102862 -377.685371) (xy 375.121664 -377.677592)
			(xy 375.131838 -377.677172) (xy 375.848118 -377.677172) (xy 375.858295 -377.67755) (xy 375.877097 -377.685347)
			(xy 375.891482 -377.699747) (xy 375.89926 -377.718557) (xy 375.89968 -377.728734) (xy 375.89968 -377.886722)
			(xy 375.900084 -377.89591) (xy 375.906602 -377.913094) (xy 375.91238 -377.92025) (xy 375.934142 -377.945923)
			(xy 375.97209 -378.001507) (xy 376.003123 -378.061228) (xy 376.026797 -378.12423) (xy 376.042771 -378.189609)
			(xy 376.050817 -378.256429) (xy 376.050819 -378.323732) (xy 376.050812 -378.323793) (xy 379.328882 -378.323793)
			(xy 379.328884 -378.256368) (xy 379.336962 -378.189428) (xy 379.352999 -378.123938) (xy 379.376765 -378.06084)
			(xy 379.407917 -378.001043) (xy 379.446007 -377.945408) (xy 379.467872 -377.919742) (xy 379.473684 -377.912608)
			(xy 379.480188 -377.895409) (xy 379.480572 -377.886214) (xy 379.480572 -377.728734) (xy 379.481056 -377.718606)
			(xy 379.488778 -377.699879) (xy 379.503066 -377.685521) (xy 379.521754 -377.677706) (xy 379.53188 -377.677172)
			(xy 380.24816 -377.677172) (xy 380.258308 -377.677654) (xy 380.277054 -377.685431) (xy 380.291378 -377.699809)
			(xy 380.299084 -377.718584) (xy 380.299468 -377.728734) (xy 380.299468 -377.886214) (xy 380.299878 -377.895401)
			(xy 380.306393 -377.912585) (xy 380.312168 -377.919742) (xy 380.334008 -377.945428) (xy 380.372099 -378.001059)
			(xy 380.403253 -378.060852) (xy 380.42702 -378.123946) (xy 380.443058 -378.189433) (xy 380.451137 -378.256369)
			(xy 380.451139 -378.323734) (xy 383.729177 -378.323734) (xy 383.729179 -378.256427) (xy 383.737226 -378.189602)
			(xy 383.753202 -378.124218) (xy 383.776879 -378.061212) (xy 383.807917 -378.001488) (xy 383.84587 -377.945902)
			(xy 383.86766 -377.92025) (xy 383.873468 -377.913113) (xy 383.879974 -377.895916) (xy 383.88036 -377.886722)
			(xy 383.88036 -377.728734) (xy 383.880792 -377.718562) (xy 383.88857 -377.699764) (xy 383.902954 -377.685377)
			(xy 383.92175 -377.677595) (xy 383.931922 -377.677172) (xy 384.648202 -377.677172) (xy 384.658378 -377.677563)
			(xy 384.677179 -377.685355) (xy 384.691565 -377.699751) (xy 384.699344 -377.718558) (xy 384.699764 -377.728734)
			(xy 384.699764 -377.886722) (xy 384.700172 -377.895909) (xy 384.706688 -377.913093) (xy 384.712464 -377.92025)
			(xy 384.734226 -377.945923) (xy 384.772175 -378.001507) (xy 384.803209 -378.061228) (xy 384.826884 -378.124229)
			(xy 384.842858 -378.189609) (xy 384.850904 -378.256429) (xy 384.850907 -378.323732) (xy 384.850907 -378.323734)
			(xy 388.128968 -378.323734) (xy 388.12897 -378.256427) (xy 388.137017 -378.189602) (xy 388.152993 -378.124218)
			(xy 388.176669 -378.061213) (xy 388.207706 -378.001489) (xy 388.245658 -377.945902) (xy 388.267448 -377.92025)
			(xy 388.273254 -377.913112) (xy 388.279762 -377.895916) (xy 388.280148 -377.886722) (xy 388.280148 -377.728734)
			(xy 388.280592 -377.718563) (xy 388.288368 -377.699768) (xy 388.302747 -377.685381) (xy 388.32154 -377.677597)
			(xy 388.33171 -377.677172) (xy 389.04799 -377.677172) (xy 389.058165 -377.677573) (xy 389.076966 -377.685361)
			(xy 389.091353 -377.699754) (xy 389.099132 -377.718559) (xy 389.099552 -377.728734) (xy 389.099552 -377.886722)
			(xy 389.099962 -377.895909) (xy 389.106477 -377.913093) (xy 389.112252 -377.92025) (xy 389.134014 -377.945923)
			(xy 389.171964 -378.001506) (xy 389.202999 -378.061227) (xy 389.226674 -378.124229) (xy 389.242649 -378.189608)
			(xy 389.250695 -378.256429) (xy 389.250698 -378.323732) (xy 389.250698 -378.323734) (xy 418.928998 -378.323734)
			(xy 418.929001 -378.256426) (xy 418.937048 -378.189601) (xy 418.953025 -378.124217) (xy 418.976703 -378.061211)
			(xy 419.007742 -378.001487) (xy 419.045697 -377.945902) (xy 419.067488 -377.92025) (xy 419.073287 -377.913106)
			(xy 419.079801 -377.895915) (xy 419.080188 -377.886722) (xy 419.080188 -377.728734) (xy 419.080593 -377.718558)
			(xy 419.088376 -377.699755) (xy 419.102768 -377.685367) (xy 419.121574 -377.67759) (xy 419.13175 -377.677172)
			(xy 419.84803 -377.677172) (xy 419.858208 -377.67754) (xy 419.87701 -377.685341) (xy 419.891395 -377.699744)
			(xy 419.899173 -377.718556) (xy 419.899592 -377.728734) (xy 419.899592 -377.886722) (xy 419.899993 -377.89591)
			(xy 419.906513 -377.913094) (xy 419.912292 -377.92025) (xy 419.934053 -377.945924) (xy 419.972001 -378.001508)
			(xy 420.003034 -378.061229) (xy 420.026706 -378.12423) (xy 420.04268 -378.189609) (xy 420.050726 -378.256429)
			(xy 420.050728 -378.323732) (xy 420.050721 -378.323793) (xy 423.328791 -378.323793) (xy 423.328793 -378.256368)
			(xy 423.336871 -378.189428) (xy 423.352909 -378.123938) (xy 423.376675 -378.06084) (xy 423.407828 -378.001043)
			(xy 423.445919 -377.945408) (xy 423.467784 -377.919742) (xy 423.473586 -377.9126) (xy 423.480098 -377.895407)
			(xy 423.480484 -377.886214) (xy 423.480484 -377.728734) (xy 423.480956 -377.718604) (xy 423.488681 -377.699875)
			(xy 423.502972 -377.685516) (xy 423.521664 -377.677704) (xy 423.531792 -377.677172) (xy 424.248072 -377.677172)
			(xy 424.258221 -377.677644) (xy 424.276967 -377.685425) (xy 424.291291 -377.699806) (xy 424.298996 -377.718584)
			(xy 424.29938 -377.728734) (xy 424.29938 -377.886214) (xy 424.299788 -377.895401) (xy 424.306303 -377.912585)
			(xy 424.31208 -377.919742) (xy 424.333919 -377.945428) (xy 424.37201 -378.001059) (xy 424.403163 -378.060852)
			(xy 424.426929 -378.123946) (xy 424.442967 -378.189433) (xy 424.451046 -378.256369) (xy 424.451048 -378.323734)
			(xy 427.729086 -378.323734) (xy 427.729089 -378.256427) (xy 427.737136 -378.189602) (xy 427.753113 -378.124218)
			(xy 427.77679 -378.061212) (xy 427.807828 -378.001488) (xy 427.845782 -377.945902) (xy 427.867572 -377.92025)
			(xy 427.873381 -377.913114) (xy 427.879886 -377.895916) (xy 427.880272 -377.886722) (xy 427.880272 -377.728734)
			(xy 427.880693 -377.71856) (xy 427.888473 -377.69976) (xy 427.90286 -377.685373) (xy 427.92166 -377.677593)
			(xy 427.931834 -377.677172) (xy 428.648114 -377.677172) (xy 428.658291 -377.677553) (xy 428.677092 -377.685349)
			(xy 428.691478 -377.699748) (xy 428.699256 -377.718557) (xy 428.699676 -377.728734) (xy 428.699676 -377.886722)
			(xy 428.700081 -377.89591) (xy 428.706599 -377.913094) (xy 428.712376 -377.92025) (xy 428.734137 -377.945924)
			(xy 428.772086 -378.001507) (xy 428.80312 -378.061228) (xy 428.826793 -378.12423) (xy 428.842767 -378.189609)
			(xy 428.850813 -378.256429) (xy 428.850816 -378.323732) (xy 428.850816 -378.323734) (xy 432.128877 -378.323734)
			(xy 432.128879 -378.256427) (xy 432.136926 -378.189602) (xy 432.152902 -378.124218) (xy 432.176579 -378.061212)
			(xy 432.207617 -378.001488) (xy 432.24557 -377.945902) (xy 432.26736 -377.92025) (xy 432.273168 -377.913113)
			(xy 432.279674 -377.895916) (xy 432.28006 -377.886722) (xy 432.28006 -377.728734) (xy 432.280492 -377.718562)
			(xy 432.28827 -377.699764) (xy 432.302654 -377.685377) (xy 432.32145 -377.677595) (xy 432.331622 -377.677172)
			(xy 433.047902 -377.677172) (xy 433.058078 -377.677563) (xy 433.076879 -377.685355) (xy 433.091265 -377.699751)
			(xy 433.099044 -377.718558) (xy 433.099464 -377.728734) (xy 433.099464 -377.886722) (xy 433.099872 -377.895909)
			(xy 433.106388 -377.913093) (xy 433.112164 -377.92025) (xy 433.133926 -377.945923) (xy 433.171875 -378.001507)
			(xy 433.202909 -378.061228) (xy 433.226584 -378.124229) (xy 433.242558 -378.189609) (xy 433.250604 -378.256429)
			(xy 433.250607 -378.323732) (xy 433.242565 -378.390553) (xy 433.226595 -378.455933) (xy 433.202925 -378.518937)
			(xy 433.171895 -378.57866) (xy 433.13395 -378.634246) (xy 433.112164 -378.659898) (xy 433.106381 -378.667053)
			(xy 433.099859 -378.684236) (xy 433.099464 -378.693426) (xy 433.099464 -379.186694) (xy 433.099885 -379.19588)
			(xy 433.106392 -379.213064) (xy 433.112164 -379.220222) (xy 433.133997 -379.245837) (xy 433.171944 -379.301429)
			(xy 433.202975 -379.361158) (xy 433.226645 -379.424167) (xy 433.242615 -379.489554) (xy 433.250655 -379.55638)
			(xy 433.250651 -379.623689) (xy 433.242603 -379.690515) (xy 433.226625 -379.755899) (xy 433.202947 -379.818906)
			(xy 433.171909 -379.878631) (xy 433.133955 -379.934218) (xy 433.112164 -379.95987) (xy 433.106351 -379.967003)
			(xy 433.099847 -379.984203) (xy 433.099464 -379.993398) (xy 433.099464 -380.151386) (xy 433.099025 -380.161556)
			(xy 433.091245 -380.180351) (xy 433.076864 -380.194736) (xy 433.058072 -380.202522) (xy 433.047902 -380.202948)
			(xy 432.331622 -380.202948) (xy 432.32145 -380.202518) (xy 432.302653 -380.194737) (xy 432.288267 -380.180353)
			(xy 432.280484 -380.161558) (xy 432.28006 -380.151386) (xy 432.28006 -379.993398) (xy 432.279637 -379.984212)
			(xy 432.273131 -379.967029) (xy 432.26736 -379.95987) (xy 432.245617 -379.934181) (xy 432.207665 -379.8786)
			(xy 432.176629 -379.818882) (xy 432.152953 -379.755882) (xy 432.136976 -379.690504) (xy 432.128928 -379.623685)
			(xy 432.128924 -379.556384) (xy 432.136964 -379.489564) (xy 432.152932 -379.424184) (xy 432.176601 -379.361181)
			(xy 432.20763 -379.301459) (xy 432.245575 -379.245874) (xy 432.26736 -379.220222) (xy 432.27318 -379.213093)
			(xy 432.279679 -379.19589) (xy 432.28006 -379.186694) (xy 432.28006 -378.693426) (xy 432.279624 -378.684242)
			(xy 432.273127 -378.667058) (xy 432.26736 -378.659898) (xy 432.245546 -378.634267) (xy 432.207596 -378.578678)
			(xy 432.176563 -378.518952) (xy 432.152891 -378.455945) (xy 432.136919 -378.39056) (xy 432.128877 -378.323734)
			(xy 428.850816 -378.323734) (xy 428.842774 -378.390552) (xy 428.826805 -378.455933) (xy 428.803136 -378.518936)
			(xy 428.772106 -378.578659) (xy 428.734161 -378.634245) (xy 428.712376 -378.659898) (xy 428.706595 -378.667054)
			(xy 428.700072 -378.684236) (xy 428.699676 -378.693426) (xy 428.699676 -379.186694) (xy 428.700094 -379.19588)
			(xy 428.706603 -379.213064) (xy 428.712376 -379.220222) (xy 428.734209 -379.245837) (xy 428.772155 -379.301429)
			(xy 428.803185 -379.361158) (xy 428.826855 -379.424167) (xy 428.842824 -379.489554) (xy 428.850865 -379.55638)
			(xy 428.85086 -379.623689) (xy 428.842812 -379.690514) (xy 428.826835 -379.755899) (xy 428.803157 -379.818905)
			(xy 428.772119 -379.87863) (xy 428.734166 -379.934218) (xy 428.712376 -379.95987) (xy 428.706564 -379.967004)
			(xy 428.70006 -379.984203) (xy 428.699676 -379.993398) (xy 428.699676 -380.151386) (xy 428.699156 -380.161541)
			(xy 428.691388 -380.180307) (xy 428.677031 -380.194673) (xy 428.658269 -380.20245) (xy 428.648114 -380.202948)
			(xy 427.931834 -380.202948) (xy 427.921663 -380.202508) (xy 427.902866 -380.194731) (xy 427.88848 -380.180351)
			(xy 427.880696 -380.161557) (xy 427.880272 -380.151386) (xy 427.880272 -379.993398) (xy 427.879869 -379.98421)
			(xy 427.873351 -379.967025) (xy 427.867572 -379.95987) (xy 427.845829 -379.934181) (xy 427.807876 -379.878601)
			(xy 427.776839 -379.818882) (xy 427.753162 -379.755883) (xy 427.737185 -379.690505) (xy 427.729137 -379.623686)
			(xy 427.729133 -379.556384) (xy 427.737173 -379.489564) (xy 427.753142 -379.424183) (xy 427.776811 -379.361181)
			(xy 427.807841 -379.301459) (xy 427.845786 -379.245874) (xy 427.867572 -379.220222) (xy 427.873393 -379.213094)
			(xy 427.879891 -379.19589) (xy 427.880272 -379.186694) (xy 427.880272 -378.693426) (xy 427.879856 -378.684239)
			(xy 427.873347 -378.667055) (xy 427.867572 -378.659898) (xy 427.845758 -378.634267) (xy 427.807808 -378.578678)
			(xy 427.776774 -378.518952) (xy 427.753101 -378.455945) (xy 427.737129 -378.39056) (xy 427.729086 -378.323734)
			(xy 424.451048 -378.323734) (xy 424.451048 -378.323791) (xy 424.442974 -378.390728) (xy 424.426941 -378.456216)
			(xy 424.403179 -378.519312) (xy 424.37203 -378.579107) (xy 424.333943 -378.634741) (xy 424.31208 -378.660406)
			(xy 424.306296 -378.66756) (xy 424.299775 -378.684744) (xy 424.29938 -378.693934) (xy 424.29938 -379.186186)
			(xy 424.299802 -379.195372) (xy 424.306308 -379.212556) (xy 424.31208 -379.219714) (xy 424.33399 -379.245342)
			(xy 424.372079 -379.300981) (xy 424.403228 -379.360782) (xy 424.426991 -379.423884) (xy 424.443024 -379.489378)
			(xy 424.451096 -379.556321) (xy 424.451092 -379.623748) (xy 424.443011 -379.69069) (xy 424.42697 -379.756182)
			(xy 424.4032 -379.819281) (xy 424.372043 -379.879078) (xy 424.333947 -379.934713) (xy 424.31208 -379.960378)
			(xy 424.306266 -379.96751) (xy 424.299762 -379.984711) (xy 424.29938 -379.993906) (xy 424.29938 -380.151386)
			(xy 424.298863 -380.161509) (xy 424.291143 -380.180226) (xy 424.276866 -380.194583) (xy 424.258193 -380.202406)
			(xy 424.248072 -380.202948) (xy 423.531792 -380.202948) (xy 423.521643 -380.202486) (xy 423.5029 -380.194697)
			(xy 423.488579 -380.180313) (xy 423.480871 -380.161536) (xy 423.480484 -380.151386) (xy 423.480484 -379.993906)
			(xy 423.480075 -379.984719) (xy 423.473561 -379.967534) (xy 423.467784 -379.960378) (xy 423.445966 -379.934675)
			(xy 423.407877 -379.879046) (xy 423.376725 -379.819255) (xy 423.352959 -379.756163) (xy 423.336921 -379.690678)
			(xy 423.328841 -379.623744) (xy 423.328837 -379.556325) (xy 423.336908 -379.48939) (xy 423.352938 -379.423904)
			(xy 423.376697 -379.360809) (xy 423.407841 -379.301014) (xy 423.445923 -379.245379) (xy 423.467784 -379.219714)
			(xy 423.473598 -379.212581) (xy 423.480103 -379.195381) (xy 423.480484 -379.186186) (xy 423.480484 -378.693934)
			(xy 423.480061 -378.684748) (xy 423.473557 -378.667563) (xy 423.467784 -378.660406) (xy 423.445895 -378.634762)
			(xy 423.407808 -378.579124) (xy 423.376659 -378.519324) (xy 423.352897 -378.456225) (xy 423.336864 -378.390733)
			(xy 423.328791 -378.323793) (xy 420.050721 -378.323793) (xy 420.042687 -378.390552) (xy 420.026718 -378.455932)
			(xy 420.003049 -378.518936) (xy 419.972021 -378.578659) (xy 419.934077 -378.634245) (xy 419.912292 -378.659898)
			(xy 419.906513 -378.667056) (xy 419.899988 -378.684237) (xy 419.899592 -378.693426) (xy 419.899592 -379.186694)
			(xy 419.900007 -379.195881) (xy 419.906518 -379.213065) (xy 419.912292 -379.220222) (xy 419.934124 -379.245837)
			(xy 419.972069 -379.30143) (xy 420.003099 -379.361159) (xy 420.026768 -379.424168) (xy 420.042737 -379.489554)
			(xy 420.050777 -379.556381) (xy 420.050772 -379.623689) (xy 420.042724 -379.690514) (xy 420.026747 -379.755898)
			(xy 420.003071 -379.818905) (xy 419.972034 -379.87863) (xy 419.934082 -379.934217) (xy 419.912292 -379.95987)
			(xy 419.906482 -379.967006) (xy 419.899976 -379.984204) (xy 419.899592 -379.993398) (xy 419.899592 -380.151386)
			(xy 419.899056 -380.161539) (xy 419.891292 -380.180302) (xy 419.876939 -380.194667) (xy 419.858183 -380.202447)
			(xy 419.84803 -380.202948) (xy 419.13175 -380.202948) (xy 419.12158 -380.202495) (xy 419.102784 -380.194724)
			(xy 419.088396 -380.180347) (xy 419.080612 -380.161556) (xy 419.080188 -380.151386) (xy 419.080188 -379.993398)
			(xy 419.079781 -379.98421) (xy 419.073266 -379.967026) (xy 419.067488 -379.95987) (xy 419.045744 -379.934181)
			(xy 419.007791 -379.878601) (xy 418.976753 -379.818883) (xy 418.953075 -379.755883) (xy 418.937097 -379.690505)
			(xy 418.929049 -379.623686) (xy 418.929045 -379.556383) (xy 418.937085 -379.489563) (xy 418.953055 -379.424183)
			(xy 418.976724 -379.36118) (xy 419.007755 -379.301458) (xy 419.045702 -379.245873) (xy 419.067488 -379.220222)
			(xy 419.073299 -379.213087) (xy 419.079805 -379.195889) (xy 419.080188 -379.186694) (xy 419.080188 -378.693426)
			(xy 419.079768 -378.68424) (xy 419.073262 -378.667055) (xy 419.067488 -378.659898) (xy 419.045673 -378.634268)
			(xy 419.007722 -378.578679) (xy 418.976687 -378.518953) (xy 418.953014 -378.455946) (xy 418.937041 -378.39056)
			(xy 418.928998 -378.323734) (xy 389.250698 -378.323734) (xy 389.242656 -378.390553) (xy 389.226686 -378.455934)
			(xy 389.203015 -378.518937) (xy 389.171985 -378.57866) (xy 389.134038 -378.634246) (xy 389.112252 -378.659898)
			(xy 389.106468 -378.667052) (xy 389.099947 -378.684236) (xy 389.099552 -378.693426) (xy 389.099552 -379.186694)
			(xy 389.099976 -379.19588) (xy 389.106481 -379.213063) (xy 389.112252 -379.220222) (xy 389.134085 -379.245837)
			(xy 389.172033 -379.301428) (xy 389.203065 -379.361157) (xy 389.226736 -379.424166) (xy 389.242706 -379.489553)
			(xy 389.250746 -379.55638) (xy 389.250742 -379.623689) (xy 389.242693 -379.690515) (xy 389.226715 -379.7559)
			(xy 389.203037 -379.818906) (xy 389.171998 -379.878631) (xy 389.134043 -379.934218) (xy 389.112252 -379.95987)
			(xy 389.106437 -379.967002) (xy 389.099935 -379.984203) (xy 389.099552 -379.993398) (xy 389.099552 -380.151386)
			(xy 389.099125 -380.161558) (xy 389.091342 -380.180354) (xy 389.076958 -380.19474) (xy 389.058162 -380.202524)
			(xy 389.04799 -380.202948) (xy 388.33171 -380.202948) (xy 388.321537 -380.202528) (xy 388.30274 -380.194743)
			(xy 388.288354 -380.180357) (xy 388.280571 -380.161559) (xy 388.280148 -380.151386) (xy 388.280148 -379.993398)
			(xy 388.279728 -379.984212) (xy 388.27322 -379.967028) (xy 388.267448 -379.95987) (xy 388.245705 -379.934181)
			(xy 388.207755 -379.8786) (xy 388.176719 -379.818881) (xy 388.153043 -379.755882) (xy 388.137067 -379.690504)
			(xy 388.129019 -379.623685) (xy 388.129015 -379.556384) (xy 388.137054 -379.489564) (xy 388.153023 -379.424184)
			(xy 388.176691 -379.361182) (xy 388.207719 -379.30146) (xy 388.245663 -379.245874) (xy 388.267448 -379.220222)
			(xy 388.273266 -379.213092) (xy 388.279767 -379.19589) (xy 388.280148 -379.186694) (xy 388.280148 -378.693426)
			(xy 388.279715 -378.684241) (xy 388.273216 -378.667057) (xy 388.267448 -378.659898) (xy 388.245634 -378.634267)
			(xy 388.207686 -378.578678) (xy 388.176653 -378.518951) (xy 388.152981 -378.455944) (xy 388.13701 -378.390559)
			(xy 388.128968 -378.323734) (xy 384.850907 -378.323734) (xy 384.842865 -378.390553) (xy 384.826895 -378.455933)
			(xy 384.803225 -378.518937) (xy 384.772195 -378.57866) (xy 384.73425 -378.634246) (xy 384.712464 -378.659898)
			(xy 384.706681 -378.667053) (xy 384.700159 -378.684236) (xy 384.699764 -378.693426) (xy 384.699764 -379.186694)
			(xy 384.700185 -379.19588) (xy 384.706692 -379.213064) (xy 384.712464 -379.220222) (xy 384.734297 -379.245837)
			(xy 384.772244 -379.301429) (xy 384.803275 -379.361158) (xy 384.826945 -379.424167) (xy 384.842915 -379.489554)
			(xy 384.850955 -379.55638) (xy 384.850951 -379.623689) (xy 384.842903 -379.690515) (xy 384.826925 -379.755899)
			(xy 384.803247 -379.818906) (xy 384.772209 -379.878631) (xy 384.734255 -379.934218) (xy 384.712464 -379.95987)
			(xy 384.706651 -379.967003) (xy 384.700147 -379.984203) (xy 384.699764 -379.993398) (xy 384.699764 -380.151386)
			(xy 384.699325 -380.161556) (xy 384.691545 -380.180351) (xy 384.677164 -380.194736) (xy 384.658372 -380.202522)
			(xy 384.648202 -380.202948) (xy 383.931922 -380.202948) (xy 383.92175 -380.202518) (xy 383.902953 -380.194737)
			(xy 383.888567 -380.180353) (xy 383.880784 -380.161558) (xy 383.88036 -380.151386) (xy 383.88036 -379.993398)
			(xy 383.879937 -379.984212) (xy 383.873431 -379.967029) (xy 383.86766 -379.95987) (xy 383.845917 -379.934181)
			(xy 383.807965 -379.8786) (xy 383.776929 -379.818882) (xy 383.753253 -379.755882) (xy 383.737276 -379.690504)
			(xy 383.729228 -379.623685) (xy 383.729224 -379.556384) (xy 383.737264 -379.489564) (xy 383.753232 -379.424184)
			(xy 383.776901 -379.361181) (xy 383.80793 -379.301459) (xy 383.845875 -379.245874) (xy 383.86766 -379.220222)
			(xy 383.87348 -379.213093) (xy 383.879979 -379.19589) (xy 383.88036 -379.186694) (xy 383.88036 -378.693426)
			(xy 383.879924 -378.684242) (xy 383.873427 -378.667058) (xy 383.86766 -378.659898) (xy 383.845846 -378.634267)
			(xy 383.807896 -378.578678) (xy 383.776863 -378.518952) (xy 383.753191 -378.455945) (xy 383.737219 -378.39056)
			(xy 383.729177 -378.323734) (xy 380.451139 -378.323734) (xy 380.451139 -378.323792) (xy 380.443065 -378.390729)
			(xy 380.427031 -378.456217) (xy 380.403269 -378.519313) (xy 380.372119 -378.579108) (xy 380.334032 -378.634741)
			(xy 380.312168 -378.660406) (xy 380.306382 -378.667559) (xy 380.299862 -378.684744) (xy 380.299468 -378.693934)
			(xy 380.299468 -379.186186) (xy 380.299892 -379.195372) (xy 380.306397 -379.212556) (xy 380.312168 -379.219714)
			(xy 380.334078 -379.245341) (xy 380.372168 -379.300981) (xy 380.403318 -379.360782) (xy 380.427081 -379.423884)
			(xy 380.443114 -379.489378) (xy 380.451187 -379.556321) (xy 380.451183 -379.623749) (xy 380.443102 -379.69069)
			(xy 380.427061 -379.756182) (xy 380.40329 -379.819281) (xy 380.372132 -379.879079) (xy 380.334036 -379.934713)
			(xy 380.312168 -379.960378) (xy 380.306352 -379.967509) (xy 380.29985 -379.984711) (xy 380.299468 -379.993906)
			(xy 380.299468 -380.151386) (xy 380.298962 -380.161511) (xy 380.291241 -380.18023) (xy 380.27696 -380.194587)
			(xy 380.258282 -380.202408) (xy 380.24816 -380.202948) (xy 379.53188 -380.202948) (xy 379.521731 -380.202496)
			(xy 379.502987 -380.194703) (xy 379.488666 -380.180316) (xy 379.480958 -380.161537) (xy 379.480572 -380.151386)
			(xy 379.480572 -379.993906) (xy 379.480165 -379.984718) (xy 379.47365 -379.967534) (xy 379.467872 -379.960378)
			(xy 379.446054 -379.934675) (xy 379.407966 -379.879045) (xy 379.376815 -379.819254) (xy 379.353049 -379.756162)
			(xy 379.337011 -379.690678) (xy 379.328932 -379.623744) (xy 379.328928 -379.556325) (xy 379.336999 -379.48939)
			(xy 379.353029 -379.423904) (xy 379.376787 -379.360809) (xy 379.40793 -379.301014) (xy 379.446012 -379.24538)
			(xy 379.467872 -379.219714) (xy 379.473696 -379.212589) (xy 379.480192 -379.195383) (xy 379.480572 -379.186186)
			(xy 379.480572 -378.693934) (xy 379.480152 -378.684748) (xy 379.473646 -378.667563) (xy 379.467872 -378.660406)
			(xy 379.445983 -378.634761) (xy 379.407897 -378.579123) (xy 379.376749 -378.519324) (xy 379.352988 -378.456224)
			(xy 379.336955 -378.390733) (xy 379.328882 -378.323793) (xy 376.050812 -378.323793) (xy 376.042778 -378.390552)
			(xy 376.026808 -378.455933) (xy 376.003139 -378.518936) (xy 375.97211 -378.578659) (xy 375.934166 -378.634246)
			(xy 375.91238 -378.659898) (xy 375.906599 -378.667054) (xy 375.900076 -378.684236) (xy 375.89968 -378.693426)
			(xy 375.89968 -379.186694) (xy 375.900098 -379.19588) (xy 375.906607 -379.213064) (xy 375.91238 -379.220222)
			(xy 375.934212 -379.245837) (xy 375.972159 -379.301429) (xy 376.003189 -379.361158) (xy 376.026858 -379.424168)
			(xy 376.042827 -379.489554) (xy 376.050868 -379.55638) (xy 376.050863 -379.623689) (xy 376.042815 -379.690514)
			(xy 376.026838 -379.755899) (xy 376.003161 -379.818905) (xy 375.972123 -379.87863) (xy 375.93417 -379.934218)
			(xy 375.91238 -379.95987) (xy 375.906569 -379.967005) (xy 375.900064 -379.984203) (xy 375.89968 -379.993398)
			(xy 375.89968 -380.151386) (xy 375.899156 -380.161541) (xy 375.891389 -380.180306) (xy 375.877033 -380.194671)
			(xy 375.858272 -380.202449) (xy 375.848118 -380.202948) (xy 375.131838 -380.202948) (xy 375.121667 -380.202505)
			(xy 375.102871 -380.19473) (xy 375.088484 -380.18035) (xy 375.0807 -380.161557) (xy 375.080276 -380.151386)
			(xy 375.080276 -379.993398) (xy 375.079872 -379.98421) (xy 375.073355 -379.967025) (xy 375.067576 -379.95987)
			(xy 375.045832 -379.934181) (xy 375.00788 -379.878601) (xy 374.976842 -379.818883) (xy 374.953165 -379.755883)
			(xy 374.937188 -379.690505) (xy 374.92914 -379.623686) (xy 374.929136 -379.556384) (xy 374.937176 -379.489563)
			(xy 374.953145 -379.424183) (xy 374.976814 -379.361181) (xy 375.007844 -379.301459) (xy 375.04579 -379.245874)
			(xy 375.067576 -379.220222) (xy 375.073385 -379.213086) (xy 375.079893 -379.195889) (xy 375.080276 -379.186694)
			(xy 375.080276 -378.693426) (xy 375.079859 -378.684239) (xy 375.073351 -378.667055) (xy 375.067576 -378.659898)
			(xy 375.045762 -378.634267) (xy 375.007811 -378.578679) (xy 374.976777 -378.518952) (xy 374.953104 -378.455945)
			(xy 374.937132 -378.39056) (xy 374.929089 -378.323734) (xy 345.250789 -378.323734) (xy 345.242747 -378.390553)
			(xy 345.226776 -378.455934) (xy 345.203105 -378.518938) (xy 345.172074 -378.57866) (xy 345.134127 -378.634246)
			(xy 345.11234 -378.659898) (xy 345.106554 -378.667051) (xy 345.100035 -378.684236) (xy 345.09964 -378.693426)
			(xy 345.09964 -379.186694) (xy 345.100066 -379.195879) (xy 345.10657 -379.213063) (xy 345.11234 -379.220222)
			(xy 345.134174 -379.245837) (xy 345.172123 -379.301428) (xy 345.203155 -379.361156) (xy 345.226826 -379.424166)
			(xy 345.242797 -379.489553) (xy 345.250837 -379.55638) (xy 345.250833 -379.623689) (xy 345.242784 -379.690515)
			(xy 345.226806 -379.7559) (xy 345.203127 -379.818907) (xy 345.172087 -379.878632) (xy 345.134131 -379.934218)
			(xy 345.11234 -379.95987) (xy 345.106524 -379.967001) (xy 345.100023 -379.984203) (xy 345.09964 -379.993398)
			(xy 345.09964 -380.151386) (xy 345.099224 -380.161559) (xy 345.09144 -380.180358) (xy 345.077051 -380.194744)
			(xy 345.058252 -380.202526) (xy 345.048078 -380.202948) (xy 344.331798 -380.202948) (xy 344.321625 -380.202537)
			(xy 344.302827 -380.194749) (xy 344.288442 -380.180359) (xy 344.280659 -380.16156) (xy 344.280236 -380.151386)
			(xy 344.280236 -379.993398) (xy 344.279819 -379.984212) (xy 344.273309 -379.967028) (xy 344.267536 -379.95987)
			(xy 344.245794 -379.93418) (xy 344.207844 -379.878599) (xy 344.176809 -379.818881) (xy 344.153133 -379.755881)
			(xy 344.137157 -379.690504) (xy 344.12911 -379.623685) (xy 344.129106 -379.556384) (xy 344.137145 -379.489565)
			(xy 344.153113 -379.424185) (xy 344.17678 -379.361182) (xy 344.207808 -379.30146) (xy 344.245751 -379.245874)
			(xy 344.267536 -379.220222) (xy 344.273353 -379.213091) (xy 344.279855 -379.19589) (xy 344.280236 -379.186694)
			(xy 344.280236 -378.693426) (xy 344.279805 -378.684241) (xy 344.273305 -378.667057) (xy 344.267536 -378.659898)
			(xy 344.245723 -378.634267) (xy 344.207775 -378.578677) (xy 344.176743 -378.518951) (xy 344.153072 -378.455944)
			(xy 344.137101 -378.390559) (xy 344.129059 -378.323734) (xy 340.850998 -378.323734) (xy 340.842956 -378.390553)
			(xy 340.826986 -378.455934) (xy 340.803315 -378.518937) (xy 340.772285 -378.57866) (xy 340.734338 -378.634246)
			(xy 340.712552 -378.659898) (xy 340.706768 -378.667052) (xy 340.700247 -378.684236) (xy 340.699852 -378.693426)
			(xy 340.699852 -379.186694) (xy 340.700276 -379.19588) (xy 340.706781 -379.213063) (xy 340.712552 -379.220222)
			(xy 340.734385 -379.245837) (xy 340.772333 -379.301428) (xy 340.803365 -379.361157) (xy 340.827036 -379.424166)
			(xy 340.843006 -379.489553) (xy 340.851046 -379.55638) (xy 340.851042 -379.623689) (xy 340.842993 -379.690515)
			(xy 340.827015 -379.7559) (xy 340.803337 -379.818906) (xy 340.772298 -379.878631) (xy 340.734343 -379.934218)
			(xy 340.712552 -379.95987) (xy 340.706737 -379.967002) (xy 340.700235 -379.984203) (xy 340.699852 -379.993398)
			(xy 340.699852 -380.151386) (xy 340.699425 -380.161558) (xy 340.691642 -380.180354) (xy 340.677258 -380.19474)
			(xy 340.658462 -380.202524) (xy 340.64829 -380.202948) (xy 339.93201 -380.202948) (xy 339.921837 -380.202528)
			(xy 339.90304 -380.194743) (xy 339.888654 -380.180357) (xy 339.880871 -380.161559) (xy 339.880448 -380.151386)
			(xy 339.880448 -379.993398) (xy 339.880028 -379.984212) (xy 339.87352 -379.967028) (xy 339.867748 -379.95987)
			(xy 339.846005 -379.934181) (xy 339.808055 -379.8786) (xy 339.777019 -379.818881) (xy 339.753343 -379.755882)
			(xy 339.737367 -379.690504) (xy 339.729319 -379.623685) (xy 339.729315 -379.556384) (xy 339.737354 -379.489564)
			(xy 339.753323 -379.424184) (xy 339.776991 -379.361182) (xy 339.808019 -379.30146) (xy 339.845963 -379.245874)
			(xy 339.867748 -379.220222) (xy 339.873566 -379.213092) (xy 339.880067 -379.19589) (xy 339.880448 -379.186694)
			(xy 339.880448 -378.693426) (xy 339.880015 -378.684241) (xy 339.873516 -378.667057) (xy 339.867748 -378.659898)
			(xy 339.845934 -378.634267) (xy 339.807986 -378.578678) (xy 339.776953 -378.518951) (xy 339.753281 -378.455944)
			(xy 339.73731 -378.390559) (xy 339.729268 -378.323734) (xy 336.45123 -378.323734) (xy 336.45123 -378.323792)
			(xy 336.443156 -378.390729) (xy 336.427122 -378.456217) (xy 336.403359 -378.519313) (xy 336.372208 -378.579108)
			(xy 336.33412 -378.634742) (xy 336.312256 -378.660406) (xy 336.306469 -378.667558) (xy 336.29995 -378.684743)
			(xy 336.299556 -378.693934) (xy 336.299556 -379.186186) (xy 336.299983 -379.195371) (xy 336.306486 -379.212555)
			(xy 336.312256 -379.219714) (xy 336.334167 -379.245341) (xy 336.372257 -379.30098) (xy 336.403408 -379.360781)
			(xy 336.427172 -379.423883) (xy 336.443205 -379.489377) (xy 336.451278 -379.55632) (xy 336.451274 -379.623749)
			(xy 336.443193 -379.690691) (xy 336.427151 -379.756183) (xy 336.40338 -379.819282) (xy 336.372221 -379.879079)
			(xy 336.334124 -379.934713) (xy 336.312256 -379.960378) (xy 336.306438 -379.967508) (xy 336.299937 -379.98471)
			(xy 336.299556 -379.993906) (xy 336.299556 -380.151386) (xy 336.299062 -380.161512) (xy 336.291338 -380.180234)
			(xy 336.277054 -380.194591) (xy 336.258372 -380.20241) (xy 336.248248 -380.202948) (xy 335.531968 -380.202948)
			(xy 335.521818 -380.202506) (xy 335.503074 -380.194708) (xy 335.488753 -380.180319) (xy 335.481046 -380.161538)
			(xy 335.48066 -380.151386) (xy 335.48066 -379.993906) (xy 335.480234 -379.984721) (xy 335.47373 -379.967537)
			(xy 335.46796 -379.960378) (xy 335.446143 -379.934675) (xy 335.408055 -379.879045) (xy 335.376905 -379.819253)
			(xy 335.35314 -379.756162) (xy 335.337102 -379.690678) (xy 335.329023 -379.623744) (xy 335.329019 -379.556325)
			(xy 335.33709 -379.48939) (xy 335.353119 -379.423904) (xy 335.376876 -379.36081) (xy 335.40802 -379.301015)
			(xy 335.4461 -379.24538) (xy 335.46796 -379.219714) (xy 335.473783 -379.212588) (xy 335.48028 -379.195382)
			(xy 335.48066 -379.186186) (xy 335.48066 -378.693934) (xy 335.48022 -378.68475) (xy 335.473726 -378.667566)
			(xy 335.46796 -378.660406) (xy 335.446072 -378.634761) (xy 335.407987 -378.579123) (xy 335.376839 -378.519323)
			(xy 335.353078 -378.456224) (xy 335.337046 -378.390733) (xy 335.328973 -378.323793) (xy 332.050903 -378.323793)
			(xy 332.042868 -378.390553) (xy 332.026898 -378.455933) (xy 332.003229 -378.518937) (xy 331.972199 -378.578659)
			(xy 331.934254 -378.634246) (xy 331.912468 -378.659898) (xy 331.906686 -378.667053) (xy 331.900163 -378.684236)
			(xy 331.899768 -378.693426) (xy 331.899768 -379.186694) (xy 331.900188 -379.19588) (xy 331.906696 -379.213064)
			(xy 331.912468 -379.220222) (xy 331.934301 -379.245837) (xy 331.972248 -379.301429) (xy 332.003279 -379.361158)
			(xy 332.026949 -379.424167) (xy 332.042918 -379.489554) (xy 332.050958 -379.55638) (xy 332.050954 -379.623689)
			(xy 332.042906 -379.690514) (xy 332.026928 -379.755899) (xy 332.00325 -379.818906) (xy 331.972212 -379.878631)
			(xy 331.934258 -379.934218) (xy 331.912468 -379.95987) (xy 331.906655 -379.967003) (xy 331.900151 -379.984203)
			(xy 331.899768 -379.993398) (xy 331.899768 -380.151386) (xy 331.899325 -380.161556) (xy 331.891546 -380.180349)
			(xy 331.877166 -380.194734) (xy 331.858376 -380.202521) (xy 331.848206 -380.202948) (xy 331.131926 -380.202948)
			(xy 331.121754 -380.202514) (xy 331.102958 -380.194735) (xy 331.088571 -380.180352) (xy 331.080788 -380.161558)
			(xy 331.080364 -380.151386) (xy 331.080364 -379.993398) (xy 331.07994 -379.984213) (xy 331.073434 -379.967029)
			(xy 331.067664 -379.95987) (xy 331.045921 -379.934181) (xy 331.007969 -379.8786) (xy 330.976932 -379.818882)
			(xy 330.953256 -379.755882) (xy 330.937279 -379.690504) (xy 330.929231 -379.623686) (xy 330.929227 -379.556384)
			(xy 330.937267 -379.489564) (xy 330.953235 -379.424184) (xy 330.976904 -379.361181) (xy 331.007933 -379.301459)
			(xy 331.045878 -379.245874) (xy 331.067664 -379.220222) (xy 331.073484 -379.213094) (xy 331.079983 -379.19589)
			(xy 331.080364 -379.186694) (xy 331.080364 -378.693426) (xy 331.079927 -378.684242) (xy 331.07343 -378.667058)
			(xy 331.067664 -378.659898) (xy 331.04585 -378.634267) (xy 331.0079 -378.578678) (xy 330.976866 -378.518952)
			(xy 330.953194 -378.455945) (xy 330.937222 -378.39056) (xy 330.92918 -378.323734) (xy 301.250878 -378.323734)
			(xy 301.250878 -378.323791) (xy 301.242805 -378.390727) (xy 301.226773 -378.456215) (xy 301.203013 -378.51931)
			(xy 301.171866 -378.579106) (xy 301.133782 -378.63474) (xy 301.11192 -378.660406) (xy 301.106141 -378.667564)
			(xy 301.099615 -378.684745) (xy 301.09922 -378.693934) (xy 301.09922 -379.186186) (xy 301.099632 -379.195373)
			(xy 301.106144 -379.212558) (xy 301.11192 -379.219714) (xy 301.133828 -379.245342) (xy 301.171914 -379.300983)
			(xy 301.203062 -379.360784) (xy 301.226823 -379.423886) (xy 301.242854 -379.489379) (xy 301.250926 -379.556321)
			(xy 301.250922 -379.623748) (xy 301.242842 -379.690689) (xy 301.226802 -379.75618) (xy 301.203034 -379.819279)
			(xy 301.171879 -379.879077) (xy 301.133786 -379.934712) (xy 301.11192 -379.960378) (xy 301.10611 -379.967514)
			(xy 301.099603 -379.984711) (xy 301.09922 -379.993906) (xy 301.09922 -380.151386) (xy 301.098761 -380.161517)
			(xy 301.09103 -380.180245) (xy 301.076735 -380.194603) (xy 301.058041 -380.202416) (xy 301.047912 -380.202948)
			(xy 300.331632 -380.202948) (xy 300.321486 -380.202453) (xy 300.302743 -380.194677) (xy 300.28842 -380.180304)
			(xy 300.280711 -380.161534) (xy 300.280324 -380.151386) (xy 300.280324 -379.993906) (xy 300.279906 -379.98472)
			(xy 300.273397 -379.967536) (xy 300.267624 -379.960378) (xy 300.245804 -379.934676) (xy 300.207713 -379.879047)
			(xy 300.176559 -379.819256) (xy 300.152791 -379.756164) (xy 300.136751 -379.690679) (xy 300.128672 -379.623745)
			(xy 300.128667 -379.556324) (xy 300.136739 -379.489389) (xy 300.15277 -379.423902) (xy 300.17653 -379.360807)
			(xy 300.207677 -379.301012) (xy 300.245762 -379.245379) (xy 300.267624 -379.219714) (xy 300.273442 -379.212584)
			(xy 300.279943 -379.195382) (xy 300.280324 -379.186186) (xy 300.280324 -378.693934) (xy 300.279892 -378.684749)
			(xy 300.273393 -378.667565) (xy 300.267624 -378.660406) (xy 300.245734 -378.634762) (xy 300.207644 -378.579125)
			(xy 300.176493 -378.519326) (xy 300.152729 -378.456227) (xy 300.136695 -378.390735) (xy 300.128621 -378.323794)
			(xy 296.851087 -378.323794) (xy 296.843014 -378.390727) (xy 296.826983 -378.456214) (xy 296.803223 -378.51931)
			(xy 296.772077 -378.579105) (xy 296.733993 -378.63474) (xy 296.712132 -378.660406) (xy 296.706342 -378.667556)
			(xy 296.699825 -378.684743) (xy 296.699432 -378.693934) (xy 296.699432 -379.186186) (xy 296.699864 -379.195371)
			(xy 296.706364 -379.212554) (xy 296.712132 -379.219714) (xy 296.73404 -379.245342) (xy 296.772125 -379.300983)
			(xy 296.803272 -379.360785) (xy 296.827032 -379.423886) (xy 296.843064 -379.489379) (xy 296.851135 -379.556321)
			(xy 296.851131 -379.623748) (xy 296.843051 -379.690689) (xy 296.827012 -379.75618) (xy 296.803244 -379.819279)
			(xy 296.77209 -379.879076) (xy 296.733998 -379.934712) (xy 296.712132 -379.960378) (xy 296.706312 -379.967506)
			(xy 296.699813 -379.98471) (xy 296.699432 -379.993906) (xy 296.699432 -380.151386) (xy 296.698961 -380.161515)
			(xy 296.691233 -380.180241) (xy 296.676941 -380.194599) (xy 296.658251 -380.202414) (xy 296.648124 -380.202948)
			(xy 295.931844 -380.202948) (xy 295.921699 -380.202443) (xy 295.902957 -380.194671) (xy 295.888633 -380.1803)
			(xy 295.880924 -380.161533) (xy 295.880536 -380.151386) (xy 295.880536 -379.993906) (xy 295.880115 -379.98472)
			(xy 295.873608 -379.967536) (xy 295.867836 -379.960378) (xy 295.846016 -379.934676) (xy 295.807924 -379.879048)
			(xy 295.776769 -379.819257) (xy 295.753 -379.756165) (xy 295.736961 -379.69068) (xy 295.728881 -379.623745)
			(xy 295.728876 -379.556324) (xy 295.736948 -379.489388) (xy 295.75298 -379.423901) (xy 295.776741 -379.360806)
			(xy 295.807888 -379.301012) (xy 295.845974 -379.245379) (xy 295.867836 -379.219714) (xy 295.873656 -379.212586)
			(xy 295.880156 -379.195382) (xy 295.880536 -379.186186) (xy 295.880536 -378.693934) (xy 295.880101 -378.68475)
			(xy 295.873604 -378.667565) (xy 295.867836 -378.660406) (xy 295.845945 -378.634762) (xy 295.807855 -378.579126)
			(xy 295.776703 -378.519327) (xy 295.752939 -378.456227) (xy 295.736904 -378.390735) (xy 295.72883 -378.323794)
			(xy 292.450785 -378.323794) (xy 292.44275 -378.390553) (xy 292.426779 -378.455934) (xy 292.403109 -378.518938)
			(xy 292.372077 -378.57866) (xy 292.334131 -378.634246) (xy 292.312344 -378.659898) (xy 292.306559 -378.667051)
			(xy 292.300039 -378.684236) (xy 292.299644 -378.693426) (xy 292.299644 -379.186694) (xy 292.30007 -379.195879)
			(xy 292.306574 -379.213063) (xy 292.312344 -379.220222) (xy 292.334178 -379.245837) (xy 292.372126 -379.301428)
			(xy 292.403158 -379.361157) (xy 292.426829 -379.424166) (xy 292.4428 -379.489553) (xy 292.45084 -379.55638)
			(xy 292.450836 -379.623689) (xy 292.442787 -379.690515) (xy 292.426809 -379.7559) (xy 292.40313 -379.818907)
			(xy 292.372091 -379.878631) (xy 292.334135 -379.934218) (xy 292.312344 -379.95987) (xy 292.306528 -379.967001)
			(xy 292.300027 -379.984203) (xy 292.299644 -379.993398) (xy 292.299644 -380.151386) (xy 292.299224 -380.161559)
			(xy 292.291441 -380.180357) (xy 292.277054 -380.194743) (xy 292.258255 -380.202525) (xy 292.248082 -380.202948)
			(xy 291.531802 -380.202948) (xy 291.521629 -380.202534) (xy 291.502831 -380.194747) (xy 291.488446 -380.180358)
			(xy 291.480663 -380.161559) (xy 291.48024 -380.151386) (xy 291.48024 -379.993398) (xy 291.479822 -379.984212)
			(xy 291.473313 -379.967028) (xy 291.46754 -379.95987) (xy 291.445798 -379.934181) (xy 291.407847 -379.878599)
			(xy 291.376812 -379.818881) (xy 291.353137 -379.755881) (xy 291.337161 -379.690504) (xy 291.329113 -379.623685)
			(xy 291.329109 -379.556384) (xy 291.337148 -379.489564) (xy 291.353116 -379.424185) (xy 291.376784 -379.361182)
			(xy 291.407812 -379.30146) (xy 291.445755 -379.245874) (xy 291.46754 -379.220222) (xy 291.473357 -379.213092)
			(xy 291.479859 -379.19589) (xy 291.48024 -379.186694) (xy 291.48024 -378.693426) (xy 291.479809 -378.684241)
			(xy 291.473309 -378.667057) (xy 291.46754 -378.659898) (xy 291.445727 -378.634267) (xy 291.407778 -378.578678)
			(xy 291.376746 -378.518951) (xy 291.353075 -378.455944) (xy 291.337104 -378.390559) (xy 291.329062 -378.323734)
			(xy 288.051024 -378.323734) (xy 288.051024 -378.323792) (xy 288.04295 -378.390729) (xy 288.026915 -378.456218)
			(xy 288.003152 -378.519314) (xy 287.972001 -378.579109) (xy 287.933912 -378.634742) (xy 287.912048 -378.660406)
			(xy 287.90626 -378.667557) (xy 287.899742 -378.684743) (xy 287.899348 -378.693934) (xy 287.899348 -379.186186)
			(xy 287.899776 -379.195371) (xy 287.906279 -379.212555) (xy 287.912048 -379.219714) (xy 287.933959 -379.245341)
			(xy 287.97205 -379.30098) (xy 288.003201 -379.360781) (xy 288.026965 -379.423883) (xy 288.042999 -379.489377)
			(xy 288.051072 -379.55632) (xy 288.051068 -379.623749) (xy 288.042987 -379.690691) (xy 288.026945 -379.756183)
			(xy 288.003173 -379.819282) (xy 287.972014 -379.879079) (xy 287.933917 -379.934714) (xy 287.912048 -379.960378)
			(xy 287.906229 -379.967507) (xy 287.899729 -379.98471) (xy 287.899348 -379.993906) (xy 287.899348 -380.151386)
			(xy 287.898862 -380.161513) (xy 287.891136 -380.180236) (xy 287.87685 -380.194594) (xy 287.858165 -380.202411)
			(xy 287.84804 -380.202948) (xy 287.13176 -380.202948) (xy 287.121609 -380.202512) (xy 287.102865 -380.194712)
			(xy 287.088545 -380.180321) (xy 287.080838 -380.161539) (xy 287.080452 -380.151386) (xy 287.080452 -379.993906)
			(xy 287.080027 -379.984721) (xy 287.073523 -379.967537) (xy 287.067752 -379.960378) (xy 287.045931 -379.934676)
			(xy 287.007838 -379.879048) (xy 286.976682 -379.819258) (xy 286.952913 -379.756165) (xy 286.936873 -379.69068)
			(xy 286.928793 -379.623745) (xy 286.928788 -379.556324) (xy 286.936861 -379.489388) (xy 286.952893 -379.423901)
			(xy 286.976654 -379.360806) (xy 287.007802 -379.301011) (xy 287.045889 -379.245378) (xy 287.067752 -379.219714)
			(xy 287.073574 -379.212587) (xy 287.080072 -379.195382) (xy 287.080452 -379.186186) (xy 287.080452 -378.693934)
			(xy 287.080014 -378.68475) (xy 287.073519 -378.667566) (xy 287.067752 -378.660406) (xy 287.045861 -378.634763)
			(xy 287.007769 -378.579126) (xy 286.976617 -378.519328) (xy 286.952852 -378.456228) (xy 286.936817 -378.390735)
			(xy 286.928742 -378.323794) (xy 277.14076 -378.323794) (xy 277.146139 -378.392568) (xy 277.15414 -378.597491)
			(xy 277.15464 -378.70003) (xy 277.15414 -378.802569) (xy 277.146139 -379.007492) (xy 277.130148 -379.211946)
			(xy 277.106193 -379.41562) (xy 277.074309 -379.618205) (xy 277.034546 -379.819391) (xy 276.986963 -380.018873)
			(xy 276.931633 -380.216347) (xy 276.868641 -380.411512) (xy 276.798083 -380.60407) (xy 276.776531 -380.656463)
			(xy 289.128932 -380.656463) (xy 289.136975 -380.589641) (xy 289.152947 -380.524259) (xy 289.17662 -380.461255)
			(xy 289.207654 -380.401532) (xy 289.245604 -380.345947) (xy 289.267392 -380.320296) (xy 289.273172 -380.313139)
			(xy 289.279697 -380.295958) (xy 289.280092 -380.286768) (xy 289.280092 -379.7935) (xy 289.279684 -379.784313)
			(xy 289.273169 -379.767128) (xy 289.267392 -379.759972) (xy 289.24565 -379.734282) (xy 289.207696 -379.678702)
			(xy 289.176658 -379.618984) (xy 289.15298 -379.555985) (xy 289.137002 -379.490606) (xy 289.128953 -379.423787)
			(xy 289.128949 -379.356485) (xy 289.136989 -379.289665) (xy 289.152959 -379.224284) (xy 289.176628 -379.161282)
			(xy 289.207659 -379.10156) (xy 289.245606 -379.045975) (xy 289.267392 -379.020324) (xy 289.273202 -379.013189)
			(xy 289.279709 -378.995991) (xy 289.280092 -378.986796) (xy 289.280092 -378.828554) (xy 289.280595 -378.818399)
			(xy 289.288376 -378.799638) (xy 289.302738 -378.785276) (xy 289.321499 -378.777495) (xy 289.331654 -378.776992)
			(xy 290.047934 -378.776992) (xy 290.058088 -378.777504) (xy 290.076849 -378.785281) (xy 290.091212 -378.799641)
			(xy 290.098993 -378.8184) (xy 290.099496 -378.828554) (xy 290.099496 -378.986796) (xy 290.099909 -378.995983)
			(xy 290.106421 -379.013167) (xy 290.112196 -379.020324) (xy 290.13403 -379.045938) (xy 290.171975 -379.101531)
			(xy 290.203004 -379.16126) (xy 290.226673 -379.224269) (xy 290.242641 -379.289656) (xy 290.250681 -379.356482)
			(xy 290.250677 -379.42379) (xy 290.242628 -379.490615) (xy 290.226651 -379.556) (xy 290.202975 -379.619006)
			(xy 290.171938 -379.678731) (xy 290.133986 -379.734319) (xy 290.112196 -379.759972) (xy 290.106386 -379.767108)
			(xy 290.099879 -379.784305) (xy 290.099496 -379.7935) (xy 290.099496 -380.286768) (xy 290.099922 -380.295953)
			(xy 290.106425 -380.313138) (xy 290.112196 -380.320296) (xy 290.134002 -380.345932) (xy 290.171948 -380.401522)
			(xy 290.202979 -380.461248) (xy 290.226649 -380.524255) (xy 290.242619 -380.589638) (xy 290.250654 -380.656404)
			(xy 293.528724 -380.656404) (xy 293.536798 -380.589467) (xy 293.552831 -380.52398) (xy 293.576592 -380.460884)
			(xy 293.60774 -380.401088) (xy 293.645826 -380.345453) (xy 293.667688 -380.319788) (xy 293.673471 -380.312633)
			(xy 293.679994 -380.29545) (xy 293.680388 -380.28626) (xy 293.680388 -379.794008) (xy 293.679977 -379.784821)
			(xy 293.673464 -379.767636) (xy 293.667688 -379.76048) (xy 293.645872 -379.734776) (xy 293.607782 -379.679146)
			(xy 293.57663 -379.619356) (xy 293.552864 -379.556264) (xy 293.536825 -379.49078) (xy 293.528746 -379.423846)
			(xy 293.528741 -379.356426) (xy 293.536812 -379.289491) (xy 293.552842 -379.224005) (xy 293.576601 -379.16091)
			(xy 293.607745 -379.101115) (xy 293.645827 -379.045481) (xy 293.667688 -379.019816) (xy 293.673501 -379.012683)
			(xy 293.680006 -378.995483) (xy 293.680388 -378.986288) (xy 293.680388 -378.828554) (xy 293.680887 -378.818431)
			(xy 293.688621 -378.799718) (xy 293.702902 -378.785366) (xy 293.721575 -378.777539) (xy 293.731696 -378.776992)
			(xy 294.447976 -378.776992) (xy 294.458128 -378.777441) (xy 294.476878 -378.785227) (xy 294.491202 -378.799615)
			(xy 294.498904 -378.818401) (xy 294.499284 -378.828554) (xy 294.499284 -378.986288) (xy 294.499704 -378.995474)
			(xy 294.506211 -379.012658) (xy 294.511984 -379.019816) (xy 294.533896 -379.045442) (xy 294.571984 -379.101082)
			(xy 294.603134 -379.160883) (xy 294.626896 -379.223985) (xy 294.642928 -379.289479) (xy 294.651001 -379.356422)
			(xy 294.650996 -379.42385) (xy 294.642915 -379.490792) (xy 294.626874 -379.556284) (xy 294.603104 -379.619383)
			(xy 294.571947 -379.67918) (xy 294.533851 -379.734815) (xy 294.511984 -379.76048) (xy 294.506169 -379.767612)
			(xy 294.499666 -379.784813) (xy 294.499284 -379.794008) (xy 294.499284 -380.28626) (xy 294.499717 -380.295445)
			(xy 294.506215 -380.312629) (xy 294.511984 -380.319788) (xy 294.533868 -380.345437) (xy 294.571957 -380.401073)
			(xy 294.603108 -380.460872) (xy 294.626872 -380.523971) (xy 294.642906 -380.589462) (xy 294.650981 -380.656402)
			(xy 294.650981 -380.656463) (xy 297.92902 -380.656463) (xy 297.937062 -380.589641) (xy 297.953034 -380.52426)
			(xy 297.976707 -380.461256) (xy 298.00774 -380.401533) (xy 298.045688 -380.345948) (xy 298.067476 -380.320296)
			(xy 298.073254 -380.313137) (xy 298.079781 -380.295957) (xy 298.080176 -380.286768) (xy 298.080176 -379.7935)
			(xy 298.079771 -379.784312) (xy 298.073254 -379.767128) (xy 298.067476 -379.759972) (xy 298.045734 -379.734282)
			(xy 298.007782 -379.678701) (xy 297.976744 -379.618984) (xy 297.953067 -379.555984) (xy 297.93709 -379.490606)
			(xy 297.929041 -379.423787) (xy 297.929037 -379.356485) (xy 297.937077 -379.289665) (xy 297.953046 -379.224285)
			(xy 297.976715 -379.161283) (xy 298.007745 -379.101561) (xy 298.04569 -379.045976) (xy 298.067476 -379.020324)
			(xy 298.073285 -379.013187) (xy 298.079793 -378.99599) (xy 298.080176 -378.986796) (xy 298.080176 -378.828554)
			(xy 298.080597 -378.818389) (xy 298.088393 -378.799611) (xy 298.102782 -378.785246) (xy 298.121572 -378.77748)
			(xy 298.131738 -378.776992) (xy 298.848018 -378.776992) (xy 298.858171 -378.777517) (xy 298.876932 -378.785289)
			(xy 298.891295 -378.799644) (xy 298.899077 -378.818401) (xy 298.89958 -378.828554) (xy 298.89958 -378.986796)
			(xy 298.899996 -378.995982) (xy 298.906506 -379.013167) (xy 298.91228 -379.020324) (xy 298.934114 -379.045938)
			(xy 298.972061 -379.10153) (xy 299.003091 -379.161259) (xy 299.02676 -379.224269) (xy 299.042729 -379.289655)
			(xy 299.050769 -379.356482) (xy 299.050765 -379.42379) (xy 299.042716 -379.490616) (xy 299.026739 -379.556)
			(xy 299.003061 -379.619007) (xy 298.972023 -379.678732) (xy 298.93407 -379.73432) (xy 298.91228 -379.759972)
			(xy 298.906468 -379.767106) (xy 298.899963 -379.784305) (xy 298.89958 -379.7935) (xy 298.89958 -380.286768)
			(xy 298.90001 -380.295953) (xy 298.90651 -380.313137) (xy 298.91228 -380.320296) (xy 298.934087 -380.345932)
			(xy 298.972034 -380.401521) (xy 299.003065 -380.461247) (xy 299.026736 -380.524254) (xy 299.042707 -380.589638)
			(xy 299.050742 -380.656404) (xy 302.328812 -380.656404) (xy 302.336886 -380.589468) (xy 302.352918 -380.52398)
			(xy 302.376679 -380.460884) (xy 302.407826 -380.401089) (xy 302.44591 -380.345454) (xy 302.467772 -380.319788)
			(xy 302.473565 -380.312641) (xy 302.48008 -380.295451) (xy 302.480472 -380.28626) (xy 302.480472 -379.794008)
			(xy 302.480064 -379.78482) (xy 302.47355 -379.767636) (xy 302.467772 -379.76048) (xy 302.445956 -379.734775)
			(xy 302.407868 -379.679146) (xy 302.376717 -379.619355) (xy 302.352951 -379.556263) (xy 302.336913 -379.490779)
			(xy 302.328834 -379.423846) (xy 302.328829 -379.356426) (xy 302.3369 -379.289492) (xy 302.35293 -379.224006)
			(xy 302.376687 -379.160911) (xy 302.407831 -379.101116) (xy 302.445912 -379.045482) (xy 302.467772 -379.019816)
			(xy 302.473595 -379.01269) (xy 302.480092 -378.995485) (xy 302.480472 -378.986288) (xy 302.480472 -378.828554)
			(xy 302.48089 -378.81842) (xy 302.488639 -378.799692) (xy 302.502946 -378.785336) (xy 302.521648 -378.777525)
			(xy 302.53178 -378.776992) (xy 303.24806 -378.776992) (xy 303.258211 -378.777454) (xy 303.27696 -378.785235)
			(xy 303.291285 -378.79962) (xy 303.298987 -378.818402) (xy 303.299368 -378.828554) (xy 303.299368 -378.986288)
			(xy 303.299791 -378.995474) (xy 303.306296 -379.012658) (xy 303.312068 -379.019816) (xy 303.33398 -379.045442)
			(xy 303.37207 -379.101081) (xy 303.40322 -379.160883) (xy 303.426983 -379.223985) (xy 303.443016 -379.289479)
			(xy 303.451089 -379.356422) (xy 303.451084 -379.42385) (xy 303.443003 -379.490792) (xy 303.426962 -379.556284)
			(xy 303.403191 -379.619383) (xy 303.372032 -379.679181) (xy 303.333936 -379.734815) (xy 303.312068 -379.76048)
			(xy 303.306251 -379.76761) (xy 303.299749 -379.784812) (xy 303.299368 -379.794008) (xy 303.299368 -380.28626)
			(xy 303.299805 -380.295444) (xy 303.306301 -380.312628) (xy 303.312068 -380.319788) (xy 303.333953 -380.345436)
			(xy 303.372043 -380.401073) (xy 303.403195 -380.460871) (xy 303.426959 -380.52397) (xy 303.442994 -380.589461)
			(xy 303.451069 -380.656402) (xy 303.451069 -380.656404) (xy 333.128842 -380.656404) (xy 333.136916 -380.589467)
			(xy 333.15295 -380.523979) (xy 333.176713 -380.460883) (xy 333.207862 -380.401087) (xy 333.245949 -380.345453)
			(xy 333.267812 -380.319788) (xy 333.273598 -380.312635) (xy 333.280118 -380.29545) (xy 333.280512 -380.28626)
			(xy 333.280512 -379.794008) (xy 333.280095 -379.784822) (xy 333.273586 -379.767637) (xy 333.267812 -379.76048)
			(xy 333.245995 -379.734776) (xy 333.207904 -379.679147) (xy 333.17675 -379.619357) (xy 333.152983 -379.556265)
			(xy 333.136944 -379.49078) (xy 333.128864 -379.423846) (xy 333.12886 -379.356426) (xy 333.136931 -379.289491)
			(xy 333.152962 -379.224004) (xy 333.176721 -379.160909) (xy 333.207867 -379.101115) (xy 333.24595 -379.045481)
			(xy 333.267812 -379.019816) (xy 333.273628 -379.012685) (xy 333.280131 -378.995483) (xy 333.280512 -378.986288)
			(xy 333.280512 -378.828554) (xy 333.280988 -378.818428) (xy 333.288726 -378.799711) (xy 333.303015 -378.785357)
			(xy 333.321696 -378.777535) (xy 333.33182 -378.776992) (xy 334.0481 -378.776992) (xy 334.058253 -378.777422)
			(xy 334.077004 -378.785216) (xy 334.091327 -378.79961) (xy 334.099028 -378.818399) (xy 334.099408 -378.828554)
			(xy 334.099408 -378.986288) (xy 334.099822 -378.995475) (xy 334.106333 -379.012659) (xy 334.112108 -379.019816)
			(xy 334.134019 -379.045442) (xy 334.172106 -379.101083) (xy 334.203254 -379.160884) (xy 334.227015 -379.223986)
			(xy 334.243047 -379.28948) (xy 334.251119 -379.356422) (xy 334.251114 -379.42385) (xy 334.243034 -379.490791)
			(xy 334.226994 -379.556283) (xy 334.203224 -379.619382) (xy 334.172068 -379.679179) (xy 334.133975 -379.734815)
			(xy 334.112108 -379.76048) (xy 334.106296 -379.767614) (xy 334.09979 -379.784813) (xy 334.099408 -379.794008)
			(xy 334.099408 -380.28626) (xy 334.099836 -380.295445) (xy 334.106337 -380.31263) (xy 334.112108 -380.319788)
			(xy 334.133991 -380.345437) (xy 334.172079 -380.401074) (xy 334.203228 -380.460873) (xy 334.226991 -380.523972)
			(xy 334.243025 -380.589463) (xy 334.251099 -380.656402) (xy 334.251099 -380.656464) (xy 337.529162 -380.656464)
			(xy 337.537203 -380.589643) (xy 337.553173 -380.524262) (xy 337.576842 -380.461259) (xy 337.607871 -380.401536)
			(xy 337.645815 -380.345949) (xy 337.6676 -380.320296) (xy 337.673381 -380.31314) (xy 337.679905 -380.295958)
			(xy 337.6803 -380.286768) (xy 337.6803 -379.7935) (xy 337.67989 -379.784313) (xy 337.673376 -379.767129)
			(xy 337.6676 -379.759972) (xy 337.645861 -379.734281) (xy 337.607913 -379.678699) (xy 337.57688 -379.61898)
			(xy 337.553206 -379.555981) (xy 337.537231 -379.490604) (xy 337.529183 -379.423786) (xy 337.529179 -379.356486)
			(xy 337.537218 -379.289667) (xy 337.553185 -379.224288) (xy 337.57685 -379.161286) (xy 337.607876 -379.101563)
			(xy 337.645816 -379.045977) (xy 337.6676 -379.020324) (xy 337.673411 -379.013189) (xy 337.679917 -378.995991)
			(xy 337.6803 -378.986796) (xy 337.6803 -378.828554) (xy 337.680795 -378.818398) (xy 337.688577 -378.799635)
			(xy 337.702942 -378.785273) (xy 337.721706 -378.777493) (xy 337.731862 -378.776992) (xy 338.448142 -378.776992)
			(xy 338.458297 -378.777498) (xy 338.477058 -378.785278) (xy 338.49142 -378.799639) (xy 338.499201 -378.818399)
			(xy 338.499704 -378.828554) (xy 338.499704 -378.986796) (xy 338.500115 -378.995983) (xy 338.506628 -379.013167)
			(xy 338.512404 -379.020324) (xy 338.534237 -379.045938) (xy 338.572182 -379.101531) (xy 338.603211 -379.16126)
			(xy 338.626879 -379.22427) (xy 338.642847 -379.289656) (xy 338.650887 -379.356482) (xy 338.650883 -379.42379)
			(xy 338.642834 -379.490615) (xy 338.626858 -379.556) (xy 338.603181 -379.619006) (xy 338.572145 -379.678731)
			(xy 338.534193 -379.734319) (xy 338.512404 -379.759972) (xy 338.506595 -379.767108) (xy 338.500088 -379.784306)
			(xy 338.499704 -379.7935) (xy 338.499704 -380.286768) (xy 338.500129 -380.295954) (xy 338.506632 -380.313138)
			(xy 338.512404 -380.320296) (xy 338.53421 -380.345933) (xy 338.572155 -380.401522) (xy 338.603185 -380.461248)
			(xy 338.626855 -380.524255) (xy 338.642826 -380.589639) (xy 338.65086 -380.656404) (xy 341.92893 -380.656404)
			(xy 341.937004 -380.589467) (xy 341.953037 -380.523979) (xy 341.976799 -380.460883) (xy 342.007947 -380.401088)
			(xy 342.046033 -380.345453) (xy 342.067896 -380.319788) (xy 342.07368 -380.312634) (xy 342.080202 -380.29545)
			(xy 342.080596 -380.28626) (xy 342.080596 -379.794008) (xy 342.080183 -379.784821) (xy 342.073671 -379.767637)
			(xy 342.067896 -379.76048) (xy 342.046079 -379.734776) (xy 342.007989 -379.679147) (xy 341.976837 -379.619356)
			(xy 341.95307 -379.556264) (xy 341.937032 -379.49078) (xy 341.928952 -379.423846) (xy 341.928948 -379.356426)
			(xy 341.937019 -379.289491) (xy 341.953049 -379.224005) (xy 341.976807 -379.16091) (xy 342.007952 -379.101115)
			(xy 342.046035 -379.045481) (xy 342.067896 -379.019816) (xy 342.07371 -379.012683) (xy 342.080215 -378.995483)
			(xy 342.080596 -378.986288) (xy 342.080596 -378.828554) (xy 342.081088 -378.81843) (xy 342.088822 -378.799716)
			(xy 342.103106 -378.785363) (xy 342.121782 -378.777538) (xy 342.131904 -378.776992) (xy 342.848184 -378.776992)
			(xy 342.858336 -378.777434) (xy 342.877087 -378.785223) (xy 342.89141 -378.799614) (xy 342.899112 -378.8184)
			(xy 342.899492 -378.828554) (xy 342.899492 -378.986288) (xy 342.89991 -378.995474) (xy 342.906418 -379.012659)
			(xy 342.912192 -379.019816) (xy 342.934103 -379.045442) (xy 342.972191 -379.101082) (xy 343.00334 -379.160884)
			(xy 343.027102 -379.223986) (xy 343.043135 -379.28948) (xy 343.051207 -379.356422) (xy 343.051202 -379.42385)
			(xy 343.043122 -379.490792) (xy 343.027081 -379.556283) (xy 343.003311 -379.619382) (xy 342.972154 -379.67918)
			(xy 342.934059 -379.734815) (xy 342.912192 -379.76048) (xy 342.906378 -379.767613) (xy 342.899874 -379.784813)
			(xy 342.899492 -379.794008) (xy 342.899492 -380.28626) (xy 342.899923 -380.295445) (xy 342.906422 -380.312629)
			(xy 342.912192 -380.319788) (xy 342.934076 -380.345437) (xy 342.972165 -380.401074) (xy 343.003315 -380.460872)
			(xy 343.027078 -380.523971) (xy 343.043113 -380.589462) (xy 343.051187 -380.656402) (xy 343.051187 -380.656463)
			(xy 346.329226 -380.656463) (xy 346.337269 -380.589641) (xy 346.353241 -380.524259) (xy 346.376913 -380.461255)
			(xy 346.407947 -380.401533) (xy 346.445896 -380.345948) (xy 346.467684 -380.320296) (xy 346.473463 -380.313138)
			(xy 346.479989 -380.295957) (xy 346.480384 -380.286768) (xy 346.480384 -379.7935) (xy 346.479977 -379.784312)
			(xy 346.473462 -379.767128) (xy 346.467684 -379.759972) (xy 346.445942 -379.734282) (xy 346.407989 -379.678702)
			(xy 346.376951 -379.618984) (xy 346.353274 -379.555984) (xy 346.337296 -379.490606) (xy 346.329247 -379.423787)
			(xy 346.329243 -379.356485) (xy 346.337283 -379.289665) (xy 346.353252 -379.224285) (xy 346.376922 -379.161282)
			(xy 346.407952 -379.10156) (xy 346.445898 -379.045976) (xy 346.467684 -379.020324) (xy 346.473493 -379.013188)
			(xy 346.480001 -378.99599) (xy 346.480384 -378.986796) (xy 346.480384 -378.828554) (xy 346.480797 -378.818388)
			(xy 346.488595 -378.799609) (xy 346.502986 -378.785243) (xy 346.521779 -378.777479) (xy 346.531946 -378.776992)
			(xy 347.248226 -378.776992) (xy 347.25838 -378.777511) (xy 347.277141 -378.785285) (xy 347.291504 -378.799642)
			(xy 347.299285 -378.8184) (xy 347.299788 -378.828554) (xy 347.299788 -378.986796) (xy 347.300203 -378.995983)
			(xy 347.306714 -379.013167) (xy 347.312488 -379.020324) (xy 347.334322 -379.045938) (xy 347.372268 -379.10153)
			(xy 347.403297 -379.161259) (xy 347.426966 -379.224269) (xy 347.442935 -379.289656) (xy 347.450975 -379.356482)
			(xy 347.450971 -379.42379) (xy 347.442922 -379.490616) (xy 347.426945 -379.556) (xy 347.403268 -379.619007)
			(xy 347.372231 -379.678732) (xy 347.334278 -379.734319) (xy 347.312488 -379.759972) (xy 347.306677 -379.767107)
			(xy 347.300171 -379.784305) (xy 347.299788 -379.7935) (xy 347.299788 -380.286768) (xy 347.300216 -380.295953)
			(xy 347.306718 -380.313138) (xy 347.312488 -380.320296) (xy 347.334295 -380.345932) (xy 347.372241 -380.401522)
			(xy 347.403272 -380.461248) (xy 347.426942 -380.524254) (xy 347.442913 -380.589638) (xy 347.450948 -380.656404)
			(xy 377.128751 -380.656404) (xy 377.136826 -380.589466) (xy 377.15286 -380.523978) (xy 377.176623 -380.460882)
			(xy 377.207772 -380.401087) (xy 377.24586 -380.345453) (xy 377.267724 -380.319788) (xy 377.273511 -380.312636)
			(xy 377.280031 -380.295451) (xy 377.280424 -380.28626) (xy 377.280424 -379.794008) (xy 377.280005 -379.784822)
			(xy 377.273497 -379.767638) (xy 377.267724 -379.76048) (xy 377.245906 -379.734776) (xy 377.207815 -379.679148)
			(xy 377.17666 -379.619357) (xy 377.152893 -379.556265) (xy 377.136853 -379.490781) (xy 377.128773 -379.423846)
			(xy 377.128769 -379.356426) (xy 377.13684 -379.28949) (xy 377.152871 -379.224004) (xy 377.176631 -379.160909)
			(xy 377.207777 -379.101114) (xy 377.245862 -379.045481) (xy 377.267724 -379.019816) (xy 377.273542 -379.012686)
			(xy 377.280043 -378.995484) (xy 377.280424 -378.986288) (xy 377.280424 -378.828554) (xy 377.280888 -378.818426)
			(xy 377.288628 -378.799707) (xy 377.302921 -378.785353) (xy 377.321607 -378.777533) (xy 377.331732 -378.776992)
			(xy 378.048012 -378.776992) (xy 378.058166 -378.777411) (xy 378.076917 -378.785209) (xy 378.09124 -378.799607)
			(xy 378.098941 -378.818398) (xy 378.09932 -378.828554) (xy 378.09932 -378.986288) (xy 378.099731 -378.995475)
			(xy 378.106244 -379.01266) (xy 378.11202 -379.019816) (xy 378.13393 -379.045443) (xy 378.172016 -379.101083)
			(xy 378.203164 -379.160885) (xy 378.226924 -379.223987) (xy 378.242956 -379.28948) (xy 378.251028 -379.356423)
			(xy 378.251023 -379.42385) (xy 378.242943 -379.490791) (xy 378.226903 -379.556282) (xy 378.203134 -379.619381)
			(xy 378.171979 -379.679179) (xy 378.133886 -379.734814) (xy 378.11202 -379.76048) (xy 378.106209 -379.767615)
			(xy 378.099702 -379.784813) (xy 378.09932 -379.794008) (xy 378.09932 -380.28626) (xy 378.099745 -380.295446)
			(xy 378.106248 -380.312631) (xy 378.11202 -380.319788) (xy 378.133903 -380.345437) (xy 378.17199 -380.401075)
			(xy 378.203138 -380.460873) (xy 378.226901 -380.523972) (xy 378.242934 -380.589463) (xy 378.251008 -380.656403)
			(xy 378.251008 -380.656464) (xy 381.529071 -380.656464) (xy 381.537113 -380.589643) (xy 381.553083 -380.524262)
			(xy 381.576752 -380.461258) (xy 381.607782 -380.401535) (xy 381.645726 -380.345948) (xy 381.667512 -380.320296)
			(xy 381.673294 -380.313141) (xy 381.679817 -380.295958) (xy 381.680212 -380.286768) (xy 381.680212 -379.7935)
			(xy 381.679799 -379.784313) (xy 381.673287 -379.767129) (xy 381.667512 -379.759972) (xy 381.645773 -379.73428)
			(xy 381.607824 -379.678699) (xy 381.57679 -379.618981) (xy 381.553116 -379.555981) (xy 381.537141 -379.490604)
			(xy 381.529093 -379.423786) (xy 381.529089 -379.356486) (xy 381.537128 -379.289667) (xy 381.553095 -379.224288)
			(xy 381.576761 -379.161285) (xy 381.607787 -379.101563) (xy 381.645728 -379.045977) (xy 381.667512 -379.020324)
			(xy 381.673325 -379.01319) (xy 381.679829 -378.995991) (xy 381.680212 -378.986796) (xy 381.680212 -378.828554)
			(xy 381.680695 -378.818397) (xy 381.68848 -378.799631) (xy 381.702848 -378.785269) (xy 381.721616 -378.777491)
			(xy 381.731774 -378.776992) (xy 382.448054 -378.776992) (xy 382.458203 -378.77757) (xy 382.476962 -378.785321)
			(xy 382.491328 -378.79966) (xy 382.499112 -378.818406) (xy 382.499616 -378.828554) (xy 382.499616 -378.986796)
			(xy 382.500025 -378.995983) (xy 382.506539 -379.013168) (xy 382.512316 -379.020324) (xy 382.534153 -379.045936)
			(xy 382.572103 -379.101528) (xy 382.603137 -379.161256) (xy 382.626809 -379.224266) (xy 382.64278 -379.289654)
			(xy 382.650821 -379.356481) (xy 382.650816 -379.423791) (xy 382.642767 -379.490618) (xy 382.626787 -379.556003)
			(xy 382.603107 -379.61901) (xy 382.572066 -379.678734) (xy 382.534108 -379.734321) (xy 382.512316 -379.759972)
			(xy 382.506508 -379.767109) (xy 382.5 -379.784306) (xy 382.499616 -379.7935) (xy 382.499616 -380.286768)
			(xy 382.500038 -380.295954) (xy 382.506543 -380.313139) (xy 382.512316 -380.320296) (xy 382.534125 -380.345931)
			(xy 382.572076 -380.401519) (xy 382.603111 -380.461245) (xy 382.626784 -380.524251) (xy 382.642757 -380.589636)
			(xy 382.650793 -380.656404) (xy 385.928839 -380.656404) (xy 385.936913 -380.589467) (xy 385.952947 -380.523979)
			(xy 385.976709 -380.460883) (xy 386.007858 -380.401087) (xy 386.045945 -380.345453) (xy 386.067808 -380.319788)
			(xy 386.073593 -380.312635) (xy 386.080114 -380.29545) (xy 386.080508 -380.28626) (xy 386.080508 -379.794008)
			(xy 386.080092 -379.784821) (xy 386.073582 -379.767637) (xy 386.067808 -379.76048) (xy 386.045991 -379.734776)
			(xy 386.0079 -379.679147) (xy 385.976747 -379.619356) (xy 385.95298 -379.556265) (xy 385.936941 -379.49078)
			(xy 385.928861 -379.423846) (xy 385.928857 -379.356426) (xy 385.936928 -379.289491) (xy 385.952958 -379.224004)
			(xy 385.976718 -379.160909) (xy 386.007863 -379.101115) (xy 386.045947 -379.045481) (xy 386.067808 -379.019816)
			(xy 386.073624 -379.012684) (xy 386.080127 -378.995483) (xy 386.080508 -378.986288) (xy 386.080508 -378.828554)
			(xy 386.080988 -378.818428) (xy 386.088725 -378.799712) (xy 386.103012 -378.785359) (xy 386.121693 -378.777535)
			(xy 386.131816 -378.776992) (xy 386.848096 -378.776992) (xy 386.858249 -378.777425) (xy 386.877 -378.785218)
			(xy 386.891323 -378.799611) (xy 386.899024 -378.818399) (xy 386.899404 -378.828554) (xy 386.899404 -378.986288)
			(xy 386.899819 -378.995475) (xy 386.906329 -379.012659) (xy 386.912104 -379.019816) (xy 386.934015 -379.045442)
			(xy 386.972102 -379.101083) (xy 387.00325 -379.160884) (xy 387.027012 -379.223986) (xy 387.043044 -379.28948)
			(xy 387.051116 -379.356422) (xy 387.051111 -379.42385) (xy 387.043031 -379.490791) (xy 387.02699 -379.556283)
			(xy 387.003221 -379.619382) (xy 386.972065 -379.679179) (xy 386.933971 -379.734815) (xy 386.912104 -379.76048)
			(xy 386.906291 -379.767614) (xy 386.899786 -379.784813) (xy 386.899404 -379.794008) (xy 386.899404 -380.28626)
			(xy 386.899832 -380.295445) (xy 386.906333 -380.31263) (xy 386.912104 -380.319788) (xy 386.933987 -380.345437)
			(xy 386.972075 -380.401074) (xy 387.003225 -380.460872) (xy 387.026988 -380.523971) (xy 387.043022 -380.589462)
			(xy 387.051096 -380.656402) (xy 387.051096 -380.656464) (xy 390.329159 -380.656464) (xy 390.3372 -380.589643)
			(xy 390.35317 -380.524263) (xy 390.376839 -380.461259) (xy 390.407867 -380.401536) (xy 390.445811 -380.345949)
			(xy 390.467596 -380.320296) (xy 390.473376 -380.313139) (xy 390.479901 -380.295958) (xy 390.480296 -380.286768)
			(xy 390.480296 -379.7935) (xy 390.479887 -379.784313) (xy 390.473372 -379.767128) (xy 390.467596 -379.759972)
			(xy 390.445857 -379.73428) (xy 390.407909 -379.678699) (xy 390.376876 -379.61898) (xy 390.353203 -379.555981)
			(xy 390.337228 -379.490604) (xy 390.32918 -379.423786) (xy 390.329176 -379.356486) (xy 390.337215 -379.289667)
			(xy 390.353181 -379.224288) (xy 390.376847 -379.161286) (xy 390.407872 -379.101563) (xy 390.445812 -379.045977)
			(xy 390.467596 -379.020324) (xy 390.473407 -379.013189) (xy 390.479913 -378.995991) (xy 390.480296 -378.986796)
			(xy 390.480296 -378.828554) (xy 390.480795 -378.818398) (xy 390.488576 -378.799636) (xy 390.50294 -378.785274)
			(xy 390.521702 -378.777494) (xy 390.531858 -378.776992) (xy 391.248138 -378.776992) (xy 391.258293 -378.777501)
			(xy 391.277054 -378.785279) (xy 391.291416 -378.79964) (xy 391.299197 -378.8184) (xy 391.2997 -378.828554)
			(xy 391.2997 -378.986796) (xy 391.300112 -378.995983) (xy 391.306625 -379.013167) (xy 391.3124 -379.020324)
			(xy 391.334234 -379.045938) (xy 391.372178 -379.101531) (xy 391.403207 -379.16126) (xy 391.426876 -379.224269)
			(xy 391.442844 -379.289656) (xy 391.450884 -379.356482) (xy 391.45088 -379.42379) (xy 391.442831 -379.490615)
			(xy 391.426855 -379.556) (xy 391.403178 -379.619006) (xy 391.372141 -379.678731) (xy 391.334189 -379.734319)
			(xy 391.3124 -379.759972) (xy 391.30659 -379.767108) (xy 391.300083 -379.784306) (xy 391.2997 -379.7935)
			(xy 391.2997 -380.286768) (xy 391.300126 -380.295954) (xy 391.306629 -380.313138) (xy 391.3124 -380.320296)
			(xy 391.334206 -380.345933) (xy 391.372152 -380.401522) (xy 391.403182 -380.461248) (xy 391.426852 -380.524255)
			(xy 391.442822 -380.589638) (xy 391.450857 -380.656404) (xy 421.12866 -380.656404) (xy 421.136735 -380.589466)
			(xy 421.152769 -380.523978) (xy 421.176533 -380.460881) (xy 421.207683 -380.401086) (xy 421.245772 -380.345453)
			(xy 421.267636 -380.319788) (xy 421.273425 -380.312637) (xy 421.279943 -380.295451) (xy 421.280336 -380.28626)
			(xy 421.280336 -379.794008) (xy 421.279914 -379.784822) (xy 421.273408 -379.767638) (xy 421.267636 -379.76048)
			(xy 421.245818 -379.734776) (xy 421.207725 -379.679148) (xy 421.176571 -379.619358) (xy 421.152802 -379.556266)
			(xy 421.136762 -379.490781) (xy 421.128682 -379.423846) (xy 421.128678 -379.356426) (xy 421.136749 -379.28949)
			(xy 421.152781 -379.224003) (xy 421.176541 -379.160908) (xy 421.207688 -379.101114) (xy 421.245774 -379.045481)
			(xy 421.267636 -379.019816) (xy 421.273455 -379.012687) (xy 421.279956 -378.995484) (xy 421.280336 -378.986288)
			(xy 421.280336 -378.828554) (xy 421.280789 -378.818425) (xy 421.288531 -378.799703) (xy 421.302827 -378.785349)
			(xy 421.321517 -378.777531) (xy 421.331644 -378.776992) (xy 422.047924 -378.776992) (xy 422.058079 -378.777402)
			(xy 422.07683 -378.785204) (xy 422.091152 -378.799604) (xy 422.098853 -378.818397) (xy 422.099232 -378.828554)
			(xy 422.099232 -378.986288) (xy 422.099663 -378.995473) (xy 422.106164 -379.012656) (xy 422.111932 -379.019816)
			(xy 422.133842 -379.045443) (xy 422.171927 -379.101084) (xy 422.203074 -379.160885) (xy 422.226834 -379.223987)
			(xy 422.242865 -379.289481) (xy 422.250937 -379.356423) (xy 422.250932 -379.423849) (xy 422.242852 -379.49079)
			(xy 422.226813 -379.556282) (xy 422.203045 -379.61938) (xy 422.17189 -379.679178) (xy 422.133798 -379.734814)
			(xy 422.111932 -379.76048) (xy 422.106111 -379.767607) (xy 422.099613 -379.784812) (xy 422.099232 -379.794008)
			(xy 422.099232 -380.28626) (xy 422.099677 -380.295443) (xy 422.106168 -380.312627) (xy 422.111932 -380.319788)
			(xy 422.133814 -380.345438) (xy 422.171901 -380.401075) (xy 422.203049 -380.460874) (xy 422.22681 -380.523973)
			(xy 422.242843 -380.589463) (xy 422.250917 -380.656403) (xy 422.250917 -380.656463) (xy 425.52898 -380.656463)
			(xy 425.537022 -380.589642) (xy 425.552992 -380.524262) (xy 425.576662 -380.461258) (xy 425.607692 -380.401535)
			(xy 425.645638 -380.345948) (xy 425.667424 -380.320296) (xy 425.673208 -380.313142) (xy 425.679729 -380.295958)
			(xy 425.680124 -380.286768) (xy 425.680124 -379.7935) (xy 425.679709 -379.784313) (xy 425.673198 -379.767129)
			(xy 425.667424 -379.759972) (xy 425.645684 -379.734281) (xy 425.607735 -379.678699) (xy 425.5767 -379.618981)
			(xy 425.553026 -379.555982) (xy 425.53705 -379.490605) (xy 425.529002 -379.423787) (xy 425.528998 -379.356486)
			(xy 425.537037 -379.289667) (xy 425.553004 -379.224287) (xy 425.576671 -379.161285) (xy 425.607698 -379.101563)
			(xy 425.64564 -379.045977) (xy 425.667424 -379.020324) (xy 425.673238 -379.013191) (xy 425.679742 -378.995991)
			(xy 425.680124 -378.986796) (xy 425.680124 -378.828554) (xy 425.680595 -378.818395) (xy 425.688382 -378.799628)
			(xy 425.702754 -378.785264) (xy 425.721527 -378.777489) (xy 425.731686 -378.776992) (xy 426.447966 -378.776992)
			(xy 426.458116 -378.77756) (xy 426.476875 -378.785315) (xy 426.49124 -378.799657) (xy 426.499024 -378.818405)
			(xy 426.499528 -378.828554) (xy 426.499528 -378.986796) (xy 426.499934 -378.995984) (xy 426.50645 -379.013168)
			(xy 426.512228 -379.020324) (xy 426.534064 -379.045937) (xy 426.572014 -379.101528) (xy 426.603047 -379.161257)
			(xy 426.626718 -379.224267) (xy 426.642689 -379.289654) (xy 426.65073 -379.356481) (xy 426.650725 -379.423791)
			(xy 426.642676 -379.490617) (xy 426.626697 -379.556003) (xy 426.603017 -379.619009) (xy 426.571977 -379.678734)
			(xy 426.53402 -379.73432) (xy 426.512228 -379.759972) (xy 426.50641 -379.767101) (xy 426.49991 -379.784304)
			(xy 426.499528 -379.7935) (xy 426.499528 -380.286768) (xy 426.499947 -380.295954) (xy 426.506454 -380.313139)
			(xy 426.512228 -380.320296) (xy 426.534036 -380.345932) (xy 426.571987 -380.40152) (xy 426.603021 -380.461245)
			(xy 426.626694 -380.524252) (xy 426.642667 -380.589636) (xy 426.650703 -380.656404) (xy 429.928748 -380.656404)
			(xy 429.936823 -380.589467) (xy 429.952857 -380.523978) (xy 429.976619 -380.460882) (xy 430.007769 -380.401087)
			(xy 430.045857 -380.345453) (xy 430.06772 -380.319788) (xy 430.073506 -380.312636) (xy 430.080027 -380.295451)
			(xy 430.08042 -380.28626) (xy 430.08042 -379.794008) (xy 430.080001 -379.784822) (xy 430.073493 -379.767638)
			(xy 430.06772 -379.76048) (xy 430.045902 -379.734776) (xy 430.007811 -379.679148) (xy 429.976657 -379.619357)
			(xy 429.952889 -379.556265) (xy 429.93685 -379.490781) (xy 429.92877 -379.423846) (xy 429.928766 -379.356426)
			(xy 429.936837 -379.289491) (xy 429.952868 -379.224004) (xy 429.976628 -379.160909) (xy 430.007774 -379.101114)
			(xy 430.045858 -379.045481) (xy 430.06772 -379.019816) (xy 430.073537 -379.012685) (xy 430.080039 -378.995484)
			(xy 430.08042 -378.986288) (xy 430.08042 -378.828554) (xy 430.080888 -378.818427) (xy 430.088628 -378.799708)
			(xy 430.102919 -378.785354) (xy 430.121603 -378.777533) (xy 430.131728 -378.776992) (xy 430.848008 -378.776992)
			(xy 430.858162 -378.777415) (xy 430.876913 -378.785212) (xy 430.891235 -378.799608) (xy 430.898936 -378.818398)
			(xy 430.899316 -378.828554) (xy 430.899316 -378.986288) (xy 430.899728 -378.995475) (xy 430.90624 -379.01266)
			(xy 430.912016 -379.019816) (xy 430.933927 -379.045443) (xy 430.972013 -379.101083) (xy 431.003161 -379.160885)
			(xy 431.026921 -379.223987) (xy 431.042953 -379.28948) (xy 431.051025 -379.356422) (xy 431.05102 -379.42385)
			(xy 431.04294 -379.490791) (xy 431.0269 -379.556282) (xy 431.003131 -379.619381) (xy 430.971976 -379.679179)
			(xy 430.933882 -379.734814) (xy 430.912016 -379.76048) (xy 430.906205 -379.767615) (xy 430.899698 -379.784813)
			(xy 430.899316 -379.794008) (xy 430.899316 -380.28626) (xy 430.899742 -380.295446) (xy 430.906244 -380.31263)
			(xy 430.912016 -380.319788) (xy 430.933899 -380.345437) (xy 430.971986 -380.401074) (xy 431.003135 -380.460873)
			(xy 431.026897 -380.523972) (xy 431.042931 -380.589463) (xy 431.051005 -380.656403) (xy 431.051005 -380.656464)
			(xy 434.329068 -380.656464) (xy 434.33711 -380.589643) (xy 434.35308 -380.524262) (xy 434.376749 -380.461259)
			(xy 434.407778 -380.401535) (xy 434.445722 -380.345949) (xy 434.467508 -380.320296) (xy 434.47329 -380.31314)
			(xy 434.479813 -380.295958) (xy 434.480208 -380.286768) (xy 434.480208 -379.7935) (xy 434.479796 -379.784313)
			(xy 434.473283 -379.767129) (xy 434.467508 -379.759972) (xy 434.445769 -379.73428) (xy 434.407821 -379.678699)
			(xy 434.376787 -379.61898) (xy 434.353113 -379.555981) (xy 434.337137 -379.490604) (xy 434.32909 -379.423786)
			(xy 434.329086 -379.356486) (xy 434.337125 -379.289667) (xy 434.353091 -379.224288) (xy 434.376757 -379.161286)
			(xy 434.407783 -379.101563) (xy 434.445724 -379.045977) (xy 434.467508 -379.020324) (xy 434.47332 -379.01319)
			(xy 434.479825 -378.995991) (xy 434.480208 -378.986796) (xy 434.480208 -378.828554) (xy 434.480695 -378.818397)
			(xy 434.488479 -378.799633) (xy 434.502846 -378.78527) (xy 434.521613 -378.777492) (xy 434.53177 -378.776992)
			(xy 435.24805 -378.776992) (xy 435.258213 -378.777504) (xy 435.276998 -378.785264) (xy 435.291383 -378.799622)
			(xy 435.299177 -378.818392) (xy 435.299612 -378.828554) (xy 435.299612 -378.986796) (xy 435.300021 -378.995983)
			(xy 435.306535 -379.013168) (xy 435.312312 -379.020324) (xy 435.334148 -379.045937) (xy 435.372099 -379.101528)
			(xy 435.403133 -379.161256) (xy 435.426805 -379.224266) (xy 435.442776 -379.289654) (xy 435.450817 -379.356481)
			(xy 435.450813 -379.423791) (xy 435.442763 -379.490618) (xy 435.426784 -379.556003) (xy 435.403103 -379.61901)
			(xy 435.372062 -379.678734) (xy 435.334104 -379.73432) (xy 435.312312 -379.759972) (xy 435.306504 -379.767109)
			(xy 435.299996 -379.784306) (xy 435.299612 -379.7935) (xy 435.299612 -380.286768) (xy 435.300035 -380.295954)
			(xy 435.306539 -380.313139) (xy 435.312312 -380.320296) (xy 435.334121 -380.345931) (xy 435.372072 -380.401519)
			(xy 435.403107 -380.461244) (xy 435.426781 -380.524251) (xy 435.442754 -380.589636) (xy 435.450797 -380.656461)
			(xy 435.450796 -380.723769) (xy 435.442749 -380.790594) (xy 435.426772 -380.855977) (xy 435.403095 -380.918983)
			(xy 435.372057 -380.978707) (xy 435.334102 -381.034292) (xy 435.312312 -381.059944) (xy 435.306516 -381.067089)
			(xy 435.3 -381.08428) (xy 435.299612 -381.093472) (xy 435.299612 -381.251206) (xy 435.29924 -381.261384)
			(xy 435.291444 -381.280189) (xy 435.277041 -381.294575) (xy 435.258229 -381.302351) (xy 435.24805 -381.302768)
			(xy 434.53177 -381.302768) (xy 434.521611 -381.302291) (xy 434.502842 -381.294508) (xy 434.488478 -381.280138)
			(xy 434.480704 -381.261365) (xy 434.480208 -381.251206) (xy 434.480208 -381.093472) (xy 434.47981 -381.084284)
			(xy 434.473288 -381.067099) (xy 434.467508 -381.059944) (xy 434.445741 -381.034275) (xy 434.407793 -380.97869)
			(xy 434.376761 -380.918969) (xy 434.353088 -380.855967) (xy 434.337115 -380.790587) (xy 434.32907 -380.723766)
			(xy 434.329068 -380.656464) (xy 431.051005 -380.656464) (xy 431.051003 -380.723827) (xy 431.042926 -380.790767)
			(xy 431.026889 -380.856257) (xy 431.003123 -380.919354) (xy 430.971971 -380.979151) (xy 430.933881 -381.034786)
			(xy 430.912016 -381.060452) (xy 430.906217 -381.067595) (xy 430.899703 -381.084787) (xy 430.899316 -381.09398)
			(xy 430.899316 -381.251206) (xy 430.898877 -381.261338) (xy 430.891139 -381.280068) (xy 430.876838 -381.294426)
			(xy 430.858138 -381.302237) (xy 430.848008 -381.302768) (xy 430.131728 -381.302768) (xy 430.121572 -381.302355)
			(xy 430.102814 -381.294563) (xy 430.088488 -381.280163) (xy 430.080793 -381.261364) (xy 430.08042 -381.251206)
			(xy 430.08042 -381.09398) (xy 430.080015 -381.084792) (xy 430.073497 -381.067608) (xy 430.06772 -381.060452)
			(xy 430.045875 -381.034771) (xy 430.007784 -380.979139) (xy 429.976632 -380.919345) (xy 429.952865 -380.85625)
			(xy 429.936828 -380.790763) (xy 429.92875 -380.723826) (xy 429.928748 -380.656404) (xy 426.650703 -380.656404)
			(xy 426.65071 -380.656461) (xy 426.650708 -380.723769) (xy 426.642661 -380.790593) (xy 426.626685 -380.855977)
			(xy 426.603009 -380.918982) (xy 426.571971 -380.978706) (xy 426.534018 -381.034292) (xy 426.512228 -381.059944)
			(xy 426.506422 -381.067082) (xy 426.499915 -381.084278) (xy 426.499528 -381.093472) (xy 426.499528 -381.251206)
			(xy 426.49914 -381.261382) (xy 426.491347 -381.280184) (xy 426.47695 -381.294569) (xy 426.458143 -381.302348)
			(xy 426.447966 -381.302768) (xy 425.731686 -381.302768) (xy 425.721528 -381.302278) (xy 425.70276 -381.2945)
			(xy 425.688395 -381.280133) (xy 425.68062 -381.261364) (xy 425.680124 -381.251206) (xy 425.680124 -381.093472)
			(xy 425.679722 -381.084284) (xy 425.673202 -381.0671) (xy 425.667424 -381.059944) (xy 425.645656 -381.034276)
			(xy 425.607708 -380.978691) (xy 425.576675 -380.91897) (xy 425.553001 -380.855967) (xy 425.537027 -380.790587)
			(xy 425.528982 -380.723767) (xy 425.52898 -380.656463) (xy 422.250917 -380.656463) (xy 422.250915 -380.723827)
			(xy 422.242838 -380.790766) (xy 422.226801 -380.856256) (xy 422.203036 -380.919354) (xy 422.171885 -380.979151)
			(xy 422.133796 -381.034786) (xy 422.111932 -381.060452) (xy 422.106123 -381.067588) (xy 422.099618 -381.084786)
			(xy 422.099232 -381.09398) (xy 422.099232 -381.251206) (xy 422.098777 -381.261337) (xy 422.091042 -381.280063)
			(xy 422.076746 -381.29442) (xy 422.058052 -381.302234) (xy 422.047924 -381.302768) (xy 421.331644 -381.302768)
			(xy 421.321489 -381.302342) (xy 421.302731 -381.294555) (xy 421.288405 -381.280159) (xy 421.28071 -381.261363)
			(xy 421.280336 -381.251206) (xy 421.280336 -381.09398) (xy 421.279927 -381.084793) (xy 421.273412 -381.067609)
			(xy 421.267636 -381.060452) (xy 421.24579 -381.034771) (xy 421.207699 -380.97914) (xy 421.176545 -380.919346)
			(xy 421.152778 -380.856251) (xy 421.13674 -380.790764) (xy 421.128662 -380.723826) (xy 421.12866 -380.656404)
			(xy 391.450857 -380.656404) (xy 391.450864 -380.656462) (xy 391.450863 -380.723768) (xy 391.442817 -380.790591)
			(xy 391.426843 -380.855974) (xy 391.40317 -380.918979) (xy 391.372136 -380.978704) (xy 391.334188 -381.034291)
			(xy 391.3124 -381.059944) (xy 391.306602 -381.067088) (xy 391.300088 -381.08428) (xy 391.2997 -381.093472)
			(xy 391.2997 -381.251206) (xy 391.299172 -381.261359) (xy 391.291403 -381.280121) (xy 391.277048 -381.294485)
			(xy 391.258291 -381.302266) (xy 391.248138 -381.302768) (xy 390.531858 -381.302768) (xy 390.521698 -381.302301)
			(xy 390.502929 -381.294514) (xy 390.488566 -381.28014) (xy 390.480792 -381.261366) (xy 390.480296 -381.251206)
			(xy 390.480296 -381.093472) (xy 390.4799 -381.084283) (xy 390.473377 -381.067099) (xy 390.467596 -381.059944)
			(xy 390.445829 -381.034275) (xy 390.407883 -380.97869) (xy 390.376851 -380.918968) (xy 390.353179 -380.855966)
			(xy 390.337206 -380.790586) (xy 390.329161 -380.723766) (xy 390.329159 -380.656464) (xy 387.051096 -380.656464)
			(xy 387.051094 -380.723828) (xy 387.043016 -380.790767) (xy 387.026979 -380.856257) (xy 387.003213 -380.919355)
			(xy 386.97206 -380.979152) (xy 386.933969 -381.034787) (xy 386.912104 -381.060452) (xy 386.906303 -381.067594)
			(xy 386.899791 -381.084787) (xy 386.899404 -381.09398) (xy 386.899404 -381.251206) (xy 386.89888 -381.261328)
			(xy 386.891158 -381.280041) (xy 386.876884 -381.294395) (xy 386.858215 -381.302222) (xy 386.848096 -381.302768)
			(xy 386.131816 -381.302768) (xy 386.121659 -381.302365) (xy 386.102901 -381.294568) (xy 386.088576 -381.280166)
			(xy 386.080881 -381.261365) (xy 386.080508 -381.251206) (xy 386.080508 -381.09398) (xy 386.080106 -381.084792)
			(xy 386.073587 -381.067608) (xy 386.067808 -381.060452) (xy 386.045963 -381.034771) (xy 386.007874 -380.979139)
			(xy 385.976722 -380.919345) (xy 385.952956 -380.85625) (xy 385.936919 -380.790763) (xy 385.928841 -380.723826)
			(xy 385.928839 -380.656404) (xy 382.650793 -380.656404) (xy 382.6508 -380.656461) (xy 382.650799 -380.723769)
			(xy 382.642752 -380.790593) (xy 382.626775 -380.855977) (xy 382.603098 -380.918983) (xy 382.57206 -380.978707)
			(xy 382.534106 -381.034292) (xy 382.512316 -381.059944) (xy 382.50652 -381.06709) (xy 382.500005 -381.08428)
			(xy 382.499616 -381.093472) (xy 382.499616 -381.251206) (xy 382.49924 -381.261384) (xy 382.491444 -381.280187)
			(xy 382.477044 -381.294574) (xy 382.458232 -381.30235) (xy 382.448054 -381.302768) (xy 381.731774 -381.302768)
			(xy 381.721615 -381.302288) (xy 381.702847 -381.294506) (xy 381.688482 -381.280137) (xy 381.680708 -381.261365)
			(xy 381.680212 -381.251206) (xy 381.680212 -381.093472) (xy 381.679813 -381.084284) (xy 381.673291 -381.0671)
			(xy 381.667512 -381.059944) (xy 381.645745 -381.034275) (xy 381.607797 -380.978691) (xy 381.576764 -380.918969)
			(xy 381.553092 -380.855967) (xy 381.537118 -380.790587) (xy 381.529073 -380.723767) (xy 381.529071 -380.656464)
			(xy 378.251008 -380.656464) (xy 378.251006 -380.723827) (xy 378.242929 -380.790767) (xy 378.226892 -380.856257)
			(xy 378.203126 -380.919354) (xy 378.171974 -380.979151) (xy 378.133884 -381.034786) (xy 378.11202 -381.060452)
			(xy 378.106221 -381.067596) (xy 378.099707 -381.084787) (xy 378.09932 -381.09398) (xy 378.09932 -381.251206)
			(xy 378.098877 -381.261338) (xy 378.09114 -381.280067) (xy 378.07684 -381.294424) (xy 378.058142 -381.302236)
			(xy 378.048012 -381.302768) (xy 377.331732 -381.302768) (xy 377.321576 -381.302352) (xy 377.302818 -381.294561)
			(xy 377.288492 -381.280162) (xy 377.280797 -381.261364) (xy 377.280424 -381.251206) (xy 377.280424 -381.09398)
			(xy 377.280018 -381.084792) (xy 377.273501 -381.067608) (xy 377.267724 -381.060452) (xy 377.245879 -381.034771)
			(xy 377.207788 -380.979139) (xy 377.176635 -380.919345) (xy 377.152869 -380.856251) (xy 377.136831 -380.790763)
			(xy 377.128753 -380.723826) (xy 377.128751 -380.656404) (xy 347.450948 -380.656404) (xy 347.450955 -380.656462)
			(xy 347.450954 -380.723768) (xy 347.442908 -380.790592) (xy 347.426934 -380.855975) (xy 347.40326 -380.91898)
			(xy 347.372226 -380.978704) (xy 347.334276 -381.034291) (xy 347.312488 -381.059944) (xy 347.306689 -381.067087)
			(xy 347.300176 -381.084279) (xy 347.299788 -381.093472) (xy 347.299788 -381.251206) (xy 347.299272 -381.261361)
			(xy 347.2915 -381.280125) (xy 347.277142 -381.294489) (xy 347.258381 -381.302268) (xy 347.248226 -381.302768)
			(xy 346.531946 -381.302768) (xy 346.521778 -381.302299) (xy 346.502986 -381.29453) (xy 346.488599 -381.280158)
			(xy 346.480812 -381.261373) (xy 346.480384 -381.251206) (xy 346.480384 -381.093472) (xy 346.479991 -381.084283)
			(xy 346.473466 -381.067099) (xy 346.467684 -381.059944) (xy 346.445915 -381.034276) (xy 346.407962 -380.978693)
			(xy 346.376926 -380.918972) (xy 346.35325 -380.85597) (xy 346.337274 -380.790589) (xy 346.329228 -380.723767)
			(xy 346.329226 -380.656463) (xy 343.051187 -380.656463) (xy 343.051185 -380.723828) (xy 343.043107 -380.790767)
			(xy 343.027069 -380.856258) (xy 343.003303 -380.919356) (xy 342.972149 -380.979152) (xy 342.934057 -381.034787)
			(xy 342.912192 -381.060452) (xy 342.90639 -381.067593) (xy 342.899879 -381.084787) (xy 342.899492 -381.09398)
			(xy 342.899492 -381.251206) (xy 342.898979 -381.261329) (xy 342.891255 -381.280044) (xy 342.876978 -381.294399)
			(xy 342.858304 -381.302224) (xy 342.848184 -381.302768) (xy 342.131904 -381.302768) (xy 342.121746 -381.302374)
			(xy 342.102988 -381.294574) (xy 342.088663 -381.280168) (xy 342.080969 -381.261366) (xy 342.080596 -381.251206)
			(xy 342.080596 -381.09398) (xy 342.080196 -381.084792) (xy 342.073675 -381.067608) (xy 342.067896 -381.060452)
			(xy 342.046052 -381.03477) (xy 342.007963 -380.979138) (xy 341.976811 -380.919344) (xy 341.953046 -380.856249)
			(xy 341.93701 -380.790762) (xy 341.928932 -380.723826) (xy 341.92893 -380.656404) (xy 338.65086 -380.656404)
			(xy 338.650867 -380.656462) (xy 338.650866 -380.723768) (xy 338.64282 -380.790591) (xy 338.626846 -380.855974)
			(xy 338.603173 -380.918979) (xy 338.57214 -380.978704) (xy 338.534192 -381.034291) (xy 338.512404 -381.059944)
			(xy 338.506607 -381.067089) (xy 338.500092 -381.08428) (xy 338.499704 -381.093472) (xy 338.499704 -381.251206)
			(xy 338.499172 -381.261359) (xy 338.491404 -381.28012) (xy 338.47705 -381.294484) (xy 338.458295 -381.302265)
			(xy 338.448142 -381.302768) (xy 337.731862 -381.302768) (xy 337.721703 -381.302298) (xy 337.702934 -381.294512)
			(xy 337.68857 -381.280139) (xy 337.680796 -381.261366) (xy 337.6803 -381.251206) (xy 337.6803 -381.093472)
			(xy 337.679904 -381.084283) (xy 337.67338 -381.067099) (xy 337.6676 -381.059944) (xy 337.645833 -381.034275)
			(xy 337.607886 -380.97869) (xy 337.576854 -380.918969) (xy 337.553182 -380.855966) (xy 337.537209 -380.790587)
			(xy 337.529164 -380.723766) (xy 337.529162 -380.656464) (xy 334.251099 -380.656464) (xy 334.251097 -380.723828)
			(xy 334.243019 -380.790767) (xy 334.226982 -380.856257) (xy 334.203216 -380.919355) (xy 334.172063 -380.979152)
			(xy 334.133973 -381.034787) (xy 334.112108 -381.060452) (xy 334.106308 -381.067595) (xy 334.099795 -381.084787)
			(xy 334.099408 -381.09398) (xy 334.099408 -381.251206) (xy 334.09888 -381.261327) (xy 334.091159 -381.280039)
			(xy 334.076886 -381.294394) (xy 334.058218 -381.302221) (xy 334.0481 -381.302768) (xy 333.33182 -381.302768)
			(xy 333.321663 -381.302362) (xy 333.302905 -381.294567) (xy 333.28858 -381.280165) (xy 333.280885 -381.261365)
			(xy 333.280512 -381.251206) (xy 333.280512 -381.09398) (xy 333.280109 -381.084792) (xy 333.27359 -381.067608)
			(xy 333.267812 -381.060452) (xy 333.245967 -381.034771) (xy 333.207877 -380.979139) (xy 333.176725 -380.919345)
			(xy 333.152959 -380.85625) (xy 333.136922 -380.790763) (xy 333.128844 -380.723826) (xy 333.128842 -380.656404)
			(xy 303.451069 -380.656404) (xy 303.451067 -380.723828) (xy 303.442989 -380.790768) (xy 303.42695 -380.856259)
			(xy 303.403182 -380.919357) (xy 303.372027 -380.979153) (xy 303.333934 -381.034787) (xy 303.312068 -381.060452)
			(xy 303.306263 -381.067591) (xy 303.299754 -381.084786) (xy 303.299368 -381.09398) (xy 303.299368 -381.251206)
			(xy 303.298878 -381.261332) (xy 303.29115 -381.280052) (xy 303.276865 -381.294408) (xy 303.258184 -381.302228)
			(xy 303.24806 -381.302768) (xy 302.53178 -381.302768) (xy 302.521621 -381.302394) (xy 302.502861 -381.294586)
			(xy 302.488538 -381.280174) (xy 302.480844 -381.261368) (xy 302.480472 -381.251206) (xy 302.480472 -381.09398)
			(xy 302.480078 -381.084791) (xy 302.473554 -381.067607) (xy 302.467772 -381.060452) (xy 302.445929 -381.03477)
			(xy 302.407841 -380.979137) (xy 302.376691 -380.919343) (xy 302.352927 -380.856248) (xy 302.336891 -380.790762)
			(xy 302.328814 -380.723826) (xy 302.328812 -380.656404) (xy 299.050742 -380.656404) (xy 299.050749 -380.656462)
			(xy 299.050747 -380.723768) (xy 299.042702 -380.790592) (xy 299.026727 -380.855975) (xy 299.003053 -380.91898)
			(xy 298.972018 -380.978704) (xy 298.934068 -381.034292) (xy 298.91228 -381.059944) (xy 298.90648 -381.067087)
			(xy 298.899968 -381.084279) (xy 298.89958 -381.093472) (xy 298.89958 -381.251206) (xy 298.899072 -381.261362)
			(xy 298.891299 -381.280128) (xy 298.876938 -381.294492) (xy 298.858174 -381.302269) (xy 298.848018 -381.302768)
			(xy 298.131738 -381.302768) (xy 298.12157 -381.302305) (xy 298.102777 -381.294534) (xy 298.088391 -381.28016)
			(xy 298.080604 -381.261374) (xy 298.080176 -381.251206) (xy 298.080176 -381.093472) (xy 298.079785 -381.084283)
			(xy 298.073258 -381.067098) (xy 298.067476 -381.059944) (xy 298.045707 -381.034276) (xy 298.007755 -380.978693)
			(xy 297.976719 -380.918972) (xy 297.953043 -380.855969) (xy 297.937068 -380.790589) (xy 297.929022 -380.723767)
			(xy 297.92902 -380.656463) (xy 294.650981 -380.656463) (xy 294.650979 -380.723828) (xy 294.642901 -380.790768)
			(xy 294.626863 -380.856258) (xy 294.603096 -380.919356) (xy 294.571942 -380.979153) (xy 294.53385 -381.034787)
			(xy 294.511984 -381.060452) (xy 294.506181 -381.067593) (xy 294.499671 -381.084787) (xy 294.499284 -381.09398)
			(xy 294.499284 -381.251206) (xy 294.498779 -381.26133) (xy 294.491054 -381.280047) (xy 294.476773 -381.294402)
			(xy 294.458097 -381.302225) (xy 294.447976 -381.302768) (xy 293.731696 -381.302768) (xy 293.721538 -381.302381)
			(xy 293.702779 -381.294578) (xy 293.688455 -381.28017) (xy 293.680761 -381.261367) (xy 293.680388 -381.251206)
			(xy 293.680388 -381.09398) (xy 293.67999 -381.084791) (xy 293.673468 -381.067607) (xy 293.667688 -381.060452)
			(xy 293.645844 -381.03477) (xy 293.607756 -380.979138) (xy 293.576605 -380.919344) (xy 293.55284 -380.856249)
			(xy 293.536803 -380.790762) (xy 293.528726 -380.723826) (xy 293.528724 -380.656404) (xy 290.250654 -380.656404)
			(xy 290.250661 -380.656462) (xy 290.25066 -380.723768) (xy 290.242614 -380.790591) (xy 290.22664 -380.855974)
			(xy 290.202966 -380.918979) (xy 290.171933 -380.978704) (xy 290.133984 -381.034291) (xy 290.112196 -381.059944)
			(xy 290.106398 -381.067088) (xy 290.099884 -381.084279) (xy 290.099496 -381.093472) (xy 290.099496 -381.251206)
			(xy 290.098972 -381.26136) (xy 290.091202 -381.280123) (xy 290.076846 -381.294486) (xy 290.058088 -381.302267)
			(xy 290.047934 -381.302768) (xy 289.331654 -381.302768) (xy 289.321494 -381.302304) (xy 289.302725 -381.294516)
			(xy 289.288362 -381.280141) (xy 289.280588 -381.261366) (xy 289.280092 -381.251206) (xy 289.280092 -381.093472)
			(xy 289.279697 -381.084283) (xy 289.273173 -381.067099) (xy 289.267392 -381.059944) (xy 289.245622 -381.034276)
			(xy 289.207669 -380.978693) (xy 289.176632 -380.918972) (xy 289.152956 -380.85597) (xy 289.13698 -380.790589)
			(xy 289.128934 -380.723767) (xy 289.128932 -380.656463) (xy 276.776531 -380.656463) (xy 276.720065 -380.793728)
			(xy 276.634707 -380.980199) (xy 276.542138 -381.163197) (xy 276.442501 -381.342444) (xy 276.335945 -381.517667)
			(xy 276.222634 -381.688599) (xy 276.102741 -381.85498) (xy 275.976447 -382.016556) (xy 275.843945 -382.173083)
			(xy 275.797584 -382.223705) (xy 286.928753 -382.223705) (xy 286.928754 -382.15628) (xy 286.936832 -382.08934)
			(xy 286.95287 -382.02385) (xy 286.976638 -381.960752) (xy 287.007792 -381.900956) (xy 287.045886 -381.845322)
			(xy 287.067752 -381.819658) (xy 287.073555 -381.812518) (xy 287.080065 -381.795323) (xy 287.080452 -381.78613)
			(xy 287.080452 -381.628904) (xy 287.080987 -381.618801) (xy 287.088715 -381.600133) (xy 287.102996 -381.585839)
			(xy 287.121658 -381.578096) (xy 287.13176 -381.577596) (xy 287.84804 -381.577596) (xy 287.858151 -381.578052)
			(xy 287.876829 -381.585802) (xy 287.891122 -381.600108) (xy 287.898856 -381.618793) (xy 287.899348 -381.628904)
			(xy 287.899348 -381.78613) (xy 287.899755 -381.795317) (xy 287.906272 -381.812501) (xy 287.912048 -381.819658)
			(xy 287.933904 -381.84533) (xy 287.971996 -381.900963) (xy 288.00315 -381.960757) (xy 288.026917 -382.023853)
			(xy 288.042955 -382.089342) (xy 288.051033 -382.156281) (xy 288.051034 -382.223645) (xy 291.329073 -382.223645)
			(xy 291.329074 -382.15634) (xy 291.337119 -382.089516) (xy 291.353093 -382.024133) (xy 291.376767 -381.961128)
			(xy 291.407801 -381.901405) (xy 291.445751 -381.845818) (xy 291.46754 -381.820166) (xy 291.473339 -381.813022)
			(xy 291.479851 -381.795831) (xy 291.48024 -381.786638) (xy 291.48024 -381.628904) (xy 291.480626 -381.618745)
			(xy 291.488427 -381.599985) (xy 291.502836 -381.58566) (xy 291.521641 -381.577968) (xy 291.531802 -381.577596)
			(xy 292.248082 -381.577596) (xy 292.258202 -381.57814) (xy 292.276915 -381.585854) (xy 292.29127 -381.600122)
			(xy 292.299098 -381.618787) (xy 292.299644 -381.628904) (xy 292.299644 -381.786638) (xy 292.300049 -381.795826)
			(xy 292.306568 -381.813009) (xy 292.312344 -381.820166) (xy 292.334122 -381.845826) (xy 292.372072 -381.901411)
			(xy 292.403107 -381.961133) (xy 292.426781 -382.024137) (xy 292.442755 -382.089518) (xy 292.450801 -382.15634)
			(xy 292.450801 -382.223645) (xy 292.450794 -382.223705) (xy 295.728841 -382.223705) (xy 295.728842 -382.15628)
			(xy 295.73692 -382.08934) (xy 295.752957 -382.02385) (xy 295.776724 -381.960753) (xy 295.807878 -381.900957)
			(xy 295.84597 -381.845323) (xy 295.867836 -381.819658) (xy 295.873637 -381.812516) (xy 295.880148 -381.795323)
			(xy 295.880536 -381.78613) (xy 295.880536 -381.628904) (xy 295.88092 -381.618777) (xy 295.888674 -381.600067)
			(xy 295.903001 -381.585751) (xy 295.921717 -381.578012) (xy 295.931844 -381.577596) (xy 296.648124 -381.577596)
			(xy 296.658234 -381.578065) (xy 296.676912 -381.58581) (xy 296.691206 -381.600112) (xy 296.69894 -381.618794)
			(xy 296.699432 -381.628904) (xy 296.699432 -381.78613) (xy 296.699843 -381.795317) (xy 296.706358 -381.8125)
			(xy 296.712132 -381.819658) (xy 296.733985 -381.845332) (xy 296.772072 -381.900966) (xy 296.803221 -381.960761)
			(xy 296.826985 -382.023857) (xy 296.84302 -382.089345) (xy 296.851096 -382.156281) (xy 296.851097 -382.223704)
			(xy 296.851097 -382.223705) (xy 300.128632 -382.223705) (xy 300.128633 -382.15628) (xy 300.13671 -382.089341)
			(xy 300.152748 -382.023851) (xy 300.176514 -381.960753) (xy 300.207667 -381.900957) (xy 300.245759 -381.845323)
			(xy 300.267624 -381.819658) (xy 300.273424 -381.812515) (xy 300.279936 -381.795323) (xy 300.280324 -381.78613)
			(xy 300.280324 -381.628904) (xy 300.28072 -381.618779) (xy 300.288471 -381.600071) (xy 300.302794 -381.585755)
			(xy 300.321507 -381.578014) (xy 300.331632 -381.577596) (xy 301.047912 -381.577596) (xy 301.058021 -381.578075)
			(xy 301.076699 -381.585816) (xy 301.090993 -381.600115) (xy 301.098728 -381.618795) (xy 301.09922 -381.628904)
			(xy 301.09922 -381.78613) (xy 301.099611 -381.795319) (xy 301.106138 -381.812504) (xy 301.11192 -381.819658)
			(xy 301.133773 -381.845332) (xy 301.171861 -381.900965) (xy 301.203011 -381.960761) (xy 301.226775 -382.023856)
			(xy 301.242811 -382.089344) (xy 301.250887 -382.156281) (xy 301.250888 -382.223646) (xy 330.929191 -382.223646)
			(xy 330.929192 -382.156339) (xy 330.937238 -382.089516) (xy 330.953213 -382.024133) (xy 330.976888 -381.961128)
			(xy 331.007923 -381.901404) (xy 331.045875 -381.845818) (xy 331.067664 -381.820166) (xy 331.073465 -381.813025)
			(xy 331.079975 -381.795831) (xy 331.080364 -381.786638) (xy 331.080364 -381.628904) (xy 331.080824 -381.618755)
			(xy 331.088612 -381.600009) (xy 331.102996 -381.585687) (xy 331.121775 -381.577981) (xy 331.131926 -381.577596)
			(xy 331.848206 -381.577596) (xy 331.858328 -381.57812) (xy 331.877041 -381.585842) (xy 331.891395 -381.600116)
			(xy 331.899222 -381.618785) (xy 331.899768 -381.628904) (xy 331.899768 -381.786638) (xy 331.900167 -381.795826)
			(xy 331.906689 -381.81301) (xy 331.912468 -381.820166) (xy 331.934246 -381.845826) (xy 331.972195 -381.901412)
			(xy 332.003228 -381.961134) (xy 332.026901 -382.024138) (xy 332.042874 -382.089519) (xy 332.050919 -382.15634)
			(xy 332.05092 -382.223645) (xy 332.050913 -382.223704) (xy 335.328984 -382.223704) (xy 335.328985 -382.156281)
			(xy 335.337061 -382.089342) (xy 335.353096 -382.023853) (xy 335.37686 -381.960756) (xy 335.40801 -381.900959)
			(xy 335.446097 -381.845324) (xy 335.46796 -381.819658) (xy 335.473764 -381.812519) (xy 335.480273 -381.795323)
			(xy 335.48066 -381.78613) (xy 335.48066 -381.628904) (xy 335.481187 -381.6188) (xy 335.488916 -381.60013)
			(xy 335.5032 -381.585837) (xy 335.521865 -381.578095) (xy 335.531968 -381.577596) (xy 336.248248 -381.577596)
			(xy 336.258359 -381.578046) (xy 336.277038 -381.585799) (xy 336.291331 -381.600106) (xy 336.299064 -381.618792)
			(xy 336.299556 -381.628904) (xy 336.299556 -381.78613) (xy 336.299962 -381.795317) (xy 336.30648 -381.812501)
			(xy 336.312256 -381.819658) (xy 336.334112 -381.845331) (xy 336.372204 -381.900963) (xy 336.403357 -381.960758)
			(xy 336.427124 -382.023854) (xy 336.443161 -382.089342) (xy 336.451239 -382.156281) (xy 336.45124 -382.223645)
			(xy 339.729279 -382.223645) (xy 339.72928 -382.156339) (xy 339.737325 -382.089516) (xy 339.753299 -382.024133)
			(xy 339.776974 -381.961128) (xy 339.808009 -381.901404) (xy 339.845959 -381.845818) (xy 339.867748 -381.820166)
			(xy 339.873547 -381.813023) (xy 339.880059 -381.795831) (xy 339.880448 -381.786638) (xy 339.880448 -381.628904)
			(xy 339.880924 -381.618757) (xy 339.888708 -381.600014) (xy 339.903088 -381.585693) (xy 339.921861 -381.577984)
			(xy 339.93201 -381.577596) (xy 340.64829 -381.577596) (xy 340.658411 -381.578133) (xy 340.677123 -381.58585)
			(xy 340.691478 -381.60012) (xy 340.699306 -381.618786) (xy 340.699852 -381.628904) (xy 340.699852 -381.786638)
			(xy 340.700255 -381.795826) (xy 340.706775 -381.813009) (xy 340.712552 -381.820166) (xy 340.73433 -381.845826)
			(xy 340.77228 -381.901411) (xy 340.803314 -381.961134) (xy 340.826988 -382.024137) (xy 340.842962 -382.089518)
			(xy 340.851007 -382.15634) (xy 340.851007 -382.223645) (xy 344.12907 -382.223645) (xy 344.129071 -382.15634)
			(xy 344.137116 -382.089516) (xy 344.15309 -382.024134) (xy 344.176764 -381.961129) (xy 344.207798 -381.901405)
			(xy 344.245748 -381.845818) (xy 344.267536 -381.820166) (xy 344.273334 -381.813022) (xy 344.279847 -381.79583)
			(xy 344.280236 -381.786638) (xy 344.280236 -381.628904) (xy 344.280626 -381.618746) (xy 344.288427 -381.599986)
			(xy 344.302834 -381.585662) (xy 344.321637 -381.577968) (xy 344.331798 -381.577596) (xy 345.048078 -381.577596)
			(xy 345.058198 -381.578143) (xy 345.07691 -381.585856) (xy 345.091266 -381.600123) (xy 345.099094 -381.618787)
			(xy 345.09964 -381.628904) (xy 345.09964 -381.786638) (xy 345.100045 -381.795825) (xy 345.106564 -381.813009)
			(xy 345.11234 -381.820166) (xy 345.134118 -381.845826) (xy 345.172069 -381.901411) (xy 345.203104 -381.961133)
			(xy 345.226778 -382.024137) (xy 345.242752 -382.089518) (xy 345.250798 -382.15634) (xy 345.250798 -382.223645)
			(xy 345.250798 -382.223646) (xy 374.9291 -382.223646) (xy 374.929101 -382.156339) (xy 374.937147 -382.089515)
			(xy 374.953122 -382.024132) (xy 374.976798 -381.961127) (xy 375.007834 -381.901404) (xy 375.045787 -381.845818)
			(xy 375.067576 -381.820166) (xy 375.073367 -381.813016) (xy 375.079886 -381.795829) (xy 375.080276 -381.786638)
			(xy 375.080276 -381.628904) (xy 375.080724 -381.618753) (xy 375.088514 -381.600005) (xy 375.102902 -381.585683)
			(xy 375.121685 -381.577979) (xy 375.131838 -381.577596) (xy 375.848118 -381.577596) (xy 375.85824 -381.57811)
			(xy 375.876954 -381.585836) (xy 375.891308 -381.600113) (xy 375.899134 -381.618784) (xy 375.89968 -381.628904)
			(xy 375.89968 -381.786638) (xy 375.900076 -381.795827) (xy 375.9066 -381.813011) (xy 375.91238 -381.820166)
			(xy 375.934157 -381.845826) (xy 375.972105 -381.901412) (xy 376.003138 -381.961135) (xy 376.02681 -382.024138)
			(xy 376.042784 -382.089519) (xy 376.050828 -382.156341) (xy 376.050829 -382.223644) (xy 376.050822 -382.223704)
			(xy 379.328893 -382.223704) (xy 379.328894 -382.156281) (xy 379.33697 -382.089342) (xy 379.353006 -382.023853)
			(xy 379.37677 -381.960756) (xy 379.40792 -381.900959) (xy 379.446008 -381.845324) (xy 379.467872 -381.819658)
			(xy 379.473678 -381.81252) (xy 379.480185 -381.795324) (xy 379.480572 -381.78613) (xy 379.480572 -381.628904)
			(xy 379.481088 -381.618799) (xy 379.488819 -381.600126) (xy 379.503106 -381.585832) (xy 379.521775 -381.578092)
			(xy 379.53188 -381.577596) (xy 380.24816 -381.577596) (xy 380.258279 -381.578049) (xy 380.276981 -381.585783)
			(xy 380.291297 -381.600088) (xy 380.299044 -381.618785) (xy 380.299468 -381.628904) (xy 380.299468 -381.78613)
			(xy 380.299871 -381.795318) (xy 380.30639 -381.812502) (xy 380.312168 -381.819658) (xy 380.334023 -381.845331)
			(xy 380.372114 -381.900963) (xy 380.403267 -381.960758) (xy 380.427033 -382.023854) (xy 380.443071 -382.089343)
			(xy 380.451148 -382.156281) (xy 380.451149 -382.223646) (xy 383.729188 -382.223646) (xy 383.729189 -382.156339)
			(xy 383.737235 -382.089516) (xy 383.753209 -382.024133) (xy 383.776884 -381.961128) (xy 383.80792 -381.901404)
			(xy 383.845871 -381.845818) (xy 383.86766 -381.820166) (xy 383.873461 -381.813024) (xy 383.879971 -381.795831)
			(xy 383.88036 -381.786638) (xy 383.88036 -381.628904) (xy 383.880824 -381.618755) (xy 383.888611 -381.600011)
			(xy 383.902994 -381.585689) (xy 383.921771 -381.577981) (xy 383.931922 -381.577596) (xy 384.648202 -381.577596)
			(xy 384.658323 -381.578124) (xy 384.677036 -381.585844) (xy 384.691391 -381.600117) (xy 384.699218 -381.618786)
			(xy 384.699764 -381.628904) (xy 384.699764 -381.786638) (xy 384.700164 -381.795826) (xy 384.706686 -381.81301)
			(xy 384.712464 -381.820166) (xy 384.734242 -381.845826) (xy 384.772191 -381.901412) (xy 384.803224 -381.961134)
			(xy 384.826898 -382.024137) (xy 384.842871 -382.089519) (xy 384.850916 -382.15634) (xy 384.850917 -382.223645)
			(xy 388.128979 -382.223645) (xy 388.12898 -382.156339) (xy 388.137025 -382.089516) (xy 388.152999 -382.024133)
			(xy 388.176674 -381.961128) (xy 388.207709 -381.901404) (xy 388.245659 -381.845818) (xy 388.267448 -381.820166)
			(xy 388.273247 -381.813023) (xy 388.279759 -381.795831) (xy 388.280148 -381.786638) (xy 388.280148 -381.628904)
			(xy 388.280624 -381.618757) (xy 388.288408 -381.600014) (xy 388.302788 -381.585693) (xy 388.321561 -381.577984)
			(xy 388.33171 -381.577596) (xy 389.04799 -381.577596) (xy 389.058111 -381.578133) (xy 389.076823 -381.58585)
			(xy 389.091178 -381.60012) (xy 389.099006 -381.618786) (xy 389.099552 -381.628904) (xy 389.099552 -381.786638)
			(xy 389.099955 -381.795826) (xy 389.106475 -381.813009) (xy 389.112252 -381.820166) (xy 389.13403 -381.845826)
			(xy 389.17198 -381.901411) (xy 389.203014 -381.961134) (xy 389.226688 -382.024137) (xy 389.242662 -382.089518)
			(xy 389.250707 -382.15634) (xy 389.250707 -382.223645) (xy 389.250707 -382.223646) (xy 418.92901 -382.223646)
			(xy 418.92901 -382.156339) (xy 418.937056 -382.089515) (xy 418.953032 -382.024132) (xy 418.976708 -381.961127)
			(xy 419.007745 -381.901403) (xy 419.045698 -381.845818) (xy 419.067488 -381.820166) (xy 419.07328 -381.813018)
			(xy 419.079798 -381.79583) (xy 419.080188 -381.786638) (xy 419.080188 -381.628904) (xy 419.080625 -381.618752)
			(xy 419.088417 -381.600002) (xy 419.102809 -381.585679) (xy 419.121596 -381.577977) (xy 419.13175 -381.577596)
			(xy 419.84803 -381.577596) (xy 419.858153 -381.578101) (xy 419.876867 -381.58583) (xy 419.89122 -381.60011)
			(xy 419.899046 -381.618783) (xy 419.899592 -381.628904) (xy 419.899592 -381.786638) (xy 419.899986 -381.795827)
			(xy 419.906511 -381.813011) (xy 419.912292 -381.820166) (xy 419.934069 -381.845827) (xy 419.972016 -381.901413)
			(xy 420.003048 -381.961135) (xy 420.02672 -382.024139) (xy 420.042693 -382.089519) (xy 420.050737 -382.156341)
			(xy 420.050738 -382.223644) (xy 420.050731 -382.223705) (xy 423.328802 -382.223705) (xy 423.328803 -382.15628)
			(xy 423.33688 -382.089342) (xy 423.352916 -382.023852) (xy 423.37668 -381.960755) (xy 423.407831 -381.900959)
			(xy 423.44592 -381.845324) (xy 423.467784 -381.819658) (xy 423.473579 -381.812512) (xy 423.480095 -381.795322)
			(xy 423.480484 -381.78613) (xy 423.480484 -381.628904) (xy 423.480988 -381.618798) (xy 423.488721 -381.600122)
			(xy 423.503012 -381.585828) (xy 423.521686 -381.57809) (xy 423.531792 -381.577596) (xy 424.248072 -381.577596)
			(xy 424.258192 -381.578039) (xy 424.276895 -381.585777) (xy 424.29121 -381.600085) (xy 424.298957 -381.618784)
			(xy 424.29938 -381.628904) (xy 424.29938 -381.78613) (xy 424.29978 -381.795318) (xy 424.306301 -381.812502)
			(xy 424.31208 -381.819658) (xy 424.333935 -381.845331) (xy 424.372025 -381.900964) (xy 424.403177 -381.960759)
			(xy 424.426943 -382.023855) (xy 424.44298 -382.089343) (xy 424.451057 -382.156281) (xy 424.451058 -382.223646)
			(xy 427.729097 -382.223646) (xy 427.729098 -382.156339) (xy 427.737144 -382.089515) (xy 427.753119 -382.024132)
			(xy 427.776794 -381.961127) (xy 427.807831 -381.901404) (xy 427.845783 -381.845818) (xy 427.867572 -381.820166)
			(xy 427.873374 -381.813025) (xy 427.879883 -381.795831) (xy 427.880272 -381.786638) (xy 427.880272 -381.628904)
			(xy 427.880724 -381.618754) (xy 427.888513 -381.600007) (xy 427.9029 -381.585684) (xy 427.921682 -381.577979)
			(xy 427.931834 -381.577596) (xy 428.648114 -381.577596) (xy 428.658236 -381.578114) (xy 428.676949 -381.585838)
			(xy 428.691303 -381.600114) (xy 428.69913 -381.618785) (xy 428.699676 -381.628904) (xy 428.699676 -381.786638)
			(xy 428.700073 -381.795826) (xy 428.706596 -381.81301) (xy 428.712376 -381.820166) (xy 428.734154 -381.845826)
			(xy 428.772102 -381.901412) (xy 428.803135 -381.961135) (xy 428.826807 -382.024138) (xy 428.84278 -382.089519)
			(xy 428.850825 -382.15634) (xy 428.850826 -382.223644) (xy 428.850826 -382.223646) (xy 432.128888 -382.223646)
			(xy 432.128889 -382.156339) (xy 432.136935 -382.089516) (xy 432.152909 -382.024133) (xy 432.176584 -381.961128)
			(xy 432.20762 -381.901404) (xy 432.245571 -381.845818) (xy 432.26736 -381.820166) (xy 432.273161 -381.813024)
			(xy 432.279671 -381.795831) (xy 432.28006 -381.786638) (xy 432.28006 -381.628904) (xy 432.280524 -381.618755)
			(xy 432.288311 -381.600011) (xy 432.302694 -381.585689) (xy 432.321471 -381.577981) (xy 432.331622 -381.577596)
			(xy 433.047902 -381.577596) (xy 433.058023 -381.578124) (xy 433.076736 -381.585844) (xy 433.091091 -381.600117)
			(xy 433.098918 -381.618786) (xy 433.099464 -381.628904) (xy 433.099464 -381.786638) (xy 433.099864 -381.795826)
			(xy 433.106386 -381.81301) (xy 433.112164 -381.820166) (xy 433.133942 -381.845826) (xy 433.171891 -381.901412)
			(xy 433.202924 -381.961134) (xy 433.226598 -382.024137) (xy 433.242571 -382.089519) (xy 433.250616 -382.15634)
			(xy 433.250617 -382.223645) (xy 433.242574 -382.290466) (xy 433.226602 -382.355848) (xy 433.202931 -382.418852)
			(xy 433.171899 -382.478576) (xy 433.133951 -382.534162) (xy 433.112164 -382.559814) (xy 433.106374 -382.566964)
			(xy 433.099856 -382.584151) (xy 433.099464 -382.593342) (xy 433.099464 -383.086864) (xy 433.0999 -383.096048)
			(xy 433.106397 -383.113232) (xy 433.112164 -383.120392) (xy 433.133967 -383.146031) (xy 433.171916 -383.20162)
			(xy 433.202948 -383.261345) (xy 433.226386 -383.323727) (xy 434.32903 -383.323727) (xy 434.329034 -383.256419)
			(xy 434.337081 -383.189595) (xy 434.353057 -383.124211) (xy 434.376732 -383.061205) (xy 434.407768 -383.00148)
			(xy 434.445719 -382.945893) (xy 434.467508 -382.92024) (xy 434.473313 -382.913101) (xy 434.479823 -382.895906)
			(xy 434.480208 -382.886712) (xy 434.480208 -382.728724) (xy 434.480641 -382.71857) (xy 434.48843 -382.699817)
			(xy 434.502824 -382.685492) (xy 434.521614 -382.677793) (xy 434.53177 -382.677416) (xy 435.24805 -382.677416)
			(xy 435.258171 -382.677967) (xy 435.276886 -382.685674) (xy 435.291243 -382.69994) (xy 435.299068 -382.718607)
			(xy 435.299612 -382.728724) (xy 435.299612 -382.886712) (xy 435.300014 -382.8959) (xy 435.306533 -382.913084)
			(xy 435.312312 -382.92024) (xy 435.334066 -382.945921) (xy 435.372019 -383.001502) (xy 435.403056 -383.061221)
			(xy 435.426733 -383.124222) (xy 435.44271 -383.189601) (xy 435.450758 -383.256421) (xy 435.450761 -383.323724)
			(xy 435.44272 -383.390546) (xy 435.426749 -383.455926) (xy 435.403079 -383.518929) (xy 435.372047 -383.578652)
			(xy 435.334099 -383.634237) (xy 435.312312 -383.659888) (xy 435.306497 -383.66702) (xy 435.299993 -383.684221)
			(xy 435.299612 -383.693416) (xy 435.299612 -384.186684) (xy 435.300027 -384.195871) (xy 435.306537 -384.213055)
			(xy 435.312312 -384.220212) (xy 435.334137 -384.245834) (xy 435.372087 -384.301424) (xy 435.403122 -384.361151)
			(xy 435.426795 -384.42416) (xy 435.442767 -384.489546) (xy 435.450809 -384.556373) (xy 435.450805 -384.623681)
			(xy 435.442757 -384.690507) (xy 435.426779 -384.755892) (xy 435.4031 -384.818898) (xy 435.37206 -384.878623)
			(xy 435.334103 -384.934208) (xy 435.312312 -384.95986) (xy 435.306509 -384.967001) (xy 435.299998 -384.984195)
			(xy 435.299612 -384.993388) (xy 435.299612 -385.151376) (xy 435.299159 -385.161527) (xy 435.291374 -385.180277)
			(xy 435.276987 -385.194601) (xy 435.258203 -385.202303) (xy 435.24805 -385.202684) (xy 434.53177 -385.202684)
			(xy 434.521644 -385.202199) (xy 434.502927 -385.194466) (xy 434.488573 -385.180179) (xy 434.48075 -385.161499)
			(xy 434.480208 -385.151376) (xy 434.480208 -384.993388) (xy 434.479802 -384.9842) (xy 434.473285 -384.967016)
			(xy 434.467508 -384.95986) (xy 434.445757 -384.934178) (xy 434.407809 -384.878595) (xy 434.376776 -384.818876)
			(xy 434.353102 -384.755875) (xy 434.337128 -384.690497) (xy 434.329081 -384.623678) (xy 434.329078 -384.556376)
			(xy 434.337118 -384.489557) (xy 434.353086 -384.424177) (xy 434.376753 -384.361174) (xy 434.407781 -384.301451)
			(xy 434.445723 -384.245864) (xy 434.467508 -384.220212) (xy 434.473325 -384.213082) (xy 434.479827 -384.19588)
			(xy 434.480208 -384.186684) (xy 434.480208 -383.693416) (xy 434.479788 -383.68423) (xy 434.473281 -383.667046)
			(xy 434.467508 -383.659888) (xy 434.445686 -383.634265) (xy 434.40774 -383.578673) (xy 434.37671 -383.518945)
			(xy 434.353041 -383.455937) (xy 434.337071 -383.390552) (xy 434.32903 -383.323727) (xy 433.226386 -383.323727)
			(xy 433.22662 -383.324351) (xy 433.242592 -383.389735) (xy 433.250634 -383.456559) (xy 433.250633 -383.523865)
			(xy 433.242587 -383.590689) (xy 433.226613 -383.656072) (xy 433.202938 -383.719077) (xy 433.171903 -383.778801)
			(xy 433.133953 -383.834388) (xy 433.112164 -383.86004) (xy 433.106363 -383.867182) (xy 433.099852 -383.884375)
			(xy 433.099464 -383.893568) (xy 433.099464 -384.051556) (xy 433.099042 -384.061712) (xy 433.091254 -384.08047)
			(xy 433.076856 -384.094796) (xy 433.05806 -384.102491) (xy 433.047902 -384.102864) (xy 432.331622 -384.102864)
			(xy 432.321497 -384.102356) (xy 432.302777 -384.094636) (xy 432.28842 -384.080356) (xy 432.2806 -384.061678)
			(xy 432.28006 -384.051556) (xy 432.28006 -383.893568) (xy 432.279652 -383.884381) (xy 432.273135 -383.867197)
			(xy 432.26736 -383.86004) (xy 432.245587 -383.834375) (xy 432.207637 -383.778791) (xy 432.176602 -383.719069)
			(xy 432.152927 -383.656066) (xy 432.136952 -383.590686) (xy 432.128907 -383.523864) (xy 432.128905 -383.45656)
			(xy 432.136948 -383.389738) (xy 432.15292 -383.324357) (xy 432.176592 -383.261353) (xy 432.207624 -383.20163)
			(xy 432.245573 -383.146044) (xy 432.26736 -383.120392) (xy 432.27315 -383.113242) (xy 432.279667 -383.096055)
			(xy 432.28006 -383.086864) (xy 432.28006 -382.593342) (xy 432.279616 -382.584159) (xy 432.273125 -382.566975)
			(xy 432.26736 -382.559814) (xy 432.245562 -382.53417) (xy 432.207612 -382.478583) (xy 432.176578 -382.418858)
			(xy 432.152905 -382.355853) (xy 432.136932 -382.290469) (xy 432.128888 -382.223646) (xy 428.850826 -382.223646)
			(xy 428.842783 -382.290466) (xy 428.826812 -382.355848) (xy 428.803141 -382.418852) (xy 428.772109 -382.478575)
			(xy 428.734163 -382.534162) (xy 428.712376 -382.559814) (xy 428.706588 -382.566965) (xy 428.700069 -382.584151)
			(xy 428.699676 -382.593342) (xy 428.699676 -383.086864) (xy 428.700109 -383.096049) (xy 428.706607 -383.113233)
			(xy 428.712376 -383.120392) (xy 428.734179 -383.146031) (xy 428.772126 -383.20162) (xy 428.803158 -383.261345)
			(xy 428.826616 -383.323786) (xy 429.928711 -383.323786) (xy 429.928714 -383.25636) (xy 429.936794 -383.189418)
			(xy 429.952834 -383.123927) (xy 429.976603 -383.060829) (xy 430.007759 -383.001032) (xy 430.045853 -382.945397)
			(xy 430.06772 -382.919732) (xy 430.07353 -382.912597) (xy 430.080036 -382.895398) (xy 430.08042 -382.886204)
			(xy 430.08042 -382.728724) (xy 430.080836 -382.718601) (xy 430.08858 -382.699894) (xy 430.102897 -382.685578)
			(xy 430.121605 -382.677835) (xy 430.131728 -382.677416) (xy 430.848008 -382.677416) (xy 430.858133 -382.67781)
			(xy 430.87684 -382.685564) (xy 430.891154 -382.699887) (xy 430.898896 -382.718599) (xy 430.899316 -382.728724)
			(xy 430.899316 -382.886204) (xy 430.899721 -382.895392) (xy 430.906238 -382.912576) (xy 430.912016 -382.919732)
			(xy 430.933844 -382.945427) (xy 430.971933 -383.001057) (xy 431.003084 -383.06085) (xy 431.02685 -383.123943)
			(xy 431.042887 -383.189428) (xy 431.050966 -383.256363) (xy 431.050969 -383.323783) (xy 431.042897 -383.390719)
			(xy 431.026866 -383.456206) (xy 431.003106 -383.519301) (xy 430.971961 -383.579096) (xy 430.933877 -383.634731)
			(xy 430.912016 -383.660396) (xy 430.90624 -383.667556) (xy 430.899713 -383.684735) (xy 430.899316 -383.693924)
			(xy 430.899316 -384.186176) (xy 430.899734 -384.195362) (xy 430.906242 -384.212547) (xy 430.912016 -384.219704)
			(xy 430.933915 -384.24534) (xy 430.972001 -384.300979) (xy 431.00315 -384.36078) (xy 431.026911 -384.42388)
			(xy 431.042944 -384.489373) (xy 431.051016 -384.556314) (xy 431.051013 -384.62374) (xy 431.042934 -384.690681)
			(xy 431.026895 -384.756171) (xy 431.003128 -384.81927) (xy 430.971974 -384.879067) (xy 430.933882 -384.934702)
			(xy 430.912016 -384.960368) (xy 430.90621 -384.967507) (xy 430.8997 -384.984702) (xy 430.899316 -384.993896)
			(xy 430.899316 -385.151376) (xy 430.898865 -385.161495) (xy 430.891128 -385.180195) (xy 430.876822 -385.19451)
			(xy 430.858127 -385.202259) (xy 430.848008 -385.202684) (xy 430.131728 -385.202684) (xy 430.121605 -385.202261)
			(xy 430.102899 -385.194519) (xy 430.088583 -385.180204) (xy 430.08084 -385.161499) (xy 430.08042 -385.151376)
			(xy 430.08042 -384.993896) (xy 430.080008 -384.984709) (xy 430.073495 -384.967525) (xy 430.06772 -384.960368)
			(xy 430.045891 -384.934674) (xy 430.0078 -384.879044) (xy 429.976646 -384.819252) (xy 429.952879 -384.756159)
			(xy 429.936841 -384.690673) (xy 429.928761 -384.623738) (xy 429.928758 -384.556316) (xy 429.936831 -384.48938)
			(xy 429.952863 -384.423893) (xy 429.976624 -384.360797) (xy 430.007772 -384.301002) (xy 430.045857 -384.245369)
			(xy 430.06772 -384.219704) (xy 430.0735 -384.212547) (xy 430.080024 -384.195365) (xy 430.08042 -384.186176)
			(xy 430.08042 -383.693924) (xy 430.079994 -383.684739) (xy 430.073491 -383.667554) (xy 430.06772 -383.660396)
			(xy 430.04582 -383.63476) (xy 430.007731 -383.579122) (xy 429.976581 -383.519322) (xy 429.952818 -383.456221)
			(xy 429.936784 -383.390728) (xy 429.928711 -383.323786) (xy 428.826616 -383.323786) (xy 428.826829 -383.324352)
			(xy 428.842801 -383.389735) (xy 428.850843 -383.456559) (xy 428.850842 -383.523865) (xy 428.842797 -383.590688)
			(xy 428.826822 -383.656071) (xy 428.803148 -383.719077) (xy 428.772114 -383.778801) (xy 428.734164 -383.834388)
			(xy 428.712376 -383.86004) (xy 428.706577 -383.867183) (xy 428.700065 -383.884375) (xy 428.699676 -383.893568)
			(xy 428.699676 -384.051556) (xy 428.699242 -384.06171) (xy 428.691456 -384.080466) (xy 428.677063 -384.094792)
			(xy 428.65827 -384.102489) (xy 428.648114 -384.102864) (xy 427.931834 -384.102864) (xy 427.92171 -384.102345)
			(xy 427.90299 -384.09463) (xy 427.888633 -384.080353) (xy 427.880812 -384.061677) (xy 427.880272 -384.051556)
			(xy 427.880272 -383.893568) (xy 427.879883 -383.884378) (xy 427.873355 -383.867194) (xy 427.867572 -383.86004)
			(xy 427.845799 -383.834375) (xy 427.807848 -383.778791) (xy 427.776812 -383.71907) (xy 427.753137 -383.656067)
			(xy 427.737162 -383.590686) (xy 427.729116 -383.523864) (xy 427.729114 -383.45656) (xy 427.737157 -383.389738)
			(xy 427.75313 -383.324356) (xy 427.776802 -383.261352) (xy 427.807835 -383.201629) (xy 427.845784 -383.146044)
			(xy 427.867572 -383.120392) (xy 427.873363 -383.113243) (xy 427.879879 -383.096055) (xy 427.880272 -383.086864)
			(xy 427.880272 -382.593342) (xy 427.879848 -382.584156) (xy 427.873344 -382.566971) (xy 427.867572 -382.559814)
			(xy 427.845774 -382.53417) (xy 427.807823 -382.478583) (xy 427.776788 -382.418859) (xy 427.753115 -382.355853)
			(xy 427.737141 -382.29047) (xy 427.729097 -382.223646) (xy 424.451058 -382.223646) (xy 424.451058 -382.223704)
			(xy 424.442983 -382.290642) (xy 424.426948 -382.356131) (xy 424.403184 -382.419227) (xy 424.372033 -382.479023)
			(xy 424.333944 -382.534657) (xy 424.31208 -382.560322) (xy 424.306289 -382.567471) (xy 424.299772 -382.584659)
			(xy 424.29938 -382.59385) (xy 424.29938 -383.086356) (xy 424.299816 -383.09554) (xy 424.306312 -383.112725)
			(xy 424.31208 -383.119884) (xy 424.33396 -383.145536) (xy 424.37205 -383.201172) (xy 424.403201 -383.26097)
			(xy 424.426837 -383.323727) (xy 425.528942 -383.323727) (xy 425.528946 -383.256419) (xy 425.536993 -383.189594)
			(xy 425.55297 -383.12421) (xy 425.576646 -383.061204) (xy 425.607682 -383.00148) (xy 425.645635 -382.945892)
			(xy 425.667424 -382.92024) (xy 425.673231 -382.913103) (xy 425.679739 -382.895906) (xy 425.680124 -382.886712)
			(xy 425.680124 -382.728724) (xy 425.680542 -382.718568) (xy 425.688334 -382.699812) (xy 425.702732 -382.685487)
			(xy 425.721528 -382.67779) (xy 425.731686 -382.677416) (xy 426.447966 -382.677416) (xy 426.458088 -382.677954)
			(xy 426.476803 -382.685666) (xy 426.49116 -382.699937) (xy 426.498984 -382.718606) (xy 426.499528 -382.728724)
			(xy 426.499528 -382.886712) (xy 426.499926 -382.895901) (xy 426.506447 -382.913085) (xy 426.512228 -382.92024)
			(xy 426.533981 -382.945921) (xy 426.571933 -383.001502) (xy 426.60297 -383.061222) (xy 426.626646 -383.124223)
			(xy 426.642623 -383.189602) (xy 426.65067 -383.256422) (xy 426.650673 -383.323724) (xy 426.642632 -383.390545)
			(xy 426.626662 -383.455926) (xy 426.602992 -383.518929) (xy 426.571961 -383.578651) (xy 426.534014 -383.634236)
			(xy 426.512228 -383.659888) (xy 426.506403 -383.667013) (xy 426.499907 -383.684219) (xy 426.499528 -383.693416)
			(xy 426.499528 -384.186684) (xy 426.499939 -384.195871) (xy 426.506451 -384.213056) (xy 426.512228 -384.220212)
			(xy 426.534052 -384.245834) (xy 426.572002 -384.301424) (xy 426.603036 -384.361152) (xy 426.626708 -384.42416)
			(xy 426.64268 -384.489546) (xy 426.650721 -384.556373) (xy 426.650718 -384.623681) (xy 426.64267 -384.690507)
			(xy 426.626692 -384.755892) (xy 426.603014 -384.818898) (xy 426.571974 -384.878622) (xy 426.534019 -384.934208)
			(xy 426.512228 -384.95986) (xy 426.506415 -384.966993) (xy 426.499912 -384.984193) (xy 426.499528 -384.993388)
			(xy 426.499528 -385.151376) (xy 426.499059 -385.161525) (xy 426.491277 -385.180272) (xy 426.476895 -385.194595)
			(xy 426.458117 -385.202301) (xy 426.447966 -385.202684) (xy 425.731686 -385.202684) (xy 425.721561 -385.202185)
			(xy 425.702845 -385.194457) (xy 425.68849 -385.180175) (xy 425.680667 -385.161498) (xy 425.680124 -385.151376)
			(xy 425.680124 -384.993388) (xy 425.679714 -384.984201) (xy 425.6732 -384.967017) (xy 425.667424 -384.95986)
			(xy 425.645672 -384.934178) (xy 425.607723 -384.878596) (xy 425.576689 -384.818876) (xy 425.553015 -384.755876)
			(xy 425.53704 -384.690497) (xy 425.528994 -384.623678) (xy 425.52899 -384.556376) (xy 425.537031 -384.489556)
			(xy 425.552999 -384.424176) (xy 425.576667 -384.361173) (xy 425.607696 -384.301451) (xy 425.645639 -384.245865)
			(xy 425.667424 -384.220212) (xy 425.673243 -384.213083) (xy 425.679744 -384.19588) (xy 425.680124 -384.186684)
			(xy 425.680124 -383.693416) (xy 425.679701 -383.68423) (xy 425.673195 -383.667046) (xy 425.667424 -383.659888)
			(xy 425.645601 -383.634265) (xy 425.607655 -383.578674) (xy 425.576624 -383.518946) (xy 425.552954 -383.455938)
			(xy 425.536984 -383.390552) (xy 425.528942 -383.323727) (xy 424.426837 -383.323727) (xy 424.426965 -383.324068)
			(xy 424.443 -383.389559) (xy 424.451075 -383.456499) (xy 424.451074 -383.523925) (xy 424.442996 -383.590864)
			(xy 424.426958 -383.656355) (xy 424.403191 -383.719452) (xy 424.372038 -383.779249) (xy 424.333946 -383.834883)
			(xy 424.31208 -383.860548) (xy 424.306278 -383.867689) (xy 424.299767 -383.884883) (xy 424.29938 -383.894076)
			(xy 424.29938 -384.051556) (xy 424.298947 -384.061678) (xy 424.29121 -384.080385) (xy 424.276898 -384.094701)
			(xy 424.258194 -384.102444) (xy 424.248072 -384.102864) (xy 423.531792 -384.102864) (xy 423.521665 -384.10249)
			(xy 423.502954 -384.094732) (xy 423.488639 -384.080402) (xy 423.4809 -384.061684) (xy 423.480484 -384.051556)
			(xy 423.480484 -383.894076) (xy 423.480089 -383.884887) (xy 423.473565 -383.867703) (xy 423.467784 -383.860548)
			(xy 423.445936 -383.83487) (xy 423.407848 -383.779237) (xy 423.376698 -383.719442) (xy 423.352933 -383.656347)
			(xy 423.336897 -383.59086) (xy 423.32882 -383.523923) (xy 423.328819 -383.456501) (xy 423.336893 -383.389564)
			(xy 423.352926 -383.324076) (xy 423.376688 -383.26098) (xy 423.407836 -383.201184) (xy 423.445922 -383.145549)
			(xy 423.467784 -383.119884) (xy 423.473568 -383.11273) (xy 423.480091 -383.095546) (xy 423.480484 -383.086356)
			(xy 423.480484 -382.59385) (xy 423.480054 -382.584665) (xy 423.473554 -382.56748) (xy 423.467784 -382.560322)
			(xy 423.445911 -382.534665) (xy 423.407823 -382.479029) (xy 423.376674 -382.419231) (xy 423.352911 -382.356133)
			(xy 423.336877 -382.290643) (xy 423.328802 -382.223705) (xy 420.050731 -382.223705) (xy 420.042695 -382.290466)
			(xy 420.026725 -382.355847) (xy 420.003054 -382.418851) (xy 419.972024 -382.478574) (xy 419.934078 -382.534161)
			(xy 419.912292 -382.559814) (xy 419.906506 -382.566967) (xy 419.899985 -382.584151) (xy 419.899592 -382.593342)
			(xy 419.899592 -383.086864) (xy 419.900021 -383.096049) (xy 419.906522 -383.113234) (xy 419.912292 -383.120392)
			(xy 419.934094 -383.146032) (xy 419.972041 -383.201621) (xy 420.003072 -383.261346) (xy 420.02653 -383.323787)
			(xy 421.128623 -383.323787) (xy 421.128626 -383.256359) (xy 421.136706 -383.189418) (xy 421.152747 -383.123926)
			(xy 421.176516 -383.060828) (xy 421.207673 -383.001031) (xy 421.245769 -382.945397) (xy 421.267636 -382.919732)
			(xy 421.273449 -382.912598) (xy 421.279953 -382.895399) (xy 421.280336 -382.886204) (xy 421.280336 -382.728724)
			(xy 421.280736 -382.718599) (xy 421.288483 -382.699889) (xy 421.302805 -382.685572) (xy 421.321518 -382.677832)
			(xy 421.331644 -382.677416) (xy 422.047924 -382.677416) (xy 422.058036 -382.677866) (xy 422.076718 -382.685614)
			(xy 422.091013 -382.699922) (xy 422.098744 -382.718611) (xy 422.099232 -382.728724) (xy 422.099232 -382.886204)
			(xy 422.099656 -382.895389) (xy 422.106162 -382.912573) (xy 422.111932 -382.919732) (xy 422.133759 -382.945427)
			(xy 422.171847 -383.001058) (xy 422.202998 -383.06085) (xy 422.226762 -383.123943) (xy 422.242799 -383.189428)
			(xy 422.250878 -383.256363) (xy 422.250881 -383.323783) (xy 422.242809 -383.390718) (xy 422.226778 -383.456205)
			(xy 422.20302 -383.5193) (xy 422.171875 -383.579096) (xy 422.133793 -383.63473) (xy 422.111932 -383.660396)
			(xy 422.106146 -383.667549) (xy 422.099627 -383.684734) (xy 422.099232 -383.693924) (xy 422.099232 -384.186176)
			(xy 422.099669 -384.19536) (xy 422.106166 -384.212544) (xy 422.111932 -384.219704) (xy 422.13383 -384.245341)
			(xy 422.171916 -384.30098) (xy 422.203063 -384.36078) (xy 422.226824 -384.423881) (xy 422.242856 -384.489373)
			(xy 422.250928 -384.556314) (xy 422.250925 -384.62374) (xy 422.242846 -384.69068) (xy 422.226808 -384.756171)
			(xy 422.203041 -384.819269) (xy 422.171888 -384.879066) (xy 422.133797 -384.934702) (xy 422.111932 -384.960368)
			(xy 422.106116 -384.967499) (xy 422.099615 -384.984701) (xy 422.099232 -384.993896) (xy 422.099232 -385.151376)
			(xy 422.098696 -385.161479) (xy 422.090972 -385.180151) (xy 422.076691 -385.194445) (xy 422.058027 -385.202187)
			(xy 422.047924 -385.202684) (xy 421.331644 -385.202684) (xy 421.321522 -385.202247) (xy 421.302817 -385.194511)
			(xy 421.2885 -385.1802) (xy 421.280756 -385.161497) (xy 421.280336 -385.151376) (xy 421.280336 -384.993896)
			(xy 421.27992 -384.98471) (xy 421.27341 -384.967526) (xy 421.267636 -384.960368) (xy 421.245806 -384.934674)
			(xy 421.207714 -384.879045) (xy 421.17656 -384.819253) (xy 421.152792 -384.756159) (xy 421.136753 -384.690673)
			(xy 421.128674 -384.623738) (xy 421.12867 -384.556316) (xy 421.136743 -384.48938) (xy 421.152776 -384.423892)
			(xy 421.176538 -384.360797) (xy 421.207686 -384.301002) (xy 421.245773 -384.245369) (xy 421.267636 -384.219704)
			(xy 421.273418 -384.212549) (xy 421.27994 -384.195366) (xy 421.280336 -384.186176) (xy 421.280336 -383.693924)
			(xy 421.279906 -383.684739) (xy 421.273405 -383.667555) (xy 421.267636 -383.660396) (xy 421.245735 -383.634761)
			(xy 421.207645 -383.579123) (xy 421.176494 -383.519323) (xy 421.152731 -383.456222) (xy 421.136696 -383.390729)
			(xy 421.128623 -383.323787) (xy 420.02653 -383.323787) (xy 420.026742 -383.324352) (xy 420.042713 -383.389736)
			(xy 420.050756 -383.456559) (xy 420.050754 -383.523865) (xy 420.042709 -383.590688) (xy 420.026735 -383.656071)
			(xy 420.003062 -383.719076) (xy 419.972028 -383.7788) (xy 419.93408 -383.834387) (xy 419.912292 -383.86004)
			(xy 419.906495 -383.867185) (xy 419.899981 -383.884376) (xy 419.899592 -383.893568) (xy 419.899592 -384.051556)
			(xy 419.899142 -384.061708) (xy 419.89136 -384.080461) (xy 419.876971 -384.094786) (xy 419.858184 -384.102486)
			(xy 419.84803 -384.102864) (xy 419.13175 -384.102864) (xy 419.121627 -384.102333) (xy 419.102908 -384.094622)
			(xy 419.08855 -384.080349) (xy 419.080728 -384.061676) (xy 419.080188 -384.051556) (xy 419.080188 -383.893568)
			(xy 419.079796 -383.884379) (xy 419.07327 -383.867194) (xy 419.067488 -383.86004) (xy 419.045715 -383.834376)
			(xy 419.007762 -383.778792) (xy 418.976725 -383.719071) (xy 418.95305 -383.656068) (xy 418.937074 -383.590686)
			(xy 418.929028 -383.523864) (xy 418.929026 -383.45656) (xy 418.93707 -383.389737) (xy 418.953042 -383.324355)
			(xy 418.976716 -383.261351) (xy 419.00775 -383.201629) (xy 419.0457 -383.146043) (xy 419.067488 -383.120392)
			(xy 419.073269 -383.113236) (xy 419.079793 -383.096054) (xy 419.080188 -383.086864) (xy 419.080188 -382.593342)
			(xy 419.07976 -382.584157) (xy 419.073259 -382.566972) (xy 419.067488 -382.559814) (xy 419.045689 -382.534171)
			(xy 419.007737 -382.478584) (xy 418.976702 -382.41886) (xy 418.953027 -382.355854) (xy 418.937054 -382.29047)
			(xy 418.92901 -382.223646) (xy 389.250707 -382.223646) (xy 389.242664 -382.290467) (xy 389.226692 -382.355848)
			(xy 389.20302 -382.418853) (xy 389.171987 -382.478576) (xy 389.134039 -382.534162) (xy 389.112252 -382.559814)
			(xy 389.106461 -382.566963) (xy 389.099944 -382.584151) (xy 389.099552 -382.593342) (xy 389.099552 -383.086864)
			(xy 389.09999 -383.096048) (xy 389.106485 -383.113232) (xy 389.112252 -383.120392) (xy 389.134056 -383.146031)
			(xy 389.172005 -383.201619) (xy 389.203038 -383.261344) (xy 389.226475 -383.323726) (xy 390.329121 -383.323726)
			(xy 390.329125 -383.256419) (xy 390.337172 -383.189595) (xy 390.353147 -383.124211) (xy 390.376822 -383.061206)
			(xy 390.407857 -383.001481) (xy 390.445807 -382.945893) (xy 390.467596 -382.92024) (xy 390.4734 -382.9131)
			(xy 390.47991 -382.895906) (xy 390.480296 -382.886712) (xy 390.480296 -382.728724) (xy 390.480741 -382.718572)
			(xy 390.488528 -382.699821) (xy 390.502918 -382.685497) (xy 390.521704 -382.677795) (xy 390.531858 -382.677416)
			(xy 391.248138 -382.677416) (xy 391.258264 -382.677895) (xy 391.276982 -382.685631) (xy 391.291336 -382.699919)
			(xy 391.299158 -382.7186) (xy 391.2997 -382.728724) (xy 391.2997 -382.886712) (xy 391.300105 -382.8959)
			(xy 391.306622 -382.913084) (xy 391.3124 -382.92024) (xy 391.334151 -382.945922) (xy 391.372099 -383.001505)
			(xy 391.403131 -383.061225) (xy 391.426804 -383.124225) (xy 391.442779 -383.189603) (xy 391.450825 -383.256422)
			(xy 391.450828 -383.323724) (xy 391.442788 -383.390543) (xy 391.42682 -383.455923) (xy 391.403153 -383.518926)
			(xy 391.372126 -383.578649) (xy 391.334184 -383.634235) (xy 391.3124 -383.659888) (xy 391.306584 -383.667019)
			(xy 391.300081 -383.68422) (xy 391.2997 -383.693416) (xy 391.2997 -384.186684) (xy 391.300118 -384.19587)
			(xy 391.306626 -384.213055) (xy 391.3124 -384.220212) (xy 391.334222 -384.245836) (xy 391.372167 -384.301427)
			(xy 391.403197 -384.361155) (xy 391.426866 -384.424163) (xy 391.442835 -384.489548) (xy 391.450876 -384.556374)
			(xy 391.450872 -384.623681) (xy 391.442825 -384.690505) (xy 391.42685 -384.755889) (xy 391.403175 -384.818895)
			(xy 391.372139 -384.878619) (xy 391.334189 -384.934207) (xy 391.3124 -384.95986) (xy 391.306595 -384.967)
			(xy 391.300086 -384.984194) (xy 391.2997 -384.993388) (xy 391.2997 -385.151376) (xy 391.299259 -385.161529)
			(xy 391.291471 -385.180281) (xy 391.27708 -385.194605) (xy 391.258292 -385.202305) (xy 391.248138 -385.202684)
			(xy 390.531858 -385.202684) (xy 390.521732 -385.202209) (xy 390.503014 -385.194471) (xy 390.48866 -385.180182)
			(xy 390.480838 -385.1615) (xy 390.480296 -385.151376) (xy 390.480296 -384.993388) (xy 390.479892 -384.9842)
			(xy 390.473374 -384.967016) (xy 390.467596 -384.95986) (xy 390.445845 -384.934178) (xy 390.407898 -384.878595)
			(xy 390.376865 -384.818875) (xy 390.353192 -384.755875) (xy 390.337218 -384.690496) (xy 390.329172 -384.623678)
			(xy 390.329169 -384.556376) (xy 390.337209 -384.489557) (xy 390.353176 -384.424177) (xy 390.376843 -384.361174)
			(xy 390.40787 -384.301452) (xy 390.445812 -384.245865) (xy 390.467596 -384.220212) (xy 390.473412 -384.21308)
			(xy 390.479915 -384.19588) (xy 390.480296 -384.186684) (xy 390.480296 -383.693416) (xy 390.479879 -383.68423)
			(xy 390.47337 -383.667045) (xy 390.467596 -383.659888) (xy 390.445774 -383.634264) (xy 390.407829 -383.578673)
			(xy 390.3768 -383.518945) (xy 390.353131 -383.455937) (xy 390.337162 -383.390552) (xy 390.329121 -383.323726)
			(xy 389.226475 -383.323726) (xy 389.22671 -383.324351) (xy 389.242682 -383.389735) (xy 389.250725 -383.456559)
			(xy 389.250724 -383.523865) (xy 389.242678 -383.590689) (xy 389.226703 -383.656072) (xy 389.203028 -383.719078)
			(xy 389.171992 -383.778802) (xy 389.134041 -383.834388) (xy 389.112252 -383.86004) (xy 389.10645 -383.867181)
			(xy 389.09994 -383.884375) (xy 389.099552 -383.893568) (xy 389.099552 -384.051556) (xy 389.099043 -384.061701)
			(xy 389.091272 -384.080442) (xy 389.076902 -384.094765) (xy 389.058136 -384.102476) (xy 389.04799 -384.102864)
			(xy 388.33171 -384.102864) (xy 388.321584 -384.102365) (xy 388.302864 -384.094642) (xy 388.288508 -384.080359)
			(xy 388.280687 -384.061679) (xy 388.280148 -384.051556) (xy 388.280148 -383.893568) (xy 388.279742 -383.884381)
			(xy 388.273224 -383.867197) (xy 388.267448 -383.86004) (xy 388.245676 -383.834375) (xy 388.207726 -383.778791)
			(xy 388.176692 -383.719069) (xy 388.153018 -383.656066) (xy 388.137043 -383.590685) (xy 388.128998 -383.523864)
			(xy 388.128996 -383.45656) (xy 388.137039 -383.389738) (xy 388.15301 -383.324357) (xy 388.176682 -383.261353)
			(xy 388.207714 -383.20163) (xy 388.245661 -383.146044) (xy 388.267448 -383.120392) (xy 388.273236 -383.113241)
			(xy 388.279755 -383.096055) (xy 388.280148 -383.086864) (xy 388.280148 -382.593342) (xy 388.279707 -382.584158)
			(xy 388.273213 -382.566974) (xy 388.267448 -382.559814) (xy 388.24565 -382.53417) (xy 388.207701 -382.478583)
			(xy 388.176668 -382.418858) (xy 388.152995 -382.355852) (xy 388.137022 -382.290469) (xy 388.128979 -382.223645)
			(xy 384.850917 -382.223645) (xy 384.842874 -382.290466) (xy 384.826902 -382.355848) (xy 384.803231 -382.418852)
			(xy 384.772199 -382.478576) (xy 384.734251 -382.534162) (xy 384.712464 -382.559814) (xy 384.706674 -382.566964)
			(xy 384.700156 -382.584151) (xy 384.699764 -382.593342) (xy 384.699764 -383.086864) (xy 384.7002 -383.096048)
			(xy 384.706697 -383.113232) (xy 384.712464 -383.120392) (xy 384.734267 -383.146031) (xy 384.772216 -383.20162)
			(xy 384.803248 -383.261345) (xy 384.826708 -383.323786) (xy 385.928802 -383.323786) (xy 385.928805 -383.25636)
			(xy 385.936885 -383.189419) (xy 385.952924 -383.123928) (xy 385.976693 -383.060829) (xy 386.007848 -383.001032)
			(xy 386.045942 -382.945397) (xy 386.067808 -382.919732) (xy 386.073617 -382.912596) (xy 386.080124 -382.895398)
			(xy 386.080508 -382.886204) (xy 386.080508 -382.728724) (xy 386.080936 -382.718602) (xy 386.088677 -382.699897)
			(xy 386.102991 -382.685582) (xy 386.121694 -382.677837) (xy 386.131816 -382.677416) (xy 386.848096 -382.677416)
			(xy 386.85822 -382.67782) (xy 386.876927 -382.685569) (xy 386.891242 -382.69989) (xy 386.898984 -382.7186)
			(xy 386.899404 -382.728724) (xy 386.899404 -382.886204) (xy 386.899811 -382.895391) (xy 386.906327 -382.912576)
			(xy 386.912104 -382.919732) (xy 386.933932 -382.945426) (xy 386.972022 -383.001057) (xy 387.003174 -383.060849)
			(xy 387.02694 -383.123942) (xy 387.042978 -383.189428) (xy 387.051057 -383.256363) (xy 387.05106 -383.323783)
			(xy 387.042988 -383.390719) (xy 387.026956 -383.456206) (xy 387.003196 -383.519301) (xy 386.97205 -383.579097)
			(xy 386.933966 -383.634731) (xy 386.912104 -383.660396) (xy 386.906327 -383.667555) (xy 386.899801 -383.684735)
			(xy 386.899404 -383.693924) (xy 386.899404 -384.186176) (xy 386.899825 -384.195362) (xy 386.906331 -384.212547)
			(xy 386.912104 -384.219704) (xy 386.934003 -384.24534) (xy 386.972091 -384.300979) (xy 387.003239 -384.360779)
			(xy 387.027001 -384.42388) (xy 387.043034 -384.489372) (xy 387.051107 -384.556314) (xy 387.051104 -384.62374)
			(xy 387.043025 -384.690681) (xy 387.026985 -384.756172) (xy 387.003217 -384.81927) (xy 386.972063 -384.879068)
			(xy 386.93397 -384.934703) (xy 386.912104 -384.960368) (xy 386.906297 -384.967506) (xy 386.899788 -384.984702)
			(xy 386.899404 -384.993896) (xy 386.899404 -385.151376) (xy 386.898965 -385.161496) (xy 386.891225 -385.180199)
			(xy 386.876916 -385.194514) (xy 386.858216 -385.202261) (xy 386.848096 -385.202684) (xy 386.131816 -385.202684)
			(xy 386.121693 -385.202271) (xy 386.102986 -385.194525) (xy 386.088671 -385.180207) (xy 386.080928 -385.1615)
			(xy 386.080508 -385.151376) (xy 386.080508 -384.993896) (xy 386.080098 -384.984709) (xy 386.073584 -384.967525)
			(xy 386.067808 -384.960368) (xy 386.045979 -384.934674) (xy 386.007889 -384.879044) (xy 385.976736 -384.819251)
			(xy 385.95297 -384.756158) (xy 385.936931 -384.690673) (xy 385.928852 -384.623738) (xy 385.928849 -384.556317)
			(xy 385.936922 -384.489381) (xy 385.952954 -384.423893) (xy 385.976714 -384.360798) (xy 386.007861 -384.301003)
			(xy 386.045946 -384.245369) (xy 386.067808 -384.219704) (xy 386.073586 -384.212546) (xy 386.080112 -384.195365)
			(xy 386.080508 -384.186176) (xy 386.080508 -383.693924) (xy 386.080084 -383.684738) (xy 386.07358 -383.667554)
			(xy 386.067808 -383.660396) (xy 386.045908 -383.63476) (xy 386.00782 -383.579122) (xy 385.976671 -383.519321)
			(xy 385.952908 -383.456221) (xy 385.936875 -383.390728) (xy 385.928802 -383.323786) (xy 384.826708 -383.323786)
			(xy 384.82692 -383.324351) (xy 384.842892 -383.389735) (xy 384.850934 -383.456559) (xy 384.850933 -383.523865)
			(xy 384.842887 -383.590689) (xy 384.826913 -383.656072) (xy 384.803238 -383.719077) (xy 384.772203 -383.778801)
			(xy 384.734253 -383.834388) (xy 384.712464 -383.86004) (xy 384.706663 -383.867182) (xy 384.700152 -383.884375)
			(xy 384.699764 -383.893568) (xy 384.699764 -384.051556) (xy 384.699342 -384.061712) (xy 384.691554 -384.08047)
			(xy 384.677156 -384.094796) (xy 384.65836 -384.102491) (xy 384.648202 -384.102864) (xy 383.931922 -384.102864)
			(xy 383.921797 -384.102356) (xy 383.903077 -384.094636) (xy 383.88872 -384.080356) (xy 383.8809 -384.061678)
			(xy 383.88036 -384.051556) (xy 383.88036 -383.893568) (xy 383.879952 -383.884381) (xy 383.873435 -383.867197)
			(xy 383.86766 -383.86004) (xy 383.845887 -383.834375) (xy 383.807937 -383.778791) (xy 383.776902 -383.719069)
			(xy 383.753227 -383.656066) (xy 383.737252 -383.590686) (xy 383.729207 -383.523864) (xy 383.729205 -383.45656)
			(xy 383.737248 -383.389738) (xy 383.75322 -383.324357) (xy 383.776892 -383.261353) (xy 383.807924 -383.20163)
			(xy 383.845873 -383.146044) (xy 383.86766 -383.120392) (xy 383.87345 -383.113242) (xy 383.879967 -383.096055)
			(xy 383.88036 -383.086864) (xy 383.88036 -382.593342) (xy 383.879916 -382.584159) (xy 383.873425 -382.566975)
			(xy 383.86766 -382.559814) (xy 383.845862 -382.53417) (xy 383.807912 -382.478583) (xy 383.776878 -382.418858)
			(xy 383.753205 -382.355853) (xy 383.737232 -382.290469) (xy 383.729188 -382.223646) (xy 380.451149 -382.223646)
			(xy 380.451149 -382.223704) (xy 380.443073 -382.290642) (xy 380.427038 -382.356131) (xy 380.403273 -382.419228)
			(xy 380.372122 -382.479024) (xy 380.334032 -382.534657) (xy 380.312168 -382.560322) (xy 380.306375 -382.56747)
			(xy 380.299859 -382.584658) (xy 380.299468 -382.59385) (xy 380.299468 -383.086356) (xy 380.299907 -383.09554)
			(xy 380.306401 -383.112724) (xy 380.312168 -383.119884) (xy 380.334049 -383.145536) (xy 380.372139 -383.201171)
			(xy 380.403291 -383.260969) (xy 380.426928 -383.323727) (xy 381.529033 -383.323727) (xy 381.529037 -383.256419)
			(xy 381.537084 -383.189595) (xy 381.55306 -383.124211) (xy 381.576736 -383.061205) (xy 381.607772 -383.00148)
			(xy 381.645723 -382.945893) (xy 381.667512 -382.92024) (xy 381.673318 -382.913101) (xy 381.679827 -382.895906)
			(xy 381.680212 -382.886712) (xy 381.680212 -382.728724) (xy 381.680641 -382.71857) (xy 381.688431 -382.699816)
			(xy 381.702826 -382.685491) (xy 381.721618 -382.677793) (xy 381.731774 -382.677416) (xy 382.448054 -382.677416)
			(xy 382.458175 -382.677964) (xy 382.47689 -382.685672) (xy 382.491247 -382.699939) (xy 382.499072 -382.718606)
			(xy 382.499616 -382.728724) (xy 382.499616 -382.886712) (xy 382.500017 -382.8959) (xy 382.506537 -382.913085)
			(xy 382.512316 -382.92024) (xy 382.53407 -382.945921) (xy 382.572023 -383.001502) (xy 382.60306 -383.061221)
			(xy 382.626737 -383.124222) (xy 382.642713 -383.189601) (xy 382.650761 -383.256421) (xy 382.650764 -383.323724)
			(xy 382.642723 -383.390545) (xy 382.626753 -383.455926) (xy 382.603082 -383.518929) (xy 382.57205 -383.578652)
			(xy 382.534103 -383.634236) (xy 382.512316 -383.659888) (xy 382.506501 -383.667021) (xy 382.499997 -383.684221)
			(xy 382.499616 -383.693416) (xy 382.499616 -384.186684) (xy 382.50003 -384.195871) (xy 382.506541 -384.213055)
			(xy 382.512316 -384.220212) (xy 382.53414 -384.245834) (xy 382.572091 -384.301424) (xy 382.603125 -384.361151)
			(xy 382.626798 -384.42416) (xy 382.64277 -384.489546) (xy 382.650812 -384.556373) (xy 382.650808 -384.623681)
			(xy 382.64276 -384.690507) (xy 382.626782 -384.755892) (xy 382.603103 -384.818898) (xy 382.572063 -384.878622)
			(xy 382.534107 -384.934208) (xy 382.512316 -384.95986) (xy 382.506513 -384.967001) (xy 382.500002 -384.984195)
			(xy 382.499616 -384.993388) (xy 382.499616 -385.151376) (xy 382.499159 -385.161527) (xy 382.491375 -385.180275)
			(xy 382.476989 -385.194599) (xy 382.458206 -385.202303) (xy 382.448054 -385.202684) (xy 381.731774 -385.202684)
			(xy 381.721649 -385.202196) (xy 381.702931 -385.194464) (xy 381.688577 -385.180179) (xy 381.680754 -385.161499)
			(xy 381.680212 -385.151376) (xy 381.680212 -384.993388) (xy 381.679805 -384.984201) (xy 381.673289 -384.967016)
			(xy 381.667512 -384.95986) (xy 381.64576 -384.934178) (xy 381.607812 -384.878596) (xy 381.576779 -384.818876)
			(xy 381.553105 -384.755875) (xy 381.537131 -384.690497) (xy 381.529084 -384.623678) (xy 381.529081 -384.556376)
			(xy 381.537121 -384.489557) (xy 381.553089 -384.424177) (xy 381.576757 -384.361174) (xy 381.607784 -384.301451)
			(xy 381.645727 -384.245864) (xy 381.667512 -384.220212) (xy 381.67333 -384.213082) (xy 381.679831 -384.19588)
			(xy 381.680212 -384.186684) (xy 381.680212 -383.693416) (xy 381.679791 -383.68423) (xy 381.673285 -383.667046)
			(xy 381.667512 -383.659888) (xy 381.64569 -383.634265) (xy 381.607744 -383.578673) (xy 381.576714 -383.518946)
			(xy 381.553044 -383.455937) (xy 381.537074 -383.390552) (xy 381.529033 -383.323727) (xy 380.426928 -383.323727)
			(xy 380.427056 -383.324068) (xy 380.443091 -383.389559) (xy 380.451166 -383.456499) (xy 380.451165 -383.523925)
			(xy 380.443087 -383.590865) (xy 380.427049 -383.656355) (xy 380.403281 -383.719453) (xy 380.372127 -383.779249)
			(xy 380.334034 -383.834883) (xy 380.312168 -383.860548) (xy 380.306364 -383.867688) (xy 380.299855 -383.884883)
			(xy 380.299468 -383.894076) (xy 380.299468 -384.051556) (xy 380.299047 -384.06168) (xy 380.291308 -384.080388)
			(xy 380.276992 -384.094705) (xy 380.258284 -384.102446) (xy 380.24816 -384.102864) (xy 379.53188 -384.102864)
			(xy 379.521752 -384.1025) (xy 379.503041 -384.094738) (xy 379.488726 -384.080405) (xy 379.480988 -384.061685)
			(xy 379.480572 -384.051556) (xy 379.480572 -383.894076) (xy 379.48018 -383.884887) (xy 379.473654 -383.867702)
			(xy 379.467872 -383.860548) (xy 379.446025 -383.834869) (xy 379.407937 -383.779236) (xy 379.376788 -383.719441)
			(xy 379.353024 -383.656346) (xy 379.336988 -383.590859) (xy 379.328911 -383.523923) (xy 379.32891 -383.456501)
			(xy 379.336984 -383.389564) (xy 379.353017 -383.324077) (xy 379.376778 -383.260981) (xy 379.407925 -383.201185)
			(xy 379.44601 -383.14555) (xy 379.467872 -383.119884) (xy 379.473667 -383.112738) (xy 379.48018 -383.095548)
			(xy 379.480572 -383.086356) (xy 379.480572 -382.59385) (xy 379.480144 -382.584665) (xy 379.473643 -382.56748)
			(xy 379.467872 -382.560322) (xy 379.445999 -382.534664) (xy 379.407913 -382.479028) (xy 379.376764 -382.419231)
			(xy 379.353002 -382.356133) (xy 379.336968 -382.290643) (xy 379.328893 -382.223704) (xy 376.050822 -382.223704)
			(xy 376.042786 -382.290466) (xy 376.026815 -382.355847) (xy 376.003144 -382.418851) (xy 375.972113 -382.478575)
			(xy 375.934167 -382.534162) (xy 375.91238 -382.559814) (xy 375.906593 -382.566966) (xy 375.900073 -382.584151)
			(xy 375.89968 -382.593342) (xy 375.89968 -383.086864) (xy 375.900112 -383.096049) (xy 375.906611 -383.113233)
			(xy 375.91238 -383.120392) (xy 375.934183 -383.146031) (xy 375.97213 -383.20162) (xy 376.003162 -383.261346)
			(xy 376.02662 -383.323786) (xy 377.128714 -383.323786) (xy 377.128717 -383.256359) (xy 377.136797 -383.189418)
			(xy 377.152837 -383.123927) (xy 377.176606 -383.060828) (xy 377.207762 -383.001031) (xy 377.245857 -382.945397)
			(xy 377.267724 -382.919732) (xy 377.273535 -382.912597) (xy 377.28004 -382.895399) (xy 377.280424 -382.886204)
			(xy 377.280424 -382.728724) (xy 377.280836 -382.7186) (xy 377.288581 -382.699892) (xy 377.302899 -382.685576)
			(xy 377.321608 -382.677834) (xy 377.331732 -382.677416) (xy 378.048012 -382.677416) (xy 378.058137 -382.677806)
			(xy 378.076844 -382.685561) (xy 378.091159 -382.699886) (xy 378.098901 -382.718598) (xy 378.09932 -382.728724)
			(xy 378.09932 -382.886204) (xy 378.099724 -382.895392) (xy 378.106241 -382.912576) (xy 378.11202 -382.919732)
			(xy 378.133848 -382.945427) (xy 378.171936 -383.001058) (xy 378.203088 -383.06085) (xy 378.226853 -383.123943)
			(xy 378.24289 -383.189428) (xy 378.250969 -383.256363) (xy 378.250972 -383.323783) (xy 378.2429 -383.390719)
			(xy 378.226869 -383.456205) (xy 378.20311 -383.519301) (xy 378.171964 -383.579096) (xy 378.133881 -383.63473)
			(xy 378.11202 -383.660396) (xy 378.106245 -383.667557) (xy 378.099717 -383.684735) (xy 378.09932 -383.693924)
			(xy 378.09932 -384.186176) (xy 378.099737 -384.195363) (xy 378.106245 -384.212547) (xy 378.11202 -384.219704)
			(xy 378.133919 -384.24534) (xy 378.172005 -384.30098) (xy 378.203153 -384.36078) (xy 378.226914 -384.423881)
			(xy 378.242947 -384.489373) (xy 378.251019 -384.556314) (xy 378.251016 -384.62374) (xy 378.242937 -384.69068)
			(xy 378.226898 -384.756171) (xy 378.203131 -384.81927) (xy 378.171977 -384.879067) (xy 378.133885 -384.934702)
			(xy 378.11202 -384.960368) (xy 378.106214 -384.967507) (xy 378.099704 -384.984702) (xy 378.09932 -384.993896)
			(xy 378.09932 -385.151376) (xy 378.098865 -385.161494) (xy 378.091128 -385.180194) (xy 378.076824 -385.194508)
			(xy 378.05813 -385.202258) (xy 378.048012 -385.202684) (xy 377.331732 -385.202684) (xy 377.32161 -385.202258)
			(xy 377.302903 -385.194517) (xy 377.288587 -385.180203) (xy 377.280844 -385.161498) (xy 377.280424 -385.151376)
			(xy 377.280424 -384.993896) (xy 377.280011 -384.984709) (xy 377.273499 -384.967525) (xy 377.267724 -384.960368)
			(xy 377.245895 -384.934674) (xy 377.207803 -384.879044) (xy 377.17665 -384.819252) (xy 377.152882 -384.756159)
			(xy 377.136844 -384.690673) (xy 377.128765 -384.623738) (xy 377.128761 -384.556316) (xy 377.136834 -384.48938)
			(xy 377.152866 -384.423893) (xy 377.176627 -384.360797) (xy 377.207775 -384.301002) (xy 377.245861 -384.245369)
			(xy 377.267724 -384.219704) (xy 377.273504 -384.212547) (xy 377.280028 -384.195365) (xy 377.280424 -384.186176)
			(xy 377.280424 -383.693924) (xy 377.279997 -383.684739) (xy 377.273494 -383.667555) (xy 377.267724 -383.660396)
			(xy 377.245824 -383.63476) (xy 377.207735 -383.579122) (xy 377.176584 -383.519322) (xy 377.152821 -383.456221)
			(xy 377.136787 -383.390728) (xy 377.128714 -383.323786) (xy 376.02662 -383.323786) (xy 376.026833 -383.324352)
			(xy 376.042804 -383.389735) (xy 376.050846 -383.456559) (xy 376.050845 -383.523865) (xy 376.0428 -383.590688)
			(xy 376.026826 -383.656071) (xy 376.003152 -383.719076) (xy 375.972118 -383.778801) (xy 375.934168 -383.834388)
			(xy 375.91238 -383.86004) (xy 375.906582 -383.867184) (xy 375.900069 -383.884375) (xy 375.89968 -383.893568)
			(xy 375.89968 -384.051556) (xy 375.899242 -384.06171) (xy 375.891457 -384.080465) (xy 375.877065 -384.094791)
			(xy 375.858274 -384.102488) (xy 375.848118 -384.102864) (xy 375.131838 -384.102864) (xy 375.121714 -384.102342)
			(xy 375.102995 -384.094628) (xy 375.088637 -384.080352) (xy 375.080816 -384.061677) (xy 375.080276 -384.051556)
			(xy 375.080276 -383.893568) (xy 375.079886 -383.884379) (xy 375.073359 -383.867194) (xy 375.067576 -383.86004)
			(xy 375.045803 -383.834375) (xy 375.007851 -383.778792) (xy 374.976815 -383.71907) (xy 374.95314 -383.656067)
			(xy 374.937165 -383.590686) (xy 374.929119 -383.523864) (xy 374.929117 -383.45656) (xy 374.93716 -383.389738)
			(xy 374.953133 -383.324356) (xy 374.976805 -383.261352) (xy 375.007839 -383.201629) (xy 375.045788 -383.146044)
			(xy 375.067576 -383.120392) (xy 375.073356 -383.113235) (xy 375.079881 -383.096054) (xy 375.080276 -383.086864)
			(xy 375.080276 -382.593342) (xy 375.079851 -382.584156) (xy 375.073348 -382.566971) (xy 375.067576 -382.559814)
			(xy 375.045777 -382.53417) (xy 375.007826 -382.478584) (xy 374.976792 -382.418859) (xy 374.953118 -382.355853)
			(xy 374.937144 -382.29047) (xy 374.9291 -382.223646) (xy 345.250798 -382.223646) (xy 345.242755 -382.290467)
			(xy 345.226782 -382.355849) (xy 345.20311 -382.418853) (xy 345.172077 -382.478576) (xy 345.134128 -382.534162)
			(xy 345.11234 -382.559814) (xy 345.106548 -382.566962) (xy 345.100032 -382.584151) (xy 345.09964 -382.593342)
			(xy 345.09964 -383.086864) (xy 345.100081 -383.096048) (xy 345.106575 -383.113232) (xy 345.11234 -383.120392)
			(xy 345.134144 -383.146031) (xy 345.172094 -383.201619) (xy 345.203127 -383.261344) (xy 345.226566 -383.323727)
			(xy 346.329188 -383.323727) (xy 346.329192 -383.256419) (xy 346.33724 -383.189593) (xy 346.353218 -383.124208)
			(xy 346.376897 -383.061202) (xy 346.407937 -383.001478) (xy 346.445893 -382.945892) (xy 346.467684 -382.92024)
			(xy 346.473487 -382.913099) (xy 346.479998 -382.895905) (xy 346.480384 -382.886712) (xy 346.480384 -382.728724)
			(xy 346.480841 -382.718573) (xy 346.488625 -382.699825) (xy 346.503011 -382.685501) (xy 346.521794 -382.677797)
			(xy 346.531946 -382.677416) (xy 347.248226 -382.677416) (xy 347.258351 -382.677904) (xy 347.277069 -382.685636)
			(xy 347.291423 -382.699921) (xy 347.299246 -382.718601) (xy 347.299788 -382.728724) (xy 347.299788 -382.886712)
			(xy 347.300195 -382.895899) (xy 347.306711 -382.913084) (xy 347.312488 -382.92024) (xy 347.33424 -382.945922)
			(xy 347.372188 -383.001504) (xy 347.403221 -383.061224) (xy 347.426895 -383.124225) (xy 347.442869 -383.189603)
			(xy 347.450916 -383.256422) (xy 347.450919 -383.323724) (xy 347.442879 -383.390543) (xy 347.426911 -383.455923)
			(xy 347.403243 -383.518926) (xy 347.372216 -383.578649) (xy 347.334273 -383.634236) (xy 347.312488 -383.659888)
			(xy 347.30667 -383.667018) (xy 347.300169 -383.68422) (xy 347.299788 -383.693416) (xy 347.299788 -384.186684)
			(xy 347.300209 -384.19587) (xy 347.306715 -384.213054) (xy 347.312488 -384.220212) (xy 347.33431 -384.245835)
			(xy 347.372256 -384.301427) (xy 347.403286 -384.361154) (xy 347.426956 -384.424163) (xy 347.442926 -384.489548)
			(xy 347.450967 -384.556373) (xy 347.450963 -384.623681) (xy 347.442916 -384.690505) (xy 347.42694 -384.755889)
			(xy 347.403264 -384.818895) (xy 347.372228 -384.87862) (xy 347.334277 -384.934207) (xy 347.312488 -384.95986)
			(xy 347.306682 -384.966999) (xy 347.300173 -384.984194) (xy 347.299788 -384.993388) (xy 347.299788 -385.151376)
			(xy 347.299359 -385.16153) (xy 347.291569 -385.180284) (xy 347.277174 -385.194609) (xy 347.258382 -385.202307)
			(xy 347.248226 -385.202684) (xy 346.531946 -385.202684) (xy 346.521825 -385.202136) (xy 346.50311 -385.194428)
			(xy 346.488753 -385.180161) (xy 346.480928 -385.161494) (xy 346.480384 -385.151376) (xy 346.480384 -384.993388)
			(xy 346.479983 -384.9842) (xy 346.473463 -384.967015) (xy 346.467684 -384.95986) (xy 346.44593 -384.934179)
			(xy 346.407977 -384.878598) (xy 346.37694 -384.818879) (xy 346.353263 -384.755878) (xy 346.337287 -384.690499)
			(xy 346.329239 -384.623679) (xy 346.329236 -384.556376) (xy 346.337277 -384.489555) (xy 346.353247 -384.424174)
			(xy 346.376918 -384.361171) (xy 346.40795 -384.301448) (xy 346.445897 -384.245864) (xy 346.467684 -384.220212)
			(xy 346.473499 -384.213079) (xy 346.480003 -384.195879) (xy 346.480384 -384.186684) (xy 346.480384 -383.693416)
			(xy 346.47997 -383.684229) (xy 346.473459 -383.667045) (xy 346.467684 -383.659888) (xy 346.44586 -383.634266)
			(xy 346.407909 -383.578676) (xy 346.376875 -383.518949) (xy 346.353202 -383.45594) (xy 346.33723 -383.390554)
			(xy 346.329188 -383.323727) (xy 345.226566 -383.323727) (xy 345.2268 -383.32435) (xy 345.242773 -383.389734)
			(xy 345.250816 -383.456559) (xy 345.250814 -383.523865) (xy 345.242768 -383.590689) (xy 345.226793 -383.656073)
			(xy 345.203118 -383.719078) (xy 345.172081 -383.778802) (xy 345.134129 -383.834388) (xy 345.11234 -383.86004)
			(xy 345.106537 -383.86718) (xy 345.100028 -383.884375) (xy 345.09964 -383.893568) (xy 345.09964 -384.051556)
			(xy 345.099143 -384.061702) (xy 345.09137 -384.080446) (xy 345.076996 -384.094769) (xy 345.058226 -384.102478)
			(xy 345.048078 -384.102864) (xy 344.331798 -384.102864) (xy 344.321672 -384.102375) (xy 344.302951 -384.094647)
			(xy 344.288595 -384.080362) (xy 344.280775 -384.06168) (xy 344.280236 -384.051556) (xy 344.280236 -383.893568)
			(xy 344.279833 -383.88438) (xy 344.273313 -383.867196) (xy 344.267536 -383.86004) (xy 344.245764 -383.834375)
			(xy 344.207815 -383.77879) (xy 344.176781 -383.719068) (xy 344.153108 -383.656066) (xy 344.137134 -383.590685)
			(xy 344.129089 -383.523864) (xy 344.129087 -383.45656) (xy 344.13713 -383.389739) (xy 344.153101 -383.324358)
			(xy 344.176772 -383.261354) (xy 344.207803 -383.201631) (xy 344.24575 -383.146044) (xy 344.267536 -383.120392)
			(xy 344.273323 -383.11324) (xy 344.279843 -383.096055) (xy 344.280236 -383.086864) (xy 344.280236 -382.593342)
			(xy 344.279797 -382.584158) (xy 344.273303 -382.566974) (xy 344.267536 -382.559814) (xy 344.245738 -382.53417)
			(xy 344.20779 -382.478582) (xy 344.176757 -382.418858) (xy 344.153085 -382.355852) (xy 344.137113 -382.290469)
			(xy 344.12907 -382.223645) (xy 340.851007 -382.223645) (xy 340.842964 -382.290467) (xy 340.826992 -382.355848)
			(xy 340.80332 -382.418853) (xy 340.772287 -382.478576) (xy 340.734339 -382.534162) (xy 340.712552 -382.559814)
			(xy 340.706761 -382.566963) (xy 340.700244 -382.584151) (xy 340.699852 -382.593342) (xy 340.699852 -383.086864)
			(xy 340.70029 -383.096048) (xy 340.706785 -383.113232) (xy 340.712552 -383.120392) (xy 340.734356 -383.146031)
			(xy 340.772305 -383.201619) (xy 340.803338 -383.261344) (xy 340.826798 -383.323786) (xy 341.928893 -383.323786)
			(xy 341.928896 -383.25636) (xy 341.936975 -383.189419) (xy 341.953015 -383.123928) (xy 341.976783 -383.06083)
			(xy 342.007937 -383.001032) (xy 342.04603 -382.945397) (xy 342.067896 -382.919732) (xy 342.073703 -382.912594)
			(xy 342.080212 -382.895398) (xy 342.080596 -382.886204) (xy 342.080596 -382.728724) (xy 342.081035 -382.718604)
			(xy 342.088775 -382.699901) (xy 342.103084 -382.685586) (xy 342.121784 -382.677839) (xy 342.131904 -382.677416)
			(xy 342.848184 -382.677416) (xy 342.858307 -382.677829) (xy 342.877014 -382.685575) (xy 342.891329 -382.699893)
			(xy 342.899072 -382.7186) (xy 342.899492 -382.728724) (xy 342.899492 -382.886204) (xy 342.899902 -382.895391)
			(xy 342.906416 -382.912575) (xy 342.912192 -382.919732) (xy 342.934021 -382.945426) (xy 342.972111 -383.001056)
			(xy 343.003264 -383.060849) (xy 343.02703 -383.123942) (xy 343.043069 -383.189427) (xy 343.051148 -383.256362)
			(xy 343.051151 -383.323783) (xy 343.043078 -383.390719) (xy 343.027046 -383.456207) (xy 343.003286 -383.519302)
			(xy 342.972139 -383.579097) (xy 342.934054 -383.634731) (xy 342.912192 -383.660396) (xy 342.906414 -383.667554)
			(xy 342.899888 -383.684735) (xy 342.899492 -383.693924) (xy 342.899492 -384.186176) (xy 342.899916 -384.195362)
			(xy 342.90642 -384.212546) (xy 342.912192 -384.219704) (xy 342.934092 -384.24534) (xy 342.97218 -384.300978)
			(xy 343.003329 -384.360779) (xy 343.027092 -384.423879) (xy 343.043125 -384.489372) (xy 343.051198 -384.556314)
			(xy 343.051195 -384.62374) (xy 343.043115 -384.690681) (xy 343.027076 -384.756172) (xy 343.003307 -384.819271)
			(xy 342.972152 -384.879068) (xy 342.934058 -384.934703) (xy 342.912192 -384.960368) (xy 342.906383 -384.967504)
			(xy 342.899876 -384.984702) (xy 342.899492 -384.993896) (xy 342.899492 -385.151376) (xy 342.899064 -385.161498)
			(xy 342.891323 -385.180203) (xy 342.877009 -385.194518) (xy 342.858306 -385.202263) (xy 342.848184 -385.202684)
			(xy 342.131904 -385.202684) (xy 342.12178 -385.20228) (xy 342.103073 -385.194531) (xy 342.088758 -385.18021)
			(xy 342.081016 -385.1615) (xy 342.080596 -385.151376) (xy 342.080596 -384.993896) (xy 342.080189 -384.984709)
			(xy 342.073673 -384.967524) (xy 342.067896 -384.960368) (xy 342.046068 -384.934674) (xy 342.007978 -384.879043)
			(xy 341.976826 -384.819251) (xy 341.95306 -384.756158) (xy 341.937022 -384.690672) (xy 341.928943 -384.623737)
			(xy 341.92894 -384.556317) (xy 341.937012 -384.489381) (xy 341.953044 -384.423894) (xy 341.976804 -384.360799)
			(xy 342.00795 -384.301003) (xy 342.046034 -384.245369) (xy 342.067896 -384.219704) (xy 342.073673 -384.212545)
			(xy 342.080199 -384.195365) (xy 342.080596 -384.186176) (xy 342.080596 -383.693924) (xy 342.080175 -383.684738)
			(xy 342.073669 -383.667553) (xy 342.067896 -383.660396) (xy 342.045997 -383.63476) (xy 342.007909 -383.579121)
			(xy 341.976761 -383.519321) (xy 341.952999 -383.45622) (xy 341.936966 -383.390728) (xy 341.928893 -383.323786)
			(xy 340.826798 -383.323786) (xy 340.82701 -383.324351) (xy 340.842982 -383.389735) (xy 340.851025 -383.456559)
			(xy 340.851024 -383.523865) (xy 340.842978 -383.590689) (xy 340.827003 -383.656072) (xy 340.803328 -383.719078)
			(xy 340.772292 -383.778802) (xy 340.734341 -383.834388) (xy 340.712552 -383.86004) (xy 340.70675 -383.867181)
			(xy 340.70024 -383.884375) (xy 340.699852 -383.893568) (xy 340.699852 -384.051556) (xy 340.699343 -384.061701)
			(xy 340.691572 -384.080442) (xy 340.677202 -384.094765) (xy 340.658436 -384.102476) (xy 340.64829 -384.102864)
			(xy 339.93201 -384.102864) (xy 339.921884 -384.102365) (xy 339.903164 -384.094642) (xy 339.888808 -384.080359)
			(xy 339.880987 -384.061679) (xy 339.880448 -384.051556) (xy 339.880448 -383.893568) (xy 339.880042 -383.884381)
			(xy 339.873524 -383.867197) (xy 339.867748 -383.86004) (xy 339.845976 -383.834375) (xy 339.808026 -383.778791)
			(xy 339.776992 -383.719069) (xy 339.753318 -383.656066) (xy 339.737343 -383.590685) (xy 339.729298 -383.523864)
			(xy 339.729296 -383.45656) (xy 339.737339 -383.389738) (xy 339.75331 -383.324357) (xy 339.776982 -383.261353)
			(xy 339.808014 -383.20163) (xy 339.845961 -383.146044) (xy 339.867748 -383.120392) (xy 339.873536 -383.113241)
			(xy 339.880055 -383.096055) (xy 339.880448 -383.086864) (xy 339.880448 -382.593342) (xy 339.880007 -382.584158)
			(xy 339.873513 -382.566974) (xy 339.867748 -382.559814) (xy 339.84595 -382.53417) (xy 339.808001 -382.478583)
			(xy 339.776968 -382.418858) (xy 339.753295 -382.355852) (xy 339.737322 -382.290469) (xy 339.729279 -382.223645)
			(xy 336.45124 -382.223645) (xy 336.45124 -382.223704) (xy 336.443164 -382.290643) (xy 336.427128 -382.356132)
			(xy 336.403363 -382.419228) (xy 336.372211 -382.479024) (xy 336.334121 -382.534658) (xy 336.312256 -382.560322)
			(xy 336.306462 -382.567469) (xy 336.299947 -382.584658) (xy 336.299556 -382.59385) (xy 336.299556 -383.086356)
			(xy 336.299997 -383.09554) (xy 336.306491 -383.112724) (xy 336.312256 -383.119884) (xy 336.334137 -383.145536)
			(xy 336.372228 -383.201171) (xy 336.403381 -383.260969) (xy 336.427018 -383.323726) (xy 337.529124 -383.323726)
			(xy 337.529128 -383.256419) (xy 337.537175 -383.189595) (xy 337.55315 -383.124211) (xy 337.576825 -383.061205)
			(xy 337.607861 -383.001481) (xy 337.645811 -382.945893) (xy 337.6676 -382.92024) (xy 337.673405 -382.9131)
			(xy 337.679914 -382.895906) (xy 337.6803 -382.886712) (xy 337.6803 -382.728724) (xy 337.680741 -382.718571)
			(xy 337.688529 -382.699819) (xy 337.70292 -382.685495) (xy 337.721708 -382.677795) (xy 337.731862 -382.677416)
			(xy 338.448142 -382.677416) (xy 338.458268 -382.677891) (xy 338.476986 -382.685629) (xy 338.49134 -382.699918)
			(xy 338.499162 -382.7186) (xy 338.499704 -382.728724) (xy 338.499704 -382.886712) (xy 338.500108 -382.8959)
			(xy 338.506626 -382.913084) (xy 338.512404 -382.92024) (xy 338.534155 -382.945922) (xy 338.572102 -383.001505)
			(xy 338.603135 -383.061225) (xy 338.626808 -383.124225) (xy 338.642782 -383.189604) (xy 338.650828 -383.256422)
			(xy 338.650831 -383.323724) (xy 338.642791 -383.390543) (xy 338.626824 -383.455923) (xy 338.603157 -383.518926)
			(xy 338.57213 -383.578648) (xy 338.534188 -383.634235) (xy 338.512404 -383.659888) (xy 338.506588 -383.66702)
			(xy 338.500085 -383.68422) (xy 338.499704 -383.693416) (xy 338.499704 -384.186684) (xy 338.500121 -384.19587)
			(xy 338.50663 -384.213055) (xy 338.512404 -384.220212) (xy 338.534226 -384.245836) (xy 338.572171 -384.301427)
			(xy 338.6032 -384.361155) (xy 338.626869 -384.424163) (xy 338.642838 -384.489548) (xy 338.650879 -384.556374)
			(xy 338.650875 -384.623681) (xy 338.642828 -384.690505) (xy 338.626853 -384.755889) (xy 338.603178 -384.818894)
			(xy 338.572143 -384.878619) (xy 338.534193 -384.934207) (xy 338.512404 -384.95986) (xy 338.5066 -384.967)
			(xy 338.50009 -384.984194) (xy 338.499704 -384.993388) (xy 338.499704 -385.151376) (xy 338.499259 -385.161528)
			(xy 338.491472 -385.180279) (xy 338.477082 -385.194603) (xy 338.458296 -385.202305) (xy 338.448142 -385.202684)
			(xy 337.731862 -385.202684) (xy 337.721736 -385.202205) (xy 337.703018 -385.194469) (xy 337.688664 -385.180181)
			(xy 337.680842 -385.1615) (xy 337.6803 -385.151376) (xy 337.6803 -384.993388) (xy 337.679895 -384.9842)
			(xy 337.673378 -384.967016) (xy 337.6676 -384.95986) (xy 337.645849 -384.934178) (xy 337.607901 -384.878595)
			(xy 337.576869 -384.818875) (xy 337.553196 -384.755875) (xy 337.537221 -384.690497) (xy 337.529175 -384.623678)
			(xy 337.529172 -384.556376) (xy 337.537212 -384.489557) (xy 337.55318 -384.424177) (xy 337.576847 -384.361174)
			(xy 337.607874 -384.301451) (xy 337.645816 -384.245865) (xy 337.6676 -384.220212) (xy 337.673416 -384.213081)
			(xy 337.679919 -384.19588) (xy 337.6803 -384.186684) (xy 337.6803 -383.693416) (xy 337.679882 -383.68423)
			(xy 337.673374 -383.667045) (xy 337.6676 -383.659888) (xy 337.645778 -383.634264) (xy 337.607833 -383.578673)
			(xy 337.576803 -383.518945) (xy 337.553134 -383.455937) (xy 337.537165 -383.390552) (xy 337.529124 -383.323726)
			(xy 336.427018 -383.323726) (xy 336.427146 -383.324067) (xy 336.443182 -383.389559) (xy 336.451257 -383.456499)
			(xy 336.451256 -383.523925) (xy 336.443177 -383.590865) (xy 336.427139 -383.656356) (xy 336.403371 -383.719453)
			(xy 336.372216 -383.77925) (xy 336.334122 -383.834883) (xy 336.312256 -383.860548) (xy 336.306451 -383.867687)
			(xy 336.299943 -383.884882) (xy 336.299556 -383.894076) (xy 336.299556 -384.051556) (xy 336.29898 -384.061655)
			(xy 336.291267 -384.080321) (xy 336.276999 -384.094616) (xy 336.258346 -384.102362) (xy 336.248248 -384.102864)
			(xy 335.531968 -384.102864) (xy 335.521839 -384.102509) (xy 335.503128 -384.094744) (xy 335.488813 -384.080408)
			(xy 335.481076 -384.061686) (xy 335.48066 -384.051556) (xy 335.48066 -383.894076) (xy 335.480248 -383.884889)
			(xy 335.473734 -383.867706) (xy 335.46796 -383.860548) (xy 335.446113 -383.834869) (xy 335.408027 -383.779236)
			(xy 335.376877 -383.719441) (xy 335.353114 -383.656346) (xy 335.337079 -383.590859) (xy 335.329002 -383.523923)
			(xy 335.329001 -383.456501) (xy 335.337074 -383.389565) (xy 335.353107 -383.324077) (xy 335.376868 -383.260981)
			(xy 335.408014 -383.201185) (xy 335.446098 -383.14555) (xy 335.46796 -383.119884) (xy 335.473753 -383.112737)
			(xy 335.480268 -383.095548) (xy 335.48066 -383.086356) (xy 335.48066 -382.59385) (xy 335.480213 -382.584667)
			(xy 335.473723 -382.567483) (xy 335.46796 -382.560322) (xy 335.446088 -382.534664) (xy 335.408002 -382.479028)
			(xy 335.376854 -382.41923) (xy 335.353092 -382.356132) (xy 335.337058 -382.290643) (xy 335.328984 -382.223704)
			(xy 332.050913 -382.223704) (xy 332.042877 -382.290466) (xy 332.026905 -382.355848) (xy 332.003234 -382.418852)
			(xy 331.972202 -382.478575) (xy 331.934255 -382.534162) (xy 331.912468 -382.559814) (xy 331.906679 -382.566964)
			(xy 331.90016 -382.584151) (xy 331.899768 -382.593342) (xy 331.899768 -383.086864) (xy 331.900203 -383.096048)
			(xy 331.9067 -383.113233) (xy 331.912468 -383.120392) (xy 331.934271 -383.146031) (xy 331.972219 -383.20162)
			(xy 332.003251 -383.261345) (xy 332.026711 -383.323786) (xy 333.128805 -383.323786) (xy 333.128808 -383.25636)
			(xy 333.136888 -383.189419) (xy 333.152927 -383.123927) (xy 333.176696 -383.060829) (xy 333.207852 -383.001032)
			(xy 333.245945 -382.945397) (xy 333.267812 -382.919732) (xy 333.273621 -382.912596) (xy 333.280128 -382.895398)
			(xy 333.280512 -382.886204) (xy 333.280512 -382.728724) (xy 333.280936 -382.718602) (xy 333.288678 -382.699896)
			(xy 333.302993 -382.685581) (xy 333.321698 -382.677837) (xy 333.33182 -382.677416) (xy 334.0481 -382.677416)
			(xy 334.058224 -382.677816) (xy 334.076931 -382.685568) (xy 334.091246 -382.699889) (xy 334.098988 -382.718599)
			(xy 334.099408 -382.728724) (xy 334.099408 -382.886204) (xy 334.099815 -382.895392) (xy 334.106331 -382.912576)
			(xy 334.112108 -382.919732) (xy 334.133936 -382.945427) (xy 334.172026 -383.001057) (xy 334.203177 -383.060849)
			(xy 334.226943 -383.123942) (xy 334.242981 -383.189428) (xy 334.25106 -383.256363) (xy 334.251063 -383.323783)
			(xy 334.242991 -383.390719) (xy 334.226959 -383.456206) (xy 334.2032 -383.519301) (xy 334.172053 -383.579096)
			(xy 334.13397 -383.634731) (xy 334.112108 -383.660396) (xy 334.106332 -383.667556) (xy 334.099805 -383.684735)
			(xy 334.099408 -383.693924) (xy 334.099408 -384.186176) (xy 334.099828 -384.195362) (xy 334.106335 -384.212547)
			(xy 334.112108 -384.219704) (xy 334.134007 -384.24534) (xy 334.172094 -384.300979) (xy 334.203243 -384.360779)
			(xy 334.227005 -384.42388) (xy 334.243037 -384.489373) (xy 334.25111 -384.556314) (xy 334.251107 -384.62374)
			(xy 334.243028 -384.690681) (xy 334.226989 -384.756172) (xy 334.203221 -384.81927) (xy 334.172066 -384.879067)
			(xy 334.133974 -384.934703) (xy 334.112108 -384.960368) (xy 334.106301 -384.967506) (xy 334.099792 -384.984702)
			(xy 334.099408 -384.993896) (xy 334.099408 -385.151376) (xy 334.098965 -385.161496) (xy 334.091226 -385.180198)
			(xy 334.076918 -385.194512) (xy 334.05822 -385.20226) (xy 334.0481 -385.202684) (xy 333.33182 -385.202684)
			(xy 333.321697 -385.202267) (xy 333.302991 -385.194523) (xy 333.288675 -385.180206) (xy 333.280932 -385.161499)
			(xy 333.280512 -385.151376) (xy 333.280512 -384.993896) (xy 333.280101 -384.984709) (xy 333.273587 -384.967525)
			(xy 333.267812 -384.960368) (xy 333.245983 -384.934674) (xy 333.207892 -384.879044) (xy 333.176739 -384.819252)
			(xy 333.152973 -384.756158) (xy 333.136934 -384.690673) (xy 333.128855 -384.623738) (xy 333.128852 -384.556316)
			(xy 333.136925 -384.48938) (xy 333.152957 -384.423893) (xy 333.176717 -384.360798) (xy 333.207865 -384.301003)
			(xy 333.24595 -384.245369) (xy 333.267812 -384.219704) (xy 333.273591 -384.212546) (xy 333.280116 -384.195365)
			(xy 333.280512 -384.186176) (xy 333.280512 -383.693924) (xy 333.280088 -383.684738) (xy 333.273583 -383.667554)
			(xy 333.267812 -383.660396) (xy 333.245912 -383.63476) (xy 333.207824 -383.579122) (xy 333.176674 -383.519322)
			(xy 333.152911 -383.456221) (xy 333.136878 -383.390728) (xy 333.128805 -383.323786) (xy 332.026711 -383.323786)
			(xy 332.026923 -383.324351) (xy 332.042895 -383.389735) (xy 332.050937 -383.456559) (xy 332.050936 -383.523865)
			(xy 332.04289 -383.590689) (xy 332.026916 -383.656072) (xy 332.003242 -383.719077) (xy 331.972207 -383.778801)
			(xy 331.934257 -383.834388) (xy 331.912468 -383.86004) (xy 331.906668 -383.867183) (xy 331.900156 -383.884375)
			(xy 331.899768 -383.893568) (xy 331.899768 -384.051556) (xy 331.899342 -384.061711) (xy 331.891555 -384.080469)
			(xy 331.877159 -384.094795) (xy 331.858363 -384.10249) (xy 331.848206 -384.102864) (xy 331.131926 -384.102864)
			(xy 331.121801 -384.102352) (xy 331.103082 -384.094634) (xy 331.088724 -384.080355) (xy 331.080904 -384.061678)
			(xy 331.080364 -384.051556) (xy 331.080364 -383.893568) (xy 331.079955 -383.884381) (xy 331.073439 -383.867198)
			(xy 331.067664 -383.86004) (xy 331.045891 -383.834375) (xy 331.00794 -383.778791) (xy 330.976905 -383.71907)
			(xy 330.95323 -383.656067) (xy 330.937256 -383.590686) (xy 330.92921 -383.523864) (xy 330.929208 -383.45656)
			(xy 330.937251 -383.389738) (xy 330.953223 -383.324356) (xy 330.976895 -383.261352) (xy 331.007928 -383.20163)
			(xy 331.045877 -383.146044) (xy 331.067664 -383.120392) (xy 331.073454 -383.113243) (xy 331.079971 -383.096055)
			(xy 331.080364 -383.086864) (xy 331.080364 -382.593342) (xy 331.079919 -382.584159) (xy 331.073428 -382.566975)
			(xy 331.067664 -382.559814) (xy 331.045866 -382.53417) (xy 331.007916 -382.478583) (xy 330.976881 -382.418859)
			(xy 330.953208 -382.355853) (xy 330.937235 -382.29047) (xy 330.929191 -382.223646) (xy 301.250888 -382.223646)
			(xy 301.250888 -382.223704) (xy 301.242813 -382.290641) (xy 301.226779 -382.356129) (xy 301.203017 -382.419226)
			(xy 301.171869 -382.479022) (xy 301.133783 -382.534656) (xy 301.11192 -382.560322) (xy 301.106134 -382.567475)
			(xy 301.099612 -382.584659) (xy 301.09922 -382.59385) (xy 301.09922 -383.086356) (xy 301.099647 -383.095542)
			(xy 301.106148 -383.112726) (xy 301.11192 -383.119884) (xy 301.133799 -383.145537) (xy 301.171886 -383.201173)
			(xy 301.203035 -383.260972) (xy 301.22669 -383.323786) (xy 302.328775 -383.323786) (xy 302.328778 -383.25636)
			(xy 302.336857 -383.18942) (xy 302.352895 -383.123929) (xy 302.376662 -383.060831) (xy 302.407816 -383.001033)
			(xy 302.445907 -382.945398) (xy 302.467772 -382.919732) (xy 302.473589 -382.912601) (xy 302.480089 -382.895399)
			(xy 302.480472 -382.886204) (xy 302.480472 -382.728724) (xy 302.480935 -382.718606) (xy 302.48867 -382.699909)
			(xy 302.502972 -382.685595) (xy 302.521663 -382.677843) (xy 302.53178 -382.677416) (xy 303.24806 -382.677416)
			(xy 303.258182 -382.677849) (xy 303.276888 -382.685587) (xy 303.291204 -382.699899) (xy 303.298948 -382.718602)
			(xy 303.299368 -382.728724) (xy 303.299368 -382.886204) (xy 303.299783 -382.89539) (xy 303.306294 -382.912575)
			(xy 303.312068 -382.919732) (xy 303.333898 -382.945426) (xy 303.37199 -383.001056) (xy 303.403144 -383.060847)
			(xy 303.426911 -383.123941) (xy 303.44295 -383.189427) (xy 303.451029 -383.256362) (xy 303.451033 -383.323784)
			(xy 303.44296 -383.39072) (xy 303.426927 -383.456208) (xy 303.403166 -383.519303) (xy 303.372017 -383.579098)
			(xy 303.333931 -383.634731) (xy 303.312068 -383.660396) (xy 303.306286 -383.667552) (xy 303.299764 -383.684734)
			(xy 303.299368 -383.693924) (xy 303.299368 -384.186176) (xy 303.299797 -384.195361) (xy 303.306299 -384.212545)
			(xy 303.312068 -384.219704) (xy 303.333968 -384.24534) (xy 303.372058 -384.300978) (xy 303.403209 -384.360778)
			(xy 303.426973 -384.423878) (xy 303.443007 -384.489371) (xy 303.45108 -384.556313) (xy 303.451077 -384.623741)
			(xy 303.442997 -384.690682) (xy 303.426957 -384.756173) (xy 303.403187 -384.819272) (xy 303.37203 -384.879069)
			(xy 303.333935 -384.934703) (xy 303.312068 -384.960368) (xy 303.306256 -384.967502) (xy 303.299751 -384.984701)
			(xy 303.299368 -384.993896) (xy 303.299368 -385.151376) (xy 303.298964 -385.161501) (xy 303.291218 -385.18021)
			(xy 303.276897 -385.194527) (xy 303.258185 -385.202267) (xy 303.24806 -385.202684) (xy 302.53178 -385.202684)
			(xy 302.521654 -385.2023) (xy 302.502947 -385.194542) (xy 302.488633 -385.180216) (xy 302.480891 -385.161502)
			(xy 302.480472 -385.151376) (xy 302.480472 -384.993896) (xy 302.48007 -384.984708) (xy 302.473551 -384.967523)
			(xy 302.467772 -384.960368) (xy 302.445944 -384.934673) (xy 302.407856 -384.879042) (xy 302.376706 -384.81925)
			(xy 302.352941 -384.756157) (xy 302.336904 -384.690672) (xy 302.328825 -384.623737) (xy 302.328822 -384.556317)
			(xy 302.336894 -384.489382) (xy 302.352925 -384.423895) (xy 302.376684 -384.3608) (xy 302.407829 -384.301004)
			(xy 302.445911 -384.24537) (xy 302.467772 -384.219704) (xy 302.473558 -384.212552) (xy 302.480077 -384.195366)
			(xy 302.480472 -384.186176) (xy 302.480472 -383.693924) (xy 302.480057 -383.684737) (xy 302.473547 -383.667552)
			(xy 302.467772 -383.660396) (xy 302.445874 -383.634759) (xy 302.407788 -383.57912) (xy 302.37664 -383.51932)
			(xy 302.352879 -383.456219) (xy 302.336847 -383.390727) (xy 302.328775 -383.323786) (xy 301.22669 -383.323786)
			(xy 301.226797 -383.32407) (xy 301.242831 -383.38956) (xy 301.250905 -383.4565) (xy 301.250904 -383.523924)
			(xy 301.242827 -383.590863) (xy 301.22679 -383.656353) (xy 301.203025 -383.71945) (xy 301.171874 -383.779247)
			(xy 301.133784 -383.834882) (xy 301.11192 -383.860548) (xy 301.106123 -383.867693) (xy 301.099608 -383.884884)
			(xy 301.09922 -383.894076) (xy 301.09922 -384.051556) (xy 301.098748 -384.061673) (xy 301.091018 -384.080372)
			(xy 301.076719 -384.094687) (xy 301.058029 -384.102437) (xy 301.047912 -384.102864) (xy 300.331632 -384.102864)
			(xy 300.321507 -384.102457) (xy 300.302797 -384.094713) (xy 300.28848 -384.080393) (xy 300.28074 -384.061681)
			(xy 300.280324 -384.051556) (xy 300.280324 -383.894076) (xy 300.27992 -383.884888) (xy 300.273402 -383.867704)
			(xy 300.267624 -383.860548) (xy 300.245775 -383.83487) (xy 300.207684 -383.779238) (xy 300.176531 -383.719444)
			(xy 300.152765 -383.656349) (xy 300.136728 -383.590861) (xy 300.12865 -383.523923) (xy 300.128649 -383.456501)
			(xy 300.136724 -383.389563) (xy 300.152758 -383.324074) (xy 300.176522 -383.260978) (xy 300.207672 -383.201183)
			(xy 300.24576 -383.145549) (xy 300.267624 -383.119884) (xy 300.273413 -383.112733) (xy 300.279931 -383.095547)
			(xy 300.280324 -383.086356) (xy 300.280324 -382.59385) (xy 300.279884 -382.584666) (xy 300.273391 -382.567482)
			(xy 300.267624 -382.560322) (xy 300.245749 -382.534665) (xy 300.207659 -382.47903) (xy 300.176508 -382.419233)
			(xy 300.152743 -382.356135) (xy 300.136708 -382.290645) (xy 300.128632 -382.223705) (xy 296.851097 -382.223705)
			(xy 296.843022 -382.290641) (xy 296.826989 -382.356129) (xy 296.803227 -382.419225) (xy 296.77208 -382.479021)
			(xy 296.733994 -382.534656) (xy 296.712132 -382.560322) (xy 296.706335 -382.567467) (xy 296.699823 -382.584658)
			(xy 296.699432 -382.59385) (xy 296.699432 -383.086356) (xy 296.699878 -383.095539) (xy 296.706368 -383.112723)
			(xy 296.712132 -383.119884) (xy 296.734011 -383.145537) (xy 296.772097 -383.201174) (xy 296.803245 -383.260972)
			(xy 296.826877 -383.323727) (xy 297.928982 -383.323727) (xy 297.928985 -383.256419) (xy 297.937033 -383.189593)
			(xy 297.953011 -383.124208) (xy 297.97669 -383.061202) (xy 298.007729 -383.001478) (xy 298.045685 -382.945891)
			(xy 298.067476 -382.92024) (xy 298.073278 -382.913098) (xy 298.07979 -382.895905) (xy 298.080176 -382.886712)
			(xy 298.080176 -382.728724) (xy 298.080641 -382.718574) (xy 298.088424 -382.699827) (xy 298.102807 -382.685504)
			(xy 298.121587 -382.677799) (xy 298.131738 -382.677416) (xy 298.848018 -382.677416) (xy 298.858143 -382.677911)
			(xy 298.87686 -382.68564) (xy 298.891215 -382.699923) (xy 298.899038 -382.718602) (xy 298.89958 -382.728724)
			(xy 298.89958 -382.886712) (xy 298.899989 -382.895899) (xy 298.906504 -382.913083) (xy 298.91228 -382.92024)
			(xy 298.934031 -382.945922) (xy 298.97198 -383.001504) (xy 299.003014 -383.061224) (xy 299.026688 -383.124225)
			(xy 299.042663 -383.189603) (xy 299.050709 -383.256422) (xy 299.050713 -383.323724) (xy 299.042672 -383.390544)
			(xy 299.026704 -383.455924) (xy 299.003036 -383.518926) (xy 298.972008 -383.578649) (xy 298.934065 -383.634235)
			(xy 298.91228 -383.659888) (xy 298.906461 -383.667017) (xy 298.89996 -383.68422) (xy 298.89958 -383.693416)
			(xy 298.89958 -384.186684) (xy 298.900003 -384.19587) (xy 298.906508 -384.213054) (xy 298.91228 -384.220212)
			(xy 298.934103 -384.245835) (xy 298.972049 -384.301426) (xy 299.00308 -384.361154) (xy 299.02675 -384.424162)
			(xy 299.04272 -384.489548) (xy 299.050761 -384.556373) (xy 299.050757 -384.623681) (xy 299.04271 -384.690506)
			(xy 299.026734 -384.75589) (xy 299.003058 -384.818895) (xy 298.972021 -384.87862) (xy 298.934069 -384.934208)
			(xy 298.91228 -384.95986) (xy 298.906473 -384.966998) (xy 298.899965 -384.984194) (xy 298.89958 -384.993388)
			(xy 298.89958 -385.151376) (xy 298.899159 -385.161531) (xy 298.891367 -385.180287) (xy 298.87697 -385.194612)
			(xy 298.858175 -385.202309) (xy 298.848018 -385.202684) (xy 298.131738 -385.202684) (xy 298.121617 -385.202143)
			(xy 298.102901 -385.194432) (xy 298.088544 -385.180162) (xy 298.08072 -385.161494) (xy 298.080176 -385.151376)
			(xy 298.080176 -384.993388) (xy 298.079777 -384.9842) (xy 298.073256 -384.967015) (xy 298.067476 -384.95986)
			(xy 298.045723 -384.934179) (xy 298.00777 -384.878598) (xy 297.976733 -384.818878) (xy 297.953057 -384.755878)
			(xy 297.93708 -384.690499) (xy 297.929033 -384.623679) (xy 297.92903 -384.556376) (xy 297.937071 -384.489555)
			(xy 297.953041 -384.424174) (xy 297.976711 -384.361171) (xy 298.007742 -384.301449) (xy 298.045689 -384.245864)
			(xy 298.067476 -384.220212) (xy 298.07329 -384.213079) (xy 298.079795 -384.195879) (xy 298.080176 -384.186684)
			(xy 298.080176 -383.693416) (xy 298.079764 -383.684229) (xy 298.073252 -383.667044) (xy 298.067476 -383.659888)
			(xy 298.045651 -383.634266) (xy 298.007701 -383.578676) (xy 297.976668 -383.518948) (xy 297.952995 -383.45594)
			(xy 297.937024 -383.390554) (xy 297.928982 -383.323727) (xy 296.826877 -383.323727) (xy 296.827007 -383.324071)
			(xy 296.84304 -383.389561) (xy 296.851114 -383.4565) (xy 296.851113 -383.523924) (xy 296.843036 -383.590863)
			(xy 296.827 -383.656352) (xy 296.803235 -383.71945) (xy 296.772084 -383.779247) (xy 296.733996 -383.834882)
			(xy 296.712132 -383.860548) (xy 296.706324 -383.867685) (xy 296.699818 -383.884882) (xy 296.699432 -383.894076)
			(xy 296.699432 -384.051556) (xy 296.698949 -384.061672) (xy 296.691221 -384.080368) (xy 296.676925 -384.094683)
			(xy 296.658239 -384.102435) (xy 296.648124 -384.102864) (xy 295.931844 -384.102864) (xy 295.92172 -384.102447)
			(xy 295.90301 -384.094707) (xy 295.888693 -384.08039) (xy 295.880953 -384.06168) (xy 295.880536 -384.051556)
			(xy 295.880536 -383.894076) (xy 295.880129 -383.884889) (xy 295.873612 -383.867705) (xy 295.867836 -383.860548)
			(xy 295.845986 -383.83487) (xy 295.807895 -383.779238) (xy 295.776742 -383.719444) (xy 295.752975 -383.656349)
			(xy 295.736937 -383.590861) (xy 295.728859 -383.523924) (xy 295.728858 -383.4565) (xy 295.736933 -383.389563)
			(xy 295.752968 -383.324074) (xy 295.776732 -383.260978) (xy 295.807883 -383.201182) (xy 295.845972 -383.145549)
			(xy 295.867836 -383.119884) (xy 295.873626 -383.112735) (xy 295.880144 -383.095547) (xy 295.880536 -383.086356)
			(xy 295.880536 -382.59385) (xy 295.880094 -382.584666) (xy 295.873601 -382.567482) (xy 295.867836 -382.560322)
			(xy 295.845961 -382.534665) (xy 295.80787 -382.479031) (xy 295.776718 -382.419233) (xy 295.752953 -382.356135)
			(xy 295.736917 -382.290645) (xy 295.728841 -382.223705) (xy 292.450794 -382.223705) (xy 292.442758 -382.290467)
			(xy 292.426786 -382.355849) (xy 292.403113 -382.418853) (xy 292.37208 -382.478576) (xy 292.334131 -382.534162)
			(xy 292.312344 -382.559814) (xy 292.306552 -382.566962) (xy 292.300036 -382.584151) (xy 292.299644 -382.593342)
			(xy 292.299644 -383.086864) (xy 292.300084 -383.096048) (xy 292.306578 -383.113232) (xy 292.312344 -383.120392)
			(xy 292.334148 -383.146031) (xy 292.372098 -383.201619) (xy 292.403131 -383.261344) (xy 292.426592 -383.323786)
			(xy 293.528687 -383.323786) (xy 293.52869 -383.25636) (xy 293.536769 -383.189419) (xy 293.552808 -383.123928)
			(xy 293.576576 -383.06083) (xy 293.60773 -383.001033) (xy 293.645822 -382.945397) (xy 293.667688 -382.919732)
			(xy 293.673495 -382.912594) (xy 293.680004 -382.895398) (xy 293.680388 -382.886204) (xy 293.680388 -382.728724)
			(xy 293.680835 -382.718605) (xy 293.688573 -382.699904) (xy 293.70288 -382.685589) (xy 293.721577 -382.677841)
			(xy 293.731696 -382.677416) (xy 294.447976 -382.677416) (xy 294.458099 -382.677836) (xy 294.476805 -382.685579)
			(xy 294.491121 -382.699895) (xy 294.498864 -382.718601) (xy 294.499284 -382.728724) (xy 294.499284 -382.886204)
			(xy 294.499696 -382.895391) (xy 294.506209 -382.912575) (xy 294.511984 -382.919732) (xy 294.533813 -382.945426)
			(xy 294.571904 -383.001056) (xy 294.603057 -383.060848) (xy 294.626824 -383.123941) (xy 294.642863 -383.189427)
			(xy 294.650942 -383.256362) (xy 294.650945 -383.323784) (xy 294.642872 -383.39072) (xy 294.62684 -383.456207)
			(xy 294.603079 -383.519302) (xy 294.571932 -383.579097) (xy 294.533846 -383.634731) (xy 294.511984 -383.660396)
			(xy 294.506205 -383.667553) (xy 294.49968 -383.684735) (xy 294.499284 -383.693924) (xy 294.499284 -384.186176)
			(xy 294.499709 -384.195361) (xy 294.506213 -384.212546) (xy 294.511984 -384.219704) (xy 294.533884 -384.24534)
			(xy 294.571973 -384.300978) (xy 294.603123 -384.360778) (xy 294.626885 -384.423879) (xy 294.642919 -384.489372)
			(xy 294.650992 -384.556314) (xy 294.650989 -384.62374) (xy 294.642909 -384.690681) (xy 294.626869 -384.756173)
			(xy 294.603101 -384.819271) (xy 294.571945 -384.879068) (xy 294.533851 -384.934703) (xy 294.511984 -384.960368)
			(xy 294.506174 -384.967504) (xy 294.499668 -384.984702) (xy 294.499284 -384.993896) (xy 294.499284 -385.151376)
			(xy 294.498864 -385.161499) (xy 294.491121 -385.180205) (xy 294.476805 -385.194521) (xy 294.458099 -385.202264)
			(xy 294.447976 -385.202684) (xy 293.731696 -385.202684) (xy 293.721571 -385.202287) (xy 293.702865 -385.194534)
			(xy 293.68855 -385.180212) (xy 293.680808 -385.161501) (xy 293.680388 -385.151376) (xy 293.680388 -384.993896)
			(xy 293.679982 -384.984708) (xy 293.673466 -384.967524) (xy 293.667688 -384.960368) (xy 293.64586 -384.934673)
			(xy 293.607771 -384.879043) (xy 293.576619 -384.819251) (xy 293.552854 -384.756158) (xy 293.536816 -384.690672)
			(xy 293.528737 -384.623737) (xy 293.528734 -384.556317) (xy 293.536806 -384.489381) (xy 293.552838 -384.423894)
			(xy 293.576597 -384.360799) (xy 293.607743 -384.301004) (xy 293.645827 -384.245369) (xy 293.667688 -384.219704)
			(xy 293.673464 -384.212544) (xy 293.679991 -384.195365) (xy 293.680388 -384.186176) (xy 293.680388 -383.693924)
			(xy 293.679969 -383.684738) (xy 293.673462 -383.667553) (xy 293.667688 -383.660396) (xy 293.645789 -383.63476)
			(xy 293.607702 -383.579121) (xy 293.576554 -383.51932) (xy 293.552792 -383.45622) (xy 293.53676 -383.390727)
			(xy 293.528687 -383.323786) (xy 292.426592 -383.323786) (xy 292.426804 -383.32435) (xy 292.442776 -383.389734)
			(xy 292.450819 -383.456559) (xy 292.450818 -383.523865) (xy 292.442772 -383.590689) (xy 292.426797 -383.656073)
			(xy 292.403121 -383.719078) (xy 292.372085 -383.778802) (xy 292.334133 -383.834388) (xy 292.312344 -383.86004)
			(xy 292.306541 -383.86718) (xy 292.300032 -383.884375) (xy 292.299644 -383.893568) (xy 292.299644 -384.051556)
			(xy 292.299143 -384.061702) (xy 292.29137 -384.080445) (xy 292.276998 -384.094768) (xy 292.258229 -384.102477)
			(xy 292.248082 -384.102864) (xy 291.531802 -384.102864) (xy 291.521676 -384.102372) (xy 291.502956 -384.094645)
			(xy 291.488599 -384.080361) (xy 291.480779 -384.06168) (xy 291.48024 -384.051556) (xy 291.48024 -383.893568)
			(xy 291.479836 -383.88438) (xy 291.473317 -383.867197) (xy 291.46754 -383.86004) (xy 291.445768 -383.834375)
			(xy 291.407819 -383.77879) (xy 291.376785 -383.719068) (xy 291.353111 -383.656066) (xy 291.337137 -383.590685)
			(xy 291.329092 -383.523864) (xy 291.32909 -383.45656) (xy 291.337133 -383.389739) (xy 291.353104 -383.324357)
			(xy 291.376775 -383.261354) (xy 291.407806 -383.20163) (xy 291.445753 -383.146044) (xy 291.46754 -383.120392)
			(xy 291.473328 -383.113241) (xy 291.479847 -383.096055) (xy 291.48024 -383.086864) (xy 291.48024 -382.593342)
			(xy 291.4798 -382.584158) (xy 291.473306 -382.566974) (xy 291.46754 -382.559814) (xy 291.445742 -382.53417)
			(xy 291.407794 -382.478582) (xy 291.376761 -382.418858) (xy 291.353088 -382.355852) (xy 291.337116 -382.290469)
			(xy 291.329073 -382.223645) (xy 288.051034 -382.223645) (xy 288.051034 -382.223704) (xy 288.042958 -382.290643)
			(xy 288.026922 -382.356132) (xy 288.003157 -382.419229) (xy 287.972004 -382.479024) (xy 287.933913 -382.534658)
			(xy 287.912048 -382.560322) (xy 287.906253 -382.567468) (xy 287.899739 -382.584658) (xy 287.899348 -382.59385)
			(xy 287.899348 -383.086356) (xy 287.899791 -383.095539) (xy 287.906283 -383.112723) (xy 287.912048 -383.119884)
			(xy 287.93393 -383.145535) (xy 287.972021 -383.201171) (xy 288.003174 -383.260968) (xy 288.026812 -383.323727)
			(xy 289.128894 -383.323727) (xy 289.128898 -383.256418) (xy 289.136946 -383.189593) (xy 289.152924 -383.124208)
			(xy 289.176604 -383.061202) (xy 289.207644 -383.001477) (xy 289.245601 -382.945891) (xy 289.267392 -382.92024)
			(xy 289.273196 -382.9131) (xy 289.279706 -382.895905) (xy 289.280092 -382.886712) (xy 289.280092 -382.728724)
			(xy 289.280541 -382.718572) (xy 289.288327 -382.699822) (xy 289.302715 -382.685498) (xy 289.321501 -382.677796)
			(xy 289.331654 -382.677416) (xy 290.047934 -382.677416) (xy 290.05806 -382.677898) (xy 290.076777 -382.685632)
			(xy 290.091132 -382.69992) (xy 290.098954 -382.7186) (xy 290.099496 -382.728724) (xy 290.099496 -382.886712)
			(xy 290.099901 -382.8959) (xy 290.106419 -382.913084) (xy 290.112196 -382.92024) (xy 290.133947 -382.945922)
			(xy 290.171895 -383.001505) (xy 290.202928 -383.061225) (xy 290.226601 -383.124225) (xy 290.242576 -383.189603)
			(xy 290.250622 -383.256422) (xy 290.250625 -383.323724) (xy 290.242585 -383.390543) (xy 290.226617 -383.455923)
			(xy 290.20295 -383.518926) (xy 290.171923 -383.578649) (xy 290.133981 -383.634235) (xy 290.112196 -383.659888)
			(xy 290.106379 -383.667019) (xy 290.099877 -383.68422) (xy 290.099496 -383.693416) (xy 290.099496 -384.186684)
			(xy 290.099915 -384.19587) (xy 290.106423 -384.213055) (xy 290.112196 -384.220212) (xy 290.134018 -384.245836)
			(xy 290.171963 -384.301427) (xy 290.202993 -384.361155) (xy 290.226662 -384.424163) (xy 290.242632 -384.489548)
			(xy 290.250673 -384.556373) (xy 290.250669 -384.623681) (xy 290.242622 -384.690505) (xy 290.226646 -384.755889)
			(xy 290.202971 -384.818895) (xy 290.171936 -384.87862) (xy 290.133985 -384.934207) (xy 290.112196 -384.95986)
			(xy 290.106391 -384.966999) (xy 290.099881 -384.984194) (xy 290.099496 -384.993388) (xy 290.099496 -385.151376)
			(xy 290.099059 -385.161529) (xy 290.09127 -385.180282) (xy 290.076878 -385.194606) (xy 290.058089 -385.202306)
			(xy 290.047934 -385.202684) (xy 289.331654 -385.202684) (xy 289.321527 -385.202212) (xy 289.30281 -385.194473)
			(xy 289.288456 -385.180183) (xy 289.280634 -385.1615) (xy 289.280092 -385.151376) (xy 289.280092 -384.993388)
			(xy 289.279689 -384.9842) (xy 289.273171 -384.967016) (xy 289.267392 -384.95986) (xy 289.245638 -384.934179)
			(xy 289.207685 -384.878598) (xy 289.176647 -384.818879) (xy 289.15297 -384.755878) (xy 289.136993 -384.690499)
			(xy 289.128945 -384.623679) (xy 289.128942 -384.556375) (xy 289.136983 -384.489554) (xy 289.152954 -384.424174)
			(xy 289.176625 -384.36117) (xy 289.207657 -384.301448) (xy 289.245605 -384.245863) (xy 289.267392 -384.220212)
			(xy 289.273208 -384.21308) (xy 289.279711 -384.195879) (xy 289.280092 -384.186684) (xy 289.280092 -383.693416)
			(xy 289.279676 -383.684229) (xy 289.273167 -383.667045) (xy 289.267392 -383.659888) (xy 289.245567 -383.634266)
			(xy 289.207616 -383.578676) (xy 289.176581 -383.518949) (xy 289.152908 -383.45594) (xy 289.136936 -383.390554)
			(xy 289.128894 -383.323727) (xy 288.026812 -383.323727) (xy 288.02694 -383.324067) (xy 288.042976 -383.389558)
			(xy 288.051051 -383.456499) (xy 288.05105 -383.523925) (xy 288.042971 -383.590865) (xy 288.026933 -383.656356)
			(xy 288.003164 -383.719454) (xy 287.972009 -383.77925) (xy 287.933915 -383.834884) (xy 287.912048 -383.860548)
			(xy 287.906242 -383.867686) (xy 287.899734 -383.884882) (xy 287.899348 -383.894076) (xy 287.899348 -384.051556)
			(xy 287.898849 -384.06167) (xy 287.891124 -384.080363) (xy 287.876834 -384.094677) (xy 287.858153 -384.102432)
			(xy 287.84804 -384.102864) (xy 287.13176 -384.102864) (xy 287.12163 -384.102516) (xy 287.102919 -384.094748)
			(xy 287.088605 -384.08041) (xy 287.080868 -384.061686) (xy 287.080452 -384.051556) (xy 287.080452 -383.894076)
			(xy 287.080042 -383.884889) (xy 287.073527 -383.867705) (xy 287.067752 -383.860548) (xy 287.045902 -383.834871)
			(xy 287.007809 -383.779239) (xy 286.976655 -383.719445) (xy 286.952888 -383.65635) (xy 286.936849 -383.590862)
			(xy 286.928772 -383.523924) (xy 286.92877 -383.4565) (xy 286.936845 -383.389562) (xy 286.952881 -383.324073)
			(xy 286.976645 -383.260977) (xy 287.007797 -383.201182) (xy 287.045887 -383.145548) (xy 287.067752 -383.119884)
			(xy 287.073544 -383.112736) (xy 287.08006 -383.095547) (xy 287.080452 -383.086356) (xy 287.080452 -382.59385)
			(xy 287.080006 -382.584667) (xy 287.073516 -382.567483) (xy 287.067752 -382.560322) (xy 287.045876 -382.534666)
			(xy 287.007785 -382.479031) (xy 286.976631 -382.419234) (xy 286.952865 -382.356136) (xy 286.936829 -382.290645)
			(xy 286.928753 -382.223705) (xy 275.797584 -382.223705) (xy 275.705437 -382.32432) (xy 275.561134 -382.470038)
			(xy 275.411255 -382.610015) (xy 275.256029 -382.744038) (xy 275.095692 -382.871902) (xy 274.930489 -382.993413)
			(xy 274.76067 -383.108386) (xy 274.586495 -383.216646) (xy 274.408229 -383.318028) (xy 274.226143 -383.412377)
			(xy 274.040514 -383.499551) (xy 273.851626 -383.579415) (xy 273.659765 -383.651849) (xy 273.465224 -383.716742)
			(xy 273.2683 -383.773996) (xy 273.069292 -383.823522) (xy 272.868503 -383.865247) (xy 272.666239 -383.899105)
			(xy 272.462807 -383.925047) (xy 272.258519 -383.943031) (xy 272.053685 -383.953032) (xy 271.848616 -383.955032)
			(xy 271.643625 -383.949031) (xy 271.439025 -383.935036) (xy 271.235126 -383.913069) (xy 271.03224 -383.883163)
			(xy 270.830675 -383.845364) (xy 270.630739 -383.79973) (xy 270.432735 -383.74633) (xy 270.236965 -383.685245)
			(xy 270.043727 -383.616568) (xy 269.853317 -383.540404) (xy 269.666022 -383.45687) (xy 269.48213 -383.366091)
			(xy 269.30192 -383.268207) (xy 269.125665 -383.163366) (xy 268.953636 -383.051728) (xy 268.786093 -382.933463)
			(xy 268.623292 -382.808752) (xy 268.46548 -382.677783) (xy 268.312899 -382.540758) (xy 268.16578 -382.397883)
			(xy 268.024347 -382.249377) (xy 267.888817 -382.095466) (xy 267.759394 -381.936384) (xy 267.636277 -381.772374)
			(xy 267.519652 -381.603685) (xy 267.409698 -381.430575) (xy 267.306582 -381.253306) (xy 267.210461 -381.072149)
			(xy 267.12148 -380.88738) (xy 267.039777 -380.69928) (xy 266.965475 -380.508135) (xy 266.898687 -380.314237)
			(xy 266.839515 -380.11788) (xy 266.788049 -379.919365) (xy 266.744367 -379.718992) (xy 266.708537 -379.517068)
			(xy 266.680612 -379.3139) (xy 266.660635 -379.109797) (xy 266.648637 -378.905069) (xy 266.644636 -378.70003)
			(xy 262.441436 -378.70003) (xy 262.561832 -378.820426) (xy 262.579119 -378.838423) (xy 262.608435 -378.878804)
			(xy 262.631082 -378.92327) (xy 262.646503 -378.970728) (xy 262.654321 -379.020012) (xy 262.654796 -379.044962)
			(xy 262.654796 -385.608376) (xy 454.303373 -385.608376) (xy 454.303373 -385.479236) (xy 454.311323 -385.350341)
			(xy 454.327193 -385.222181) (xy 454.350922 -385.09524) (xy 454.382421 -384.970001) (xy 454.42157 -384.846938)
			(xy 454.468221 -384.726519) (xy 454.522196 -384.6092) (xy 454.583291 -384.495426) (xy 454.651274 -384.385629)
			(xy 454.725888 -384.280226) (xy 454.806849 -384.179616) (xy 454.893849 -384.084181) (xy 454.98656 -383.994282)
			(xy 455.08463 -383.910261) (xy 455.187685 -383.832437) (xy 455.295336 -383.761105) (xy 455.407175 -383.696535)
			(xy 455.522776 -383.638973) (xy 455.641701 -383.588636) (xy 455.7635 -383.545716) (xy 455.88771 -383.510375)
			(xy 456.013859 -383.482748) (xy 456.141471 -383.462939) (xy 456.27006 -383.451023) (xy 456.399138 -383.447047)
			(xy 456.528216 -383.451023) (xy 456.656805 -383.462939) (xy 456.784417 -383.482748) (xy 456.910566 -383.510375)
			(xy 457.034776 -383.545716) (xy 457.156575 -383.588636) (xy 457.2755 -383.638973) (xy 457.391101 -383.696535)
			(xy 457.50294 -383.761105) (xy 457.610591 -383.832437) (xy 457.713646 -383.910261) (xy 457.811716 -383.994282)
			(xy 457.904427 -384.084181) (xy 457.991427 -384.179616) (xy 458.072388 -384.280226) (xy 458.147002 -384.385629)
			(xy 458.214985 -384.495426) (xy 458.27608 -384.6092) (xy 458.330055 -384.726519) (xy 458.376706 -384.846938)
			(xy 458.415855 -384.970001) (xy 458.447354 -385.09524) (xy 458.471083 -385.222181) (xy 458.486953 -385.350341)
			(xy 458.494903 -385.479236) (xy 458.4954 -385.543806) (xy 458.494903 -385.608376) (xy 458.486953 -385.737271)
			(xy 458.471083 -385.865431) (xy 458.447354 -385.992372) (xy 458.415855 -386.117611) (xy 458.376706 -386.240674)
			(xy 458.330055 -386.361093) (xy 458.27608 -386.478412) (xy 458.214985 -386.592186) (xy 458.147002 -386.701983)
			(xy 458.072388 -386.807386) (xy 457.991427 -386.907996) (xy 457.904427 -387.003431) (xy 457.811716 -387.09333)
			(xy 457.713646 -387.177351) (xy 457.610591 -387.255175) (xy 457.50294 -387.326507) (xy 457.391101 -387.391077)
			(xy 457.2755 -387.448639) (xy 457.156575 -387.498976) (xy 457.034776 -387.541896) (xy 456.910566 -387.577237)
			(xy 456.784417 -387.604864) (xy 456.656805 -387.624673) (xy 456.528216 -387.636589) (xy 456.399138 -387.640566)
			(xy 456.27006 -387.636589) (xy 456.141471 -387.624673) (xy 456.013859 -387.604864) (xy 455.88771 -387.577237)
			(xy 455.7635 -387.541896) (xy 455.641701 -387.498976) (xy 455.522776 -387.448639) (xy 455.407175 -387.391077)
			(xy 455.295336 -387.326507) (xy 455.187685 -387.255175) (xy 455.08463 -387.177351) (xy 454.98656 -387.09333)
			(xy 454.893849 -387.003431) (xy 454.806849 -386.907996) (xy 454.725888 -386.807386) (xy 454.651274 -386.701983)
			(xy 454.583291 -386.592186) (xy 454.522196 -386.478412) (xy 454.468221 -386.361093) (xy 454.42157 -386.240674)
			(xy 454.382421 -386.117611) (xy 454.350922 -385.992372) (xy 454.327193 -385.865431) (xy 454.311323 -385.737271)
			(xy 454.303373 -385.608376) (xy 262.654796 -385.608376) (xy 262.654796 -387.940042) (xy 262.654337 -387.964995)
			(xy 262.646538 -388.014288) (xy 262.631124 -388.061754) (xy 262.608473 -388.106223) (xy 262.579145 -388.146602)
			(xy 262.561832 -388.164578) (xy 259.433314 -391.293096) (xy 259.415314 -391.310377) (xy 259.374929 -391.339679)
			(xy 259.330463 -391.362313) (xy 259.283006 -391.377722) (xy 259.233726 -391.385529) (xy 259.208778 -391.38606)
			(xy 245.30812 -391.38606) (xy 245.298058 -391.386499) (xy 245.27948 -391.394241) (xy 245.272052 -391.401046)
			(xy 244.461792 -392.211306) (xy 244.454947 -392.218705) (xy 244.447216 -392.237303) (xy 244.446806 -392.247374)
			(xy 244.446806 -393.099798) (xy 262.940808 -393.099798) (xy 262.944812 -392.89461) (xy 262.956819 -392.689734)
			(xy 262.97681 -392.485483) (xy 263.004755 -392.282168) (xy 263.040611 -392.080097) (xy 263.084325 -391.879579)
			(xy 263.135828 -391.68092) (xy 263.195043 -391.484421) (xy 263.261879 -391.290382) (xy 263.336235 -391.099099)
			(xy 263.417998 -390.910862) (xy 263.507043 -390.725959) (xy 263.603234 -390.544671) (xy 263.706425 -390.367274)
			(xy 263.816459 -390.194037) (xy 263.933168 -390.025226) (xy 264.056374 -389.861097) (xy 264.185891 -389.7019)
			(xy 264.32152 -389.547878) (xy 264.463055 -389.399264) (xy 264.61028 -389.256286) (xy 264.762972 -389.119161)
			(xy 264.920898 -388.988097) (xy 265.083817 -388.863295) (xy 265.251482 -388.744945) (xy 265.423636 -388.633226)
			(xy 265.600018 -388.528309) (xy 265.780359 -388.430354) (xy 265.964385 -388.33951) (xy 266.151815 -388.255914)
			(xy 266.342364 -388.179695) (xy 266.535741 -388.110969) (xy 266.731653 -388.04984) (xy 266.9298 -387.996401)
			(xy 267.129882 -387.950734) (xy 267.331593 -387.912907) (xy 267.534626 -387.88298) (xy 267.738673 -387.860997)
			(xy 267.943422 -387.846992) (xy 268.148561 -387.840986) (xy 268.353778 -387.842988) (xy 268.558761 -387.852996)
			(xy 268.763198 -387.870993) (xy 268.966776 -387.896953) (xy 269.169187 -387.930836) (xy 269.370121 -387.972591)
			(xy 269.569274 -388.022154) (xy 269.766341 -388.079449) (xy 269.961023 -388.144389) (xy 270.153023 -388.216875)
			(xy 270.342048 -388.296798) (xy 270.527811 -388.384034) (xy 270.710029 -388.478452) (xy 270.888425 -388.579907)
			(xy 271.062726 -388.688246) (xy 271.232668 -388.803302) (xy 271.397991 -388.924902) (xy 271.558444 -389.052859)
			(xy 271.713783 -389.186978) (xy 271.86377 -389.327057) (xy 272.008178 -389.472881) (xy 272.146786 -389.624227)
			(xy 272.279384 -389.780867) (xy 272.40577 -389.942561) (xy 272.52575 -390.109063) (xy 272.639143 -390.280119)
			(xy 272.745776 -390.455469) (xy 272.845486 -390.634846) (xy 272.938122 -390.817976) (xy 273.023542 -391.004582)
			(xy 273.101616 -391.194378) (xy 273.172226 -391.387076) (xy 273.235263 -391.582382) (xy 273.290633 -391.779998)
			(xy 273.33825 -391.979625) (xy 273.378042 -392.180957) (xy 273.409949 -392.383689) (xy 273.433922 -392.587511)
			(xy 273.449924 -392.792114) (xy 273.457931 -392.997184) (xy 273.458432 -393.099798) (xy 273.457931 -393.202412)
			(xy 273.449924 -393.407482) (xy 273.433922 -393.612085) (xy 273.409949 -393.815907) (xy 273.378042 -394.018639)
			(xy 273.33825 -394.219971) (xy 273.290633 -394.419598) (xy 273.235263 -394.617214) (xy 273.172226 -394.81252)
			(xy 273.101616 -395.005218) (xy 273.023542 -395.195014) (xy 272.938122 -395.38162) (xy 272.845486 -395.56475)
			(xy 272.745776 -395.744127) (xy 272.639143 -395.919477) (xy 272.52575 -396.090533) (xy 272.40577 -396.257035)
			(xy 272.279384 -396.418729) (xy 272.146786 -396.575369) (xy 272.008178 -396.726715) (xy 271.86377 -396.872539)
			(xy 271.713783 -397.012618) (xy 271.558444 -397.146737) (xy 271.397991 -397.274694) (xy 271.232668 -397.396294)
			(xy 271.062726 -397.51135) (xy 270.888425 -397.619689) (xy 270.710029 -397.721144) (xy 270.527811 -397.815562)
			(xy 270.510088 -397.823885) (xy 286.928734 -397.823885) (xy 286.928737 -397.756458) (xy 286.936817 -397.689516)
			(xy 286.952859 -397.624024) (xy 286.976629 -397.560925) (xy 287.007787 -397.501128) (xy 287.045884 -397.445494)
			(xy 287.067752 -397.41983) (xy 287.073567 -397.412698) (xy 287.080069 -397.395497) (xy 287.080452 -397.386302)
			(xy 287.080452 -396.89405) (xy 287.080006 -396.884867) (xy 287.073516 -396.867683) (xy 287.067752 -396.860522)
			(xy 287.045876 -396.834866) (xy 287.007785 -396.779231) (xy 286.976631 -396.719434) (xy 286.952865 -396.656336)
			(xy 286.936829 -396.590845) (xy 286.928753 -396.523905) (xy 286.928754 -396.45648) (xy 286.936832 -396.38954)
			(xy 286.95287 -396.32405) (xy 286.976638 -396.260952) (xy 287.007792 -396.201156) (xy 287.045886 -396.145522)
			(xy 287.067752 -396.119858) (xy 287.073555 -396.112718) (xy 287.080065 -396.095523) (xy 287.080452 -396.08633)
			(xy 287.080452 -395.92885) (xy 287.080968 -395.918725) (xy 287.088682 -395.900003) (xy 287.102959 -395.885644)
			(xy 287.121638 -395.877825) (xy 287.13176 -395.877288) (xy 287.84804 -395.877288) (xy 287.858195 -395.877689)
			(xy 287.876946 -395.885495) (xy 287.891268 -395.899898) (xy 287.898968 -395.918693) (xy 287.899348 -395.92885)
			(xy 287.899348 -396.08633) (xy 287.899755 -396.095517) (xy 287.906272 -396.112701) (xy 287.912048 -396.119858)
			(xy 287.933904 -396.14553) (xy 287.971996 -396.201163) (xy 288.00315 -396.260957) (xy 288.026917 -396.324053)
			(xy 288.042955 -396.389542) (xy 288.051033 -396.456481) (xy 288.051034 -396.523904) (xy 288.042958 -396.590843)
			(xy 288.026922 -396.656332) (xy 288.003157 -396.719429) (xy 287.972004 -396.779224) (xy 287.933913 -396.834858)
			(xy 287.912048 -396.860522) (xy 287.906253 -396.867668) (xy 287.899739 -396.884858) (xy 287.899348 -396.89405)
			(xy 287.899348 -397.386302) (xy 287.899769 -397.395488) (xy 287.906276 -397.412672) (xy 287.912048 -397.41983)
			(xy 287.933876 -397.445525) (xy 287.97197 -397.501154) (xy 288.000733 -397.556355) (xy 289.128926 -397.556355)
			(xy 289.13697 -397.489532) (xy 289.152943 -397.42415) (xy 289.176617 -397.361145) (xy 289.207652 -397.301423)
			(xy 289.245603 -397.245837) (xy 289.267392 -397.220186) (xy 289.273176 -397.213032) (xy 289.279698 -397.195848)
			(xy 289.280092 -397.186658) (xy 289.280092 -397.028924) (xy 289.280541 -397.018772) (xy 289.288327 -397.000022)
			(xy 289.302715 -396.985698) (xy 289.321501 -396.977996) (xy 289.331654 -396.977616) (xy 290.047934 -396.977616)
			(xy 290.05806 -396.978098) (xy 290.076777 -396.985832) (xy 290.091132 -397.00012) (xy 290.098954 -397.0188)
			(xy 290.099496 -397.028924) (xy 290.099496 -397.186658) (xy 290.099927 -397.195843) (xy 290.106426 -397.213027)
			(xy 290.112196 -397.220186) (xy 290.133992 -397.245831) (xy 290.171939 -397.301419) (xy 290.20297 -397.361144)
			(xy 290.22664 -397.424149) (xy 290.242612 -397.489532) (xy 290.250654 -397.556355) (xy 290.250653 -397.62366)
			(xy 290.242609 -397.690483) (xy 290.226636 -397.755865) (xy 290.202963 -397.81887) (xy 290.200388 -397.823825)
			(xy 291.329053 -397.823825) (xy 291.329057 -397.756517) (xy 291.337105 -397.689692) (xy 291.353082 -397.624308)
			(xy 291.376759 -397.561302) (xy 291.407796 -397.501577) (xy 291.44575 -397.44599) (xy 291.46754 -397.420338)
			(xy 291.47335 -397.413203) (xy 291.479856 -397.396004) (xy 291.48024 -397.38681) (xy 291.48024 -396.893542)
			(xy 291.4798 -396.884358) (xy 291.473306 -396.867174) (xy 291.46754 -396.860014) (xy 291.445742 -396.83437)
			(xy 291.407794 -396.778782) (xy 291.376761 -396.719058) (xy 291.353088 -396.656052) (xy 291.337116 -396.590669)
			(xy 291.329073 -396.523845) (xy 291.329074 -396.45654) (xy 291.337119 -396.389716) (xy 291.353093 -396.324333)
			(xy 291.376767 -396.261328) (xy 291.407801 -396.201605) (xy 291.445751 -396.146018) (xy 291.46754 -396.120366)
			(xy 291.473339 -396.113222) (xy 291.479851 -396.096031) (xy 291.48024 -396.086838) (xy 291.48024 -395.92885)
			(xy 291.480705 -395.918681) (xy 291.488474 -395.899887) (xy 291.502847 -395.885501) (xy 291.521634 -395.877714)
			(xy 291.531802 -395.877288) (xy 292.248082 -395.877288) (xy 292.258259 -395.87768) (xy 292.277063 -395.885468)
			(xy 292.29145 -395.899864) (xy 292.299227 -395.918673) (xy 292.299644 -395.92885) (xy 292.299644 -396.086838)
			(xy 292.300049 -396.096026) (xy 292.306568 -396.113209) (xy 292.312344 -396.120366) (xy 292.334122 -396.146026)
			(xy 292.372072 -396.201611) (xy 292.403107 -396.261333) (xy 292.426781 -396.324337) (xy 292.442755 -396.389718)
			(xy 292.450801 -396.45654) (xy 292.450801 -396.523845) (xy 292.442758 -396.590667) (xy 292.426786 -396.656049)
			(xy 292.403113 -396.719053) (xy 292.37208 -396.778776) (xy 292.334131 -396.834362) (xy 292.312344 -396.860014)
			(xy 292.306552 -396.867162) (xy 292.300036 -396.884351) (xy 292.299644 -396.893542) (xy 292.299644 -397.38681)
			(xy 292.300062 -397.395996) (xy 292.306572 -397.41318) (xy 292.312344 -397.420338) (xy 292.334095 -397.446021)
			(xy 292.372046 -397.501602) (xy 292.40047 -397.556296) (xy 293.528718 -397.556296) (xy 293.536793 -397.489359)
			(xy 293.552827 -397.42387) (xy 293.576589 -397.360774) (xy 293.607738 -397.300978) (xy 293.645825 -397.245343)
			(xy 293.667688 -397.219678) (xy 293.673475 -397.212526) (xy 293.679996 -397.195341) (xy 293.680388 -397.18615)
			(xy 293.680388 -397.028924) (xy 293.680835 -397.018805) (xy 293.688573 -397.000104) (xy 293.70288 -396.985789)
			(xy 293.721577 -396.978041) (xy 293.731696 -396.977616) (xy 294.447976 -396.977616) (xy 294.458099 -396.978036)
			(xy 294.476805 -396.985779) (xy 294.491121 -397.000095) (xy 294.498864 -397.018801) (xy 294.499284 -397.028924)
			(xy 294.499284 -397.18615) (xy 294.499722 -397.195334) (xy 294.506217 -397.212519) (xy 294.511984 -397.219678)
			(xy 294.533858 -397.245335) (xy 294.571948 -397.30097) (xy 294.603099 -397.360767) (xy 294.626863 -397.423865)
			(xy 294.642899 -397.489356) (xy 294.650974 -397.556295) (xy 294.650973 -397.62372) (xy 294.642896 -397.690659)
			(xy 294.626859 -397.756149) (xy 294.603093 -397.819246) (xy 294.600676 -397.823885) (xy 295.728821 -397.823885)
			(xy 295.728825 -397.756458) (xy 295.736905 -397.689516) (xy 295.752946 -397.624025) (xy 295.776716 -397.560926)
			(xy 295.807873 -397.501129) (xy 295.845969 -397.445495) (xy 295.867836 -397.41983) (xy 295.873649 -397.412697)
			(xy 295.880153 -397.395497) (xy 295.880536 -397.386302) (xy 295.880536 -396.89405) (xy 295.880094 -396.884866)
			(xy 295.873601 -396.867682) (xy 295.867836 -396.860522) (xy 295.845961 -396.834865) (xy 295.80787 -396.779231)
			(xy 295.776718 -396.719433) (xy 295.752953 -396.656335) (xy 295.736917 -396.590845) (xy 295.728841 -396.523905)
			(xy 295.728842 -396.45648) (xy 295.73692 -396.38954) (xy 295.752957 -396.32405) (xy 295.776724 -396.260953)
			(xy 295.807878 -396.201157) (xy 295.84597 -396.145523) (xy 295.867836 -396.119858) (xy 295.873637 -396.112716)
			(xy 295.880148 -396.095523) (xy 295.880536 -396.08633) (xy 295.880536 -395.92885) (xy 295.881067 -395.918727)
			(xy 295.888778 -395.900008) (xy 295.903051 -395.88565) (xy 295.921724 -395.877828) (xy 295.931844 -395.877288)
			(xy 296.648124 -395.877288) (xy 296.658278 -395.877702) (xy 296.677029 -395.885503) (xy 296.691351 -395.899902)
			(xy 296.699052 -395.918694) (xy 296.699432 -395.92885) (xy 296.699432 -396.08633) (xy 296.699843 -396.095517)
			(xy 296.706358 -396.1127) (xy 296.712132 -396.119858) (xy 296.733985 -396.145532) (xy 296.772072 -396.201166)
			(xy 296.803221 -396.260961) (xy 296.826985 -396.324057) (xy 296.84302 -396.389545) (xy 296.851096 -396.456481)
			(xy 296.851097 -396.523904) (xy 296.843022 -396.590841) (xy 296.826989 -396.656329) (xy 296.803227 -396.719425)
			(xy 296.77208 -396.779221) (xy 296.733994 -396.834856) (xy 296.712132 -396.860522) (xy 296.706335 -396.867667)
			(xy 296.699823 -396.884858) (xy 296.699432 -396.89405) (xy 296.699432 -397.386302) (xy 296.699856 -397.395487)
			(xy 296.706362 -397.412671) (xy 296.712132 -397.41983) (xy 296.733958 -397.445527) (xy 296.772045 -397.501157)
			(xy 296.800802 -397.556355) (xy 297.929014 -397.556355) (xy 297.937057 -397.489532) (xy 297.95303 -397.42415)
			(xy 297.976704 -397.361146) (xy 298.007738 -397.301423) (xy 298.045688 -397.245838) (xy 298.067476 -397.220186)
			(xy 298.073258 -397.21303) (xy 298.079782 -397.195848) (xy 298.080176 -397.186658) (xy 298.080176 -397.028924)
			(xy 298.080641 -397.018774) (xy 298.088424 -397.000027) (xy 298.102807 -396.985704) (xy 298.121587 -396.977999)
			(xy 298.131738 -396.977616) (xy 298.848018 -396.977616) (xy 298.858143 -396.978111) (xy 298.87686 -396.98584)
			(xy 298.891215 -397.000123) (xy 298.899038 -397.018802) (xy 298.89958 -397.028924) (xy 298.89958 -397.186658)
			(xy 298.900015 -397.195842) (xy 298.906512 -397.213027) (xy 298.91228 -397.220186) (xy 298.934077 -397.24583)
			(xy 298.972024 -397.301418) (xy 299.003056 -397.361143) (xy 299.026728 -397.424149) (xy 299.042699 -397.489532)
			(xy 299.050742 -397.556355) (xy 299.050741 -397.62366) (xy 299.042697 -397.690483) (xy 299.026723 -397.755866)
			(xy 299.00305 -397.818871) (xy 299.000445 -397.823885) (xy 300.128612 -397.823885) (xy 300.128616 -397.756458)
			(xy 300.136696 -397.689517) (xy 300.152736 -397.624025) (xy 300.176506 -397.560927) (xy 300.207662 -397.501129)
			(xy 300.245757 -397.445495) (xy 300.267624 -397.41983) (xy 300.273436 -397.412696) (xy 300.27994 -397.395497)
			(xy 300.280324 -397.386302) (xy 300.280324 -396.89405) (xy 300.279884 -396.884866) (xy 300.273391 -396.867682)
			(xy 300.267624 -396.860522) (xy 300.245749 -396.834865) (xy 300.207659 -396.77923) (xy 300.176508 -396.719433)
			(xy 300.152743 -396.656335) (xy 300.136708 -396.590845) (xy 300.128632 -396.523905) (xy 300.128633 -396.45648)
			(xy 300.13671 -396.389541) (xy 300.152748 -396.324051) (xy 300.176514 -396.260953) (xy 300.207667 -396.201157)
			(xy 300.245759 -396.145523) (xy 300.267624 -396.119858) (xy 300.273424 -396.112715) (xy 300.279936 -396.095523)
			(xy 300.280324 -396.08633) (xy 300.280324 -395.92885) (xy 300.280867 -395.918728) (xy 300.288576 -395.900011)
			(xy 300.302845 -395.885654) (xy 300.321514 -395.87783) (xy 300.331632 -395.877288) (xy 301.047912 -395.877288)
			(xy 301.058065 -395.877711) (xy 301.076816 -395.885509) (xy 301.091138 -395.899904) (xy 301.09884 -395.918694)
			(xy 301.09922 -395.92885) (xy 301.09922 -396.08633) (xy 301.099611 -396.095519) (xy 301.106138 -396.112704)
			(xy 301.11192 -396.119858) (xy 301.133773 -396.145532) (xy 301.171861 -396.201165) (xy 301.203011 -396.260961)
			(xy 301.226775 -396.324056) (xy 301.242811 -396.389544) (xy 301.250887 -396.456481) (xy 301.250888 -396.523904)
			(xy 301.242813 -396.590841) (xy 301.226779 -396.656329) (xy 301.203017 -396.719426) (xy 301.171869 -396.779222)
			(xy 301.133783 -396.834856) (xy 301.11192 -396.860522) (xy 301.106134 -396.867675) (xy 301.099612 -396.884859)
			(xy 301.09922 -396.89405) (xy 301.09922 -397.386302) (xy 301.099625 -397.39549) (xy 301.106142 -397.412674)
			(xy 301.11192 -397.41983) (xy 301.133746 -397.445526) (xy 301.171834 -397.501157) (xy 301.200562 -397.556296)
			(xy 302.328806 -397.556296) (xy 302.336881 -397.489359) (xy 302.352914 -397.423871) (xy 302.376676 -397.360775)
			(xy 302.407824 -397.300979) (xy 302.44591 -397.245344) (xy 302.467772 -397.219678) (xy 302.473569 -397.212534)
			(xy 302.480081 -397.195342) (xy 302.480472 -397.18615) (xy 302.480472 -397.028924) (xy 302.480935 -397.018806)
			(xy 302.48867 -397.000109) (xy 302.502972 -396.985795) (xy 302.521663 -396.978043) (xy 302.53178 -396.977616)
			(xy 303.24806 -396.977616) (xy 303.258182 -396.978049) (xy 303.276888 -396.985787) (xy 303.291204 -397.000099)
			(xy 303.298948 -397.018802) (xy 303.299368 -397.028924) (xy 303.299368 -397.18615) (xy 303.299809 -397.195334)
			(xy 303.306302 -397.212518) (xy 303.312068 -397.219678) (xy 303.333943 -397.245335) (xy 303.372033 -397.30097)
			(xy 303.403185 -397.360767) (xy 303.426951 -397.423865) (xy 303.442986 -397.489355) (xy 303.451062 -397.556295)
			(xy 303.451061 -397.62372) (xy 303.442984 -397.69066) (xy 303.426946 -397.75615) (xy 303.403179 -397.819247)
			(xy 303.372026 -397.879043) (xy 303.333934 -397.934677) (xy 303.312068 -397.960342) (xy 303.306267 -397.967484)
			(xy 303.299756 -397.984677) (xy 303.299368 -397.99387) (xy 303.299368 -398.486376) (xy 303.299797 -398.495561)
			(xy 303.306299 -398.512745) (xy 303.312068 -398.519904) (xy 303.333968 -398.54554) (xy 303.372058 -398.601178)
			(xy 303.403209 -398.660978) (xy 303.426973 -398.724078) (xy 303.443007 -398.789571) (xy 303.45108 -398.856513)
			(xy 303.451077 -398.923941) (xy 303.442997 -398.990882) (xy 303.426957 -399.056373) (xy 303.403187 -399.119472)
			(xy 303.37203 -399.179269) (xy 303.333935 -399.234903) (xy 303.312068 -399.260568) (xy 303.306256 -399.267702)
			(xy 303.299751 -399.284901) (xy 303.299368 -399.294096) (xy 303.299368 -399.451576) (xy 303.298964 -399.461701)
			(xy 303.291218 -399.48041) (xy 303.276897 -399.494727) (xy 303.258185 -399.502467) (xy 303.24806 -399.502884)
			(xy 302.53178 -399.502884) (xy 302.521654 -399.5025) (xy 302.502947 -399.494742) (xy 302.488633 -399.480416)
			(xy 302.480891 -399.461702) (xy 302.480472 -399.451576) (xy 302.480472 -399.294096) (xy 302.48007 -399.284908)
			(xy 302.473551 -399.267723) (xy 302.467772 -399.260568) (xy 302.445944 -399.234873) (xy 302.407856 -399.179242)
			(xy 302.376706 -399.11945) (xy 302.352941 -399.056357) (xy 302.336904 -398.990872) (xy 302.328825 -398.923937)
			(xy 302.328822 -398.856517) (xy 302.336894 -398.789582) (xy 302.352925 -398.724095) (xy 302.376684 -398.661)
			(xy 302.407829 -398.601204) (xy 302.445911 -398.54557) (xy 302.467772 -398.519904) (xy 302.473558 -398.512752)
			(xy 302.480077 -398.495566) (xy 302.480472 -398.486376) (xy 302.480472 -397.99387) (xy 302.480082 -397.98468)
			(xy 302.473555 -397.967496) (xy 302.467772 -397.960342) (xy 302.445919 -397.934668) (xy 302.407832 -397.879034)
			(xy 302.376682 -397.819239) (xy 302.352919 -397.756143) (xy 302.336883 -397.690656) (xy 302.328807 -397.623719)
			(xy 302.328806 -397.556296) (xy 301.200562 -397.556296) (xy 301.202986 -397.560949) (xy 301.226751 -397.624042)
			(xy 301.242789 -397.689527) (xy 301.250867 -397.756461) (xy 301.250871 -397.823882) (xy 301.242799 -397.890817)
			(xy 301.226768 -397.956304) (xy 301.203009 -398.019399) (xy 301.171864 -398.079194) (xy 301.133781 -398.134828)
			(xy 301.11192 -398.160494) (xy 301.106146 -398.167655) (xy 301.099617 -398.184833) (xy 301.09922 -398.194022)
			(xy 301.09922 -398.351502) (xy 301.098774 -398.361634) (xy 301.091038 -398.380362) (xy 301.076739 -398.39472)
			(xy 301.058042 -398.402532) (xy 301.047912 -398.403064) (xy 300.331632 -398.403064) (xy 300.321475 -398.402652)
			(xy 300.302717 -398.39486) (xy 300.288391 -398.38046) (xy 300.280696 -398.361661) (xy 300.280324 -398.351502)
			(xy 300.280324 -398.194022) (xy 300.279898 -398.184837) (xy 300.273395 -398.167652) (xy 300.267624 -398.160494)
			(xy 300.245722 -398.13486) (xy 300.207633 -398.079222) (xy 300.176482 -398.019421) (xy 300.152719 -397.95632)
			(xy 300.136686 -397.890827) (xy 300.128612 -397.823885) (xy 299.000445 -397.823885) (xy 298.972017 -397.878595)
			(xy 298.934068 -397.934182) (xy 298.91228 -397.959834) (xy 298.906484 -397.96698) (xy 298.89997 -397.98417)
			(xy 298.89958 -397.993362) (xy 298.89958 -398.486884) (xy 298.900003 -398.49607) (xy 298.906508 -398.513254)
			(xy 298.91228 -398.520412) (xy 298.934103 -398.546035) (xy 298.972049 -398.601626) (xy 299.00308 -398.661354)
			(xy 299.02675 -398.724362) (xy 299.04272 -398.789748) (xy 299.050761 -398.856573) (xy 299.050757 -398.923881)
			(xy 299.04271 -398.990706) (xy 299.026734 -399.05609) (xy 299.003058 -399.119095) (xy 298.972021 -399.17882)
			(xy 298.934069 -399.234408) (xy 298.91228 -399.26006) (xy 298.906473 -399.267198) (xy 298.899965 -399.284394)
			(xy 298.89958 -399.293588) (xy 298.89958 -399.451576) (xy 298.899159 -399.461731) (xy 298.891367 -399.480487)
			(xy 298.87697 -399.494812) (xy 298.858175 -399.502509) (xy 298.848018 -399.502884) (xy 298.131738 -399.502884)
			(xy 298.121617 -399.502343) (xy 298.102901 -399.494632) (xy 298.088544 -399.480362) (xy 298.08072 -399.461694)
			(xy 298.080176 -399.451576) (xy 298.080176 -399.293588) (xy 298.079777 -399.2844) (xy 298.073256 -399.267215)
			(xy 298.067476 -399.26006) (xy 298.045723 -399.234379) (xy 298.00777 -399.178798) (xy 297.976733 -399.119078)
			(xy 297.953057 -399.056078) (xy 297.93708 -398.990699) (xy 297.929033 -398.923879) (xy 297.92903 -398.856576)
			(xy 297.937071 -398.789755) (xy 297.953041 -398.724374) (xy 297.976711 -398.661371) (xy 298.007742 -398.601649)
			(xy 298.045689 -398.546064) (xy 298.067476 -398.520412) (xy 298.07329 -398.513279) (xy 298.079795 -398.496079)
			(xy 298.080176 -398.486884) (xy 298.080176 -397.993362) (xy 298.079789 -397.984172) (xy 298.07326 -397.966988)
			(xy 298.067476 -397.959834) (xy 298.045697 -397.934174) (xy 298.007746 -397.87859) (xy 297.97671 -397.818868)
			(xy 297.953035 -397.755864) (xy 297.93706 -397.690482) (xy 297.929015 -397.62366) (xy 297.929014 -397.556355)
			(xy 296.800802 -397.556355) (xy 296.803196 -397.56095) (xy 296.826961 -397.624042) (xy 296.842998 -397.689527)
			(xy 296.851076 -397.756461) (xy 296.85108 -397.823881) (xy 296.843008 -397.890817) (xy 296.826978 -397.956303)
			(xy 296.803219 -398.019398) (xy 296.772075 -398.079194) (xy 296.733993 -398.134828) (xy 296.712132 -398.160494)
			(xy 296.706347 -398.167647) (xy 296.699827 -398.184832) (xy 296.699432 -398.194022) (xy 296.699432 -398.351502)
			(xy 296.698974 -398.361632) (xy 296.691241 -398.380359) (xy 296.676945 -398.394716) (xy 296.658252 -398.40253)
			(xy 296.648124 -398.403064) (xy 295.931844 -398.403064) (xy 295.921688 -398.402642) (xy 295.90293 -398.394854)
			(xy 295.888604 -398.380456) (xy 295.880909 -398.36166) (xy 295.880536 -398.351502) (xy 295.880536 -398.194022)
			(xy 295.880107 -398.184837) (xy 295.873606 -398.167653) (xy 295.867836 -398.160494) (xy 295.845933 -398.13486)
			(xy 295.807843 -398.079222) (xy 295.776692 -398.019422) (xy 295.752929 -397.956321) (xy 295.736895 -397.890827)
			(xy 295.728821 -397.823885) (xy 294.600676 -397.823885) (xy 294.57194 -397.879043) (xy 294.533849 -397.934677)
			(xy 294.511984 -397.960342) (xy 294.506185 -397.967486) (xy 294.499672 -397.984677) (xy 294.499284 -397.99387)
			(xy 294.499284 -398.486376) (xy 294.499709 -398.495561) (xy 294.506213 -398.512746) (xy 294.511984 -398.519904)
			(xy 294.533884 -398.54554) (xy 294.571973 -398.601178) (xy 294.603123 -398.660978) (xy 294.626885 -398.724079)
			(xy 294.642919 -398.789572) (xy 294.650992 -398.856514) (xy 294.650989 -398.92394) (xy 294.642909 -398.990881)
			(xy 294.626869 -399.056373) (xy 294.603101 -399.119471) (xy 294.571945 -399.179268) (xy 294.533851 -399.234903)
			(xy 294.511984 -399.260568) (xy 294.506174 -399.267704) (xy 294.499668 -399.284902) (xy 294.499284 -399.294096)
			(xy 294.499284 -399.451576) (xy 294.498864 -399.461699) (xy 294.491121 -399.480405) (xy 294.476805 -399.494721)
			(xy 294.458099 -399.502464) (xy 294.447976 -399.502884) (xy 293.731696 -399.502884) (xy 293.721571 -399.502487)
			(xy 293.702865 -399.494734) (xy 293.68855 -399.480412) (xy 293.680808 -399.461701) (xy 293.680388 -399.451576)
			(xy 293.680388 -399.294096) (xy 293.679982 -399.284908) (xy 293.673466 -399.267724) (xy 293.667688 -399.260568)
			(xy 293.64586 -399.234873) (xy 293.607771 -399.179243) (xy 293.576619 -399.119451) (xy 293.552854 -399.056358)
			(xy 293.536816 -398.990872) (xy 293.528737 -398.923937) (xy 293.528734 -398.856517) (xy 293.536806 -398.789581)
			(xy 293.552838 -398.724094) (xy 293.576597 -398.660999) (xy 293.607743 -398.601204) (xy 293.645827 -398.545569)
			(xy 293.667688 -398.519904) (xy 293.673464 -398.512744) (xy 293.679991 -398.495565) (xy 293.680388 -398.486376)
			(xy 293.680388 -397.99387) (xy 293.679995 -397.984681) (xy 293.673469 -397.967497) (xy 293.667688 -397.960342)
			(xy 293.645834 -397.934668) (xy 293.607746 -397.879035) (xy 293.576596 -397.81924) (xy 293.552831 -397.756144)
			(xy 293.536796 -397.690656) (xy 293.528719 -397.623719) (xy 293.528718 -397.556296) (xy 292.40047 -397.556296)
			(xy 292.403082 -397.561322) (xy 292.426757 -397.624322) (xy 292.442733 -397.689701) (xy 292.450781 -397.75652)
			(xy 292.450784 -397.823823) (xy 292.442744 -397.890643) (xy 292.426774 -397.956023) (xy 292.403105 -398.019026)
			(xy 292.372075 -398.078748) (xy 292.33413 -398.134334) (xy 292.312344 -398.159986) (xy 292.306522 -398.167113)
			(xy 292.300024 -398.184318) (xy 292.299644 -398.193514) (xy 292.299644 -398.351502) (xy 292.299237 -398.361676)
			(xy 292.291448 -398.380474) (xy 292.277057 -398.39486) (xy 292.258256 -398.402641) (xy 292.248082 -398.403064)
			(xy 291.531802 -398.403064) (xy 291.521645 -398.402565) (xy 291.502876 -398.394792) (xy 291.488511 -398.380427)
			(xy 291.480736 -398.361659) (xy 291.48024 -398.351502) (xy 291.48024 -398.193514) (xy 291.479814 -398.184329)
			(xy 291.473311 -398.167145) (xy 291.46754 -398.159986) (xy 291.445715 -398.134365) (xy 291.407767 -398.078774)
			(xy 291.376735 -398.019046) (xy 291.353065 -397.956037) (xy 291.337094 -397.890651) (xy 291.329053 -397.823825)
			(xy 290.200388 -397.823825) (xy 290.171931 -397.878594) (xy 290.133983 -397.934181) (xy 290.112196 -397.959834)
			(xy 290.106402 -397.966981) (xy 290.099886 -397.98417) (xy 290.099496 -397.993362) (xy 290.099496 -398.486884)
			(xy 290.099915 -398.49607) (xy 290.106423 -398.513255) (xy 290.112196 -398.520412) (xy 290.134018 -398.546036)
			(xy 290.171963 -398.601627) (xy 290.202993 -398.661355) (xy 290.226662 -398.724363) (xy 290.242632 -398.789748)
			(xy 290.250673 -398.856573) (xy 290.250669 -398.923881) (xy 290.242622 -398.990705) (xy 290.226646 -399.056089)
			(xy 290.202971 -399.119095) (xy 290.171936 -399.17882) (xy 290.133985 -399.234407) (xy 290.112196 -399.26006)
			(xy 290.106391 -399.267199) (xy 290.099881 -399.284394) (xy 290.099496 -399.293588) (xy 290.099496 -399.451576)
			(xy 290.099059 -399.461729) (xy 290.09127 -399.480482) (xy 290.076878 -399.494806) (xy 290.058089 -399.502506)
			(xy 290.047934 -399.502884) (xy 289.331654 -399.502884) (xy 289.321527 -399.502412) (xy 289.30281 -399.494673)
			(xy 289.288456 -399.480383) (xy 289.280634 -399.4617) (xy 289.280092 -399.451576) (xy 289.280092 -399.293588)
			(xy 289.279689 -399.2844) (xy 289.273171 -399.267216) (xy 289.267392 -399.26006) (xy 289.245638 -399.234379)
			(xy 289.207685 -399.178798) (xy 289.176647 -399.119079) (xy 289.15297 -399.056078) (xy 289.136993 -398.990699)
			(xy 289.128945 -398.923879) (xy 289.128942 -398.856575) (xy 289.136983 -398.789754) (xy 289.152954 -398.724374)
			(xy 289.176625 -398.66137) (xy 289.207657 -398.601648) (xy 289.245605 -398.546063) (xy 289.267392 -398.520412)
			(xy 289.273208 -398.51328) (xy 289.279711 -398.496079) (xy 289.280092 -398.486884) (xy 289.280092 -397.993362)
			(xy 289.279702 -397.984173) (xy 289.273175 -397.966988) (xy 289.267392 -397.959834) (xy 289.245612 -397.934174)
			(xy 289.20766 -397.87859) (xy 289.176623 -397.818868) (xy 289.152948 -397.755865) (xy 289.136972 -397.690483)
			(xy 289.128927 -397.62366) (xy 289.128926 -397.556355) (xy 288.000733 -397.556355) (xy 288.003125 -397.560946)
			(xy 288.026894 -397.624039) (xy 288.042933 -397.689525) (xy 288.051013 -397.756461) (xy 288.051016 -397.823882)
			(xy 288.042944 -397.890819) (xy 288.026911 -397.956307) (xy 288.003148 -398.019402) (xy 287.971999 -398.079197)
			(xy 287.933912 -398.13483) (xy 287.912048 -398.160494) (xy 287.906265 -398.167649) (xy 287.899744 -398.184832)
			(xy 287.899348 -398.194022) (xy 287.899348 -398.351502) (xy 287.898875 -398.36163) (xy 287.891144 -398.380354)
			(xy 287.876853 -398.39471) (xy 287.858166 -398.402527) (xy 287.84804 -398.403064) (xy 287.13176 -398.403064)
			(xy 287.121599 -398.40271) (xy 287.102839 -398.394895) (xy 287.088515 -398.380477) (xy 287.080824 -398.361666)
			(xy 287.080452 -398.351502) (xy 287.080452 -398.194022) (xy 287.08002 -398.184837) (xy 287.07352 -398.167653)
			(xy 287.067752 -398.160494) (xy 287.045849 -398.13486) (xy 287.007758 -398.079223) (xy 286.976606 -398.019423)
			(xy 286.952842 -397.956321) (xy 286.936807 -397.890828) (xy 286.928734 -397.823885) (xy 270.510088 -397.823885)
			(xy 270.342048 -397.902798) (xy 270.153023 -397.982721) (xy 269.961023 -398.055207) (xy 269.766341 -398.120147)
			(xy 269.569274 -398.177442) (xy 269.370121 -398.227005) (xy 269.169187 -398.26876) (xy 268.966776 -398.302643)
			(xy 268.763198 -398.328603) (xy 268.558761 -398.3466) (xy 268.353778 -398.356608) (xy 268.148561 -398.35861)
			(xy 267.943422 -398.352604) (xy 267.738673 -398.338599) (xy 267.534626 -398.316616) (xy 267.331593 -398.286689)
			(xy 267.129882 -398.248862) (xy 266.9298 -398.203195) (xy 266.731653 -398.149756) (xy 266.535741 -398.088627)
			(xy 266.342364 -398.019901) (xy 266.151815 -397.943682) (xy 265.964385 -397.860086) (xy 265.780359 -397.769242)
			(xy 265.600018 -397.671287) (xy 265.423636 -397.56637) (xy 265.251482 -397.454651) (xy 265.083817 -397.336301)
			(xy 264.920898 -397.211499) (xy 264.762972 -397.080435) (xy 264.61028 -396.94331) (xy 264.463055 -396.800332)
			(xy 264.32152 -396.651718) (xy 264.185891 -396.497696) (xy 264.056374 -396.338499) (xy 263.933168 -396.17437)
			(xy 263.816459 -396.005559) (xy 263.706425 -395.832322) (xy 263.603234 -395.654925) (xy 263.507043 -395.473637)
			(xy 263.417998 -395.288734) (xy 263.336235 -395.100497) (xy 263.261879 -394.909214) (xy 263.195043 -394.715175)
			(xy 263.135828 -394.518676) (xy 263.084325 -394.320017) (xy 263.040611 -394.119499) (xy 263.004755 -393.917428)
			(xy 262.97681 -393.714113) (xy 262.956819 -393.509862) (xy 262.944812 -393.304986) (xy 262.940808 -393.099798)
			(xy 244.446806 -393.099798) (xy 244.446806 -399.877788) (xy 244.446318 -399.902738) (xy 244.438514 -399.952023)
			(xy 244.423096 -399.999481) (xy 244.400444 -400.043942) (xy 244.371115 -400.084313) (xy 244.353842 -400.102324)
			(xy 243.288058 -401.168108) (xy 243.270059 -401.185391) (xy 243.229675 -401.214698) (xy 243.185209 -401.237337)
			(xy 243.137752 -401.252752) (xy 243.08847 -401.260565) (xy 243.063522 -401.261072) (xy 239.143794 -401.261072)
			(xy 239.133724 -401.261495) (xy 239.115118 -401.269208) (xy 239.107726 -401.276058) (xy 238.659987 -401.723797)
			(xy 286.928745 -401.723797) (xy 286.928747 -401.65637) (xy 286.936826 -401.58943) (xy 286.952865 -401.523939)
			(xy 286.976634 -401.460841) (xy 287.00779 -401.401044) (xy 287.045885 -401.34541) (xy 287.067752 -401.319746)
			(xy 287.07356 -401.312609) (xy 287.080067 -401.295412) (xy 287.080452 -401.286218) (xy 287.080452 -400.793966)
			(xy 287.080046 -400.784779) (xy 287.073528 -400.767595) (xy 287.067752 -400.760438) (xy 287.045892 -400.734769)
			(xy 287.0078 -400.679136) (xy 286.976646 -400.619341) (xy 286.952879 -400.556244) (xy 286.936842 -400.490755)
			(xy 286.928764 -400.423817) (xy 286.928764 -400.356392) (xy 286.93684 -400.289454) (xy 286.952876 -400.223964)
			(xy 286.976642 -400.160867) (xy 287.007795 -400.101072) (xy 287.045887 -400.045438) (xy 287.067752 -400.019774)
			(xy 287.073549 -400.012629) (xy 287.080062 -399.995438) (xy 287.080452 -399.986246) (xy 287.080452 -399.828766)
			(xy 287.080899 -399.818636) (xy 287.08864 -399.799911) (xy 287.102939 -399.785556) (xy 287.121632 -399.77774)
			(xy 287.13176 -399.777204) (xy 287.84804 -399.777204) (xy 287.858197 -399.777589) (xy 287.876951 -399.785399)
			(xy 287.891273 -399.799806) (xy 287.898971 -399.818606) (xy 287.899348 -399.828766) (xy 287.899348 -399.986246)
			(xy 287.899796 -399.995429) (xy 287.906285 -400.012613) (xy 287.912048 -400.019774) (xy 287.93392 -400.045433)
			(xy 287.972012 -400.101068) (xy 288.003165 -400.160864) (xy 288.026931 -400.223962) (xy 288.042968 -400.289452)
			(xy 288.051044 -400.356392) (xy 288.051043 -400.423817) (xy 288.042966 -400.490757) (xy 288.026928 -400.556247)
			(xy 288.003161 -400.619344) (xy 287.972007 -400.67914) (xy 287.933914 -400.734774) (xy 287.912048 -400.760438)
			(xy 287.906246 -400.767579) (xy 287.899736 -400.784773) (xy 287.899348 -400.793966) (xy 287.899348 -401.286218)
			(xy 287.899761 -401.295405) (xy 287.906274 -401.312588) (xy 287.912048 -401.319746) (xy 287.933892 -401.345428)
			(xy 287.971985 -401.401059) (xy 288.00314 -401.460852) (xy 288.026907 -401.523947) (xy 288.042946 -401.589435)
			(xy 288.051024 -401.656372) (xy 288.051026 -401.723795) (xy 288.042952 -401.790733) (xy 288.026917 -401.856221)
			(xy 288.003153 -401.919317) (xy 287.972002 -401.979113) (xy 287.933912 -402.034746) (xy 287.912048 -402.06041)
			(xy 287.906258 -402.06756) (xy 287.899741 -402.084747) (xy 287.899348 -402.093938) (xy 287.899348 -402.251418)
			(xy 287.898888 -402.261547) (xy 287.891152 -402.280271) (xy 287.876858 -402.294627) (xy 287.858167 -402.302444)
			(xy 287.84804 -402.30298) (xy 287.13176 -402.30298) (xy 287.121601 -402.302611) (xy 287.102844 -402.294798)
			(xy 287.088521 -402.280385) (xy 287.080826 -402.26158) (xy 287.080452 -402.251418) (xy 287.080452 -402.093938)
			(xy 287.080012 -402.084754) (xy 287.073518 -402.06757) (xy 287.067752 -402.06041) (xy 287.045865 -402.034763)
			(xy 287.007773 -401.979127) (xy 286.97662 -401.919329) (xy 286.952855 -401.85623) (xy 286.93682 -401.790738)
			(xy 286.928745 -401.723797) (xy 238.659987 -401.723797) (xy 237.559965 -402.823819) (xy 289.128886 -402.823819)
			(xy 289.12889 -402.756509) (xy 289.13694 -402.689682) (xy 289.15292 -402.624297) (xy 289.1766 -402.56129)
			(xy 289.207642 -402.501565) (xy 289.2456 -402.445979) (xy 289.267392 -402.420328) (xy 289.273201 -402.413191)
			(xy 289.279708 -402.395994) (xy 289.280092 -402.3868) (xy 289.280092 -401.893532) (xy 289.279668 -401.884346)
			(xy 289.273164 -401.867162) (xy 289.267392 -401.860004) (xy 289.245583 -401.834369) (xy 289.207631 -401.778781)
			(xy 289.176596 -401.719056) (xy 289.152922 -401.656049) (xy 289.136949 -401.590664) (xy 289.128906 -401.523839)
			(xy 289.128907 -401.456531) (xy 289.136954 -401.389706) (xy 289.152931 -401.324322) (xy 289.176608 -401.261317)
			(xy 289.207647 -401.201593) (xy 289.245601 -401.146007) (xy 289.267392 -401.120356) (xy 289.273189 -401.113211)
			(xy 289.279704 -401.09602) (xy 289.280092 -401.086828) (xy 289.280092 -400.92884) (xy 289.280554 -400.918689)
			(xy 289.288335 -400.89994) (xy 289.30272 -400.885615) (xy 289.321502 -400.877913) (xy 289.331654 -400.877532)
			(xy 290.047934 -400.877532) (xy 290.058062 -400.877998) (xy 290.076782 -400.885736) (xy 290.091137 -400.900028)
			(xy 290.098957 -400.918714) (xy 290.099496 -400.92884) (xy 290.099496 -401.086828) (xy 290.099893 -401.096017)
			(xy 290.106416 -401.113201) (xy 290.112196 -401.120356) (xy 290.133963 -401.146025) (xy 290.17191 -401.20161)
			(xy 290.202942 -401.261331) (xy 290.226615 -401.324334) (xy 290.242588 -401.389713) (xy 290.250633 -401.456534)
			(xy 290.250635 -401.523836) (xy 290.242593 -401.590657) (xy 290.226624 -401.656038) (xy 290.202955 -401.719041)
			(xy 290.200515 -401.723737) (xy 291.329064 -401.723737) (xy 291.329066 -401.65643) (xy 291.337113 -401.589606)
			(xy 291.353088 -401.524222) (xy 291.376763 -401.461217) (xy 291.407799 -401.401493) (xy 291.445751 -401.345906)
			(xy 291.46754 -401.320254) (xy 291.473344 -401.313114) (xy 291.479853 -401.295919) (xy 291.48024 -401.286726)
			(xy 291.48024 -400.793458) (xy 291.479841 -400.78427) (xy 291.473319 -400.767086) (xy 291.46754 -400.75993)
			(xy 291.445758 -400.734273) (xy 291.407809 -400.678687) (xy 291.376776 -400.618964) (xy 291.353103 -400.55596)
			(xy 291.337129 -400.490579) (xy 291.329085 -400.423757) (xy 291.329084 -400.356452) (xy 291.337128 -400.28963)
			(xy 291.3531 -400.224248) (xy 291.376772 -400.161244) (xy 291.407805 -400.101521) (xy 291.445753 -400.045934)
			(xy 291.46754 -400.020282) (xy 291.473332 -400.013134) (xy 291.479848 -399.995945) (xy 291.48024 -399.986754)
			(xy 291.48024 -399.828766) (xy 291.480706 -399.818606) (xy 291.488492 -399.799835) (xy 291.502866 -399.785471)
			(xy 291.521641 -399.777698) (xy 291.531802 -399.777204) (xy 292.248082 -399.777204) (xy 292.258234 -399.777747)
			(xy 292.276997 -399.785509) (xy 292.291361 -399.79986) (xy 292.299143 -399.818614) (xy 292.299644 -399.828766)
			(xy 292.299644 -399.986754) (xy 292.300089 -399.995937) (xy 292.30658 -400.013121) (xy 292.312344 -400.020282)
			(xy 292.334138 -400.045929) (xy 292.372088 -400.101516) (xy 292.403122 -400.16124) (xy 292.426795 -400.224245)
			(xy 292.442768 -400.289628) (xy 292.450812 -400.356452) (xy 292.450811 -400.423757) (xy 292.442766 -400.490581)
			(xy 292.426792 -400.555963) (xy 292.403118 -400.618968) (xy 292.372083 -400.678692) (xy 292.334132 -400.734278)
			(xy 292.312344 -400.75993) (xy 292.306545 -400.767073) (xy 292.300033 -400.784266) (xy 292.299644 -400.793458)
			(xy 292.299644 -401.286726) (xy 292.300054 -401.295913) (xy 292.306569 -401.313097) (xy 292.312344 -401.320254)
			(xy 292.33411 -401.345924) (xy 292.372061 -401.401507) (xy 292.403096 -401.461228) (xy 292.426771 -401.524231)
			(xy 292.442746 -401.589611) (xy 292.450792 -401.656432) (xy 292.450794 -401.723735) (xy 292.442752 -401.790557)
			(xy 292.426781 -401.855938) (xy 292.40311 -401.918941) (xy 292.372078 -401.978664) (xy 292.334131 -402.03425)
			(xy 292.312344 -402.059902) (xy 292.306557 -402.067054) (xy 292.300038 -402.084239) (xy 292.299644 -402.09343)
			(xy 292.299644 -402.251418) (xy 292.299181 -402.261579) (xy 292.291397 -402.280352) (xy 292.277022 -402.294718)
			(xy 292.258244 -402.302488) (xy 292.248082 -402.30298) (xy 291.531802 -402.30298) (xy 291.521647 -402.302465)
			(xy 291.502881 -402.294695) (xy 291.488516 -402.280336) (xy 291.480739 -402.261573) (xy 291.48024 -402.251418)
			(xy 291.48024 -402.09343) (xy 291.479806 -402.084246) (xy 291.473308 -402.067061) (xy 291.46754 -402.059902)
			(xy 291.44573 -402.034268) (xy 291.407782 -401.978679) (xy 291.37675 -401.918953) (xy 291.353078 -401.855946)
			(xy 291.337107 -401.790561) (xy 291.329064 -401.723737) (xy 290.200515 -401.723737) (xy 290.171926 -401.778764)
			(xy 290.133981 -401.834351) (xy 290.112196 -401.860004) (xy 290.106415 -401.86716) (xy 290.099891 -401.884342)
			(xy 290.099496 -401.893532) (xy 290.099496 -402.3868) (xy 290.099907 -402.395987) (xy 290.10642 -402.413171)
			(xy 290.112196 -402.420328) (xy 290.133935 -402.44602) (xy 290.171883 -402.501601) (xy 290.202916 -402.56132)
			(xy 290.22659 -402.624319) (xy 290.242566 -402.689696) (xy 290.250613 -402.756514) (xy 290.250617 -402.823814)
			(xy 290.250609 -402.823878) (xy 293.528678 -402.823878) (xy 293.528683 -402.75645) (xy 293.536763 -402.689509)
			(xy 293.552803 -402.624017) (xy 293.576572 -402.560919) (xy 293.607728 -402.501121) (xy 293.645822 -402.445485)
			(xy 293.667688 -402.41982) (xy 293.6735 -402.412685) (xy 293.680006 -402.395487) (xy 293.680388 -402.386292)
			(xy 293.680388 -401.89404) (xy 293.679961 -401.884854) (xy 293.67346 -401.86767) (xy 293.667688 -401.860512)
			(xy 293.645805 -401.834863) (xy 293.607717 -401.779226) (xy 293.576568 -401.719427) (xy 293.552806 -401.656328)
			(xy 293.536772 -401.590837) (xy 293.528698 -401.523897) (xy 293.5287 -401.456472) (xy 293.536777 -401.389533)
			(xy 293.552815 -401.324043) (xy 293.576581 -401.260945) (xy 293.607733 -401.201149) (xy 293.645823 -401.145513)
			(xy 293.667688 -401.119848) (xy 293.673488 -401.112705) (xy 293.680001 -401.095513) (xy 293.680388 -401.08632)
			(xy 293.680388 -400.92884) (xy 293.680849 -400.918722) (xy 293.688581 -400.900021) (xy 293.702884 -400.885706)
			(xy 293.721578 -400.877957) (xy 293.731696 -400.877532) (xy 294.447976 -400.877532) (xy 294.458101 -400.877936)
			(xy 294.47681 -400.885682) (xy 294.491127 -400.900003) (xy 294.498867 -400.918715) (xy 294.499284 -400.92884)
			(xy 294.499284 -401.08632) (xy 294.499688 -401.095508) (xy 294.506206 -401.112692) (xy 294.511984 -401.119848)
			(xy 294.533829 -401.145529) (xy 294.571919 -401.201161) (xy 294.603072 -401.260955) (xy 294.626838 -401.32405)
			(xy 294.642875 -401.389537) (xy 294.650953 -401.456474) (xy 294.650955 -401.523896) (xy 294.64288 -401.590833)
			(xy 294.626847 -401.656322) (xy 294.603084 -401.719418) (xy 294.600803 -401.723797) (xy 295.728833 -401.723797)
			(xy 295.728835 -401.65637) (xy 295.736913 -401.58943) (xy 295.752952 -401.523939) (xy 295.77672 -401.460841)
			(xy 295.807876 -401.401045) (xy 295.845969 -401.345411) (xy 295.867836 -401.319746) (xy 295.873643 -401.312608)
			(xy 295.88015 -401.295412) (xy 295.880536 -401.286218) (xy 295.880536 -400.793966) (xy 295.880134 -400.784778)
			(xy 295.873614 -400.767594) (xy 295.867836 -400.760438) (xy 295.845977 -400.734769) (xy 295.807885 -400.679135)
			(xy 295.776732 -400.61934) (xy 295.752966 -400.556244) (xy 295.736929 -400.490755) (xy 295.728852 -400.423816)
			(xy 295.728852 -400.356393) (xy 295.736928 -400.289454) (xy 295.752964 -400.223965) (xy 295.776729 -400.160868)
			(xy 295.807881 -400.101072) (xy 295.845971 -400.045439) (xy 295.867836 -400.019774) (xy 295.873631 -400.012628)
			(xy 295.880146 -399.995438) (xy 295.880536 -399.986246) (xy 295.880536 -399.828766) (xy 295.880999 -399.818638)
			(xy 295.888737 -399.799916) (xy 295.90303 -399.785561) (xy 295.921718 -399.777743) (xy 295.931844 -399.777204)
			(xy 296.648124 -399.777204) (xy 296.65828 -399.777602) (xy 296.677034 -399.785406) (xy 296.691357 -399.79981)
			(xy 296.699055 -399.818608) (xy 296.699432 -399.828766) (xy 296.699432 -399.986246) (xy 296.699883 -399.995429)
			(xy 296.70637 -400.012613) (xy 296.712132 -400.019774) (xy 296.734001 -400.045435) (xy 296.772087 -400.101071)
			(xy 296.803236 -400.160868) (xy 296.826998 -400.223965) (xy 296.843032 -400.289455) (xy 296.851107 -400.356393)
			(xy 296.851107 -400.423816) (xy 296.843031 -400.490754) (xy 296.826996 -400.556243) (xy 296.803232 -400.61934)
			(xy 296.772083 -400.679137) (xy 296.733995 -400.734772) (xy 296.712132 -400.760438) (xy 296.706329 -400.767578)
			(xy 296.69982 -400.784773) (xy 296.699432 -400.793966) (xy 296.699432 -401.286218) (xy 296.699849 -401.295404)
			(xy 296.70636 -401.312588) (xy 296.712132 -401.319746) (xy 296.733973 -401.34543) (xy 296.77206 -401.401062)
			(xy 296.80321 -401.460856) (xy 296.826974 -401.523951) (xy 296.84301 -401.589437) (xy 296.851088 -401.656373)
			(xy 296.85109 -401.723794) (xy 296.843016 -401.79073) (xy 296.826984 -401.856218) (xy 296.803224 -401.919314)
			(xy 296.772078 -401.979109) (xy 296.733994 -402.034744) (xy 296.712132 -402.06041) (xy 296.70634 -402.067558)
			(xy 296.699825 -402.084747) (xy 296.699432 -402.093938) (xy 296.699432 -402.251418) (xy 296.698988 -402.261549)
			(xy 296.691249 -402.280276) (xy 296.676949 -402.294633) (xy 296.658253 -402.302447) (xy 296.648124 -402.30298)
			(xy 295.931844 -402.30298) (xy 295.92169 -402.302542) (xy 295.902935 -402.294757) (xy 295.888609 -402.280365)
			(xy 295.880912 -402.261574) (xy 295.880536 -402.251418) (xy 295.880536 -402.093938) (xy 295.880099 -402.084754)
			(xy 295.873603 -402.06757) (xy 295.867836 -402.06041) (xy 295.845949 -402.034763) (xy 295.807859 -401.979127)
			(xy 295.776707 -401.919328) (xy 295.752942 -401.856229) (xy 295.736907 -401.790737) (xy 295.728833 -401.723797)
			(xy 294.600803 -401.723797) (xy 294.571935 -401.779213) (xy 294.533847 -401.834847) (xy 294.511984 -401.860512)
			(xy 294.506198 -401.867665) (xy 294.499678 -401.88485) (xy 294.499284 -401.89404) (xy 294.499284 -402.386292)
			(xy 294.499702 -402.395478) (xy 294.506211 -402.412662) (xy 294.511984 -402.41982) (xy 294.533801 -402.445524)
			(xy 294.571893 -402.501152) (xy 294.603046 -402.560943) (xy 294.626814 -402.624035) (xy 294.642853 -402.68952)
			(xy 294.650933 -402.756454) (xy 294.650937 -402.823819) (xy 297.928973 -402.823819) (xy 297.928978 -402.756509)
			(xy 297.937027 -402.689683) (xy 297.953006 -402.624297) (xy 297.976686 -402.561291) (xy 298.007727 -402.501566)
			(xy 298.045684 -402.445979) (xy 298.067476 -402.420328) (xy 298.073283 -402.41319) (xy 298.079792 -402.395994)
			(xy 298.080176 -402.3868) (xy 298.080176 -401.893532) (xy 298.079756 -401.884346) (xy 298.07325 -401.867161)
			(xy 298.067476 -401.860004) (xy 298.045668 -401.834368) (xy 298.007717 -401.77878) (xy 297.976683 -401.719055)
			(xy 297.953009 -401.656048) (xy 297.937037 -401.590664) (xy 297.928993 -401.523839) (xy 297.928995 -401.456531)
			(xy 297.937042 -401.389707) (xy 297.953018 -401.324323) (xy 297.976695 -401.261318) (xy 298.007732 -401.201594)
			(xy 298.045686 -401.146008) (xy 298.067476 -401.120356) (xy 298.073271 -401.113209) (xy 298.079787 -401.09602)
			(xy 298.080176 -401.086828) (xy 298.080176 -400.92884) (xy 298.080654 -400.918691) (xy 298.088432 -400.899945)
			(xy 298.102811 -400.885621) (xy 298.121588 -400.877915) (xy 298.131738 -400.877532) (xy 298.848018 -400.877532)
			(xy 298.858145 -400.878011) (xy 298.876865 -400.885744) (xy 298.89122 -400.900032) (xy 298.89904 -400.918716)
			(xy 298.89958 -400.92884) (xy 298.89958 -401.086828) (xy 298.899981 -401.096016) (xy 298.906502 -401.1132)
			(xy 298.91228 -401.120356) (xy 298.934048 -401.146024) (xy 298.971996 -401.201609) (xy 299.003029 -401.261331)
			(xy 299.026702 -401.324333) (xy 299.042676 -401.389713) (xy 299.050721 -401.456533) (xy 299.050723 -401.523837)
			(xy 299.042681 -401.590657) (xy 299.026711 -401.656038) (xy 299.003041 -401.719042) (xy 299.000571 -401.723796)
			(xy 300.128624 -401.723796) (xy 300.128626 -401.656371) (xy 300.136704 -401.58943) (xy 300.152743 -401.52394)
			(xy 300.17651 -401.460842) (xy 300.207665 -401.401045) (xy 300.245758 -401.345411) (xy 300.267624 -401.319746)
			(xy 300.273429 -401.312607) (xy 300.279938 -401.295412) (xy 300.280324 -401.286218) (xy 300.280324 -400.793966)
			(xy 300.279925 -400.784778) (xy 300.273403 -400.767594) (xy 300.267624 -400.760438) (xy 300.245765 -400.734768)
			(xy 300.207675 -400.679135) (xy 300.176522 -400.61934) (xy 300.152757 -400.556243) (xy 300.13672 -400.490755)
			(xy 300.128643 -400.423816) (xy 300.128643 -400.356393) (xy 300.136719 -400.289454) (xy 300.152754 -400.223965)
			(xy 300.176519 -400.160869) (xy 300.20767 -400.101073) (xy 300.24576 -400.045439) (xy 300.267624 -400.019774)
			(xy 300.273417 -400.012626) (xy 300.279933 -399.995438) (xy 300.280324 -399.986246) (xy 300.280324 -399.828766)
			(xy 300.280798 -399.818639) (xy 300.288534 -399.79992) (xy 300.302824 -399.785566) (xy 300.321507 -399.777745)
			(xy 300.331632 -399.777204) (xy 301.047912 -399.777204) (xy 301.058067 -399.777612) (xy 301.076821 -399.785412)
			(xy 301.091144 -399.799813) (xy 301.098843 -399.818608) (xy 301.09922 -399.828766) (xy 301.09922 -399.986246)
			(xy 301.099652 -399.995431) (xy 301.10615 -400.012616) (xy 301.11192 -400.019774) (xy 301.133789 -400.045435)
			(xy 301.171876 -400.10107) (xy 301.203026 -400.160867) (xy 301.226789 -400.223965) (xy 301.242823 -400.289454)
			(xy 301.250898 -400.356393) (xy 301.250898 -400.423816) (xy 301.242821 -400.490755) (xy 301.226786 -400.556244)
			(xy 301.203022 -400.619341) (xy 301.171872 -400.679137) (xy 301.133784 -400.734772) (xy 301.11192 -400.760438)
			(xy 301.106127 -400.767586) (xy 301.09961 -400.784774) (xy 301.09922 -400.793966) (xy 301.09922 -401.286218)
			(xy 301.099617 -401.295407) (xy 301.106139 -401.312591) (xy 301.11192 -401.319746) (xy 301.133762 -401.345429)
			(xy 301.17185 -401.401062) (xy 301.203 -401.460856) (xy 301.226765 -401.52395) (xy 301.242801 -401.589437)
			(xy 301.250878 -401.656373) (xy 301.25088 -401.723794) (xy 301.242807 -401.790731) (xy 301.226775 -401.856218)
			(xy 301.203014 -401.919314) (xy 301.171867 -401.97911) (xy 301.133782 -402.034744) (xy 301.11192 -402.06041)
			(xy 301.106139 -402.067566) (xy 301.099614 -402.084748) (xy 301.09922 -402.093938) (xy 301.09922 -402.251418)
			(xy 301.098787 -402.261551) (xy 301.091046 -402.28028) (xy 301.076743 -402.294637) (xy 301.058043 -402.302449)
			(xy 301.047912 -402.30298) (xy 300.331632 -402.30298) (xy 300.321477 -402.302552) (xy 300.302722 -402.294763)
			(xy 300.288396 -402.280368) (xy 300.280699 -402.261575) (xy 300.280324 -402.251418) (xy 300.280324 -402.093938)
			(xy 300.27989 -402.084753) (xy 300.273392 -402.067569) (xy 300.267624 -402.06041) (xy 300.245738 -402.034763)
			(xy 300.207648 -401.979126) (xy 300.176497 -401.919328) (xy 300.152733 -401.856229) (xy 300.136698 -401.790737)
			(xy 300.128624 -401.723796) (xy 299.000571 -401.723796) (xy 298.972011 -401.778765) (xy 298.934066 -401.834352)
			(xy 298.91228 -401.860004) (xy 298.906497 -401.867159) (xy 298.899975 -401.884342) (xy 298.89958 -401.893532)
			(xy 298.89958 -402.3868) (xy 298.899994 -402.395987) (xy 298.906505 -402.413171) (xy 298.91228 -402.420328)
			(xy 298.93402 -402.446019) (xy 298.971969 -402.501601) (xy 299.003003 -402.561319) (xy 299.026678 -402.624318)
			(xy 299.042653 -402.689696) (xy 299.050701 -402.756513) (xy 299.050705 -402.823814) (xy 299.050697 -402.823877)
			(xy 302.328766 -402.823877) (xy 302.328771 -402.75645) (xy 302.336851 -402.689509) (xy 302.35289 -402.624018)
			(xy 302.376659 -402.560919) (xy 302.407814 -402.501122) (xy 302.445906 -402.445486) (xy 302.467772 -402.41982)
			(xy 302.473594 -402.412693) (xy 302.480091 -402.395488) (xy 302.480472 -402.386292) (xy 302.480472 -401.89404)
			(xy 302.480049 -401.884854) (xy 302.473545 -401.867669) (xy 302.467772 -401.860512) (xy 302.445889 -401.834863)
			(xy 302.407803 -401.779225) (xy 302.376655 -401.719426) (xy 302.352893 -401.656328) (xy 302.33686 -401.590837)
			(xy 302.328786 -401.523897) (xy 302.328788 -401.456473) (xy 302.336865 -401.389534) (xy 302.352902 -401.324044)
			(xy 302.376667 -401.260946) (xy 302.407819 -401.201149) (xy 302.445908 -401.145514) (xy 302.467772 -401.119848)
			(xy 302.473582 -401.112713) (xy 302.480087 -401.095514) (xy 302.480472 -401.08632) (xy 302.480472 -400.92884)
			(xy 302.480948 -400.918724) (xy 302.488678 -400.900026) (xy 302.502976 -400.885712) (xy 302.521664 -400.87796)
			(xy 302.53178 -400.877532) (xy 303.24806 -400.877532) (xy 303.258184 -400.87795) (xy 303.276893 -400.885691)
			(xy 303.291209 -400.900007) (xy 303.29895 -400.918716) (xy 303.299368 -400.92884) (xy 303.299368 -401.08632)
			(xy 303.299776 -401.095507) (xy 303.306292 -401.112691) (xy 303.312068 -401.119848) (xy 303.333913 -401.145529)
			(xy 303.372005 -401.20116) (xy 303.403158 -401.260954) (xy 303.426925 -401.324049) (xy 303.442963 -401.389537)
			(xy 303.451041 -401.456474) (xy 303.451043 -401.523896) (xy 303.442968 -401.590834) (xy 303.426934 -401.656322)
			(xy 303.40317 -401.719418) (xy 303.37202 -401.779214) (xy 303.333932 -401.834847) (xy 303.312068 -401.860512)
			(xy 303.30628 -401.867663) (xy 303.299761 -401.884849) (xy 303.299368 -401.89404) (xy 303.299368 -402.386292)
			(xy 303.299789 -402.395478) (xy 303.306296 -402.412662) (xy 303.312068 -402.41982) (xy 303.333886 -402.445524)
			(xy 303.371978 -402.501152) (xy 303.403133 -402.560942) (xy 303.426901 -402.624034) (xy 303.442941 -402.689519)
			(xy 303.451021 -402.756454) (xy 303.451025 -402.823874) (xy 303.442954 -402.89081) (xy 303.426922 -402.956297)
			(xy 303.403162 -403.019392) (xy 303.372015 -403.079186) (xy 303.33393 -403.134819) (xy 303.312068 -403.160484)
			(xy 303.306249 -403.167613) (xy 303.299749 -403.184816) (xy 303.299368 -403.194012) (xy 303.299368 -403.351492)
			(xy 303.298977 -403.361618) (xy 303.291225 -403.380328) (xy 303.276901 -403.394643) (xy 303.258186 -403.402383)
			(xy 303.24806 -403.4028) (xy 302.53178 -403.4028) (xy 302.52167 -403.402331) (xy 302.502991 -403.394587)
			(xy 302.488697 -403.380285) (xy 302.480963 -403.361602) (xy 302.480472 -403.351492) (xy 302.480472 -403.194012)
			(xy 302.480062 -403.184825) (xy 302.473549 -403.16764) (xy 302.467772 -403.160484) (xy 302.445862 -403.134857)
			(xy 302.407776 -403.079216) (xy 302.376629 -403.019415) (xy 302.352869 -402.956313) (xy 302.336838 -402.890819)
			(xy 302.328766 -402.823877) (xy 299.050697 -402.823877) (xy 299.042666 -402.890633) (xy 299.026699 -402.956013)
			(xy 299.003032 -403.019015) (xy 298.972006 -403.078737) (xy 298.934064 -403.134323) (xy 298.91228 -403.159976)
			(xy 298.906466 -403.167109) (xy 298.899963 -403.184309) (xy 298.89958 -403.193504) (xy 298.89958 -403.351492)
			(xy 298.899171 -403.361648) (xy 298.891375 -403.380404) (xy 298.876974 -403.394729) (xy 298.858176 -403.402425)
			(xy 298.848018 -403.4028) (xy 298.131738 -403.4028) (xy 298.121619 -403.402243) (xy 298.102906 -403.394535)
			(xy 298.08855 -403.380271) (xy 298.080722 -403.361608) (xy 298.080176 -403.351492) (xy 298.080176 -403.193504)
			(xy 298.079769 -403.184316) (xy 298.073254 -403.167132) (xy 298.067476 -403.159976) (xy 298.04564 -403.134363)
			(xy 298.00769 -403.078772) (xy 297.976657 -403.019043) (xy 297.952985 -402.956034) (xy 297.937014 -402.890646)
			(xy 297.928973 -402.823819) (xy 294.650937 -402.823819) (xy 294.650937 -402.823874) (xy 294.642866 -402.890809)
			(xy 294.626835 -402.956296) (xy 294.603076 -403.019391) (xy 294.57193 -403.079186) (xy 294.533846 -403.134819)
			(xy 294.511984 -403.160484) (xy 294.506167 -403.167615) (xy 294.499665 -403.184816) (xy 294.499284 -403.194012)
			(xy 294.499284 -403.351492) (xy 294.498877 -403.361616) (xy 294.491129 -403.380322) (xy 294.476809 -403.394638)
			(xy 294.4581 -403.40238) (xy 294.447976 -403.4028) (xy 293.731696 -403.4028) (xy 293.721573 -403.402387)
			(xy 293.70287 -403.394638) (xy 293.688556 -403.38032) (xy 293.68081 -403.361615) (xy 293.680388 -403.351492)
			(xy 293.680388 -403.194012) (xy 293.679975 -403.184825) (xy 293.673464 -403.167641) (xy 293.667688 -403.160484)
			(xy 293.645777 -403.134857) (xy 293.607691 -403.079217) (xy 293.576543 -403.019415) (xy 293.552782 -402.956314)
			(xy 293.53675 -402.89082) (xy 293.528678 -402.823878) (xy 290.250609 -402.823878) (xy 290.242579 -402.890633)
			(xy 290.226612 -402.956012) (xy 290.202946 -403.019014) (xy 290.17192 -403.078737) (xy 290.133979 -403.134323)
			(xy 290.112196 -403.159976) (xy 290.106384 -403.16711) (xy 290.099879 -403.184309) (xy 290.099496 -403.193504)
			(xy 290.099496 -403.351492) (xy 290.099072 -403.361646) (xy 290.091278 -403.380399) (xy 290.076882 -403.394723)
			(xy 290.05809 -403.402422) (xy 290.047934 -403.4028) (xy 289.331654 -403.4028) (xy 289.321529 -403.402312)
			(xy 289.302815 -403.394577) (xy 289.288461 -403.380292) (xy 289.280637 -403.361614) (xy 289.280092 -403.351492)
			(xy 289.280092 -403.193504) (xy 289.279682 -403.184317) (xy 289.273168 -403.167132) (xy 289.267392 -403.159976)
			(xy 289.245556 -403.134363) (xy 289.207605 -403.078772) (xy 289.176571 -403.019044) (xy 289.152898 -402.956034)
			(xy 289.136927 -402.890647) (xy 289.128886 -402.823819) (xy 237.559965 -402.823819) (xy 237.421928 -402.961856)
			(xy 237.415087 -402.969256) (xy 237.407369 -402.987855) (xy 237.406942 -402.997924) (xy 237.406942 -405.623708)
			(xy 286.928756 -405.623708) (xy 286.928757 -405.556283) (xy 286.936834 -405.489343) (xy 286.952872 -405.423853)
			(xy 286.976639 -405.360756) (xy 287.007793 -405.30096) (xy 287.045886 -405.245326) (xy 287.067752 -405.219662)
			(xy 287.073554 -405.212521) (xy 287.080064 -405.195327) (xy 287.080452 -405.186134) (xy 287.080452 -404.693882)
			(xy 287.080039 -404.684695) (xy 287.073526 -404.667512) (xy 287.067752 -404.660354) (xy 287.045908 -404.634672)
			(xy 287.007815 -404.579041) (xy 286.97666 -404.519248) (xy 286.952893 -404.456153) (xy 286.936854 -404.390665)
			(xy 286.928776 -404.323728) (xy 286.928774 -404.256305) (xy 286.936848 -404.189367) (xy 286.952883 -404.123879)
			(xy 286.976647 -404.060783) (xy 287.007798 -404.000987) (xy 287.045888 -403.945354) (xy 287.067752 -403.91969)
			(xy 287.073542 -403.91254) (xy 287.080059 -403.895353) (xy 287.080452 -403.886162) (xy 287.080452 -403.728682)
			(xy 287.080912 -403.718553) (xy 287.088648 -403.699829) (xy 287.102942 -403.685473) (xy 287.121633 -403.677656)
			(xy 287.13176 -403.67712) (xy 287.84804 -403.67712) (xy 287.858199 -403.677489) (xy 287.876956 -403.685302)
			(xy 287.891279 -403.699715) (xy 287.898974 -403.71852) (xy 287.899348 -403.728682) (xy 287.899348 -403.886162)
			(xy 287.899788 -403.895346) (xy 287.906282 -403.91253) (xy 287.912048 -403.91969) (xy 287.933935 -403.945337)
			(xy 287.972027 -404.000973) (xy 288.00318 -404.060771) (xy 288.026945 -404.12387) (xy 288.04298 -404.189362)
			(xy 288.051055 -404.256303) (xy 288.051053 -404.32373) (xy 288.042974 -404.39067) (xy 288.026935 -404.456161)
			(xy 288.003166 -404.519259) (xy 287.97201 -404.579056) (xy 287.933915 -404.63469) (xy 287.912048 -404.660354)
			(xy 287.90624 -404.667491) (xy 287.899733 -404.684688) (xy 287.899348 -404.693882) (xy 287.899348 -405.186134)
			(xy 287.899754 -405.195321) (xy 287.906272 -405.212505) (xy 287.912048 -405.219662) (xy 287.933908 -405.245331)
			(xy 287.972 -405.300964) (xy 288.003154 -405.360759) (xy 288.026921 -405.423856) (xy 288.042958 -405.489345)
			(xy 288.051036 -405.556283) (xy 288.051036 -405.623708) (xy 288.04296 -405.690646) (xy 288.026924 -405.756136)
			(xy 288.003158 -405.819233) (xy 287.972005 -405.879028) (xy 287.933913 -405.934662) (xy 287.912048 -405.960326)
			(xy 287.906251 -405.967471) (xy 287.899738 -405.984662) (xy 287.899348 -405.993854) (xy 287.899348 -406.151334)
			(xy 287.898901 -406.161464) (xy 287.89116 -406.180189) (xy 287.876861 -406.194544) (xy 287.858168 -406.20236)
			(xy 287.84804 -406.202896) (xy 287.13176 -406.202896) (xy 287.121603 -406.202511) (xy 287.102849 -406.194701)
			(xy 287.088527 -406.180294) (xy 287.080829 -406.161494) (xy 287.080452 -406.151334) (xy 287.080452 -405.993854)
			(xy 287.080004 -405.984671) (xy 287.073515 -405.967487) (xy 287.067752 -405.960326) (xy 287.04588 -405.934667)
			(xy 287.007788 -405.879032) (xy 286.976635 -405.819236) (xy 286.952869 -405.756138) (xy 286.936832 -405.690648)
			(xy 286.928756 -405.623708) (xy 237.406942 -405.623708) (xy 237.406942 -406.72373) (xy 289.128897 -406.72373)
			(xy 289.1289 -406.656422) (xy 289.136948 -406.589596) (xy 289.152926 -406.524211) (xy 289.176605 -406.461205)
			(xy 289.207645 -406.401481) (xy 289.245601 -406.345895) (xy 289.267392 -406.320244) (xy 289.273194 -406.313103)
			(xy 289.279706 -406.295909) (xy 289.280092 -406.286716) (xy 289.280092 -405.793448) (xy 289.279661 -405.784263)
			(xy 289.273162 -405.767078) (xy 289.267392 -405.75992) (xy 289.245599 -405.734272) (xy 289.207647 -405.678686)
			(xy 289.176611 -405.618962) (xy 289.152936 -405.555957) (xy 289.136961 -405.490574) (xy 289.128917 -405.42375)
			(xy 289.128917 -405.356444) (xy 289.136962 -405.28962) (xy 289.152937 -405.224237) (xy 289.176613 -405.161232)
			(xy 289.20765 -405.101509) (xy 289.245602 -405.045923) (xy 289.267392 -405.020272) (xy 289.273182 -405.013122)
			(xy 289.279701 -404.995935) (xy 289.280092 -404.986744) (xy 289.280092 -404.828756) (xy 289.280486 -404.8186)
			(xy 289.288294 -404.799848) (xy 289.302699 -404.785527) (xy 289.321496 -404.777827) (xy 289.331654 -404.777448)
			(xy 290.047934 -404.777448) (xy 290.058064 -404.777899) (xy 290.076787 -404.785639) (xy 290.091143 -404.799936)
			(xy 290.098959 -404.818628) (xy 290.099496 -404.828756) (xy 290.099496 -404.986744) (xy 290.099886 -404.995933)
			(xy 290.106414 -405.013117) (xy 290.112196 -405.020272) (xy 290.133979 -405.045928) (xy 290.171925 -405.101515)
			(xy 290.202957 -405.161238) (xy 290.226628 -405.224242) (xy 290.242601 -405.289623) (xy 290.250644 -405.356445)
			(xy 290.250645 -405.423749) (xy 290.242602 -405.490571) (xy 290.22663 -405.555952) (xy 290.202959 -405.618957)
			(xy 290.200522 -405.623648) (xy 291.329076 -405.623648) (xy 291.329076 -405.556343) (xy 291.337121 -405.48952)
			(xy 291.353095 -405.424137) (xy 291.376768 -405.361132) (xy 291.407802 -405.301409) (xy 291.445752 -405.245822)
			(xy 291.46754 -405.22017) (xy 291.473337 -405.213025) (xy 291.47985 -405.195834) (xy 291.48024 -405.186642)
			(xy 291.48024 -404.693374) (xy 291.479833 -404.684187) (xy 291.473316 -404.667003) (xy 291.46754 -404.659846)
			(xy 291.445774 -404.634176) (xy 291.407825 -404.578592) (xy 291.37679 -404.518871) (xy 291.353116 -404.455869)
			(xy 291.337142 -404.390489) (xy 291.329096 -404.323668) (xy 291.329094 -404.256365) (xy 291.337136 -404.189544)
			(xy 291.353106 -404.124163) (xy 291.376777 -404.061159) (xy 291.407808 -404.001436) (xy 291.445754 -403.94585)
			(xy 291.46754 -403.920198) (xy 291.473325 -403.913045) (xy 291.479846 -403.89586) (xy 291.48024 -403.88667)
			(xy 291.48024 -403.728682) (xy 291.480718 -403.718523) (xy 291.488499 -403.699753) (xy 291.50287 -403.685388)
			(xy 291.521643 -403.677615) (xy 291.531802 -403.67712) (xy 292.248082 -403.67712) (xy 292.258236 -403.677648)
			(xy 292.277002 -403.685413) (xy 292.291367 -403.699768) (xy 292.299145 -403.718528) (xy 292.299644 -403.728682)
			(xy 292.299644 -403.88667) (xy 292.300081 -403.895854) (xy 292.306577 -403.913038) (xy 292.312344 -403.920198)
			(xy 292.334154 -403.945832) (xy 292.372103 -404.001421) (xy 292.403137 -404.061147) (xy 292.426809 -404.124153)
			(xy 292.442781 -404.189538) (xy 292.450824 -404.256363) (xy 292.450822 -404.32367) (xy 292.442775 -404.390495)
			(xy 292.426799 -404.455878) (xy 292.403123 -404.518884) (xy 292.372086 -404.578608) (xy 292.334134 -404.634194)
			(xy 292.312344 -404.659846) (xy 292.306539 -404.666985) (xy 292.300031 -404.68418) (xy 292.299644 -404.693374)
			(xy 292.299644 -405.186642) (xy 292.300047 -405.19583) (xy 292.306567 -405.213013) (xy 292.312344 -405.22017)
			(xy 292.334126 -405.245827) (xy 292.372076 -405.301412) (xy 292.403111 -405.361135) (xy 292.426785 -405.424139)
			(xy 292.442758 -405.489521) (xy 292.450803 -405.556343) (xy 292.450804 -405.623648) (xy 292.44276 -405.69047)
			(xy 292.426787 -405.755852) (xy 292.403114 -405.818857) (xy 292.372081 -405.87858) (xy 292.334132 -405.934166)
			(xy 292.312344 -405.959818) (xy 292.30655 -405.966965) (xy 292.300035 -405.984154) (xy 292.299644 -405.993346)
			(xy 292.299644 -406.151334) (xy 292.299194 -406.161496) (xy 292.291405 -406.18027) (xy 292.277026 -406.194634)
			(xy 292.258245 -406.202404) (xy 292.248082 -406.202896) (xy 291.531802 -406.202896) (xy 291.521649 -406.202366)
			(xy 291.502886 -406.194598) (xy 291.488522 -406.180244) (xy 291.480741 -406.161487) (xy 291.48024 -406.151334)
			(xy 291.48024 -405.993346) (xy 291.479799 -405.984162) (xy 291.473306 -405.966978) (xy 291.46754 -405.959818)
			(xy 291.445746 -405.934171) (xy 291.407797 -405.878584) (xy 291.376764 -405.818859) (xy 291.353092 -405.755854)
			(xy 291.337119 -405.690471) (xy 291.329076 -405.623648) (xy 290.200522 -405.623648) (xy 290.171928 -405.67868)
			(xy 290.133982 -405.734267) (xy 290.112196 -405.75992) (xy 290.106408 -405.767071) (xy 290.099888 -405.784257)
			(xy 290.099496 -405.793448) (xy 290.099496 -406.286716) (xy 290.099899 -406.295904) (xy 290.106418 -406.313088)
			(xy 290.112196 -406.320244) (xy 290.133951 -406.345922) (xy 290.171899 -406.401506) (xy 290.202931 -406.461226)
			(xy 290.226605 -406.524227) (xy 290.242579 -406.589606) (xy 290.250625 -406.656425) (xy 290.250628 -406.723727)
			(xy 290.250621 -406.723789) (xy 293.52869 -406.723789) (xy 293.528692 -406.656363) (xy 293.536771 -406.589423)
			(xy 293.55281 -406.523932) (xy 293.576577 -406.460834) (xy 293.607731 -406.401037) (xy 293.645823 -406.345401)
			(xy 293.667688 -406.319736) (xy 293.673493 -406.312597) (xy 293.680003 -406.295402) (xy 293.680388 -406.286208)
			(xy 293.680388 -405.793956) (xy 293.680002 -405.784766) (xy 293.673472 -405.767582) (xy 293.667688 -405.760428)
			(xy 293.645821 -405.734766) (xy 293.607733 -405.679131) (xy 293.576583 -405.619334) (xy 293.552819 -405.556237)
			(xy 293.536785 -405.490747) (xy 293.528709 -405.423809) (xy 293.52871 -405.356385) (xy 293.536786 -405.289447)
			(xy 293.552821 -405.223958) (xy 293.576585 -405.160861) (xy 293.607736 -405.101064) (xy 293.645824 -405.045429)
			(xy 293.667688 -405.019764) (xy 293.673481 -405.012616) (xy 293.679998 -404.995428) (xy 293.680388 -404.986236)
			(xy 293.680388 -404.828756) (xy 293.680849 -404.818646) (xy 293.688599 -404.799969) (xy 293.702903 -404.785676)
			(xy 293.721586 -404.777941) (xy 293.731696 -404.777448) (xy 294.447976 -404.777448) (xy 294.458077 -404.778003)
			(xy 294.476745 -404.785723) (xy 294.491038 -404.799998) (xy 294.498783 -404.818656) (xy 294.499284 -404.828756)
			(xy 294.499284 -404.986236) (xy 294.49968 -404.995425) (xy 294.506204 -405.012609) (xy 294.511984 -405.019764)
			(xy 294.533845 -405.045432) (xy 294.571934 -405.101066) (xy 294.603086 -405.160862) (xy 294.626851 -405.223958)
			(xy 294.642888 -405.289447) (xy 294.650964 -405.356385) (xy 294.650964 -405.423809) (xy 294.642889 -405.490747)
			(xy 294.626853 -405.556236) (xy 294.603089 -405.619333) (xy 294.60081 -405.623708) (xy 295.728844 -405.623708)
			(xy 295.728845 -405.556283) (xy 295.736922 -405.489344) (xy 295.752959 -405.423854) (xy 295.776725 -405.360757)
			(xy 295.807879 -405.30096) (xy 295.84597 -405.245327) (xy 295.867836 -405.219662) (xy 295.873636 -405.212519)
			(xy 295.880148 -405.195327) (xy 295.880536 -405.186134) (xy 295.880536 -404.693882) (xy 295.880126 -404.684695)
			(xy 295.873611 -404.667511) (xy 295.867836 -404.660354) (xy 295.845992 -404.634672) (xy 295.807901 -404.57904)
			(xy 295.776747 -404.519247) (xy 295.75298 -404.456152) (xy 295.736942 -404.390665) (xy 295.728864 -404.323728)
			(xy 295.728862 -404.256305) (xy 295.736936 -404.189368) (xy 295.75297 -404.123879) (xy 295.776733 -404.060783)
			(xy 295.807884 -404.000988) (xy 295.845972 -403.945355) (xy 295.867836 -403.91969) (xy 295.873624 -403.912539)
			(xy 295.880143 -403.895353) (xy 295.880536 -403.886162) (xy 295.880536 -403.728682) (xy 295.881011 -403.718555)
			(xy 295.888744 -403.699834) (xy 295.903034 -403.685478) (xy 295.921719 -403.677659) (xy 295.931844 -403.67712)
			(xy 296.648124 -403.67712) (xy 296.658282 -403.677502) (xy 296.677039 -403.685309) (xy 296.691362 -403.699718)
			(xy 296.699058 -403.718521) (xy 296.699432 -403.728682) (xy 296.699432 -403.886162) (xy 296.699876 -403.895345)
			(xy 296.706368 -403.912529) (xy 296.712132 -403.91969) (xy 296.734016 -403.945338) (xy 296.772102 -404.000976)
			(xy 296.80325 -404.060775) (xy 296.827012 -404.123874) (xy 296.843045 -404.189364) (xy 296.851118 -404.256304)
			(xy 296.851117 -404.323729) (xy 296.843039 -404.390668) (xy 296.827002 -404.456158) (xy 296.803237 -404.519256)
			(xy 296.772085 -404.579053) (xy 296.733996 -404.634688) (xy 296.712132 -404.660354) (xy 296.706322 -404.667489)
			(xy 296.699817 -404.684688) (xy 296.699432 -404.693882) (xy 296.699432 -405.186134) (xy 296.699841 -405.195321)
			(xy 296.706357 -405.212505) (xy 296.712132 -405.219662) (xy 296.733989 -405.245333) (xy 296.772076 -405.300967)
			(xy 296.803225 -405.360763) (xy 296.826988 -405.423859) (xy 296.843023 -405.489347) (xy 296.851099 -405.556284)
			(xy 296.851099 -405.623707) (xy 296.843025 -405.690644) (xy 296.826991 -405.756132) (xy 296.803229 -405.819229)
			(xy 296.77208 -405.879025) (xy 296.733994 -405.93466) (xy 296.712132 -405.960326) (xy 296.706334 -405.96747)
			(xy 296.699822 -405.984662) (xy 296.699432 -405.993854) (xy 296.699432 -406.151334) (xy 296.699001 -406.161466)
			(xy 296.691256 -406.180194) (xy 296.676953 -406.19455) (xy 296.658254 -406.202363) (xy 296.648124 -406.202896)
			(xy 295.931844 -406.202896) (xy 295.921692 -406.202442) (xy 295.90294 -406.19466) (xy 295.888615 -406.180273)
			(xy 295.880915 -406.161487) (xy 295.880536 -406.151334) (xy 295.880536 -405.993854) (xy 295.880092 -405.984671)
			(xy 295.873601 -405.967486) (xy 295.867836 -405.960326) (xy 295.845965 -405.934666) (xy 295.807874 -405.879032)
			(xy 295.776722 -405.819235) (xy 295.752956 -405.756137) (xy 295.73692 -405.690647) (xy 295.728844 -405.623708)
			(xy 294.60081 -405.623708) (xy 294.571938 -405.679129) (xy 294.533848 -405.734763) (xy 294.511984 -405.760428)
			(xy 294.506191 -405.767576) (xy 294.499675 -405.784764) (xy 294.499284 -405.793956) (xy 294.499284 -406.286208)
			(xy 294.499694 -406.295395) (xy 294.506208 -406.312579) (xy 294.511984 -406.319736) (xy 294.533817 -406.345427)
			(xy 294.571908 -406.401057) (xy 294.603061 -406.46085) (xy 294.626827 -406.523943) (xy 294.642866 -406.58943)
			(xy 294.650944 -406.656365) (xy 294.650947 -406.72373) (xy 297.928985 -406.72373) (xy 297.928988 -406.656422)
			(xy 297.937036 -406.589596) (xy 297.953013 -406.524212) (xy 297.976691 -406.461206) (xy 298.00773 -406.401482)
			(xy 298.045685 -406.345896) (xy 298.067476 -406.320244) (xy 298.073276 -406.313101) (xy 298.079789 -406.295909)
			(xy 298.080176 -406.286716) (xy 298.080176 -405.793448) (xy 298.079748 -405.784263) (xy 298.073247 -405.767078)
			(xy 298.067476 -405.75992) (xy 298.045683 -405.734272) (xy 298.007732 -405.678685) (xy 297.976697 -405.618962)
			(xy 297.953023 -405.555957) (xy 297.937049 -405.490574) (xy 297.929005 -405.42375) (xy 297.929005 -405.356444)
			(xy 297.93705 -405.28962) (xy 297.953025 -405.224238) (xy 297.9767 -405.161233) (xy 298.007735 -405.101509)
			(xy 298.045687 -405.045924) (xy 298.067476 -405.020272) (xy 298.073264 -405.013121) (xy 298.079785 -404.995935)
			(xy 298.080176 -404.986744) (xy 298.080176 -404.828756) (xy 298.080585 -404.818602) (xy 298.088391 -404.799853)
			(xy 298.102791 -404.785532) (xy 298.121582 -404.77783) (xy 298.131738 -404.777448) (xy 298.848018 -404.777448)
			(xy 298.858147 -404.777912) (xy 298.87687 -404.785647) (xy 298.891226 -404.79994) (xy 298.899043 -404.818629)
			(xy 298.89958 -404.828756) (xy 298.89958 -404.986744) (xy 298.899973 -404.995933) (xy 298.906499 -405.013117)
			(xy 298.91228 -405.020272) (xy 298.934063 -405.045928) (xy 298.972011 -405.101514) (xy 299.003043 -405.161237)
			(xy 299.026716 -405.224241) (xy 299.042688 -405.289623) (xy 299.050732 -405.356445) (xy 299.050733 -405.423749)
			(xy 299.042689 -405.490571) (xy 299.026717 -405.555953) (xy 299.003046 -405.618957) (xy 299.000577 -405.623708)
			(xy 300.128635 -405.623708) (xy 300.128635 -405.556283) (xy 300.136712 -405.489344) (xy 300.152749 -405.423854)
			(xy 300.176515 -405.360757) (xy 300.207668 -405.300961) (xy 300.245759 -405.245327) (xy 300.267624 -405.219662)
			(xy 300.273422 -405.212518) (xy 300.279935 -405.195326) (xy 300.280324 -405.186134) (xy 300.280324 -404.693882)
			(xy 300.279917 -404.684695) (xy 300.273401 -404.66751) (xy 300.267624 -404.660354) (xy 300.245781 -404.634671)
			(xy 300.20769 -404.57904) (xy 300.176537 -404.519246) (xy 300.15277 -404.456152) (xy 300.136733 -404.390664)
			(xy 300.128655 -404.323728) (xy 300.128653 -404.256305) (xy 300.136727 -404.189368) (xy 300.152761 -404.12388)
			(xy 300.176523 -404.060784) (xy 300.207673 -404.000989) (xy 300.245761 -403.945355) (xy 300.267624 -403.91969)
			(xy 300.27341 -403.912538) (xy 300.27993 -403.895352) (xy 300.280324 -403.886162) (xy 300.280324 -403.728682)
			(xy 300.280811 -403.718556) (xy 300.288542 -403.699837) (xy 300.302828 -403.685482) (xy 300.321509 -403.677661)
			(xy 300.331632 -403.67712) (xy 301.047912 -403.67712) (xy 301.058069 -403.677512) (xy 301.076826 -403.685315)
			(xy 301.09115 -403.699721) (xy 301.098846 -403.718522) (xy 301.09922 -403.728682) (xy 301.09922 -403.886162)
			(xy 301.099644 -403.895348) (xy 301.106147 -403.912533) (xy 301.11192 -403.91969) (xy 301.133805 -403.945338)
			(xy 301.171892 -404.000975) (xy 301.20304 -404.060774) (xy 301.226802 -404.123873) (xy 301.242836 -404.189364)
			(xy 301.250909 -404.256304) (xy 301.250907 -404.323729) (xy 301.24283 -404.390668) (xy 301.226793 -404.456158)
			(xy 301.203027 -404.519256) (xy 301.171875 -404.579053) (xy 301.133785 -404.634688) (xy 301.11192 -404.660354)
			(xy 301.10612 -404.667497) (xy 301.099607 -404.684689) (xy 301.09922 -404.693882) (xy 301.09922 -405.186134)
			(xy 301.099609 -405.195323) (xy 301.106137 -405.212508) (xy 301.11192 -405.219662) (xy 301.133777 -405.245332)
			(xy 301.171865 -405.300967) (xy 301.203015 -405.360762) (xy 301.226778 -405.423859) (xy 301.242814 -405.489347)
			(xy 301.25089 -405.556284) (xy 301.25089 -405.623707) (xy 301.242815 -405.690644) (xy 301.226781 -405.756133)
			(xy 301.203018 -405.819229) (xy 301.17187 -405.879026) (xy 301.133783 -405.93466) (xy 301.11192 -405.960326)
			(xy 301.106132 -405.967478) (xy 301.099612 -405.984663) (xy 301.09922 -405.993854) (xy 301.09922 -406.151334)
			(xy 301.0988 -406.161468) (xy 301.091054 -406.180197) (xy 301.076747 -406.194554) (xy 301.058044 -406.202365)
			(xy 301.047912 -406.202896) (xy 300.331632 -406.202896) (xy 300.321479 -406.202452) (xy 300.302727 -406.194667)
			(xy 300.288402 -406.180276) (xy 300.280702 -406.161488) (xy 300.280324 -406.151334) (xy 300.280324 -405.993854)
			(xy 300.279882 -405.98467) (xy 300.27339 -405.967486) (xy 300.267624 -405.960326) (xy 300.245753 -405.934666)
			(xy 300.207663 -405.879031) (xy 300.176511 -405.819235) (xy 300.152747 -405.756137) (xy 300.136711 -405.690647)
			(xy 300.128635 -405.623708) (xy 299.000577 -405.623708) (xy 298.972014 -405.678681) (xy 298.934067 -405.734268)
			(xy 298.91228 -405.75992) (xy 298.90649 -405.76707) (xy 298.899972 -405.784257) (xy 298.89958 -405.793448)
			(xy 298.89958 -406.286716) (xy 298.899987 -406.295903) (xy 298.906503 -406.313088) (xy 298.91228 -406.320244)
			(xy 298.934035 -406.345922) (xy 298.971984 -406.401506) (xy 299.003018 -406.461226) (xy 299.026691 -406.524227)
			(xy 299.042666 -406.589606) (xy 299.050712 -406.656425) (xy 299.050715 -406.723727) (xy 299.050708 -406.723789)
			(xy 302.328777 -406.723789) (xy 302.32878 -406.656363) (xy 302.336859 -406.589423) (xy 302.352897 -406.523933)
			(xy 302.376664 -406.460835) (xy 302.407816 -406.401037) (xy 302.445907 -406.345402) (xy 302.467772 -406.319736)
			(xy 302.473587 -406.312604) (xy 302.480089 -406.295403) (xy 302.480472 -406.286208) (xy 302.480472 -405.793956)
			(xy 302.480089 -405.784766) (xy 302.473557 -405.767581) (xy 302.467772 -405.760428) (xy 302.445905 -405.734766)
			(xy 302.407818 -405.67913) (xy 302.376669 -405.619333) (xy 302.352907 -405.556236) (xy 302.336872 -405.490747)
			(xy 302.328797 -405.423809) (xy 302.328798 -405.356385) (xy 302.336873 -405.289447) (xy 302.352908 -405.223958)
			(xy 302.376672 -405.160861) (xy 302.407821 -405.101065) (xy 302.445909 -405.04543) (xy 302.467772 -405.019764)
			(xy 302.473575 -405.012624) (xy 302.480084 -404.995429) (xy 302.480472 -404.986236) (xy 302.480472 -404.828756)
			(xy 302.480948 -404.818648) (xy 302.488695 -404.799974) (xy 302.502994 -404.785682) (xy 302.521672 -404.777944)
			(xy 302.53178 -404.777448) (xy 303.24806 -404.777448) (xy 303.25816 -404.778017) (xy 303.276827 -404.785732)
			(xy 303.291121 -404.800002) (xy 303.298867 -404.818657) (xy 303.299368 -404.828756) (xy 303.299368 -404.986236)
			(xy 303.299768 -404.995424) (xy 303.30629 -405.012608) (xy 303.312068 -405.019764) (xy 303.333929 -405.045432)
			(xy 303.37202 -405.101065) (xy 303.403173 -405.160861) (xy 303.426939 -405.223957) (xy 303.442975 -405.289447)
			(xy 303.451052 -405.356385) (xy 303.451052 -405.423809) (xy 303.442976 -405.490748) (xy 303.42694 -405.556237)
			(xy 303.403175 -405.619334) (xy 303.372023 -405.67913) (xy 303.333933 -405.734763) (xy 303.312068 -405.760428)
			(xy 303.306273 -405.767574) (xy 303.299758 -405.784764) (xy 303.299368 -405.793956) (xy 303.299368 -406.286208)
			(xy 303.299781 -406.295395) (xy 303.306294 -406.312579) (xy 303.312068 -406.319736) (xy 303.333902 -406.345427)
			(xy 303.371993 -406.401057) (xy 303.403147 -406.460849) (xy 303.426915 -406.523943) (xy 303.442953 -406.589429)
			(xy 303.451032 -406.656365) (xy 303.451035 -406.723787) (xy 303.442962 -406.790724) (xy 303.426929 -406.856211)
			(xy 303.403167 -406.919307) (xy 303.372018 -406.979102) (xy 303.333931 -407.034735) (xy 303.312068 -407.0604)
			(xy 303.306285 -407.067555) (xy 303.299763 -407.084738) (xy 303.299368 -407.093928) (xy 303.299368 -407.251408)
			(xy 303.29899 -407.261535) (xy 303.291233 -407.280245) (xy 303.276904 -407.29456) (xy 303.258187 -407.302299)
			(xy 303.24806 -407.302716) (xy 302.53178 -407.302716) (xy 302.521672 -407.302232) (xy 302.502996 -407.294491)
			(xy 302.488703 -407.280194) (xy 302.480966 -407.261516) (xy 302.480472 -407.251408) (xy 302.480472 -407.093928)
			(xy 302.480055 -407.084741) (xy 302.473547 -407.067557) (xy 302.467772 -407.0604) (xy 302.445878 -407.03476)
			(xy 302.407792 -406.979121) (xy 302.376644 -406.919321) (xy 302.352883 -406.856221) (xy 302.33685 -406.790729)
			(xy 302.328777 -406.723789) (xy 299.050708 -406.723789) (xy 299.042674 -406.790547) (xy 299.026705 -406.855927)
			(xy 299.003037 -406.91893) (xy 298.972009 -406.978653) (xy 298.934065 -407.034239) (xy 298.91228 -407.059892)
			(xy 298.906502 -407.06705) (xy 298.899977 -407.084231) (xy 298.89958 -407.09342) (xy 298.89958 -407.251408)
			(xy 298.899184 -407.261565) (xy 298.891382 -407.280321) (xy 298.876978 -407.294645) (xy 298.858177 -407.302341)
			(xy 298.848018 -407.302716) (xy 298.131738 -407.302716) (xy 298.121608 -407.302241) (xy 298.10288 -407.294517)
			(xy 298.088521 -407.280227) (xy 298.080708 -407.261535) (xy 298.080176 -407.251408) (xy 298.080176 -407.09342)
			(xy 298.079762 -407.084233) (xy 298.073252 -407.067048) (xy 298.067476 -407.059892) (xy 298.045656 -407.034266)
			(xy 298.007706 -406.978677) (xy 297.976672 -406.91895) (xy 297.952999 -406.855942) (xy 297.937027 -406.790556)
			(xy 297.928985 -406.72373) (xy 294.650947 -406.72373) (xy 294.650947 -406.723787) (xy 294.642874 -406.790723)
			(xy 294.626842 -406.856211) (xy 294.60308 -406.919306) (xy 294.571933 -406.979101) (xy 294.533847 -407.034735)
			(xy 294.511984 -407.0604) (xy 294.506203 -407.067556) (xy 294.49968 -407.084738) (xy 294.499284 -407.093928)
			(xy 294.499284 -407.251408) (xy 294.49889 -407.261533) (xy 294.491136 -407.28024) (xy 294.476813 -407.294554)
			(xy 294.458101 -407.302296) (xy 294.447976 -407.302716) (xy 293.731696 -407.302716) (xy 293.721589 -407.302218)
			(xy 293.702914 -407.294482) (xy 293.68862 -407.28019) (xy 293.680882 -407.261515) (xy 293.680388 -407.251408)
			(xy 293.680388 -407.093928) (xy 293.679967 -407.084742) (xy 293.673461 -407.067557) (xy 293.667688 -407.0604)
			(xy 293.645793 -407.03476) (xy 293.607706 -406.979122) (xy 293.576557 -406.919322) (xy 293.552796 -406.856222)
			(xy 293.536763 -406.79073) (xy 293.52869 -406.723789) (xy 290.250621 -406.723789) (xy 290.242587 -406.790547)
			(xy 290.226619 -406.855927) (xy 290.202951 -406.91893) (xy 290.171924 -406.978653) (xy 290.133981 -407.034239)
			(xy 290.112196 -407.059892) (xy 290.10642 -407.067052) (xy 290.099893 -407.084231) (xy 290.099496 -407.09342)
			(xy 290.099496 -407.251408) (xy 290.099085 -407.261563) (xy 290.091286 -407.280316) (xy 290.076886 -407.29464)
			(xy 290.058091 -407.302338) (xy 290.047934 -407.302716) (xy 289.331654 -407.302716) (xy 289.321519 -407.30231)
			(xy 289.302788 -407.294559) (xy 289.288432 -407.280248) (xy 289.280622 -407.261541) (xy 289.280092 -407.251408)
			(xy 289.280092 -407.09342) (xy 289.279674 -407.084234) (xy 289.273166 -407.067049) (xy 289.267392 -407.059892)
			(xy 289.245571 -407.034266) (xy 289.20762 -406.978677) (xy 289.176585 -406.918951) (xy 289.152912 -406.855943)
			(xy 289.136939 -406.790557) (xy 289.128897 -406.72373) (xy 237.406942 -406.72373) (xy 237.406942 -409.523887)
			(xy 286.928735 -409.523887) (xy 286.928738 -409.456459) (xy 286.936818 -409.389518) (xy 286.952859 -409.324026)
			(xy 286.97663 -409.260927) (xy 287.007788 -409.20113) (xy 287.045884 -409.145496) (xy 287.067752 -409.119832)
			(xy 287.073566 -409.1127) (xy 287.080069 -409.095499) (xy 287.080452 -409.086304) (xy 287.080452 -408.594052)
			(xy 287.080005 -408.584869) (xy 287.073516 -408.567685) (xy 287.067752 -408.560524) (xy 287.045878 -408.534866)
			(xy 287.007786 -408.479232) (xy 286.976633 -408.419435) (xy 286.952867 -408.356337) (xy 286.936831 -408.290847)
			(xy 286.928755 -408.223907) (xy 286.928755 -408.156481) (xy 286.936833 -408.089542) (xy 286.952871 -408.024051)
			(xy 286.976638 -407.960954) (xy 287.007793 -407.901158) (xy 287.045886 -407.845524) (xy 287.067752 -407.81986)
			(xy 287.073554 -407.812719) (xy 287.080064 -407.795525) (xy 287.080452 -407.786332) (xy 287.080452 -407.628852)
			(xy 287.080945 -407.618746) (xy 287.088689 -407.600076) (xy 287.102983 -407.585785) (xy 287.121654 -407.578043)
			(xy 287.13176 -407.577544) (xy 287.84804 -407.577544) (xy 287.858144 -407.578051) (xy 287.876813 -407.585791)
			(xy 287.891104 -407.600081) (xy 287.898847 -407.618748) (xy 287.899348 -407.628852) (xy 287.899348 -407.786332)
			(xy 287.899755 -407.795519) (xy 287.906272 -407.812703) (xy 287.912048 -407.81986) (xy 287.933906 -407.845531)
			(xy 287.971998 -407.901163) (xy 288.003152 -407.960958) (xy 288.026919 -408.024055) (xy 288.042957 -408.089543)
			(xy 288.051034 -408.156482) (xy 288.051035 -408.223906) (xy 288.042959 -408.290845) (xy 288.026923 -408.356334)
			(xy 288.003157 -408.419431) (xy 287.972004 -408.479226) (xy 287.933913 -408.53486) (xy 287.912048 -408.560524)
			(xy 287.906252 -408.56767) (xy 287.899739 -408.58486) (xy 287.899348 -408.594052) (xy 287.899348 -409.086304)
			(xy 287.899768 -409.09549) (xy 287.906276 -409.112674) (xy 287.912048 -409.119832) (xy 287.933878 -409.145526)
			(xy 287.971972 -409.201155) (xy 288.003127 -409.260947) (xy 288.026895 -409.32404) (xy 288.042935 -409.389526)
			(xy 288.051014 -409.456462) (xy 288.051018 -409.523884) (xy 288.042945 -409.590821) (xy 288.026911 -409.656308)
			(xy 288.003149 -409.719404) (xy 287.971999 -409.779199) (xy 287.933912 -409.834832) (xy 287.912048 -409.860496)
			(xy 287.906264 -409.86765) (xy 287.899743 -409.884834) (xy 287.899348 -409.894024) (xy 287.899348 -410.051504)
			(xy 287.898819 -410.061607) (xy 287.891089 -410.080276) (xy 287.876806 -410.094569) (xy 287.858143 -410.102312)
			(xy 287.84804 -410.102812) (xy 287.13176 -410.102812) (xy 287.12165 -410.102348) (xy 287.102973 -410.094599)
			(xy 287.08868 -410.080296) (xy 287.080945 -410.061614) (xy 287.080452 -410.051504) (xy 287.080452 -409.894024)
			(xy 287.080019 -409.884839) (xy 287.07352 -409.867655) (xy 287.067752 -409.860496) (xy 287.045851 -409.834861)
			(xy 287.00776 -409.779223) (xy 286.976608 -409.719423) (xy 286.952843 -409.656322) (xy 286.936809 -409.590829)
			(xy 286.928735 -409.523887) (xy 237.406942 -409.523887) (xy 237.406942 -410.623642) (xy 289.128908 -410.623642)
			(xy 289.12891 -410.556334) (xy 289.136956 -410.48951) (xy 289.152933 -410.424126) (xy 289.176609 -410.361121)
			(xy 289.207648 -410.301397) (xy 289.245602 -410.245811) (xy 289.267392 -410.22016) (xy 289.273187 -410.213014)
			(xy 289.279703 -410.195824) (xy 289.280092 -410.186632) (xy 289.280092 -409.693364) (xy 289.279701 -409.684175)
			(xy 289.273174 -409.66699) (xy 289.267392 -409.659836) (xy 289.245614 -409.634175) (xy 289.207662 -409.578591)
			(xy 289.176625 -409.518869) (xy 289.152949 -409.455866) (xy 289.136974 -409.390484) (xy 289.128928 -409.323662)
			(xy 289.128927 -409.256356) (xy 289.136971 -409.189534) (xy 289.152944 -409.124152) (xy 289.176618 -409.061147)
			(xy 289.207653 -409.001425) (xy 289.245603 -408.945839) (xy 289.267392 -408.920188) (xy 289.273175 -408.913033)
			(xy 289.279698 -408.89585) (xy 289.280092 -408.88666) (xy 289.280092 -408.728672) (xy 289.280498 -408.718517)
			(xy 289.288302 -408.699766) (xy 289.302703 -408.685443) (xy 289.321497 -408.677743) (xy 289.331654 -408.677364)
			(xy 290.047934 -408.677364) (xy 290.058066 -408.677799) (xy 290.076792 -408.685543) (xy 290.091148 -408.699845)
			(xy 290.098962 -408.718542) (xy 290.099496 -408.728672) (xy 290.099496 -408.88666) (xy 290.099926 -408.895845)
			(xy 290.106426 -408.91303) (xy 290.112196 -408.920188) (xy 290.133994 -408.945831) (xy 290.171941 -409.00142)
			(xy 290.202971 -409.061145) (xy 290.226642 -409.12415) (xy 290.242613 -409.189533) (xy 290.250656 -409.256356)
			(xy 290.250655 -409.323662) (xy 290.24261 -409.390484) (xy 290.226637 -409.455867) (xy 290.202964 -409.518872)
			(xy 290.200389 -409.523827) (xy 291.329055 -409.523827) (xy 291.329058 -409.456519) (xy 291.337106 -409.389694)
			(xy 291.353082 -409.32431) (xy 291.376759 -409.261304) (xy 291.407797 -409.201579) (xy 291.44575 -409.145992)
			(xy 291.46754 -409.12034) (xy 291.47335 -409.113204) (xy 291.479855 -409.096006) (xy 291.48024 -409.086812)
			(xy 291.48024 -408.593544) (xy 291.4798 -408.58436) (xy 291.473306 -408.567176) (xy 291.46754 -408.560016)
			(xy 291.445744 -408.53437) (xy 291.407796 -408.478783) (xy 291.376763 -408.419059) (xy 291.35309 -408.356053)
			(xy 291.337118 -408.29067) (xy 291.329074 -408.223847) (xy 291.329075 -408.156541) (xy 291.33712 -408.089718)
			(xy 291.353094 -408.024335) (xy 291.376767 -407.96133) (xy 291.407802 -407.901607) (xy 291.445752 -407.84602)
			(xy 291.46754 -407.820368) (xy 291.473338 -407.813224) (xy 291.479851 -407.796032) (xy 291.48024 -407.78684)
			(xy 291.48024 -407.628852) (xy 291.480583 -407.61869) (xy 291.488402 -407.599929) (xy 291.502823 -407.585606)
			(xy 291.521637 -407.577915) (xy 291.531802 -407.577544) (xy 292.248082 -407.577544) (xy 292.258208 -407.578041)
			(xy 292.27693 -407.585764) (xy 292.291287 -407.600047) (xy 292.299106 -407.618729) (xy 292.299644 -407.628852)
			(xy 292.299644 -407.78684) (xy 292.300048 -407.796028) (xy 292.306567 -407.813211) (xy 292.312344 -407.820368)
			(xy 292.334124 -407.846026) (xy 292.372074 -407.901612) (xy 292.403109 -407.961334) (xy 292.426783 -408.024338)
			(xy 292.442757 -408.089719) (xy 292.450802 -408.156542) (xy 292.450803 -408.223846) (xy 292.442759 -408.290669)
			(xy 292.426786 -408.356051) (xy 292.403114 -408.419055) (xy 292.372081 -408.478778) (xy 292.334132 -408.534364)
			(xy 292.312344 -408.560016) (xy 292.306551 -408.567164) (xy 292.300036 -408.584353) (xy 292.299644 -408.593544)
			(xy 292.299644 -409.086812) (xy 292.300061 -409.095998) (xy 292.306571 -409.113182) (xy 292.312344 -409.12034)
			(xy 292.334097 -409.146021) (xy 292.372048 -409.201603) (xy 292.403083 -409.261322) (xy 292.426759 -409.324323)
			(xy 292.442735 -409.389702) (xy 292.450782 -409.456522) (xy 292.450786 -409.523824) (xy 292.442745 -409.590645)
			(xy 292.426775 -409.656025) (xy 292.403106 -409.719028) (xy 292.372076 -409.77875) (xy 292.33413 -409.834336)
			(xy 292.312344 -409.859988) (xy 292.306521 -409.867114) (xy 292.300024 -409.884319) (xy 292.299644 -409.893516)
			(xy 292.299644 -410.051504) (xy 292.299182 -410.061653) (xy 292.291394 -410.080397) (xy 292.27701 -410.094718)
			(xy 292.258233 -410.102426) (xy 292.248082 -410.102812) (xy 291.531802 -410.102812) (xy 291.521682 -410.102273)
			(xy 291.502971 -410.094556) (xy 291.488616 -410.080286) (xy 291.480788 -410.061621) (xy 291.48024 -410.051504)
			(xy 291.48024 -409.893516) (xy 291.479813 -409.884331) (xy 291.47331 -409.867147) (xy 291.46754 -409.859988)
			(xy 291.445717 -409.834365) (xy 291.407769 -409.778774) (xy 291.376737 -409.719047) (xy 291.353066 -409.656039)
			(xy 291.337096 -409.590653) (xy 291.329055 -409.523827) (xy 290.200389 -409.523827) (xy 290.171931 -409.578596)
			(xy 290.133983 -409.634183) (xy 290.112196 -409.659836) (xy 290.106401 -409.666982) (xy 290.099886 -409.684172)
			(xy 290.099496 -409.693364) (xy 290.099496 -410.186632) (xy 290.099891 -410.195821) (xy 290.106415 -410.213005)
			(xy 290.112196 -410.22016) (xy 290.133967 -410.245826) (xy 290.171914 -410.301411) (xy 290.202946 -410.361133)
			(xy 290.226618 -410.424136) (xy 290.242591 -410.489516) (xy 290.250636 -410.556336) (xy 290.250638 -410.62364)
			(xy 290.250631 -410.6237) (xy 293.528701 -410.6237) (xy 293.528702 -410.556276) (xy 293.53678 -410.489336)
			(xy 293.552816 -410.423847) (xy 293.576582 -410.360749) (xy 293.607734 -410.300952) (xy 293.645824 -410.245317)
			(xy 293.667688 -410.219652) (xy 293.673486 -410.212508) (xy 293.68 -410.195317) (xy 293.680388 -410.186124)
			(xy 293.680388 -409.693872) (xy 293.679994 -409.684683) (xy 293.673469 -409.667499) (xy 293.667688 -409.660344)
			(xy 293.645836 -409.634669) (xy 293.607748 -409.579035) (xy 293.576597 -409.519241) (xy 293.552833 -409.456145)
			(xy 293.536797 -409.390657) (xy 293.52872 -409.32372) (xy 293.528719 -409.256298) (xy 293.536794 -409.189361)
			(xy 293.552828 -409.123872) (xy 293.57659 -409.060776) (xy 293.607739 -409.00098) (xy 293.645825 -408.945345)
			(xy 293.667688 -408.91968) (xy 293.673474 -408.912527) (xy 293.679995 -408.895343) (xy 293.680388 -408.886152)
			(xy 293.680388 -408.728672) (xy 293.680862 -408.718563) (xy 293.688606 -408.699886) (xy 293.702907 -408.685593)
			(xy 293.721587 -408.677857) (xy 293.731696 -408.677364) (xy 294.447976 -408.677364) (xy 294.458079 -408.677904)
			(xy 294.47675 -408.685627) (xy 294.491044 -408.699907) (xy 294.498786 -408.71857) (xy 294.499284 -408.728672)
			(xy 294.499284 -408.886152) (xy 294.499721 -408.895336) (xy 294.506216 -408.912521) (xy 294.511984 -408.91968)
			(xy 294.53386 -408.945335) (xy 294.57195 -409.000971) (xy 294.603101 -409.060768) (xy 294.626865 -409.123866)
			(xy 294.6429 -409.189357) (xy 294.650975 -409.256297) (xy 294.650974 -409.323721) (xy 294.642897 -409.390661)
			(xy 294.62686 -409.456151) (xy 294.603093 -409.519248) (xy 294.600676 -409.523887) (xy 295.728823 -409.523887)
			(xy 295.728826 -409.456459) (xy 295.736906 -409.389518) (xy 295.752947 -409.324026) (xy 295.776716 -409.260928)
			(xy 295.807873 -409.201131) (xy 295.845969 -409.145497) (xy 295.867836 -409.119832) (xy 295.873649 -409.112698)
			(xy 295.880153 -409.095499) (xy 295.880536 -409.086304) (xy 295.880536 -408.594052) (xy 295.880093 -408.584869)
			(xy 295.873601 -408.567684) (xy 295.867836 -408.560524) (xy 295.845963 -408.534866) (xy 295.807872 -408.479231)
			(xy 295.77672 -408.419434) (xy 295.752954 -408.356336) (xy 295.736918 -408.290846) (xy 295.728843 -408.223907)
			(xy 295.728843 -408.156481) (xy 295.736921 -408.089542) (xy 295.752958 -408.024052) (xy 295.776725 -407.960955)
			(xy 295.807878 -407.901159) (xy 295.84597 -407.845525) (xy 295.867836 -407.81986) (xy 295.873637 -407.812718)
			(xy 295.880148 -407.795525) (xy 295.880536 -407.786332) (xy 295.880536 -407.628852) (xy 295.880947 -407.618736)
			(xy 295.888707 -407.60005) (xy 295.903027 -407.585755) (xy 295.921727 -407.578029) (xy 295.931844 -407.577544)
			(xy 296.648124 -407.577544) (xy 296.658227 -407.578064) (xy 296.676895 -407.585799) (xy 296.691187 -407.600084)
			(xy 296.698931 -407.618749) (xy 296.699432 -407.628852) (xy 296.699432 -407.786332) (xy 296.699842 -407.795519)
			(xy 296.706357 -407.812703) (xy 296.712132 -407.81986) (xy 296.733987 -407.845532) (xy 296.772074 -407.901167)
			(xy 296.803223 -407.960962) (xy 296.826986 -408.024058) (xy 296.843021 -408.089546) (xy 296.851097 -408.156483)
			(xy 296.851098 -408.223905) (xy 296.843024 -408.290842) (xy 296.82699 -408.356331) (xy 296.803228 -408.419427)
			(xy 296.77208 -408.479223) (xy 296.733994 -408.534858) (xy 296.712132 -408.560524) (xy 296.706334 -408.567668)
			(xy 296.699822 -408.58486) (xy 296.699432 -408.594052) (xy 296.699432 -409.086304) (xy 296.699856 -409.095489)
			(xy 296.706362 -409.112673) (xy 296.712132 -409.119832) (xy 296.733959 -409.145527) (xy 296.772047 -409.201158)
			(xy 296.803198 -409.26095) (xy 296.826962 -409.324043) (xy 296.842999 -409.389528) (xy 296.851078 -409.456463)
			(xy 296.851081 -409.523883) (xy 296.843009 -409.590818) (xy 296.826978 -409.656305) (xy 296.80322 -409.7194)
			(xy 296.772075 -409.779196) (xy 296.733993 -409.83483) (xy 296.712132 -409.860496) (xy 296.706346 -409.867649)
			(xy 296.699827 -409.884834) (xy 296.699432 -409.894024) (xy 296.699432 -410.051504) (xy 296.698919 -410.061609)
			(xy 296.691186 -410.080281) (xy 296.676898 -410.094575) (xy 296.658229 -410.102315) (xy 296.648124 -410.102812)
			(xy 295.931844 -410.102812) (xy 295.921726 -410.102348) (xy 295.903026 -410.094617) (xy 295.88871 -410.080315)
			(xy 295.880961 -410.061622) (xy 295.880536 -410.051504) (xy 295.880536 -409.894024) (xy 295.880106 -409.884839)
			(xy 295.873605 -409.867655) (xy 295.867836 -409.860496) (xy 295.845935 -409.834861) (xy 295.807845 -409.779223)
			(xy 295.776694 -409.719423) (xy 295.752931 -409.656322) (xy 295.736896 -409.590829) (xy 295.728823 -409.523887)
			(xy 294.600676 -409.523887) (xy 294.57194 -409.579045) (xy 294.533849 -409.634679) (xy 294.511984 -409.660344)
			(xy 294.506184 -409.667487) (xy 294.499672 -409.684679) (xy 294.499284 -409.693872) (xy 294.499284 -410.186124)
			(xy 294.499686 -410.195312) (xy 294.506206 -410.212496) (xy 294.511984 -410.219652) (xy 294.533833 -410.24533)
			(xy 294.571923 -410.300962) (xy 294.603075 -410.360757) (xy 294.626841 -410.423852) (xy 294.642878 -410.489339)
			(xy 294.650956 -410.556277) (xy 294.650957 -410.623641) (xy 297.928996 -410.623641) (xy 297.928998 -410.556334)
			(xy 297.937044 -410.48951) (xy 297.95302 -410.424127) (xy 297.976696 -410.361121) (xy 298.007733 -410.301398)
			(xy 298.045686 -410.245812) (xy 298.067476 -410.22016) (xy 298.073269 -410.213012) (xy 298.079787 -410.195824)
			(xy 298.080176 -410.186632) (xy 298.080176 -409.693364) (xy 298.079788 -409.684174) (xy 298.07326 -409.66699)
			(xy 298.067476 -409.659836) (xy 298.045699 -409.634175) (xy 298.007747 -409.57859) (xy 297.976712 -409.518868)
			(xy 297.953037 -409.455865) (xy 297.937062 -409.390484) (xy 297.929016 -409.323661) (xy 297.929015 -409.256357)
			(xy 297.937058 -409.189534) (xy 297.953031 -409.124152) (xy 297.976704 -409.061148) (xy 298.007738 -409.001425)
			(xy 298.045688 -408.94584) (xy 298.067476 -408.920188) (xy 298.073257 -408.913032) (xy 298.079782 -408.89585)
			(xy 298.080176 -408.88666) (xy 298.080176 -408.728672) (xy 298.080598 -408.718519) (xy 298.088398 -408.699771)
			(xy 298.102794 -408.685449) (xy 298.121583 -408.677746) (xy 298.131738 -408.677364) (xy 298.848018 -408.677364)
			(xy 298.858149 -408.677812) (xy 298.876875 -408.68555) (xy 298.891232 -408.699849) (xy 298.899046 -408.718543)
			(xy 298.89958 -408.728672) (xy 298.89958 -408.88666) (xy 298.900014 -408.895845) (xy 298.906512 -408.913029)
			(xy 298.91228 -408.920188) (xy 298.934079 -408.945831) (xy 298.972026 -409.001419) (xy 299.003058 -409.061144)
			(xy 299.026729 -409.12415) (xy 299.042701 -409.189533) (xy 299.050744 -409.256356) (xy 299.050743 -409.323662)
			(xy 299.042698 -409.390485) (xy 299.026724 -409.455868) (xy 299.003051 -409.518873) (xy 299.000446 -409.523886)
			(xy 300.128614 -409.523886) (xy 300.128617 -409.456459) (xy 300.136697 -409.389518) (xy 300.152737 -409.324027)
			(xy 300.176506 -409.260928) (xy 300.207662 -409.201131) (xy 300.245757 -409.145497) (xy 300.267624 -409.119832)
			(xy 300.273435 -409.112697) (xy 300.27994 -409.095499) (xy 300.280324 -409.086304) (xy 300.280324 -408.594052)
			(xy 300.279883 -408.584868) (xy 300.27339 -408.567684) (xy 300.267624 -408.560524) (xy 300.245751 -408.534866)
			(xy 300.207661 -408.479231) (xy 300.17651 -408.419434) (xy 300.152745 -408.356336) (xy 300.136709 -408.290846)
			(xy 300.128634 -408.223906) (xy 300.128634 -408.156482) (xy 300.136711 -408.089542) (xy 300.152748 -408.024053)
			(xy 300.176514 -407.960955) (xy 300.207667 -407.901159) (xy 300.245759 -407.845525) (xy 300.267624 -407.81986)
			(xy 300.273423 -407.812717) (xy 300.279935 -407.795525) (xy 300.280324 -407.786332) (xy 300.280324 -407.628852)
			(xy 300.280747 -407.618737) (xy 300.288504 -407.600053) (xy 300.302821 -407.585759) (xy 300.321516 -407.578031)
			(xy 300.331632 -407.577544) (xy 301.047912 -407.577544) (xy 301.058015 -407.578074) (xy 301.076682 -407.585805)
			(xy 301.090975 -407.600088) (xy 301.098719 -407.61875) (xy 301.09922 -407.628852) (xy 301.09922 -407.786332)
			(xy 301.09961 -407.795521) (xy 301.106137 -407.812706) (xy 301.11192 -407.81986) (xy 301.133775 -407.845532)
			(xy 301.171863 -407.901166) (xy 301.203013 -407.960962) (xy 301.226777 -408.024057) (xy 301.242812 -408.089545)
			(xy 301.250888 -408.156483) (xy 301.250889 -408.223905) (xy 301.242814 -408.290843) (xy 301.22678 -408.356331)
			(xy 301.203018 -408.419427) (xy 301.171869 -408.479224) (xy 301.133783 -408.534858) (xy 301.11192 -408.560524)
			(xy 301.106133 -408.567676) (xy 301.099612 -408.584861) (xy 301.09922 -408.594052) (xy 301.09922 -409.086304)
			(xy 301.099624 -409.095492) (xy 301.106141 -409.112676) (xy 301.11192 -409.119832) (xy 301.133748 -409.145527)
			(xy 301.171836 -409.201158) (xy 301.202988 -409.26095) (xy 301.226753 -409.324043) (xy 301.24279 -409.389528)
			(xy 301.250869 -409.456463) (xy 301.250872 -409.523883) (xy 301.2428 -409.590819) (xy 301.226769 -409.656305)
			(xy 301.20301 -409.719401) (xy 301.171864 -409.779196) (xy 301.133781 -409.83483) (xy 301.11192 -409.860496)
			(xy 301.106145 -409.867657) (xy 301.099617 -409.884835) (xy 301.09922 -409.894024) (xy 301.09922 -410.051504)
			(xy 301.098719 -410.06161) (xy 301.090983 -410.080285) (xy 301.076692 -410.094579) (xy 301.058018 -410.102317)
			(xy 301.047912 -410.102812) (xy 300.331632 -410.102812) (xy 300.321513 -410.102358) (xy 300.302812 -410.094623)
			(xy 300.288497 -410.080318) (xy 300.280749 -410.061623) (xy 300.280324 -410.051504) (xy 300.280324 -409.894024)
			(xy 300.279897 -409.884839) (xy 300.273394 -409.867655) (xy 300.267624 -409.860496) (xy 300.245724 -409.83486)
			(xy 300.207635 -409.779222) (xy 300.176484 -409.719422) (xy 300.152721 -409.656321) (xy 300.136687 -409.590828)
			(xy 300.128614 -409.523886) (xy 299.000446 -409.523886) (xy 298.972017 -409.578597) (xy 298.934068 -409.634184)
			(xy 298.91228 -409.659836) (xy 298.906483 -409.666981) (xy 298.899969 -409.684172) (xy 298.89958 -409.693364)
			(xy 298.89958 -410.186632) (xy 298.899979 -410.19582) (xy 298.906501 -410.213004) (xy 298.91228 -410.22016)
			(xy 298.934052 -410.245825) (xy 298.972 -410.30141) (xy 299.003032 -410.361132) (xy 299.026705 -410.424135)
			(xy 299.042679 -410.489515) (xy 299.050724 -410.556336) (xy 299.050725 -410.62364) (xy 299.050718 -410.6237)
			(xy 302.328789 -410.6237) (xy 302.32879 -410.556276) (xy 302.336867 -410.489337) (xy 302.352904 -410.423847)
			(xy 302.376668 -410.36075) (xy 302.407819 -410.300953) (xy 302.445908 -410.245318) (xy 302.467772 -410.219652)
			(xy 302.47358 -410.212515) (xy 302.480086 -410.195318) (xy 302.480472 -410.186124) (xy 302.480472 -409.693872)
			(xy 302.480082 -409.684683) (xy 302.473555 -409.667498) (xy 302.467772 -409.660344) (xy 302.445921 -409.634669)
			(xy 302.407834 -409.579035) (xy 302.376684 -409.51924) (xy 302.35292 -409.456144) (xy 302.336885 -409.390657)
			(xy 302.328808 -409.32372) (xy 302.328807 -409.256298) (xy 302.336882 -409.189361) (xy 302.352915 -409.123873)
			(xy 302.376677 -409.060777) (xy 302.407824 -409.000981) (xy 302.44591 -408.945346) (xy 302.467772 -408.91968)
			(xy 302.473568 -408.912535) (xy 302.480081 -408.895344) (xy 302.480472 -408.886152) (xy 302.480472 -408.728672)
			(xy 302.480961 -408.718565) (xy 302.488703 -408.699891) (xy 302.502998 -408.685599) (xy 302.521673 -408.67786)
			(xy 302.53178 -408.677364) (xy 303.24806 -408.677364) (xy 303.258175 -408.677848) (xy 303.276871 -408.685576)
			(xy 303.291186 -408.699872) (xy 303.298939 -408.718557) (xy 303.299368 -408.728672) (xy 303.299368 -408.886152)
			(xy 303.299809 -408.895336) (xy 303.306302 -408.91252) (xy 303.312068 -408.91968) (xy 303.333945 -408.945335)
			(xy 303.372035 -409.00097) (xy 303.403187 -409.060768) (xy 303.426952 -409.123866) (xy 303.442988 -409.189356)
			(xy 303.451063 -409.256296) (xy 303.451062 -409.323722) (xy 303.442985 -409.390661) (xy 303.426947 -409.456151)
			(xy 303.40318 -409.519249) (xy 303.372026 -409.579045) (xy 303.333934 -409.634679) (xy 303.312068 -409.660344)
			(xy 303.306266 -409.667485) (xy 303.299755 -409.684679) (xy 303.299368 -409.693872) (xy 303.299368 -410.186124)
			(xy 303.299774 -410.195312) (xy 303.306291 -410.212495) (xy 303.312068 -410.219652) (xy 303.333917 -410.24533)
			(xy 303.372009 -410.300962) (xy 303.403162 -410.360756) (xy 303.426928 -410.423851) (xy 303.442966 -410.489339)
			(xy 303.451044 -410.556276) (xy 303.451045 -410.6237) (xy 303.44297 -410.690637) (xy 303.426935 -410.756126)
			(xy 303.403172 -410.819222) (xy 303.372021 -410.879018) (xy 303.333932 -410.934651) (xy 303.312068 -410.960316)
			(xy 303.306278 -410.967466) (xy 303.29976 -410.984653) (xy 303.299368 -410.993844) (xy 303.299368 -411.151324)
			(xy 303.299003 -411.161452) (xy 303.291241 -411.180162) (xy 303.276909 -411.194477) (xy 303.258189 -411.202216)
			(xy 303.24806 -411.202632) (xy 302.53178 -411.202632) (xy 302.521674 -411.202132) (xy 302.503001 -411.194394)
			(xy 302.488708 -411.180102) (xy 302.480969 -411.16143) (xy 302.480472 -411.151324) (xy 302.480472 -410.993844)
			(xy 302.480047 -410.984658) (xy 302.473544 -410.967474) (xy 302.467772 -410.960316) (xy 302.445893 -410.934663)
			(xy 302.407807 -410.879026) (xy 302.376658 -410.819228) (xy 302.352896 -410.75613) (xy 302.336863 -410.690639)
			(xy 302.328789 -410.6237) (xy 299.050718 -410.6237) (xy 299.042683 -410.690461) (xy 299.026712 -410.755842)
			(xy 299.003042 -410.818846) (xy 298.972012 -410.878569) (xy 298.934066 -410.934156) (xy 298.91228 -410.959808)
			(xy 298.906495 -410.966961) (xy 298.899974 -410.984146) (xy 298.89958 -410.993336) (xy 298.89958 -411.151324)
			(xy 298.899198 -411.161482) (xy 298.891391 -411.180239) (xy 298.876982 -411.194562) (xy 298.858179 -411.202258)
			(xy 298.848018 -411.202632) (xy 298.131738 -411.202632) (xy 298.12161 -411.202141) (xy 298.102885 -411.194421)
			(xy 298.088526 -411.180135) (xy 298.080711 -411.161449) (xy 298.080176 -411.151324) (xy 298.080176 -410.993336)
			(xy 298.079754 -410.98415) (xy 298.073249 -410.966965) (xy 298.067476 -410.959808) (xy 298.045672 -410.934169)
			(xy 298.007721 -410.878582) (xy 297.976686 -410.818857) (xy 297.953013 -410.75585) (xy 297.93704 -410.690466)
			(xy 297.928996 -410.623641) (xy 294.650957 -410.623641) (xy 294.650957 -410.623699) (xy 294.642883 -410.690637)
			(xy 294.626848 -410.756125) (xy 294.603085 -410.819221) (xy 294.571935 -410.879017) (xy 294.533848 -410.934651)
			(xy 294.511984 -410.960316) (xy 294.506196 -410.967467) (xy 294.499677 -410.984653) (xy 294.499284 -410.993844)
			(xy 294.499284 -411.151324) (xy 294.498834 -411.161436) (xy 294.491086 -411.180118) (xy 294.476778 -411.194413)
			(xy 294.458089 -411.202144) (xy 294.447976 -411.202632) (xy 293.731696 -411.202632) (xy 293.721591 -411.202119)
			(xy 293.702919 -411.194386) (xy 293.688625 -411.180098) (xy 293.680885 -411.161429) (xy 293.680388 -411.151324)
			(xy 293.680388 -410.993844) (xy 293.679959 -410.984659) (xy 293.673459 -410.967474) (xy 293.667688 -410.960316)
			(xy 293.645809 -410.934664) (xy 293.607721 -410.879027) (xy 293.576572 -410.819229) (xy 293.552809 -410.75613)
			(xy 293.536775 -410.69064) (xy 293.528701 -410.6237) (xy 290.250631 -410.6237) (xy 290.242595 -410.69046)
			(xy 290.226625 -410.755841) (xy 290.202956 -410.818845) (xy 290.171926 -410.878568) (xy 290.133982 -410.934155)
			(xy 290.112196 -410.959808) (xy 290.106413 -410.966963) (xy 290.09989 -410.984146) (xy 290.099496 -410.993336)
			(xy 290.099496 -411.151324) (xy 290.099098 -411.16148) (xy 290.091294 -411.180234) (xy 290.07689 -411.194557)
			(xy 290.058092 -411.202255) (xy 290.047934 -411.202632) (xy 289.331654 -411.202632) (xy 289.321521 -411.20221)
			(xy 289.302793 -411.194462) (xy 289.288438 -411.180156) (xy 289.280625 -411.161455) (xy 289.280092 -411.151324)
			(xy 289.280092 -410.993336) (xy 289.279666 -410.98415) (xy 289.273164 -410.966966) (xy 289.267392 -410.959808)
			(xy 289.245587 -410.934169) (xy 289.207635 -410.878582) (xy 289.1766 -410.818857) (xy 289.152925 -410.755851)
			(xy 289.136952 -410.690467) (xy 289.128908 -410.623642) (xy 237.406942 -410.623642) (xy 237.406942 -412.06928)
			(xy 237.406454 -412.09423) (xy 237.398652 -412.143517) (xy 237.383236 -412.190976) (xy 237.360587 -412.23544)
			(xy 237.331261 -412.275814) (xy 237.313978 -412.293816) (xy 235.9787 -413.629094) (xy 235.960702 -413.64638)
			(xy 235.92032 -413.675693) (xy 235.875854 -413.698339) (xy 235.828397 -413.713762) (xy 235.779114 -413.721582)
			(xy 235.754164 -413.722058) (xy 208.805526 -413.722058) (xy 208.780575 -413.721571) (xy 208.731288 -413.71377)
			(xy 208.683827 -413.698355) (xy 208.639362 -413.675707) (xy 208.598986 -413.646383) (xy 208.58099 -413.629094)
			(xy 207.025748 -412.073852) (xy 207.008463 -412.055854) (xy 206.979152 -412.015471) (xy 206.956509 -411.971006)
			(xy 206.941092 -411.923548) (xy 206.933278 -411.874265) (xy 206.932784 -411.849316) (xy 206.932784 -389.931402)
			(xy 206.932361 -389.921332) (xy 206.924645 -389.902729) (xy 206.917798 -389.895334) (xy 204.423264 -387.4008)
			(xy 204.405975 -387.382803) (xy 204.376657 -387.342423) (xy 204.354006 -387.297957) (xy 204.338581 -387.2505)
			(xy 204.33076 -387.201215) (xy 204.3303 -387.176264) (xy 204.3303 -378.650754) (xy 204.31379 -378.625608)
			(xy 204.299566 -378.619512) (xy 204.274164 -378.608112) (xy 204.226684 -378.579033) (xy 204.183937 -378.54336)
			(xy 204.146829 -378.501851) (xy 204.11615 -378.45539) (xy 204.092551 -378.404961) (xy 204.076533 -378.351638)
			(xy 204.068437 -378.296553) (xy 204.068435 -378.240876) (xy 204.076526 -378.185791) (xy 204.09254 -378.132466)
			(xy 204.116135 -378.082037) (xy 204.146811 -378.035572) (xy 204.183915 -377.994061) (xy 204.22666 -377.958385)
			(xy 204.274137 -377.929301) (xy 204.299566 -377.917964) (xy 204.31379 -377.911868) (xy 204.3303 -377.886722)
			(xy 204.3303 -374.857518) (xy 204.324458 -374.851676) (xy 204.307171 -374.833679) (xy 204.277856 -374.793297)
			(xy 204.25521 -374.748832) (xy 204.239788 -374.701374) (xy 204.231971 -374.65209) (xy 204.231494 -374.62714)
			(xy 204.231494 -371.243098) (xy 204.23107 -371.233028) (xy 204.223355 -371.214425) (xy 204.216508 -371.20703)
			(xy 204.18298 -371.173502) (xy 204.16569 -371.155506) (xy 204.13637 -371.115126) (xy 204.113718 -371.07066)
			(xy 204.098292 -371.023202) (xy 204.09047 -370.973917) (xy 204.090016 -370.948966) (xy 204.090016 -368.72545)
			(xy 204.089584 -368.715383) (xy 204.081859 -368.696791) (xy 204.07503 -368.689382) (xy 203.985114 -368.599466)
			(xy 203.977714 -368.592626) (xy 203.959115 -368.584913) (xy 203.949046 -368.58448) (xy 201.915268 -368.58448)
			(xy 201.903938 -368.585085) (xy 201.883488 -368.594842) (xy 201.869256 -368.612473) (xy 201.865992 -368.623342)
			(xy 201.858803 -368.650669) (xy 201.837471 -368.702992) (xy 201.808659 -368.751598) (xy 201.772996 -368.795426)
			(xy 201.731261 -368.833517) (xy 201.684368 -368.86504) (xy 201.633339 -368.889305) (xy 201.579291 -368.905783)
			(xy 201.523404 -368.914113) (xy 201.4669 -368.914113) (xy 201.411013 -368.905783) (xy 201.356965 -368.889305)
			(xy 201.305936 -368.86504) (xy 201.259043 -368.833517) (xy 201.217308 -368.795426) (xy 201.181645 -368.751598)
			(xy 201.152833 -368.702992) (xy 201.131501 -368.650669) (xy 201.124312 -368.623342) (xy 201.121047 -368.612481)
			(xy 201.106782 -368.594888) (xy 201.086358 -368.585096) (xy 201.075036 -368.58448) (xy 197.866254 -368.58448)
			(xy 197.828154 -368.601752) (xy 197.809958 -368.621643) (xy 197.768932 -368.656614) (xy 197.723394 -368.685464)
			(xy 197.674249 -368.70762) (xy 197.622476 -368.72264) (xy 197.569104 -368.730226) (xy 197.515196 -368.730226)
			(xy 197.461824 -368.72264) (xy 197.410051 -368.70762) (xy 197.360906 -368.685464) (xy 197.315368 -368.656614)
			(xy 197.274342 -368.621643) (xy 197.256146 -368.601752) (xy 197.218046 -368.58448) (xy 104.800146 -368.58448)
			(xy 104.772206 -368.607594) (xy 104.76865 -368.625628) (xy 104.762947 -368.652795) (xy 104.74473 -368.705231)
			(xy 104.719106 -368.754472) (xy 104.686614 -368.799478) (xy 104.647942 -368.8393) (xy 104.603906 -368.873096)
			(xy 104.555436 -368.900152) (xy 104.503556 -368.919896) (xy 104.449363 -368.931912) (xy 104.394 -368.935946)
			(xy 104.338637 -368.931912) (xy 104.284444 -368.919896) (xy 104.232564 -368.900152) (xy 104.184094 -368.873096)
			(xy 104.140058 -368.8393) (xy 104.101386 -368.799478) (xy 104.068894 -368.754472) (xy 104.04327 -368.705231)
			(xy 104.025053 -368.652795) (xy 104.01935 -368.625628) (xy 104.015794 -368.607594) (xy 103.987854 -368.58448)
			(xy 103.781606 -368.58448) (xy 103.772208 -368.588544) (xy 103.748711 -368.597952) (xy 103.699859 -368.611188)
			(xy 103.649687 -368.617857) (xy 103.62438 -368.618262) (xy 103.599072 -368.617867) (xy 103.548898 -368.611203)
			(xy 103.500048 -368.597956) (xy 103.476552 -368.588544) (xy 103.467154 -368.58448) (xy 100.835206 -368.58448)
			(xy 100.82629 -368.584882) (xy 100.809539 -368.591006) (xy 100.80244 -368.596418) (xy 100.781664 -368.613454)
			(xy 100.736231 -368.642133) (xy 100.687224 -368.664155) (xy 100.635612 -368.679083) (xy 100.582416 -368.686621)
			(xy 100.528688 -368.686621) (xy 100.475492 -368.679083) (xy 100.42388 -368.664155) (xy 100.374873 -368.642133)
			(xy 100.32944 -368.613454) (xy 100.308664 -368.596418) (xy 100.301618 -368.590913) (xy 100.284833 -368.584781)
			(xy 100.275898 -368.58448) (xy 58.120026 -368.58448) (xy 58.092848 -368.605054) (xy 58.088276 -368.62131)
			(xy 58.080312 -368.647571) (xy 58.057892 -368.697659) (xy 58.028529 -368.744019) (xy 57.992828 -368.785695)
			(xy 57.951525 -368.821827) (xy 57.905472 -368.851669) (xy 57.855619 -368.874607) (xy 57.802995 -368.890167)
			(xy 57.748684 -368.898028) (xy 57.693808 -368.898028) (xy 57.639497 -368.890167) (xy 57.586873 -368.874607)
			(xy 57.53702 -368.851669) (xy 57.490967 -368.821827) (xy 57.449664 -368.785695) (xy 57.413963 -368.744019)
			(xy 57.3846 -368.697659) (xy 57.36218 -368.647571) (xy 57.354216 -368.62131) (xy 57.349644 -368.605054)
			(xy 57.322466 -368.58448) (xy 54.746906 -368.58448) (xy 54.719728 -368.605054) (xy 54.715156 -368.62131)
			(xy 54.707192 -368.647571) (xy 54.684772 -368.697659) (xy 54.655409 -368.744019) (xy 54.619708 -368.785695)
			(xy 54.578405 -368.821827) (xy 54.532352 -368.851669) (xy 54.482499 -368.874607) (xy 54.429875 -368.890167)
			(xy 54.375564 -368.898028) (xy 54.320688 -368.898028) (xy 54.266377 -368.890167) (xy 54.213753 -368.874607)
			(xy 54.1639 -368.851669) (xy 54.117847 -368.821827) (xy 54.076544 -368.785695) (xy 54.040843 -368.744019)
			(xy 54.01148 -368.697659) (xy 53.98906 -368.647571) (xy 53.981096 -368.62131) (xy 53.976524 -368.605054)
			(xy 53.949346 -368.58448) (xy 6.14299 -368.58448) (xy 6.1341 -368.588036) (xy 6.111889 -368.596339)
			(xy 6.065927 -368.608) (xy 6.018872 -368.613861) (xy 5.995162 -368.614198) (xy 5.971455 -368.613833)
			(xy 5.924406 -368.607955) (xy 5.878444 -368.596308) (xy 5.856224 -368.588036) (xy 5.847334 -368.58448)
			(xy 1.5748 -368.58448) (xy 1.564791 -368.584968) (xy 1.546296 -368.592626) (xy 1.532138 -368.606779)
			(xy 1.524472 -368.625271) (xy 1.524 -368.63528) (xy 1.524 -370.523703) (xy 27.348898 -370.523703)
			(xy 27.348899 -370.456279) (xy 27.356975 -370.38934) (xy 27.373012 -370.323851) (xy 27.396776 -370.260753)
			(xy 27.427927 -370.200957) (xy 27.466016 -370.145322) (xy 27.48788 -370.119656) (xy 27.493675 -370.11251)
			(xy 27.500191 -370.09532) (xy 27.50058 -370.086128) (xy 27.50058 -369.928902) (xy 27.501029 -369.918771)
			(xy 27.508764 -369.900042) (xy 27.523062 -369.885684) (xy 27.541759 -369.877872) (xy 27.551888 -369.87734)
			(xy 28.268168 -369.87734) (xy 28.278325 -369.877748) (xy 28.297085 -369.885541) (xy 28.311411 -369.899943)
			(xy 28.319104 -369.918743) (xy 28.319476 -369.928902) (xy 28.319476 -370.086128) (xy 28.319878 -370.095316)
			(xy 28.326398 -370.1125) (xy 28.332176 -370.119656) (xy 28.354029 -370.145331) (xy 28.39212 -370.200963)
			(xy 28.423272 -370.260758) (xy 28.447038 -370.323854) (xy 28.463075 -370.389342) (xy 28.471152 -370.456279)
			(xy 28.471153 -370.523644) (xy 31.749193 -370.523644) (xy 31.749194 -370.456338) (xy 31.75724 -370.389514)
			(xy 31.773215 -370.324131) (xy 31.79689 -370.261126) (xy 31.827927 -370.201402) (xy 31.865879 -370.145816)
			(xy 31.887668 -370.120164) (xy 31.893471 -370.113023) (xy 31.89998 -370.095829) (xy 31.900368 -370.086636)
			(xy 31.900368 -369.928902) (xy 31.900766 -369.918727) (xy 31.908556 -369.899926) (xy 31.92295 -369.88554)
			(xy 31.941755 -369.877761) (xy 31.95193 -369.87734) (xy 32.66821 -369.87734) (xy 32.678369 -369.877825)
			(xy 32.697138 -369.885603) (xy 32.711503 -369.899972) (xy 32.719277 -369.918743) (xy 32.719772 -369.928902)
			(xy 32.719772 -370.086636) (xy 32.720171 -370.095824) (xy 32.726693 -370.113008) (xy 32.732472 -370.120164)
			(xy 32.754248 -370.145826) (xy 32.792196 -370.201411) (xy 32.823229 -370.261134) (xy 32.846902 -370.324137)
			(xy 32.862876 -370.389518) (xy 32.870921 -370.456339) (xy 32.870922 -370.523643) (xy 32.870915 -370.523703)
			(xy 36.148986 -370.523703) (xy 36.148987 -370.456279) (xy 36.157063 -370.389341) (xy 36.173099 -370.323851)
			(xy 36.196863 -370.260754) (xy 36.228013 -370.200957) (xy 36.266101 -370.145322) (xy 36.287964 -370.119656)
			(xy 36.29377 -370.112518) (xy 36.300277 -370.095322) (xy 36.300664 -370.086128) (xy 36.300664 -369.928902)
			(xy 36.301129 -369.918772) (xy 36.308861 -369.900047) (xy 36.323154 -369.88569) (xy 36.341845 -369.877875)
			(xy 36.351972 -369.87734) (xy 37.068252 -369.87734) (xy 37.078408 -369.877762) (xy 37.097167 -369.885549)
			(xy 37.111494 -369.899947) (xy 37.119188 -369.918744) (xy 37.11956 -369.928902) (xy 37.11956 -370.086128)
			(xy 37.119966 -370.095315) (xy 37.126483 -370.112499) (xy 37.13226 -370.119656) (xy 37.154114 -370.14533)
			(xy 37.192205 -370.200963) (xy 37.223359 -370.260757) (xy 37.247125 -370.323853) (xy 37.263163 -370.389341)
			(xy 37.27124 -370.456279) (xy 37.271241 -370.523703) (xy 37.271241 -370.523704) (xy 40.548752 -370.523704)
			(xy 40.548753 -370.456278) (xy 40.556831 -370.389338) (xy 40.572869 -370.323848) (xy 40.596637 -370.26075)
			(xy 40.627792 -370.200954) (xy 40.665885 -370.14532) (xy 40.687752 -370.119656) (xy 40.693556 -370.112516)
			(xy 40.700065 -370.095321) (xy 40.700452 -370.086128) (xy 40.700452 -369.928902) (xy 40.700929 -369.918774)
			(xy 40.708658 -369.900051) (xy 40.722947 -369.885694) (xy 40.741634 -369.877877) (xy 40.75176 -369.87734)
			(xy 41.46804 -369.87734) (xy 41.478202 -369.87769) (xy 41.496963 -369.885506) (xy 41.511286 -369.899925)
			(xy 41.518977 -369.918738) (xy 41.519348 -369.928902) (xy 41.519348 -370.086128) (xy 41.519756 -370.095315)
			(xy 41.526273 -370.112499) (xy 41.532048 -370.119656) (xy 41.553902 -370.14533) (xy 41.591994 -370.200962)
			(xy 41.623149 -370.260757) (xy 41.646916 -370.323852) (xy 41.662954 -370.389341) (xy 41.671031 -370.456279)
			(xy 41.671032 -370.523644) (xy 44.949071 -370.523644) (xy 44.949073 -370.456338) (xy 44.957118 -370.389515)
			(xy 44.973092 -370.324132) (xy 44.996766 -370.261127) (xy 45.027801 -370.201403) (xy 45.065751 -370.145816)
			(xy 45.08754 -370.120164) (xy 45.093339 -370.113021) (xy 45.099851 -370.095829) (xy 45.10024 -370.086636)
			(xy 45.10024 -369.928902) (xy 45.100665 -369.91873) (xy 45.10845 -369.899935) (xy 45.122835 -369.88555)
			(xy 45.14163 -369.877765) (xy 45.151802 -369.87734) (xy 45.868082 -369.87734) (xy 45.878253 -369.877778)
			(xy 45.897047 -369.885558) (xy 45.911433 -369.899939) (xy 45.919218 -369.918731) (xy 45.919644 -369.928902)
			(xy 45.919644 -370.086636) (xy 45.92005 -370.095823) (xy 45.926568 -370.113007) (xy 45.932344 -370.120164)
			(xy 45.95412 -370.145826) (xy 45.992071 -370.20141) (xy 46.023105 -370.261132) (xy 46.046779 -370.324136)
			(xy 46.062754 -370.389517) (xy 46.070799 -370.456339) (xy 46.0708 -370.523643) (xy 46.062757 -370.590465)
			(xy 46.046785 -370.655847) (xy 46.023113 -370.718851) (xy 45.99208 -370.778574) (xy 45.954131 -370.83416)
			(xy 45.932344 -370.859812) (xy 45.926553 -370.866961) (xy 45.920036 -370.884149) (xy 45.919644 -370.89334)
			(xy 45.919644 -371.386862) (xy 45.920085 -371.396046) (xy 45.926578 -371.41323) (xy 45.932344 -371.42039)
			(xy 45.954146 -371.44603) (xy 45.992096 -371.501618) (xy 46.023129 -371.561343) (xy 46.046568 -371.623726)
			(xy 47.14919 -371.623726) (xy 47.149193 -371.556417) (xy 47.157242 -371.489591) (xy 47.17322 -371.424206)
			(xy 47.1969 -371.3612) (xy 47.22794 -371.301475) (xy 47.265897 -371.24589) (xy 47.287688 -371.220238)
			(xy 47.293492 -371.213098) (xy 47.300003 -371.195904) (xy 47.300388 -371.18671) (xy 47.300388 -371.028722)
			(xy 47.300783 -371.018546) (xy 47.30857 -370.999742) (xy 47.322966 -370.985355) (xy 47.341773 -370.977578)
			(xy 47.35195 -370.97716) (xy 48.06823 -370.97716) (xy 48.078392 -370.977609) (xy 48.097167 -370.985398)
			(xy 48.111532 -370.999777) (xy 48.119301 -371.018559) (xy 48.119792 -371.028722) (xy 48.119792 -371.18671)
			(xy 48.120199 -371.195898) (xy 48.126715 -371.213082) (xy 48.132492 -371.220238) (xy 48.154241 -371.245921)
			(xy 48.192189 -371.301504) (xy 48.196948 -371.310662) (xy 53.966364 -371.310662) (xy 53.966364 -370.447062)
			(xy 53.96685 -370.419793) (xy 53.974612 -370.365809) (xy 53.989977 -370.313479) (xy 54.012634 -370.263869)
			(xy 54.04212 -370.217988) (xy 54.077835 -370.176771) (xy 54.119052 -370.141056) (xy 54.164933 -370.11157)
			(xy 54.214543 -370.088913) (xy 54.266873 -370.073548) (xy 54.320857 -370.065786) (xy 54.375395 -370.065786)
			(xy 54.429379 -370.073548) (xy 54.481709 -370.088913) (xy 54.531319 -370.11157) (xy 54.5772 -370.141056)
			(xy 54.618417 -370.176771) (xy 54.654132 -370.217988) (xy 54.683618 -370.263869) (xy 54.706275 -370.313479)
			(xy 54.72164 -370.365809) (xy 54.729402 -370.419793) (xy 54.729888 -370.447062) (xy 54.729888 -371.310662)
			(xy 57.339484 -371.310662) (xy 57.339484 -370.447062) (xy 57.33997 -370.419793) (xy 57.347732 -370.365809)
			(xy 57.363097 -370.313479) (xy 57.385754 -370.263869) (xy 57.41524 -370.217988) (xy 57.450955 -370.176771)
			(xy 57.492172 -370.141056) (xy 57.538053 -370.11157) (xy 57.587663 -370.088913) (xy 57.639993 -370.073548)
			(xy 57.693977 -370.065786) (xy 57.748515 -370.065786) (xy 57.802499 -370.073548) (xy 57.854829 -370.088913)
			(xy 57.904439 -370.11157) (xy 57.95032 -370.141056) (xy 57.991537 -370.176771) (xy 58.027252 -370.217988)
			(xy 58.056738 -370.263869) (xy 58.079395 -370.313479) (xy 58.09476 -370.365809) (xy 58.102522 -370.419793)
			(xy 58.103008 -370.447062) (xy 58.103008 -370.523703) (xy 71.348807 -370.523703) (xy 71.348808 -370.456279)
			(xy 71.356885 -370.38934) (xy 71.372921 -370.32385) (xy 71.396686 -370.260753) (xy 71.427838 -370.200956)
			(xy 71.465928 -370.145321) (xy 71.487792 -370.119656) (xy 71.493589 -370.112511) (xy 71.500104 -370.09532)
			(xy 71.500492 -370.086128) (xy 71.500492 -369.928902) (xy 71.501027 -369.918781) (xy 71.508745 -369.900069)
			(xy 71.523016 -369.885715) (xy 71.541682 -369.877887) (xy 71.5518 -369.87734) (xy 72.26808 -369.87734)
			(xy 72.278238 -369.877739) (xy 72.296998 -369.885535) (xy 72.311323 -369.89994) (xy 72.319016 -369.918742)
			(xy 72.319388 -369.928902) (xy 72.319388 -370.086128) (xy 72.319787 -370.095316) (xy 72.326309 -370.1125)
			(xy 72.332088 -370.119656) (xy 72.353941 -370.145331) (xy 72.39203 -370.200964) (xy 72.423182 -370.260758)
			(xy 72.446948 -370.323854) (xy 72.462984 -370.389342) (xy 72.471061 -370.45628) (xy 72.471063 -370.523644)
			(xy 75.749102 -370.523644) (xy 75.749103 -370.456338) (xy 75.757149 -370.389513) (xy 75.773125 -370.32413)
			(xy 75.796801 -370.261125) (xy 75.827837 -370.201401) (xy 75.86579 -370.145816) (xy 75.88758 -370.120164)
			(xy 75.893372 -370.113015) (xy 75.89989 -370.095828) (xy 75.90028 -370.086636) (xy 75.90028 -369.928902)
			(xy 75.900666 -369.918725) (xy 75.908459 -369.899923) (xy 75.922856 -369.885536) (xy 75.941665 -369.877759)
			(xy 75.951842 -369.87734) (xy 76.668122 -369.87734) (xy 76.678281 -369.877815) (xy 76.697052 -369.885597)
			(xy 76.711416 -369.899969) (xy 76.71919 -369.918742) (xy 76.719684 -369.928902) (xy 76.719684 -370.086636)
			(xy 76.72008 -370.095825) (xy 76.726604 -370.113009) (xy 76.732384 -370.120164) (xy 76.754159 -370.145826)
			(xy 76.792107 -370.201412) (xy 76.82314 -370.261134) (xy 76.846812 -370.324137) (xy 76.862785 -370.389518)
			(xy 76.87083 -370.456339) (xy 76.870831 -370.523643) (xy 76.870824 -370.523703) (xy 80.148895 -370.523703)
			(xy 80.148896 -370.456279) (xy 80.156972 -370.38934) (xy 80.173008 -370.323851) (xy 80.196773 -370.260754)
			(xy 80.227924 -370.200957) (xy 80.266012 -370.145322) (xy 80.287876 -370.119656) (xy 80.293671 -370.112509)
			(xy 80.300187 -370.09532) (xy 80.300576 -370.086128) (xy 80.300576 -369.928902) (xy 80.301029 -369.918771)
			(xy 80.308763 -369.900043) (xy 80.32306 -369.885685) (xy 80.341755 -369.877873) (xy 80.351884 -369.87734)
			(xy 81.068164 -369.87734) (xy 81.078321 -369.877752) (xy 81.09708 -369.885543) (xy 81.111406 -369.899944)
			(xy 81.1191 -369.918743) (xy 81.119472 -369.928902) (xy 81.119472 -370.086128) (xy 81.119875 -370.095316)
			(xy 81.126394 -370.1125) (xy 81.132172 -370.119656) (xy 81.154025 -370.14533) (xy 81.192116 -370.200963)
			(xy 81.223269 -370.260758) (xy 81.247035 -370.323853) (xy 81.263072 -370.389342) (xy 81.271149 -370.456279)
			(xy 81.27115 -370.523703) (xy 84.548686 -370.523703) (xy 84.548687 -370.456279) (xy 84.556763 -370.389341)
			(xy 84.572799 -370.323851) (xy 84.596563 -370.260754) (xy 84.627713 -370.200957) (xy 84.665801 -370.145322)
			(xy 84.687664 -370.119656) (xy 84.69347 -370.112518) (xy 84.699977 -370.095322) (xy 84.700364 -370.086128)
			(xy 84.700364 -369.928902) (xy 84.700829 -369.918772) (xy 84.708561 -369.900047) (xy 84.722854 -369.88569)
			(xy 84.741545 -369.877875) (xy 84.751672 -369.87734) (xy 85.467952 -369.87734) (xy 85.478108 -369.877762)
			(xy 85.496867 -369.885549) (xy 85.511194 -369.899947) (xy 85.518888 -369.918744) (xy 85.51926 -369.928902)
			(xy 85.51926 -370.086128) (xy 85.519666 -370.095315) (xy 85.526183 -370.112499) (xy 85.53196 -370.119656)
			(xy 85.553814 -370.14533) (xy 85.591905 -370.200963) (xy 85.623059 -370.260757) (xy 85.646825 -370.323853)
			(xy 85.662863 -370.389341) (xy 85.67094 -370.456279) (xy 85.670941 -370.523644) (xy 115.349244 -370.523644)
			(xy 115.349245 -370.456338) (xy 115.35729 -370.389516) (xy 115.373263 -370.324133) (xy 115.396936 -370.261128)
			(xy 115.427969 -370.201404) (xy 115.465917 -370.145817) (xy 115.487704 -370.120164) (xy 115.493499 -370.113018)
			(xy 115.500014 -370.095828) (xy 115.500404 -370.086636) (xy 115.500404 -369.928902) (xy 115.500934 -369.918749)
			(xy 115.508702 -369.899986) (xy 115.523056 -369.885622) (xy 115.541813 -369.877841) (xy 115.551966 -369.87734)
			(xy 116.268246 -369.87734) (xy 116.278407 -369.877796) (xy 116.297177 -369.885586) (xy 116.311541 -369.899963)
			(xy 116.319314 -369.918741) (xy 116.319808 -369.928902) (xy 116.319808 -370.086636) (xy 116.320199 -370.095825)
			(xy 116.326726 -370.11301) (xy 116.332508 -370.120164) (xy 116.354286 -370.145825) (xy 116.392238 -370.201409)
			(xy 116.423275 -370.261131) (xy 116.446951 -370.324134) (xy 116.462926 -370.389516) (xy 116.470972 -370.456338)
			(xy 116.470973 -370.523644) (xy 116.470966 -370.523703) (xy 119.749013 -370.523703) (xy 119.749014 -370.456279)
			(xy 119.757091 -370.38934) (xy 119.773128 -370.32385) (xy 119.796893 -370.260752) (xy 119.828045 -370.200956)
			(xy 119.866135 -370.145321) (xy 119.888 -370.119656) (xy 119.893798 -370.112512) (xy 119.900312 -370.09532)
			(xy 119.9007 -370.086128) (xy 119.9007 -369.928902) (xy 119.901227 -369.91878) (xy 119.908947 -369.900067)
			(xy 119.92322 -369.885712) (xy 119.941889 -369.877886) (xy 119.952008 -369.87734) (xy 120.668288 -369.87734)
			(xy 120.678446 -369.877732) (xy 120.697206 -369.885531) (xy 120.711531 -369.899938) (xy 120.719224 -369.918741)
			(xy 120.719596 -369.928902) (xy 120.719596 -370.086128) (xy 120.719993 -370.095317) (xy 120.726516 -370.112501)
			(xy 120.732296 -370.119656) (xy 120.754148 -370.145331) (xy 120.792238 -370.200964) (xy 120.823389 -370.260759)
			(xy 120.847154 -370.323854) (xy 120.863191 -370.389342) (xy 120.871267 -370.45628) (xy 120.871269 -370.523644)
			(xy 124.149308 -370.523644) (xy 124.149309 -370.456338) (xy 124.157355 -370.389513) (xy 124.173331 -370.32413)
			(xy 124.197007 -370.261125) (xy 124.228045 -370.201401) (xy 124.265998 -370.145816) (xy 124.287788 -370.120164)
			(xy 124.293581 -370.113016) (xy 124.300098 -370.095828) (xy 124.300488 -370.086636) (xy 124.300488 -369.928902)
			(xy 124.300867 -369.918724) (xy 124.30866 -369.89992) (xy 124.32306 -369.885533) (xy 124.341872 -369.877757)
			(xy 124.35205 -369.87734) (xy 125.06833 -369.87734) (xy 125.07849 -369.877809) (xy 125.09726 -369.885593)
			(xy 125.111625 -369.899967) (xy 125.119398 -369.918742) (xy 125.119892 -369.928902) (xy 125.119892 -370.086636)
			(xy 125.120286 -370.095825) (xy 125.126811 -370.113009) (xy 125.132592 -370.120164) (xy 125.154367 -370.145826)
			(xy 125.192314 -370.201412) (xy 125.223346 -370.261134) (xy 125.247018 -370.324138) (xy 125.262991 -370.389518)
			(xy 125.271036 -370.456339) (xy 125.271037 -370.523643) (xy 125.271037 -370.523644) (xy 128.549099 -370.523644)
			(xy 128.5491 -370.456338) (xy 128.557146 -370.389514) (xy 128.573121 -370.32413) (xy 128.596797 -370.261125)
			(xy 128.627834 -370.201402) (xy 128.665787 -370.145816) (xy 128.687576 -370.120164) (xy 128.693368 -370.113015)
			(xy 128.699886 -370.095828) (xy 128.700276 -370.086636) (xy 128.700276 -369.928902) (xy 128.700666 -369.918726)
			(xy 128.708458 -369.899924) (xy 128.722854 -369.885538) (xy 128.741661 -369.877759) (xy 128.751838 -369.87734)
			(xy 129.468118 -369.87734) (xy 129.478277 -369.877818) (xy 129.497047 -369.885599) (xy 129.511412 -369.89997)
			(xy 129.519185 -369.918743) (xy 129.51968 -369.928902) (xy 129.51968 -370.086636) (xy 129.520077 -370.095824)
			(xy 129.5266 -370.113008) (xy 129.53238 -370.120164) (xy 129.554155 -370.145826) (xy 129.592103 -370.201412)
			(xy 129.623136 -370.261134) (xy 129.646809 -370.324137) (xy 129.662782 -370.389518) (xy 129.670827 -370.456339)
			(xy 129.670828 -370.523643) (xy 129.670828 -370.523644) (xy 159.349153 -370.523644) (xy 159.349154 -370.456338)
			(xy 159.357199 -370.389515) (xy 159.373173 -370.324133) (xy 159.396846 -370.261128) (xy 159.427879 -370.201404)
			(xy 159.465828 -370.145816) (xy 159.487616 -370.120164) (xy 159.493412 -370.113019) (xy 159.499927 -370.095828)
			(xy 159.500316 -370.086636) (xy 159.500316 -369.928902) (xy 159.500835 -369.918747) (xy 159.508604 -369.899982)
			(xy 159.522962 -369.885618) (xy 159.541723 -369.877839) (xy 159.551878 -369.87734) (xy 160.268158 -369.87734)
			(xy 160.278327 -369.877798) (xy 160.297121 -369.88557) (xy 160.311508 -369.899945) (xy 160.319294 -369.918733)
			(xy 160.31972 -369.928902) (xy 160.31972 -370.086636) (xy 160.320109 -370.095826) (xy 160.326637 -370.11301)
			(xy 160.33242 -370.120164) (xy 160.354197 -370.145825) (xy 160.392149 -370.20141) (xy 160.423185 -370.261131)
			(xy 160.44686 -370.324135) (xy 160.462835 -370.389516) (xy 160.470881 -370.456339) (xy 160.470882 -370.523643)
			(xy 160.470875 -370.523703) (xy 163.748922 -370.523703) (xy 163.748923 -370.456279) (xy 163.757 -370.389339)
			(xy 163.773037 -370.323849) (xy 163.796803 -370.260752) (xy 163.827956 -370.200955) (xy 163.866047 -370.145321)
			(xy 163.887912 -370.119656) (xy 163.893711 -370.112513) (xy 163.900224 -370.095321) (xy 163.900612 -370.086128)
			(xy 163.900612 -369.928902) (xy 163.901127 -369.918779) (xy 163.908849 -369.900063) (xy 163.923126 -369.885708)
			(xy 163.9418 -369.877884) (xy 163.95192 -369.87734) (xy 164.6682 -369.87734) (xy 164.678359 -369.877722)
			(xy 164.697119 -369.885526) (xy 164.711444 -369.899935) (xy 164.719136 -369.918741) (xy 164.719508 -369.928902)
			(xy 164.719508 -370.086128) (xy 164.719903 -370.095317) (xy 164.726427 -370.112501) (xy 164.732208 -370.119656)
			(xy 164.75406 -370.145331) (xy 164.792148 -370.200964) (xy 164.823299 -370.260759) (xy 164.847064 -370.323855)
			(xy 164.8631 -370.389343) (xy 164.871176 -370.45628) (xy 164.871178 -370.523644) (xy 168.149241 -370.523644)
			(xy 168.149242 -370.456338) (xy 168.157287 -370.389516) (xy 168.17326 -370.324133) (xy 168.196933 -370.261128)
			(xy 168.227965 -370.201404) (xy 168.265913 -370.145817) (xy 168.2877 -370.120164) (xy 168.293494 -370.113017)
			(xy 168.30001 -370.095828) (xy 168.3004 -370.086636) (xy 168.3004 -369.928902) (xy 168.300934 -369.918749)
			(xy 168.308701 -369.899987) (xy 168.323054 -369.885623) (xy 168.341809 -369.877842) (xy 168.351962 -369.87734)
			(xy 169.068242 -369.87734) (xy 169.078403 -369.877799) (xy 169.097173 -369.885588) (xy 169.111537 -369.899964)
			(xy 169.11931 -369.918741) (xy 169.119804 -369.928902) (xy 169.119804 -370.086636) (xy 169.120196 -370.095825)
			(xy 169.126722 -370.113009) (xy 169.132504 -370.120164) (xy 169.154279 -370.145826) (xy 169.192225 -370.201412)
			(xy 169.223256 -370.261135) (xy 169.246928 -370.324138) (xy 169.2629 -370.389519) (xy 169.270945 -370.456339)
			(xy 169.270946 -370.523643) (xy 169.270946 -370.523644) (xy 172.549008 -370.523644) (xy 172.549009 -370.456338)
			(xy 172.557055 -370.389513) (xy 172.573031 -370.32413) (xy 172.596707 -370.261125) (xy 172.627745 -370.201401)
			(xy 172.665698 -370.145816) (xy 172.687488 -370.120164) (xy 172.693281 -370.113016) (xy 172.699798 -370.095828)
			(xy 172.700188 -370.086636) (xy 172.700188 -369.928902) (xy 172.700567 -369.918724) (xy 172.70836 -369.89992)
			(xy 172.72276 -369.885533) (xy 172.741572 -369.877757) (xy 172.75175 -369.87734) (xy 173.46803 -369.87734)
			(xy 173.47819 -369.877809) (xy 173.49696 -369.885593) (xy 173.511325 -369.899967) (xy 173.519098 -369.918742)
			(xy 173.519592 -369.928902) (xy 173.519592 -370.086636) (xy 173.519986 -370.095825) (xy 173.526511 -370.113009)
			(xy 173.532292 -370.120164) (xy 173.554067 -370.145826) (xy 173.592014 -370.201412) (xy 173.623046 -370.261134)
			(xy 173.646718 -370.324138) (xy 173.662691 -370.389518) (xy 173.670736 -370.456339) (xy 173.670737 -370.523643)
			(xy 173.662694 -370.590464) (xy 173.646724 -370.655845) (xy 173.623054 -370.718849) (xy 173.592023 -370.778573)
			(xy 173.554078 -370.834159) (xy 173.532292 -370.859812) (xy 173.526507 -370.866965) (xy 173.519986 -370.88415)
			(xy 173.519592 -370.89334) (xy 173.519592 -371.386862) (xy 173.520022 -371.396047) (xy 173.526522 -371.413231)
			(xy 173.532292 -371.42039) (xy 173.554093 -371.446031) (xy 173.592039 -371.50162) (xy 173.62307 -371.561345)
			(xy 173.646506 -371.623725) (xy 174.74915 -371.623725) (xy 174.749154 -371.556417) (xy 174.757201 -371.489592)
			(xy 174.773178 -371.424208) (xy 174.796855 -371.361202) (xy 174.827893 -371.301477) (xy 174.865846 -371.24589)
			(xy 174.887636 -371.220238) (xy 174.893446 -371.213102) (xy 174.899952 -371.195904) (xy 174.900336 -371.18671)
			(xy 174.900336 -371.028722) (xy 174.900782 -371.018552) (xy 174.908559 -370.999758) (xy 174.922938 -370.985373)
			(xy 174.941728 -370.977587) (xy 174.951898 -370.97716) (xy 175.668178 -370.97716) (xy 175.678351 -370.977583)
			(xy 175.697149 -370.985364) (xy 175.711536 -370.999751) (xy 175.719317 -371.018549) (xy 175.71974 -371.028722)
			(xy 175.71974 -371.18671) (xy 175.720159 -371.195896) (xy 175.726668 -371.21308) (xy 175.73244 -371.220238)
			(xy 175.754191 -371.245921) (xy 175.792142 -371.301502) (xy 175.823178 -371.361221) (xy 175.846854 -371.424222)
			(xy 175.86283 -371.489601) (xy 175.870878 -371.55642) (xy 175.870881 -371.623723) (xy 175.862841 -371.690543)
			(xy 175.846871 -371.755923) (xy 175.823202 -371.818926) (xy 175.792172 -371.878649) (xy 175.754226 -371.934234)
			(xy 175.73244 -371.959886) (xy 175.726617 -371.967012) (xy 175.72012 -371.984218) (xy 175.71974 -371.993414)
			(xy 175.71974 -372.486682) (xy 175.720172 -372.495867) (xy 175.726672 -372.51305) (xy 175.73244 -372.52021)
			(xy 175.754262 -372.545834) (xy 175.792211 -372.601424) (xy 175.823244 -372.661151) (xy 175.846916 -372.72416)
			(xy 175.862887 -372.789545) (xy 175.870929 -372.856371) (xy 175.870926 -372.92368) (xy 175.862878 -372.990505)
			(xy 175.846901 -373.055889) (xy 175.823223 -373.118895) (xy 175.792185 -373.17862) (xy 175.754231 -373.234206)
			(xy 175.73244 -373.259858) (xy 175.726629 -373.266993) (xy 175.720125 -373.284191) (xy 175.71974 -373.293386)
			(xy 175.71974 -373.451374) (xy 175.719314 -373.461547) (xy 175.711534 -373.480345) (xy 175.697148 -373.494731)
			(xy 175.678351 -373.502513) (xy 175.668178 -373.502936) (xy 174.951898 -373.502936) (xy 174.941723 -373.502537)
			(xy 174.922923 -373.494747) (xy 174.908538 -373.480353) (xy 174.900757 -373.461549) (xy 174.900336 -373.451374)
			(xy 174.900336 -373.293386) (xy 174.899925 -373.284199) (xy 174.893411 -373.267015) (xy 174.887636 -373.259858)
			(xy 174.865882 -373.234178) (xy 174.827932 -373.178596) (xy 174.796898 -373.118876) (xy 174.773223 -373.055875)
			(xy 174.757248 -372.990496) (xy 174.749201 -372.923677) (xy 174.749198 -372.856374) (xy 174.757239 -372.789554)
			(xy 174.773208 -372.724174) (xy 174.796877 -372.661171) (xy 174.827906 -372.601448) (xy 174.865851 -372.545862)
			(xy 174.887636 -372.52021) (xy 174.893458 -372.513083) (xy 174.899957 -372.495878) (xy 174.900336 -372.486682)
			(xy 174.900336 -371.993414) (xy 174.899911 -371.984229) (xy 174.893407 -371.967044) (xy 174.887636 -371.959886)
			(xy 174.865811 -371.934265) (xy 174.827863 -371.878674) (xy 174.796832 -371.818946) (xy 174.773161 -371.755937)
			(xy 174.757191 -371.690551) (xy 174.74915 -371.623725) (xy 173.646506 -371.623725) (xy 173.646741 -371.624351)
			(xy 173.662712 -371.689734) (xy 173.670754 -371.756558) (xy 173.670753 -371.823863) (xy 173.662708 -371.890686)
			(xy 173.646734 -371.956069) (xy 173.623061 -372.019074) (xy 173.592028 -372.078798) (xy 173.55408 -372.134385)
			(xy 173.532292 -372.160038) (xy 173.526496 -372.167183) (xy 173.519981 -372.184374) (xy 173.519592 -372.193566)
			(xy 173.519592 -372.351554) (xy 173.519099 -372.361719) (xy 173.511335 -372.380507) (xy 173.496971 -372.394892)
			(xy 173.478194 -372.402684) (xy 173.46803 -372.403116) (xy 172.75175 -372.403116) (xy 172.741576 -372.402694)
			(xy 172.722773 -372.394917) (xy 172.708385 -372.38053) (xy 172.700607 -372.361728) (xy 172.700188 -372.351554)
			(xy 172.700188 -372.193566) (xy 172.699797 -372.184377) (xy 172.69327 -372.167192) (xy 172.687488 -372.160038)
			(xy 172.665713 -372.134375) (xy 172.62776 -372.078791) (xy 172.596724 -372.01907) (xy 172.573048 -371.956067)
			(xy 172.557072 -371.890685) (xy 172.549026 -371.823863) (xy 172.549025 -371.756558) (xy 172.557069 -371.689736)
			(xy 172.573042 -371.624354) (xy 172.596715 -371.561349) (xy 172.627749 -371.501627) (xy 172.6657 -371.446041)
			(xy 172.687488 -371.42039) (xy 172.69327 -371.413234) (xy 172.699794 -371.396052) (xy 172.700188 -371.386862)
			(xy 172.700188 -370.89334) (xy 172.699761 -370.884154) (xy 172.69326 -370.86697) (xy 172.687488 -370.859812)
			(xy 172.665687 -370.83417) (xy 172.627735 -370.778583) (xy 172.5967 -370.718859) (xy 172.573026 -370.655853)
			(xy 172.557052 -370.590469) (xy 172.549008 -370.523644) (xy 169.270946 -370.523644) (xy 169.262904 -370.590464)
			(xy 169.246933 -370.655845) (xy 169.223264 -370.718849) (xy 169.192234 -370.778572) (xy 169.15429 -370.834159)
			(xy 169.132504 -370.859812) (xy 169.12672 -370.866966) (xy 169.120198 -370.88415) (xy 169.119804 -370.89334)
			(xy 169.119804 -371.386862) (xy 169.120231 -371.396047) (xy 169.126733 -371.413232) (xy 169.132504 -371.42039)
			(xy 169.154304 -371.446031) (xy 169.19225 -371.50162) (xy 169.22328 -371.561346) (xy 169.246737 -371.623785)
			(xy 170.348831 -371.623785) (xy 170.348834 -371.556358) (xy 170.356914 -371.489416) (xy 170.372955 -371.423924)
			(xy 170.396726 -371.360825) (xy 170.427884 -371.301029) (xy 170.46598 -371.245394) (xy 170.487848 -371.21973)
			(xy 170.493663 -371.212598) (xy 170.500165 -371.195397) (xy 170.500548 -371.186202) (xy 170.500548 -371.028722)
			(xy 170.501045 -371.018596) (xy 170.508767 -370.999873) (xy 170.52305 -370.985516) (xy 170.541732 -370.977698)
			(xy 170.551856 -370.97716) (xy 171.268136 -370.97716) (xy 171.278287 -370.977591) (xy 171.297033 -370.985391)
			(xy 171.311354 -370.999784) (xy 171.319059 -371.018568) (xy 171.319444 -371.028722) (xy 171.319444 -371.186202)
			(xy 171.319866 -371.195388) (xy 171.326373 -371.212571) (xy 171.332144 -371.21973) (xy 171.353973 -371.245425)
			(xy 171.392066 -371.301054) (xy 171.423222 -371.360846) (xy 171.44699 -371.423939) (xy 171.46303 -371.489425)
			(xy 171.47111 -371.556361) (xy 171.471113 -371.623782) (xy 171.46304 -371.690719) (xy 171.447007 -371.756207)
			(xy 171.423245 -371.819302) (xy 171.392096 -371.879097) (xy 171.354008 -371.93473) (xy 171.332144 -371.960394)
			(xy 171.326361 -371.967548) (xy 171.31984 -371.984732) (xy 171.319444 -371.993922) (xy 171.319444 -372.486174)
			(xy 171.319879 -372.495358) (xy 171.326377 -372.512542) (xy 171.332144 -372.519702) (xy 171.354043 -372.545339)
			(xy 171.392135 -372.600976) (xy 171.423287 -372.660776) (xy 171.447052 -372.723876) (xy 171.463087 -372.789369)
			(xy 171.471161 -372.856312) (xy 171.471158 -372.923739) (xy 171.463077 -372.990681) (xy 171.447037 -373.056172)
			(xy 171.423266 -373.119271) (xy 171.392108 -373.179068) (xy 171.354012 -373.234702) (xy 171.332144 -373.260366)
			(xy 171.32633 -373.267499) (xy 171.319827 -373.284699) (xy 171.319444 -373.293894) (xy 171.319444 -373.451374)
			(xy 171.318952 -373.461501) (xy 171.31123 -373.480225) (xy 171.296945 -373.494583) (xy 171.27826 -373.5024)
			(xy 171.268136 -373.502936) (xy 170.551856 -373.502936) (xy 170.541704 -373.502515) (xy 170.522957 -373.494712)
			(xy 170.508637 -373.480316) (xy 170.500932 -373.461529) (xy 170.500548 -373.451374) (xy 170.500548 -373.293894)
			(xy 170.50013 -373.284708) (xy 170.493621 -373.267524) (xy 170.487848 -373.260366) (xy 170.466016 -373.234674)
			(xy 170.427923 -373.179044) (xy 170.396768 -373.119252) (xy 170.373 -373.056159) (xy 170.356961 -372.990673)
			(xy 170.348881 -372.923736) (xy 170.348878 -372.856315) (xy 170.356951 -372.789378) (xy 170.372985 -372.72389)
			(xy 170.396747 -372.660794) (xy 170.427897 -372.600999) (xy 170.465984 -372.545366) (xy 170.487848 -372.519702)
			(xy 170.493632 -372.512548) (xy 170.500153 -372.495364) (xy 170.500548 -372.486174) (xy 170.500548 -371.993922)
			(xy 170.500117 -371.984737) (xy 170.493617 -371.967553) (xy 170.487848 -371.960394) (xy 170.465945 -371.93476)
			(xy 170.427854 -371.879122) (xy 170.396703 -371.819322) (xy 170.372938 -371.756221) (xy 170.356904 -371.690728)
			(xy 170.348831 -371.623785) (xy 169.246737 -371.623785) (xy 169.24695 -371.624352) (xy 169.262921 -371.689735)
			(xy 169.270963 -371.756558) (xy 169.270962 -371.823863) (xy 169.262917 -371.890686) (xy 169.246944 -371.956068)
			(xy 169.223271 -372.019073) (xy 169.192239 -372.078798) (xy 169.154291 -372.134385) (xy 169.132504 -372.160038)
			(xy 169.126709 -372.167185) (xy 169.120193 -372.184374) (xy 169.119804 -372.193566) (xy 169.119804 -372.351554)
			(xy 169.1193 -372.361717) (xy 169.111537 -372.380503) (xy 169.097177 -372.394888) (xy 169.078405 -372.402682)
			(xy 169.068242 -372.403116) (xy 168.351962 -372.403116) (xy 168.341782 -372.402766) (xy 168.322978 -372.39496)
			(xy 168.308593 -372.380552) (xy 168.300817 -372.361734) (xy 168.3004 -372.351554) (xy 168.3004 -372.193566)
			(xy 168.300006 -372.184377) (xy 168.293481 -372.167193) (xy 168.2877 -372.160038) (xy 168.265927 -372.134374)
			(xy 168.227981 -372.078788) (xy 168.196949 -372.019066) (xy 168.173277 -371.956063) (xy 168.157304 -371.890683)
			(xy 168.14926 -371.823862) (xy 168.149258 -371.756559) (xy 168.1573 -371.689738) (xy 168.173271 -371.624357)
			(xy 168.19694 -371.561353) (xy 168.22797 -371.50163) (xy 168.265914 -371.446043) (xy 168.2877 -371.42039)
			(xy 168.293483 -371.413235) (xy 168.300006 -371.396052) (xy 168.3004 -371.386862) (xy 168.3004 -370.89334)
			(xy 168.299971 -370.884155) (xy 168.29347 -370.86697) (xy 168.2877 -370.859812) (xy 168.265902 -370.834169)
			(xy 168.227956 -370.77858) (xy 168.196925 -370.718855) (xy 168.173255 -370.65585) (xy 168.157284 -370.590467)
			(xy 168.149241 -370.523644) (xy 164.871178 -370.523644) (xy 164.871178 -370.523702) (xy 164.863103 -370.59064)
			(xy 164.847069 -370.656128) (xy 164.823307 -370.719224) (xy 164.792158 -370.77902) (xy 164.754071 -370.834655)
			(xy 164.732208 -370.86032) (xy 164.726421 -370.867472) (xy 164.7199 -370.884657) (xy 164.719508 -370.893848)
			(xy 164.719508 -371.386354) (xy 164.719938 -371.395539) (xy 164.726438 -371.412724) (xy 164.732208 -371.419882)
			(xy 164.754085 -371.445536) (xy 164.792173 -371.501172) (xy 164.823323 -371.56097) (xy 164.846957 -371.623726)
			(xy 165.949062 -371.623726) (xy 165.949066 -371.556417) (xy 165.957114 -371.489592) (xy 165.973091 -371.424207)
			(xy 165.996769 -371.361201) (xy 166.027807 -371.301477) (xy 166.065761 -371.24589) (xy 166.087552 -371.220238)
			(xy 166.093364 -371.213104) (xy 166.099868 -371.195905) (xy 166.100252 -371.18671) (xy 166.100252 -371.028722)
			(xy 166.100682 -371.01855) (xy 166.108463 -370.999753) (xy 166.122847 -370.985367) (xy 166.141642 -370.977584)
			(xy 166.151814 -370.97716) (xy 166.868094 -370.97716) (xy 166.878268 -370.977569) (xy 166.897067 -370.985356)
			(xy 166.911453 -370.999747) (xy 166.919234 -371.018548) (xy 166.919656 -371.028722) (xy 166.919656 -371.18671)
			(xy 166.920071 -371.195896) (xy 166.926582 -371.21308) (xy 166.932356 -371.220238) (xy 166.954106 -371.245921)
			(xy 166.992057 -371.301503) (xy 167.023092 -371.361222) (xy 167.046767 -371.424223) (xy 167.062743 -371.489601)
			(xy 167.07079 -371.55642) (xy 167.070793 -371.623722) (xy 167.062753 -371.690543) (xy 167.046784 -371.755923)
			(xy 167.023115 -371.818926) (xy 166.992086 -371.878648) (xy 166.954141 -371.934234) (xy 166.932356 -371.959886)
			(xy 166.926535 -371.967014) (xy 166.920036 -371.984218) (xy 166.919656 -371.993414) (xy 166.919656 -372.486682)
			(xy 166.920085 -372.495867) (xy 166.926586 -372.513051) (xy 166.932356 -372.52021) (xy 166.954177 -372.545834)
			(xy 166.992126 -372.601425) (xy 167.023158 -372.661152) (xy 167.046829 -372.72416) (xy 167.0628 -372.789546)
			(xy 167.070841 -372.856372) (xy 167.070838 -372.923679) (xy 167.06279 -372.990504) (xy 167.046814 -373.055889)
			(xy 167.023137 -373.118895) (xy 166.992099 -373.178619) (xy 166.954146 -373.234206) (xy 166.932356 -373.259858)
			(xy 166.926547 -373.266994) (xy 166.920041 -373.284192) (xy 166.919656 -373.293386) (xy 166.919656 -373.451374)
			(xy 166.919215 -373.461545) (xy 166.911437 -373.48034) (xy 166.897057 -373.494726) (xy 166.878264 -373.502511)
			(xy 166.868094 -373.502936) (xy 166.151814 -373.502936) (xy 166.14164 -373.502524) (xy 166.122841 -373.494739)
			(xy 166.108454 -373.480349) (xy 166.100673 -373.461548) (xy 166.100252 -373.451374) (xy 166.100252 -373.293386)
			(xy 166.099837 -373.2842) (xy 166.093325 -373.267016) (xy 166.087552 -373.259858) (xy 166.065797 -373.234178)
			(xy 166.027847 -373.178596) (xy 165.996811 -373.118877) (xy 165.973136 -373.055876) (xy 165.95716 -372.990497)
			(xy 165.949113 -372.923677) (xy 165.94911 -372.856374) (xy 165.957151 -372.789554) (xy 165.973121 -372.724173)
			(xy 165.99679 -372.66117) (xy 166.02782 -372.601448) (xy 166.065766 -372.545862) (xy 166.087552 -372.52021)
			(xy 166.093376 -372.513084) (xy 166.099873 -372.495879) (xy 166.100252 -372.486682) (xy 166.100252 -371.993414)
			(xy 166.099824 -371.984229) (xy 166.093321 -371.967045) (xy 166.087552 -371.959886) (xy 166.065726 -371.934265)
			(xy 166.027778 -371.878674) (xy 165.996745 -371.818947) (xy 165.973074 -371.755938) (xy 165.957104 -371.690552)
			(xy 165.949062 -371.623726) (xy 164.846957 -371.623726) (xy 164.847086 -371.624068) (xy 164.86312 -371.689559)
			(xy 164.871195 -371.756498) (xy 164.871194 -371.823923) (xy 164.863116 -371.890862) (xy 164.84708 -371.956352)
			(xy 164.823314 -372.019449) (xy 164.792162 -372.079246) (xy 164.754073 -372.134881) (xy 164.732208 -372.160546)
			(xy 164.72641 -372.16769) (xy 164.719896 -372.184881) (xy 164.719508 -372.194074) (xy 164.719508 -372.351554)
			(xy 164.718937 -372.361672) (xy 164.711233 -372.380383) (xy 164.696973 -372.394739) (xy 164.678314 -372.402568)
			(xy 164.6682 -372.403116) (xy 163.95192 -372.403116) (xy 163.941769 -372.402662) (xy 163.92302 -372.394876)
			(xy 163.908697 -372.38049) (xy 163.900993 -372.361707) (xy 163.900612 -372.351554) (xy 163.900612 -372.194074)
			(xy 163.900212 -372.184886) (xy 163.893691 -372.167702) (xy 163.887912 -372.160546) (xy 163.866061 -372.13487)
			(xy 163.827971 -372.079237) (xy 163.796819 -372.019442) (xy 163.773054 -371.956347) (xy 163.757017 -371.890859)
			(xy 163.74894 -371.823922) (xy 163.748939 -371.756499) (xy 163.757013 -371.689562) (xy 163.773048 -371.624073)
			(xy 163.796811 -371.560977) (xy 163.827961 -371.501181) (xy 163.866048 -371.445547) (xy 163.887912 -371.419882)
			(xy 163.8937 -371.412731) (xy 163.900219 -371.395545) (xy 163.900612 -371.386354) (xy 163.900612 -370.893848)
			(xy 163.900176 -370.884664) (xy 163.89368 -370.867479) (xy 163.887912 -370.86032) (xy 163.866036 -370.834665)
			(xy 163.827947 -370.779029) (xy 163.796796 -370.719232) (xy 163.773032 -370.656133) (xy 163.756997 -370.590643)
			(xy 163.748922 -370.523703) (xy 160.470875 -370.523703) (xy 160.462839 -370.590466) (xy 160.446866 -370.655848)
			(xy 160.423192 -370.718852) (xy 160.392158 -370.778575) (xy 160.354208 -370.83416) (xy 160.33242 -370.859812)
			(xy 160.326638 -370.866968) (xy 160.320114 -370.88415) (xy 160.31972 -370.89334) (xy 160.31972 -371.386862)
			(xy 160.320144 -371.396048) (xy 160.326647 -371.413233) (xy 160.33242 -371.42039) (xy 160.354223 -371.44603)
			(xy 160.392174 -371.501618) (xy 160.423209 -371.561342) (xy 160.44667 -371.623784) (xy 161.548767 -371.623784)
			(xy 161.548771 -371.556358) (xy 161.55685 -371.489418) (xy 161.572888 -371.423928) (xy 161.596655 -371.360829)
			(xy 161.627808 -371.301032) (xy 161.665899 -371.245396) (xy 161.687764 -371.21973) (xy 161.693581 -371.212599)
			(xy 161.700082 -371.195397) (xy 161.700464 -371.186202) (xy 161.700464 -371.028722) (xy 161.700945 -371.018594)
			(xy 161.70867 -370.999868) (xy 161.722959 -370.985511) (xy 161.741646 -370.977695) (xy 161.751772 -370.97716)
			(xy 162.468052 -370.97716) (xy 162.478198 -370.97766) (xy 162.496942 -370.985432) (xy 162.511265 -370.999805)
			(xy 162.518974 -371.018575) (xy 162.51936 -371.028722) (xy 162.51936 -371.186202) (xy 162.519778 -371.195388)
			(xy 162.526287 -371.212572) (xy 162.53206 -371.21973) (xy 162.553888 -371.245425) (xy 162.591981 -371.301055)
			(xy 162.623135 -371.360846) (xy 162.646903 -371.423939) (xy 162.662942 -371.489425) (xy 162.671022 -371.556361)
			(xy 162.671025 -371.623782) (xy 162.662953 -371.690719) (xy 162.64692 -371.756206) (xy 162.623158 -371.819302)
			(xy 162.59201 -371.879096) (xy 162.553923 -371.934729) (xy 162.53206 -371.960394) (xy 162.526278 -371.96755)
			(xy 162.519756 -371.984732) (xy 162.51936 -371.993922) (xy 162.51936 -372.486174) (xy 162.519791 -372.495359)
			(xy 162.526291 -372.512543) (xy 162.53206 -372.519702) (xy 162.553959 -372.545339) (xy 162.592049 -372.600977)
			(xy 162.623201 -372.660776) (xy 162.646965 -372.723877) (xy 162.662999 -372.78937) (xy 162.671073 -372.856312)
			(xy 162.67107 -372.923739) (xy 162.66299 -372.99068) (xy 162.646949 -373.056172) (xy 162.62318 -373.11927)
			(xy 162.592023 -373.179067) (xy 162.553927 -373.234701) (xy 162.53206 -373.260366) (xy 162.526248 -373.2675)
			(xy 162.519743 -373.284699) (xy 162.51936 -373.293894) (xy 162.51936 -373.451374) (xy 162.518852 -373.461499)
			(xy 162.511133 -373.48022) (xy 162.496853 -373.494577) (xy 162.478174 -373.502397) (xy 162.468052 -373.502936)
			(xy 161.751772 -373.502936) (xy 161.741621 -373.502502) (xy 161.722874 -373.494704) (xy 161.708553 -373.480312)
			(xy 161.700848 -373.461527) (xy 161.700464 -373.451374) (xy 161.700464 -373.293894) (xy 161.700042 -373.284708)
			(xy 161.693535 -373.267525) (xy 161.687764 -373.260366) (xy 161.665935 -373.234673) (xy 161.627847 -373.179041)
			(xy 161.596697 -373.119249) (xy 161.572933 -373.056155) (xy 161.556896 -372.99067) (xy 161.548818 -372.923736)
			(xy 161.548815 -372.856315) (xy 161.556887 -372.78938) (xy 161.572918 -372.723893) (xy 161.596676 -372.660798)
			(xy 161.627821 -372.601003) (xy 161.665903 -372.545368) (xy 161.687764 -372.519702) (xy 161.69355 -372.51255)
			(xy 161.700069 -372.495364) (xy 161.700464 -372.486174) (xy 161.700464 -371.993922) (xy 161.700029 -371.984738)
			(xy 161.693531 -371.967554) (xy 161.687764 -371.960394) (xy 161.665864 -371.934759) (xy 161.627779 -371.879119)
			(xy 161.596632 -371.819319) (xy 161.572871 -371.756218) (xy 161.55684 -371.690725) (xy 161.548767 -371.623784)
			(xy 160.44667 -371.623784) (xy 160.446882 -371.624348) (xy 160.462856 -371.689733) (xy 160.470899 -371.756557)
			(xy 160.470898 -371.823864) (xy 160.462852 -371.890688) (xy 160.446876 -371.956072) (xy 160.4232 -372.019077)
			(xy 160.392163 -372.078801) (xy 160.35421 -372.134386) (xy 160.33242 -372.160038) (xy 160.326627 -372.167186)
			(xy 160.32011 -372.184374) (xy 160.31972 -372.193566) (xy 160.31972 -372.351554) (xy 160.319297 -372.361728)
			(xy 160.31152 -372.38053) (xy 160.297133 -372.394918) (xy 160.278332 -372.402697) (xy 160.268158 -372.403116)
			(xy 159.551878 -372.403116) (xy 159.541699 -372.402753) (xy 159.522895 -372.394952) (xy 159.50851 -372.380547)
			(xy 159.500734 -372.361733) (xy 159.500316 -372.351554) (xy 159.500316 -372.193566) (xy 159.499919 -372.184378)
			(xy 159.493396 -372.167193) (xy 159.487616 -372.160038) (xy 159.465843 -372.134374) (xy 159.427895 -372.078789)
			(xy 159.396862 -372.019067) (xy 159.37319 -371.956064) (xy 159.357216 -371.890683) (xy 159.349172 -371.823862)
			(xy 159.34917 -371.756559) (xy 159.357213 -371.689738) (xy 159.373184 -371.624356) (xy 159.396854 -371.561353)
			(xy 159.427884 -371.501629) (xy 159.46583 -371.446042) (xy 159.487616 -371.42039) (xy 159.493401 -371.413237)
			(xy 159.499922 -371.396052) (xy 159.500316 -371.386862) (xy 159.500316 -370.89334) (xy 159.499883 -370.884155)
			(xy 159.493385 -370.866971) (xy 159.487616 -370.859812) (xy 159.465817 -370.834169) (xy 159.42787 -370.778581)
			(xy 159.396839 -370.718856) (xy 159.373168 -370.65585) (xy 159.357196 -370.590467) (xy 159.349153 -370.523644)
			(xy 129.670828 -370.523644) (xy 129.662785 -370.590464) (xy 129.646814 -370.655846) (xy 129.623143 -370.71885)
			(xy 129.592113 -370.778573) (xy 129.554166 -370.83416) (xy 129.53238 -370.859812) (xy 129.526594 -370.866964)
			(xy 129.520073 -370.884149) (xy 129.51968 -370.89334) (xy 129.51968 -371.386862) (xy 129.520113 -371.396047)
			(xy 129.526611 -371.413231) (xy 129.53238 -371.42039) (xy 129.554181 -371.446031) (xy 129.592128 -371.50162)
			(xy 129.62316 -371.561345) (xy 129.646596 -371.623725) (xy 130.749241 -371.623725) (xy 130.749245 -371.556418)
			(xy 130.757292 -371.489593) (xy 130.773269 -371.424208) (xy 130.796945 -371.361202) (xy 130.827982 -371.301478)
			(xy 130.865934 -371.24589) (xy 130.887724 -371.220238) (xy 130.893532 -371.213101) (xy 130.900039 -371.195904)
			(xy 130.900424 -371.18671) (xy 130.900424 -371.028722) (xy 130.900882 -371.018554) (xy 130.908657 -370.999762)
			(xy 130.923032 -370.985377) (xy 130.941818 -370.977589) (xy 130.951986 -370.97716) (xy 131.668266 -370.97716)
			(xy 131.678438 -370.977592) (xy 131.697236 -370.98537) (xy 131.711623 -370.999754) (xy 131.719405 -371.01855)
			(xy 131.719828 -371.028722) (xy 131.719828 -371.18671) (xy 131.720227 -371.195898) (xy 131.726748 -371.213083)
			(xy 131.732528 -371.220238) (xy 131.754279 -371.24592) (xy 131.792231 -371.301502) (xy 131.823268 -371.361221)
			(xy 131.846945 -371.424221) (xy 131.862921 -371.4896) (xy 131.870969 -371.55642) (xy 131.870972 -371.623723)
			(xy 131.862931 -371.690543) (xy 131.846961 -371.755924) (xy 131.823291 -371.818927) (xy 131.792261 -371.878649)
			(xy 131.754314 -371.934234) (xy 131.732528 -371.959886) (xy 131.726704 -371.967011) (xy 131.720208 -371.984217)
			(xy 131.719828 -371.993414) (xy 131.719828 -372.486682) (xy 131.72024 -372.495869) (xy 131.726752 -372.513054)
			(xy 131.732528 -372.52021) (xy 131.75435 -372.545834) (xy 131.7923 -372.601424) (xy 131.823334 -372.661151)
			(xy 131.847006 -372.724159) (xy 131.862978 -372.789545) (xy 131.87102 -372.856371) (xy 131.871017 -372.92368)
			(xy 131.862969 -372.990505) (xy 131.846991 -373.05589) (xy 131.823313 -373.118896) (xy 131.792274 -373.17862)
			(xy 131.754319 -373.234206) (xy 131.732528 -373.259858) (xy 131.726716 -373.266992) (xy 131.720212 -373.284191)
			(xy 131.719828 -373.293386) (xy 131.719828 -373.451374) (xy 131.719414 -373.461548) (xy 131.711631 -373.480349)
			(xy 131.697242 -373.494736) (xy 131.67844 -373.502515) (xy 131.668266 -373.502936) (xy 130.951986 -373.502936)
			(xy 130.94181 -373.502547) (xy 130.92301 -373.494752) (xy 130.908625 -373.480356) (xy 130.900845 -373.46155)
			(xy 130.900424 -373.451374) (xy 130.900424 -373.293386) (xy 130.900015 -373.284199) (xy 130.8935 -373.267015)
			(xy 130.887724 -373.259858) (xy 130.86597 -373.234178) (xy 130.828022 -373.178595) (xy 130.796988 -373.118875)
			(xy 130.773314 -373.055874) (xy 130.757339 -372.990496) (xy 130.749292 -372.923677) (xy 130.749289 -372.856375)
			(xy 130.75733 -372.789555) (xy 130.773299 -372.724174) (xy 130.796967 -372.661171) (xy 130.827995 -372.601449)
			(xy 130.865939 -372.545863) (xy 130.887724 -372.52021) (xy 130.893544 -372.513082) (xy 130.900044 -372.495878)
			(xy 130.900424 -372.486682) (xy 130.900424 -371.993414) (xy 130.900002 -371.984228) (xy 130.893496 -371.967044)
			(xy 130.887724 -371.959886) (xy 130.865899 -371.934264) (xy 130.827953 -371.878673) (xy 130.796922 -371.818945)
			(xy 130.773252 -371.755937) (xy 130.757282 -371.690551) (xy 130.749241 -371.623725) (xy 129.646596 -371.623725)
			(xy 129.646831 -371.624351) (xy 129.662802 -371.689734) (xy 129.670845 -371.756558) (xy 129.670844 -371.823863)
			(xy 129.662799 -371.890687) (xy 129.646825 -371.956069) (xy 129.623151 -372.019074) (xy 129.592117 -372.078799)
			(xy 129.554168 -372.134386) (xy 129.53238 -372.160038) (xy 129.526582 -372.167182) (xy 129.520069 -372.184374)
			(xy 129.51968 -372.193566) (xy 129.51968 -372.351554) (xy 129.519199 -372.36172) (xy 129.511432 -372.380511)
			(xy 129.497064 -372.394896) (xy 129.478284 -372.402686) (xy 129.468118 -372.403116) (xy 128.751838 -372.403116)
			(xy 128.741663 -372.402704) (xy 128.722861 -372.394923) (xy 128.708473 -372.380533) (xy 128.700695 -372.361729)
			(xy 128.700276 -372.351554) (xy 128.700276 -372.193566) (xy 128.699887 -372.184376) (xy 128.693359 -372.167192)
			(xy 128.687576 -372.160038) (xy 128.665801 -372.134375) (xy 128.627849 -372.078791) (xy 128.596813 -372.019069)
			(xy 128.573138 -371.956066) (xy 128.557163 -371.890685) (xy 128.549117 -371.823863) (xy 128.549116 -371.756558)
			(xy 128.557159 -371.689736) (xy 128.573132 -371.624354) (xy 128.596805 -371.56135) (xy 128.627838 -371.501627)
			(xy 128.665788 -371.446042) (xy 128.687576 -371.42039) (xy 128.693357 -371.413233) (xy 128.699882 -371.396052)
			(xy 128.700276 -371.386862) (xy 128.700276 -370.89334) (xy 128.699852 -370.884154) (xy 128.693349 -370.866969)
			(xy 128.687576 -370.859812) (xy 128.665775 -370.83417) (xy 128.627825 -370.778583) (xy 128.59679 -370.718858)
			(xy 128.573116 -370.655852) (xy 128.557143 -370.590469) (xy 128.549099 -370.523644) (xy 125.271037 -370.523644)
			(xy 125.262994 -370.590464) (xy 125.247024 -370.655845) (xy 125.223354 -370.718849) (xy 125.192323 -370.778573)
			(xy 125.154378 -370.834159) (xy 125.132592 -370.859812) (xy 125.126807 -370.866965) (xy 125.120286 -370.88415)
			(xy 125.119892 -370.89334) (xy 125.119892 -371.386862) (xy 125.120322 -371.396047) (xy 125.126822 -371.413231)
			(xy 125.132592 -371.42039) (xy 125.154393 -371.446031) (xy 125.192339 -371.50162) (xy 125.22337 -371.561345)
			(xy 125.246828 -371.623785) (xy 126.348921 -371.623785) (xy 126.348925 -371.556358) (xy 126.357005 -371.489416)
			(xy 126.373046 -371.423925) (xy 126.396816 -371.360826) (xy 126.427973 -371.301029) (xy 126.466069 -371.245395)
			(xy 126.487936 -371.21973) (xy 126.493749 -371.212597) (xy 126.500253 -371.195397) (xy 126.500636 -371.186202)
			(xy 126.500636 -371.028722) (xy 126.501144 -371.018597) (xy 126.508864 -370.999877) (xy 126.523144 -370.98552)
			(xy 126.541822 -370.9777) (xy 126.551944 -370.97716) (xy 127.268224 -370.97716) (xy 127.278375 -370.977601)
			(xy 127.29712 -370.985397) (xy 127.311441 -370.999787) (xy 127.319147 -371.018569) (xy 127.319532 -371.028722)
			(xy 127.319532 -371.186202) (xy 127.319956 -371.195387) (xy 127.326462 -371.212571) (xy 127.332232 -371.21973)
			(xy 127.354058 -371.245427) (xy 127.392145 -371.301057) (xy 127.423296 -371.36085) (xy 127.447061 -371.423942)
			(xy 127.463098 -371.489427) (xy 127.471176 -371.556361) (xy 127.47118 -371.623781) (xy 127.463108 -371.690717)
			(xy 127.447078 -371.756203) (xy 127.423319 -371.819298) (xy 127.392175 -371.879094) (xy 127.354093 -371.934728)
			(xy 127.332232 -371.960394) (xy 127.326447 -371.967547) (xy 127.319927 -371.984732) (xy 127.319532 -371.993922)
			(xy 127.319532 -372.486174) (xy 127.31997 -372.495358) (xy 127.326466 -372.512542) (xy 127.332232 -372.519702)
			(xy 127.354128 -372.54534) (xy 127.392214 -372.600979) (xy 127.423361 -372.66078) (xy 127.447122 -372.72388)
			(xy 127.463154 -372.789372) (xy 127.471227 -372.856313) (xy 127.471224 -372.923738) (xy 127.463145 -372.990678)
			(xy 127.447107 -373.056169) (xy 127.42334 -373.119267) (xy 127.392188 -373.179064) (xy 127.354097 -373.2347)
			(xy 127.332232 -373.260366) (xy 127.326417 -373.267498) (xy 127.319915 -373.284699) (xy 127.319532 -373.293894)
			(xy 127.319532 -373.451374) (xy 127.319051 -373.461503) (xy 127.311327 -373.480228) (xy 127.297038 -373.494587)
			(xy 127.27835 -373.502402) (xy 127.268224 -373.502936) (xy 126.551944 -373.502936) (xy 126.541797 -373.502443)
			(xy 126.523053 -373.494669) (xy 126.508729 -373.480294) (xy 126.501021 -373.461522) (xy 126.500636 -373.451374)
			(xy 126.500636 -373.293894) (xy 126.500221 -373.284708) (xy 126.49371 -373.267524) (xy 126.487936 -373.260366)
			(xy 126.466104 -373.234674) (xy 126.428012 -373.179044) (xy 126.396858 -373.119252) (xy 126.37309 -373.056158)
			(xy 126.357051 -372.990672) (xy 126.348972 -372.923736) (xy 126.348969 -372.856315) (xy 126.357042 -372.789378)
			(xy 126.373075 -372.72389) (xy 126.396837 -372.660795) (xy 126.427986 -372.601) (xy 126.466073 -372.545367)
			(xy 126.487936 -372.519702) (xy 126.493719 -372.512547) (xy 126.500241 -372.495364) (xy 126.500636 -372.486174)
			(xy 126.500636 -371.993922) (xy 126.500207 -371.984737) (xy 126.493706 -371.967553) (xy 126.487936 -371.960394)
			(xy 126.466033 -371.93476) (xy 126.427943 -371.879122) (xy 126.396792 -371.819322) (xy 126.373029 -371.756221)
			(xy 126.356995 -371.690727) (xy 126.348921 -371.623785) (xy 125.246828 -371.623785) (xy 125.247041 -371.624351)
			(xy 125.263012 -371.689734) (xy 125.271054 -371.756558) (xy 125.271053 -371.823863) (xy 125.263008 -371.890686)
			(xy 125.247034 -371.956069) (xy 125.223361 -372.019074) (xy 125.192328 -372.078798) (xy 125.15438 -372.134385)
			(xy 125.132592 -372.160038) (xy 125.126796 -372.167183) (xy 125.120281 -372.184374) (xy 125.119892 -372.193566)
			(xy 125.119892 -372.351554) (xy 125.119399 -372.361719) (xy 125.111635 -372.380507) (xy 125.097271 -372.394892)
			(xy 125.078494 -372.402684) (xy 125.06833 -372.403116) (xy 124.35205 -372.403116) (xy 124.341876 -372.402694)
			(xy 124.323073 -372.394917) (xy 124.308685 -372.38053) (xy 124.300907 -372.361728) (xy 124.300488 -372.351554)
			(xy 124.300488 -372.193566) (xy 124.300097 -372.184377) (xy 124.29357 -372.167192) (xy 124.287788 -372.160038)
			(xy 124.266013 -372.134375) (xy 124.22806 -372.078791) (xy 124.197024 -372.01907) (xy 124.173348 -371.956067)
			(xy 124.157372 -371.890685) (xy 124.149326 -371.823863) (xy 124.149325 -371.756558) (xy 124.157369 -371.689736)
			(xy 124.173342 -371.624354) (xy 124.197015 -371.561349) (xy 124.228049 -371.501627) (xy 124.266 -371.446041)
			(xy 124.287788 -371.42039) (xy 124.29357 -371.413234) (xy 124.300094 -371.396052) (xy 124.300488 -371.386862)
			(xy 124.300488 -370.89334) (xy 124.300061 -370.884154) (xy 124.29356 -370.86697) (xy 124.287788 -370.859812)
			(xy 124.265987 -370.83417) (xy 124.228035 -370.778583) (xy 124.197 -370.718859) (xy 124.173326 -370.655853)
			(xy 124.157352 -370.590469) (xy 124.149308 -370.523644) (xy 120.871269 -370.523644) (xy 120.871269 -370.523702)
			(xy 120.863194 -370.59064) (xy 120.847159 -370.656128) (xy 120.823396 -370.719225) (xy 120.792247 -370.779021)
			(xy 120.754159 -370.834655) (xy 120.732296 -370.86032) (xy 120.726508 -370.867471) (xy 120.719988 -370.884657)
			(xy 120.719596 -370.893848) (xy 120.719596 -371.386354) (xy 120.720029 -371.395539) (xy 120.726527 -371.412723)
			(xy 120.732296 -371.419882) (xy 120.754174 -371.445536) (xy 120.792262 -371.501172) (xy 120.823413 -371.56097)
			(xy 120.847047 -371.623725) (xy 121.949153 -371.623725) (xy 121.949157 -371.556417) (xy 121.957205 -371.489592)
			(xy 121.973182 -371.424208) (xy 121.996859 -371.361202) (xy 122.027896 -371.301477) (xy 122.06585 -371.24589)
			(xy 122.08764 -371.220238) (xy 122.09345 -371.213103) (xy 122.099956 -371.195904) (xy 122.10034 -371.18671)
			(xy 122.10034 -371.028722) (xy 122.100782 -371.018552) (xy 122.10856 -370.999757) (xy 122.12294 -370.985371)
			(xy 122.141732 -370.977586) (xy 122.151902 -370.97716) (xy 122.868182 -370.97716) (xy 122.878355 -370.977579)
			(xy 122.897154 -370.985362) (xy 122.91154 -370.99975) (xy 122.919322 -371.018549) (xy 122.919744 -371.028722)
			(xy 122.919744 -371.18671) (xy 122.920162 -371.195896) (xy 122.926672 -371.21308) (xy 122.932444 -371.220238)
			(xy 122.954195 -371.245921) (xy 122.992146 -371.301502) (xy 123.023182 -371.361222) (xy 123.046857 -371.424222)
			(xy 123.062833 -371.489601) (xy 123.070881 -371.55642) (xy 123.070884 -371.623723) (xy 123.062844 -371.690543)
			(xy 123.046874 -371.755923) (xy 123.023205 -371.818926) (xy 122.992175 -371.878648) (xy 122.95423 -371.934234)
			(xy 122.932444 -371.959886) (xy 122.926622 -371.967013) (xy 122.920124 -371.984218) (xy 122.919744 -371.993414)
			(xy 122.919744 -372.486682) (xy 122.920175 -372.495867) (xy 122.926676 -372.513051) (xy 122.932444 -372.52021)
			(xy 122.954266 -372.545834) (xy 122.992215 -372.601424) (xy 123.023248 -372.661152) (xy 123.046919 -372.72416)
			(xy 123.06289 -372.789546) (xy 123.070932 -372.856372) (xy 123.070929 -372.92368) (xy 123.062881 -372.990505)
			(xy 123.046904 -373.055889) (xy 123.023227 -373.118895) (xy 122.992188 -373.17862) (xy 122.954234 -373.234206)
			(xy 122.932444 -373.259858) (xy 122.926633 -373.266993) (xy 122.920129 -373.284192) (xy 122.919744 -373.293386)
			(xy 122.919744 -373.451374) (xy 122.919314 -373.461546) (xy 122.911534 -373.480344) (xy 122.89715 -373.49473)
			(xy 122.878354 -373.502513) (xy 122.868182 -373.502936) (xy 122.151902 -373.502936) (xy 122.141727 -373.502534)
			(xy 122.122928 -373.494745) (xy 122.108542 -373.480352) (xy 122.100761 -373.461549) (xy 122.10034 -373.451374)
			(xy 122.10034 -373.293386) (xy 122.099928 -373.284199) (xy 122.093415 -373.267015) (xy 122.08764 -373.259858)
			(xy 122.065886 -373.234178) (xy 122.027936 -373.178596) (xy 121.996901 -373.118876) (xy 121.973226 -373.055875)
			(xy 121.957251 -372.990496) (xy 121.949204 -372.923677) (xy 121.949201 -372.856374) (xy 121.957242 -372.789554)
			(xy 121.973211 -372.724174) (xy 121.99688 -372.661171) (xy 122.02791 -372.601448) (xy 122.065855 -372.545862)
			(xy 122.08764 -372.52021) (xy 122.093462 -372.513083) (xy 122.099961 -372.495878) (xy 122.10034 -372.486682)
			(xy 122.10034 -371.993414) (xy 122.099914 -371.984229) (xy 122.093411 -371.967045) (xy 122.08764 -371.959886)
			(xy 122.065815 -371.934265) (xy 122.027867 -371.878674) (xy 121.996835 -371.818946) (xy 121.973165 -371.755937)
			(xy 121.957194 -371.690551) (xy 121.949153 -371.623725) (xy 120.847047 -371.623725) (xy 120.847176 -371.624068)
			(xy 120.863211 -371.689558) (xy 120.871286 -371.756498) (xy 120.871284 -371.823923) (xy 120.863207 -371.890862)
			(xy 120.84717 -371.956352) (xy 120.823404 -372.01945) (xy 120.792252 -372.079246) (xy 120.754161 -372.134881)
			(xy 120.732296 -372.160546) (xy 120.726497 -372.167689) (xy 120.719984 -372.184881) (xy 120.719596 -372.194074)
			(xy 120.719596 -372.351554) (xy 120.719037 -372.361673) (xy 120.711331 -372.380387) (xy 120.697067 -372.394743)
			(xy 120.678404 -372.40257) (xy 120.668288 -372.403116) (xy 119.952008 -372.403116) (xy 119.941856 -372.402672)
			(xy 119.923107 -372.394882) (xy 119.908784 -372.380493) (xy 119.901081 -372.361707) (xy 119.9007 -372.351554)
			(xy 119.9007 -372.194074) (xy 119.900303 -372.184885) (xy 119.89378 -372.167701) (xy 119.888 -372.160546)
			(xy 119.86615 -372.134869) (xy 119.828061 -372.079237) (xy 119.796909 -372.019442) (xy 119.773144 -371.956346)
			(xy 119.757108 -371.890859) (xy 119.749031 -371.823922) (xy 119.74903 -371.756499) (xy 119.757104 -371.689562)
			(xy 119.773138 -371.624074) (xy 119.796901 -371.560977) (xy 119.82805 -371.501182) (xy 119.866137 -371.445547)
			(xy 119.888 -371.419882) (xy 119.893787 -371.41273) (xy 119.900307 -371.395545) (xy 119.9007 -371.386354)
			(xy 119.9007 -370.893848) (xy 119.900267 -370.884663) (xy 119.893769 -370.867479) (xy 119.888 -370.86032)
			(xy 119.866124 -370.834664) (xy 119.828036 -370.779029) (xy 119.796886 -370.719231) (xy 119.773122 -370.656133)
			(xy 119.757088 -370.590643) (xy 119.749013 -370.523703) (xy 116.470966 -370.523703) (xy 116.462929 -370.590466)
			(xy 116.446956 -370.655848) (xy 116.423282 -370.718853) (xy 116.392247 -370.778575) (xy 116.354297 -370.834161)
			(xy 116.332508 -370.859812) (xy 116.326725 -370.866967) (xy 116.320202 -370.88415) (xy 116.319808 -370.89334)
			(xy 116.319808 -371.386862) (xy 116.320235 -371.396047) (xy 116.326737 -371.413232) (xy 116.332508 -371.42039)
			(xy 116.354311 -371.44603) (xy 116.392263 -371.501617) (xy 116.423299 -371.561342) (xy 116.446761 -371.623785)
			(xy 117.548834 -371.623785) (xy 117.548837 -371.556358) (xy 117.556917 -371.489416) (xy 117.572959 -371.423924)
			(xy 117.596729 -371.360825) (xy 117.627887 -371.301028) (xy 117.665984 -371.245394) (xy 117.687852 -371.21973)
			(xy 117.693667 -371.212598) (xy 117.700169 -371.195397) (xy 117.700552 -371.186202) (xy 117.700552 -371.028722)
			(xy 117.701045 -371.018595) (xy 117.708768 -370.999872) (xy 117.723052 -370.985515) (xy 117.741736 -370.977697)
			(xy 117.75186 -370.97716) (xy 118.46814 -370.97716) (xy 118.478292 -370.977588) (xy 118.497037 -370.985389)
			(xy 118.511358 -370.999783) (xy 118.519063 -371.018568) (xy 118.519448 -371.028722) (xy 118.519448 -371.186202)
			(xy 118.519869 -371.195388) (xy 118.526376 -371.212572) (xy 118.532148 -371.21973) (xy 118.553976 -371.245425)
			(xy 118.59207 -371.301054) (xy 118.623225 -371.360846) (xy 118.646994 -371.423939) (xy 118.663033 -371.489425)
			(xy 118.671113 -371.556361) (xy 118.671116 -371.623782) (xy 118.663044 -371.690719) (xy 118.647011 -371.756207)
			(xy 118.623248 -371.819302) (xy 118.592099 -371.879097) (xy 118.554012 -371.93473) (xy 118.532148 -371.960394)
			(xy 118.526365 -371.967549) (xy 118.519844 -371.984732) (xy 118.519448 -371.993922) (xy 118.519448 -372.486174)
			(xy 118.519882 -372.495358) (xy 118.52638 -372.512542) (xy 118.532148 -372.519702) (xy 118.554047 -372.545339)
			(xy 118.592138 -372.600976) (xy 118.62329 -372.660776) (xy 118.647055 -372.723877) (xy 118.66309 -372.78937)
			(xy 118.671164 -372.856312) (xy 118.671161 -372.923739) (xy 118.663081 -372.990681) (xy 118.64704 -373.056172)
			(xy 118.62327 -373.119271) (xy 118.592112 -373.179068) (xy 118.554016 -373.234702) (xy 118.532148 -373.260366)
			(xy 118.526334 -373.267499) (xy 118.519831 -373.284699) (xy 118.519448 -373.293894) (xy 118.519448 -373.451374)
			(xy 118.518952 -373.461501) (xy 118.51123 -373.480223) (xy 118.496947 -373.494581) (xy 118.478264 -373.502399)
			(xy 118.46814 -373.502936) (xy 117.75186 -373.502936) (xy 117.741708 -373.502512) (xy 117.722961 -373.49471)
			(xy 117.708641 -373.480315) (xy 117.700936 -373.461528) (xy 117.700552 -373.451374) (xy 117.700552 -373.293894)
			(xy 117.700133 -373.284708) (xy 117.693624 -373.267524) (xy 117.687852 -373.260366) (xy 117.66602 -373.234674)
			(xy 117.627926 -373.179045) (xy 117.596771 -373.119253) (xy 117.573003 -373.056159) (xy 117.556964 -372.990673)
			(xy 117.548884 -372.923737) (xy 117.548881 -372.856315) (xy 117.556954 -372.789378) (xy 117.572988 -372.72389)
			(xy 117.596751 -372.660794) (xy 117.6279 -372.600999) (xy 117.665988 -372.545366) (xy 117.687852 -372.519702)
			(xy 117.693637 -372.512549) (xy 117.700157 -372.495364) (xy 117.700552 -372.486174) (xy 117.700552 -371.993922)
			(xy 117.70012 -371.984737) (xy 117.69362 -371.967553) (xy 117.687852 -371.960394) (xy 117.665949 -371.93476)
			(xy 117.627858 -371.879123) (xy 117.596706 -371.819323) (xy 117.572942 -371.756221) (xy 117.556907 -371.690728)
			(xy 117.548834 -371.623785) (xy 116.446761 -371.623785) (xy 116.446973 -371.624348) (xy 116.462946 -371.689732)
			(xy 116.47099 -371.756557) (xy 116.470989 -371.823864) (xy 116.462943 -371.890689) (xy 116.446967 -371.956072)
			(xy 116.42329 -372.019077) (xy 116.392252 -372.078801) (xy 116.354298 -372.134387) (xy 116.332508 -372.160038)
			(xy 116.326714 -372.167185) (xy 116.320197 -372.184374) (xy 116.319808 -372.193566) (xy 116.319808 -372.351554)
			(xy 116.31923 -372.361703) (xy 116.311479 -372.380462) (xy 116.29714 -372.394828) (xy 116.278394 -372.402612)
			(xy 116.268246 -372.403116) (xy 115.551966 -372.403116) (xy 115.541786 -372.402763) (xy 115.522982 -372.394958)
			(xy 115.508597 -372.380551) (xy 115.500821 -372.361734) (xy 115.500404 -372.351554) (xy 115.500404 -372.193566)
			(xy 115.500009 -372.184377) (xy 115.493485 -372.167193) (xy 115.487704 -372.160038) (xy 115.465931 -372.134374)
			(xy 115.427984 -372.078788) (xy 115.396952 -372.019066) (xy 115.37328 -371.956063) (xy 115.357307 -371.890683)
			(xy 115.349263 -371.823862) (xy 115.349261 -371.756559) (xy 115.357303 -371.689738) (xy 115.373274 -371.624357)
			(xy 115.396944 -371.561353) (xy 115.427973 -371.50163) (xy 115.465918 -371.446043) (xy 115.487704 -371.42039)
			(xy 115.493488 -371.413236) (xy 115.50001 -371.396052) (xy 115.500404 -371.386862) (xy 115.500404 -370.89334)
			(xy 115.499974 -370.884155) (xy 115.493474 -370.86697) (xy 115.487704 -370.859812) (xy 115.465906 -370.834169)
			(xy 115.427959 -370.77858) (xy 115.396929 -370.718855) (xy 115.373258 -370.65585) (xy 115.357287 -370.590467)
			(xy 115.349244 -370.523644) (xy 85.670941 -370.523644) (xy 85.670941 -370.523703) (xy 85.662866 -370.590641)
			(xy 85.646831 -370.65613) (xy 85.623066 -370.719226) (xy 85.591915 -370.779022) (xy 85.553825 -370.834655)
			(xy 85.53196 -370.86032) (xy 85.526167 -370.867468) (xy 85.519651 -370.884656) (xy 85.51926 -370.893848)
			(xy 85.51926 -371.386354) (xy 85.519701 -371.395538) (xy 85.526194 -371.412722) (xy 85.53196 -371.419882)
			(xy 85.553839 -371.445535) (xy 85.59193 -371.501171) (xy 85.623082 -371.560968) (xy 85.646742 -371.623785)
			(xy 86.748803 -371.623785) (xy 86.748807 -371.556358) (xy 86.756887 -371.489417) (xy 86.772927 -371.423926)
			(xy 86.796696 -371.360827) (xy 86.827851 -371.30103) (xy 86.865945 -371.245395) (xy 86.887812 -371.21973)
			(xy 86.893622 -371.212594) (xy 86.900128 -371.195397) (xy 86.900512 -371.186202) (xy 86.900512 -371.028722)
			(xy 86.901044 -371.0186) (xy 86.908759 -370.999885) (xy 86.923031 -370.985529) (xy 86.941701 -370.977704)
			(xy 86.95182 -370.97716) (xy 87.6681 -370.97716) (xy 87.678249 -370.977621) (xy 87.696994 -370.985409)
			(xy 87.711316 -370.999793) (xy 87.719023 -371.018571) (xy 87.719408 -371.028722) (xy 87.719408 -371.186202)
			(xy 87.719815 -371.195389) (xy 87.726331 -371.212574) (xy 87.732108 -371.21973) (xy 87.753934 -371.245426)
			(xy 87.792024 -371.301056) (xy 87.823176 -371.360848) (xy 87.846942 -371.423941) (xy 87.862979 -371.489426)
			(xy 87.871058 -371.556361) (xy 87.871062 -371.623782) (xy 87.86299 -371.690717) (xy 87.846958 -371.756204)
			(xy 87.823199 -371.819299) (xy 87.792053 -371.879095) (xy 87.753969 -371.934729) (xy 87.732108 -371.960394)
			(xy 87.726332 -371.967554) (xy 87.719805 -371.984733) (xy 87.719408 -371.993922) (xy 87.719408 -372.486174)
			(xy 87.719829 -372.49536) (xy 87.726335 -372.512545) (xy 87.732108 -372.519702) (xy 87.754005 -372.54534)
			(xy 87.792092 -372.600978) (xy 87.823241 -372.660779) (xy 87.847003 -372.723879) (xy 87.863036 -372.789371)
			(xy 87.871109 -372.856312) (xy 87.871106 -372.923739) (xy 87.863027 -372.990679) (xy 87.846988 -373.05617)
			(xy 87.82322 -373.119268) (xy 87.792066 -373.179065) (xy 87.753974 -373.234701) (xy 87.732108 -373.260366)
			(xy 87.726302 -373.267504) (xy 87.719793 -373.2847) (xy 87.719408 -373.293894) (xy 87.719408 -373.451374)
			(xy 87.718854 -373.461493) (xy 87.711143 -373.480205) (xy 87.696878 -373.49456) (xy 87.678216 -373.502389)
			(xy 87.6681 -373.502936) (xy 86.95182 -373.502936) (xy 86.941672 -373.502463) (xy 86.922927 -373.494681)
			(xy 86.908604 -373.4803) (xy 86.900897 -373.461524) (xy 86.900512 -373.451374) (xy 86.900512 -373.293894)
			(xy 86.900102 -373.284707) (xy 86.893588 -373.267523) (xy 86.887812 -373.260366) (xy 86.865981 -373.234673)
			(xy 86.82789 -373.179043) (xy 86.796738 -373.119251) (xy 86.772971 -373.056157) (xy 86.756933 -372.990672)
			(xy 86.748854 -372.923736) (xy 86.748851 -372.856315) (xy 86.756924 -372.789379) (xy 86.772956 -372.723891)
			(xy 86.796717 -372.660796) (xy 86.827864 -372.601001) (xy 86.86595 -372.545367) (xy 86.887812 -372.519702)
			(xy 86.893592 -372.512545) (xy 86.900116 -372.495363) (xy 86.900512 -372.486174) (xy 86.900512 -371.993922)
			(xy 86.900088 -371.984736) (xy 86.893584 -371.967552) (xy 86.887812 -371.960394) (xy 86.86591 -371.93476)
			(xy 86.827822 -371.879121) (xy 86.796672 -371.819321) (xy 86.77291 -371.75622) (xy 86.756876 -371.690727)
			(xy 86.748803 -371.623785) (xy 85.646742 -371.623785) (xy 85.646848 -371.624067) (xy 85.662883 -371.689557)
			(xy 85.670959 -371.756498) (xy 85.670957 -371.823923) (xy 85.662879 -371.890863) (xy 85.646841 -371.956354)
			(xy 85.623074 -372.019451) (xy 85.591919 -372.079248) (xy 85.553826 -372.134881) (xy 85.53196 -372.160546)
			(xy 85.526156 -372.167686) (xy 85.519647 -372.184881) (xy 85.51926 -372.194074) (xy 85.51926 -372.351554)
			(xy 85.518736 -372.361678) (xy 85.511023 -372.380398) (xy 85.496748 -372.394756) (xy 85.478073 -372.402576)
			(xy 85.467952 -372.403116) (xy 84.751672 -372.403116) (xy 84.741518 -372.402702) (xy 84.722768 -372.3949)
			(xy 84.708446 -372.380501) (xy 84.700745 -372.36171) (xy 84.700364 -372.351554) (xy 84.700364 -372.194074)
			(xy 84.699952 -372.184887) (xy 84.693438 -372.167704) (xy 84.687664 -372.160546) (xy 84.665815 -372.134869)
			(xy 84.627728 -372.079235) (xy 84.596579 -372.01944) (xy 84.572816 -371.956345) (xy 84.55678 -371.890858)
			(xy 84.548704 -371.823921) (xy 84.548703 -371.7565) (xy 84.556776 -371.689563) (xy 84.572809 -371.624075)
			(xy 84.59657 -371.560979) (xy 84.627717 -371.501183) (xy 84.665802 -371.445548) (xy 84.687664 -371.419882)
			(xy 84.693459 -371.412736) (xy 84.699973 -371.395546) (xy 84.700364 -371.386354) (xy 84.700364 -370.893848)
			(xy 84.699917 -370.884665) (xy 84.693427 -370.867481) (xy 84.687664 -370.86032) (xy 84.66579 -370.834664)
			(xy 84.627704 -370.779027) (xy 84.596555 -370.719229) (xy 84.572793 -370.656131) (xy 84.55676 -370.590642)
			(xy 84.548686 -370.523703) (xy 81.27115 -370.523703) (xy 81.263075 -370.590641) (xy 81.24704 -370.656129)
			(xy 81.223276 -370.719226) (xy 81.192125 -370.779021) (xy 81.154036 -370.834655) (xy 81.132172 -370.86032)
			(xy 81.126381 -370.867469) (xy 81.119864 -370.884657) (xy 81.119472 -370.893848) (xy 81.119472 -371.386354)
			(xy 81.119911 -371.395538) (xy 81.126405 -371.412722) (xy 81.132172 -371.419882) (xy 81.154051 -371.445535)
			(xy 81.192141 -371.501171) (xy 81.223293 -371.560969) (xy 81.246928 -371.623725) (xy 82.349035 -371.623725)
			(xy 82.349038 -371.556418) (xy 82.357086 -371.489593) (xy 82.373062 -371.424209) (xy 82.396738 -371.361203)
			(xy 82.427775 -371.301478) (xy 82.465727 -371.24589) (xy 82.487516 -371.220238) (xy 82.493323 -371.2131)
			(xy 82.499831 -371.195904) (xy 82.500216 -371.18671) (xy 82.500216 -371.028722) (xy 82.500751 -371.018568)
			(xy 82.508514 -370.999804) (xy 82.522867 -370.985439) (xy 82.541625 -370.977659) (xy 82.551778 -370.97716)
			(xy 83.268058 -370.97716) (xy 83.27823 -370.977599) (xy 83.297028 -370.985374) (xy 83.311415 -370.999756)
			(xy 83.319197 -371.018551) (xy 83.31962 -371.028722) (xy 83.31962 -371.18671) (xy 83.320021 -371.195898)
			(xy 83.326541 -371.213083) (xy 83.33232 -371.220238) (xy 83.354072 -371.24592) (xy 83.392024 -371.301501)
			(xy 83.423061 -371.361221) (xy 83.446738 -371.424221) (xy 83.462715 -371.4896) (xy 83.470763 -371.55642)
			(xy 83.470766 -371.623723) (xy 83.462725 -371.690544) (xy 83.446755 -371.755924) (xy 83.423085 -371.818927)
			(xy 83.392054 -371.878649) (xy 83.354107 -371.934234) (xy 83.33232 -371.959886) (xy 83.326507 -371.96702)
			(xy 83.320001 -371.984219) (xy 83.31962 -371.993414) (xy 83.31962 -372.486682) (xy 83.320034 -372.495869)
			(xy 83.326545 -372.513054) (xy 83.33232 -372.52021) (xy 83.354142 -372.545834) (xy 83.392093 -372.601424)
			(xy 83.423127 -372.661151) (xy 83.446799 -372.724159) (xy 83.462771 -372.789545) (xy 83.470813 -372.856371)
			(xy 83.47081 -372.92368) (xy 83.462762 -372.990505) (xy 83.446784 -373.05589) (xy 83.423106 -373.118896)
			(xy 83.392066 -373.17862) (xy 83.354111 -373.234206) (xy 83.33232 -373.259858) (xy 83.326519 -373.267)
			(xy 83.320006 -373.284193) (xy 83.31962 -373.293386) (xy 83.31962 -373.451374) (xy 83.319214 -373.461549)
			(xy 83.311429 -373.480351) (xy 83.297038 -373.494738) (xy 83.278233 -373.502517) (xy 83.268058 -373.502936)
			(xy 82.551778 -373.502936) (xy 82.541602 -373.502553) (xy 82.522802 -373.494756) (xy 82.508417 -373.480358)
			(xy 82.500637 -373.461551) (xy 82.500216 -373.451374) (xy 82.500216 -373.293386) (xy 82.499809 -373.284199)
			(xy 82.493293 -373.267014) (xy 82.487516 -373.259858) (xy 82.465763 -373.234178) (xy 82.427814 -373.178595)
			(xy 82.396781 -373.118875) (xy 82.373107 -373.055874) (xy 82.357133 -372.990496) (xy 82.349086 -372.923677)
			(xy 82.349083 -372.856375) (xy 82.357123 -372.789555) (xy 82.373092 -372.724175) (xy 82.39676 -372.661172)
			(xy 82.427788 -372.601449) (xy 82.465731 -372.545863) (xy 82.487516 -372.52021) (xy 82.493335 -372.513081)
			(xy 82.499836 -372.495878) (xy 82.500216 -372.486682) (xy 82.500216 -371.993414) (xy 82.499795 -371.984228)
			(xy 82.493288 -371.967044) (xy 82.487516 -371.959886) (xy 82.465692 -371.934264) (xy 82.427745 -371.878673)
			(xy 82.396715 -371.818945) (xy 82.373045 -371.755936) (xy 82.357076 -371.690551) (xy 82.349035 -371.623725)
			(xy 81.246928 -371.623725) (xy 81.247057 -371.624067) (xy 81.263092 -371.689558) (xy 81.271168 -371.756498)
			(xy 81.271166 -371.823923) (xy 81.263089 -371.890863) (xy 81.247051 -371.956353) (xy 81.223284 -372.019451)
			(xy 81.19213 -372.079247) (xy 81.154038 -372.134881) (xy 81.132172 -372.160546) (xy 81.12637 -372.167687)
			(xy 81.119859 -372.184881) (xy 81.119472 -372.194074) (xy 81.119472 -372.351554) (xy 81.118936 -372.361676)
			(xy 81.111226 -372.380394) (xy 81.096954 -372.394752) (xy 81.078283 -372.402574) (xy 81.068164 -372.403116)
			(xy 80.351884 -372.403116) (xy 80.341731 -372.402692) (xy 80.322981 -372.394894) (xy 80.308659 -372.380499)
			(xy 80.300957 -372.361709) (xy 80.300576 -372.351554) (xy 80.300576 -372.194074) (xy 80.300184 -372.184885)
			(xy 80.293658 -372.1677) (xy 80.287876 -372.160546) (xy 80.266027 -372.134869) (xy 80.227939 -372.079236)
			(xy 80.196789 -372.019441) (xy 80.173025 -371.956346) (xy 80.156989 -371.890858) (xy 80.148913 -371.823922)
			(xy 80.148912 -371.756499) (xy 80.156986 -371.689563) (xy 80.173019 -371.624075) (xy 80.196781 -371.560978)
			(xy 80.227928 -371.501182) (xy 80.266014 -371.445548) (xy 80.287876 -371.419882) (xy 80.29366 -371.412728)
			(xy 80.300183 -371.395544) (xy 80.300576 -371.386354) (xy 80.300576 -370.893848) (xy 80.300148 -370.884663)
			(xy 80.293647 -370.867478) (xy 80.287876 -370.86032) (xy 80.266001 -370.834664) (xy 80.227914 -370.779028)
			(xy 80.196765 -370.71923) (xy 80.173003 -370.656132) (xy 80.156969 -370.590642) (xy 80.148895 -370.523703)
			(xy 76.870824 -370.523703) (xy 76.862788 -370.590464) (xy 76.846817 -370.655845) (xy 76.823147 -370.718849)
			(xy 76.792116 -370.778573) (xy 76.75417 -370.83416) (xy 76.732384 -370.859812) (xy 76.726598 -370.866965)
			(xy 76.720078 -370.88415) (xy 76.719684 -370.89334) (xy 76.719684 -371.386862) (xy 76.720116 -371.396047)
			(xy 76.726615 -371.413231) (xy 76.732384 -371.42039) (xy 76.754185 -371.446031) (xy 76.792132 -371.50162)
			(xy 76.823163 -371.561345) (xy 76.846621 -371.623785) (xy 77.948715 -371.623785) (xy 77.948719 -371.556358)
			(xy 77.956799 -371.489417) (xy 77.972839 -371.423925) (xy 77.996609 -371.360826) (xy 78.027766 -371.301029)
			(xy 78.065861 -371.245395) (xy 78.087728 -371.21973) (xy 78.09354 -371.212596) (xy 78.100045 -371.195397)
			(xy 78.100428 -371.186202) (xy 78.100428 -371.028722) (xy 78.100944 -371.018598) (xy 78.108662 -370.99988)
			(xy 78.12294 -370.985523) (xy 78.141615 -370.977701) (xy 78.151736 -370.97716) (xy 78.868016 -370.97716)
			(xy 78.878166 -370.977607) (xy 78.896911 -370.985401) (xy 78.911233 -370.999789) (xy 78.918939 -371.01857)
			(xy 78.919324 -371.028722) (xy 78.919324 -371.186202) (xy 78.919728 -371.19539) (xy 78.926245 -371.212575)
			(xy 78.932024 -371.21973) (xy 78.95385 -371.245426) (xy 78.991938 -371.301057) (xy 79.023089 -371.360849)
			(xy 79.046854 -371.423942) (xy 79.062892 -371.489427) (xy 79.07097 -371.556361) (xy 79.070974 -371.623782)
			(xy 79.062902 -371.690717) (xy 79.046871 -371.756203) (xy 79.023112 -371.819299) (xy 78.991967 -371.879094)
			(xy 78.953885 -371.934728) (xy 78.932024 -371.960394) (xy 78.92625 -371.967556) (xy 78.919721 -371.984733)
			(xy 78.919324 -371.993922) (xy 78.919324 -372.486174) (xy 78.919741 -372.495361) (xy 78.926249 -372.512545)
			(xy 78.932024 -372.519702) (xy 78.953921 -372.54534) (xy 78.992007 -372.600979) (xy 79.023155 -372.660779)
			(xy 79.046916 -372.72388) (xy 79.062948 -372.789372) (xy 79.071021 -372.856313) (xy 79.071018 -372.923738)
			(xy 79.062939 -372.990679) (xy 79.046901 -373.056169) (xy 79.023134 -373.119267) (xy 78.99198 -373.179065)
			(xy 78.953889 -373.2347) (xy 78.932024 -373.260366) (xy 78.92622 -373.267506) (xy 78.919709 -373.2847)
			(xy 78.919324 -373.293894) (xy 78.919324 -373.451374) (xy 78.918851 -373.461504) (xy 78.911125 -373.480231)
			(xy 78.896834 -373.49459) (xy 78.878143 -373.502403) (xy 78.868016 -373.502936) (xy 78.151736 -373.502936)
			(xy 78.141589 -373.502449) (xy 78.122844 -373.494673) (xy 78.108521 -373.480296) (xy 78.100813 -373.461523)
			(xy 78.100428 -373.451374) (xy 78.100428 -373.293894) (xy 78.100015 -373.284707) (xy 78.093503 -373.267523)
			(xy 78.087728 -373.260366) (xy 78.065896 -373.234674) (xy 78.027805 -373.179044) (xy 77.996651 -373.119251)
			(xy 77.972884 -373.056158) (xy 77.956845 -372.990672) (xy 77.948766 -372.923736) (xy 77.948763 -372.856315)
			(xy 77.956836 -372.789378) (xy 77.972869 -372.723891) (xy 77.99663 -372.660795) (xy 78.027779 -372.601)
			(xy 78.065865 -372.545367) (xy 78.087728 -372.519702) (xy 78.09351 -372.512547) (xy 78.100033 -372.495364)
			(xy 78.100428 -372.486174) (xy 78.100428 -371.993922) (xy 78.100001 -371.984737) (xy 78.093498 -371.967553)
			(xy 78.087728 -371.960394) (xy 78.065826 -371.93476) (xy 78.027736 -371.879122) (xy 77.996586 -371.819321)
			(xy 77.972822 -371.75622) (xy 77.956789 -371.690727) (xy 77.948715 -371.623785) (xy 76.846621 -371.623785)
			(xy 76.846834 -371.624351) (xy 76.862805 -371.689734) (xy 76.870848 -371.756558) (xy 76.870847 -371.823863)
			(xy 76.862802 -371.890687) (xy 76.846828 -371.956069) (xy 76.823155 -372.019074) (xy 76.792121 -372.078798)
			(xy 76.754172 -372.134386) (xy 76.732384 -372.160038) (xy 76.726587 -372.167183) (xy 76.720073 -372.184374)
			(xy 76.719684 -372.193566) (xy 76.719684 -372.351554) (xy 76.719199 -372.36172) (xy 76.711433 -372.380509)
			(xy 76.697067 -372.394895) (xy 76.678287 -372.402686) (xy 76.668122 -372.403116) (xy 75.951842 -372.403116)
			(xy 75.941667 -372.402701) (xy 75.922865 -372.394921) (xy 75.908477 -372.380532) (xy 75.900699 -372.361729)
			(xy 75.90028 -372.351554) (xy 75.90028 -372.193566) (xy 75.899891 -372.184377) (xy 75.893363 -372.167192)
			(xy 75.88758 -372.160038) (xy 75.865805 -372.134375) (xy 75.827853 -372.078791) (xy 75.796817 -372.019069)
			(xy 75.773141 -371.956066) (xy 75.757166 -371.890685) (xy 75.74912 -371.823863) (xy 75.749119 -371.756558)
			(xy 75.757162 -371.689736) (xy 75.773135 -371.624354) (xy 75.796808 -371.56135) (xy 75.827842 -371.501627)
			(xy 75.865792 -371.446042) (xy 75.88758 -371.42039) (xy 75.893361 -371.413234) (xy 75.899886 -371.396052)
			(xy 75.90028 -371.386862) (xy 75.90028 -370.89334) (xy 75.899855 -370.884154) (xy 75.893352 -370.866969)
			(xy 75.88758 -370.859812) (xy 75.865779 -370.83417) (xy 75.827828 -370.778583) (xy 75.796793 -370.718859)
			(xy 75.773119 -370.655853) (xy 75.757146 -370.590469) (xy 75.749102 -370.523644) (xy 72.471063 -370.523644)
			(xy 72.471063 -370.523702) (xy 72.462988 -370.59064) (xy 72.446953 -370.656129) (xy 72.42319 -370.719225)
			(xy 72.39204 -370.779021) (xy 72.353952 -370.834655) (xy 72.332088 -370.86032) (xy 72.326299 -370.867471)
			(xy 72.31978 -370.884657) (xy 72.319388 -370.893848) (xy 72.319388 -371.386354) (xy 72.319823 -371.395539)
			(xy 72.32632 -371.412723) (xy 72.332088 -371.419882) (xy 72.353966 -371.445536) (xy 72.392055 -371.501172)
			(xy 72.423206 -371.560969) (xy 72.446841 -371.623725) (xy 73.548947 -371.623725) (xy 73.548951 -371.556417)
			(xy 73.556998 -371.489592) (xy 73.572975 -371.424208) (xy 73.596652 -371.361202) (xy 73.627689 -371.301477)
			(xy 73.665642 -371.24589) (xy 73.687432 -371.220238) (xy 73.693242 -371.213102) (xy 73.699748 -371.195904)
			(xy 73.700132 -371.18671) (xy 73.700132 -371.028722) (xy 73.700582 -371.018553) (xy 73.708359 -370.99976)
			(xy 73.722736 -370.985374) (xy 73.741525 -370.977587) (xy 73.751694 -370.97716) (xy 74.467974 -370.97716)
			(xy 74.478147 -370.977586) (xy 74.496945 -370.985366) (xy 74.511331 -370.999752) (xy 74.519113 -371.018549)
			(xy 74.519536 -371.028722) (xy 74.519536 -371.18671) (xy 74.519956 -371.195896) (xy 74.526464 -371.21308)
			(xy 74.532236 -371.220238) (xy 74.553987 -371.245921) (xy 74.591939 -371.301502) (xy 74.622975 -371.361221)
			(xy 74.646651 -371.424222) (xy 74.662627 -371.489601) (xy 74.670675 -371.55642) (xy 74.670678 -371.623723)
			(xy 74.662638 -371.690543) (xy 74.646668 -371.755924) (xy 74.622998 -371.818926) (xy 74.591968 -371.878649)
			(xy 74.554022 -371.934234) (xy 74.532236 -371.959886) (xy 74.526413 -371.967012) (xy 74.519916 -371.984217)
			(xy 74.519536 -371.993414) (xy 74.519536 -372.486682) (xy 74.519969 -372.495866) (xy 74.526468 -372.51305)
			(xy 74.532236 -372.52021) (xy 74.554058 -372.545834) (xy 74.592008 -372.601424) (xy 74.623041 -372.661151)
			(xy 74.646713 -372.724159) (xy 74.662684 -372.789545) (xy 74.670726 -372.856371) (xy 74.670723 -372.92368)
			(xy 74.662675 -372.990505) (xy 74.646698 -373.055889) (xy 74.62302 -373.118896) (xy 74.591981 -373.17862)
			(xy 74.554027 -373.234206) (xy 74.532236 -373.259858) (xy 74.526425 -373.266992) (xy 74.519921 -373.284191)
			(xy 74.519536 -373.293386) (xy 74.519536 -373.451374) (xy 74.519114 -373.461547) (xy 74.511333 -373.480346)
			(xy 74.496946 -373.494733) (xy 74.478147 -373.502514) (xy 74.467974 -373.502936) (xy 73.751694 -373.502936)
			(xy 73.741519 -373.50254) (xy 73.722719 -373.494749) (xy 73.708333 -373.480354) (xy 73.700553 -373.461549)
			(xy 73.700132 -373.451374) (xy 73.700132 -373.293386) (xy 73.699722 -373.284199) (xy 73.693207 -373.267015)
			(xy 73.687432 -373.259858) (xy 73.665678 -373.234178) (xy 73.627729 -373.178595) (xy 73.596694 -373.118876)
			(xy 73.57302 -373.055875) (xy 73.557045 -372.990496) (xy 73.548998 -372.923677) (xy 73.548995 -372.856374)
			(xy 73.557036 -372.789554) (xy 73.573005 -372.724174) (xy 73.596674 -372.661171) (xy 73.627702 -372.601448)
			(xy 73.665647 -372.545862) (xy 73.687432 -372.52021) (xy 73.693253 -372.513083) (xy 73.699753 -372.495878)
			(xy 73.700132 -372.486682) (xy 73.700132 -371.993414) (xy 73.699708 -371.984228) (xy 73.693203 -371.967044)
			(xy 73.687432 -371.959886) (xy 73.665607 -371.934265) (xy 73.62766 -371.878674) (xy 73.596629 -371.818946)
			(xy 73.572958 -371.755937) (xy 73.556988 -371.690551) (xy 73.548947 -371.623725) (xy 72.446841 -371.623725)
			(xy 72.44697 -371.624068) (xy 72.463005 -371.689558) (xy 72.47108 -371.756498) (xy 72.471078 -371.823923)
			(xy 72.463001 -371.890862) (xy 72.446964 -371.956352) (xy 72.423197 -372.01945) (xy 72.392044 -372.079246)
			(xy 72.353953 -372.134881) (xy 72.332088 -372.160546) (xy 72.326288 -372.167689) (xy 72.319776 -372.184881)
			(xy 72.319388 -372.194074) (xy 72.319388 -372.351554) (xy 72.318836 -372.361674) (xy 72.311129 -372.380389)
			(xy 72.296863 -372.394746) (xy 72.278197 -372.402572) (xy 72.26808 -372.403116) (xy 71.5518 -372.403116)
			(xy 71.541648 -372.402679) (xy 71.522899 -372.394886) (xy 71.508576 -372.380494) (xy 71.500873 -372.361708)
			(xy 71.500492 -372.351554) (xy 71.500492 -372.194074) (xy 71.500096 -372.184885) (xy 71.493573 -372.167701)
			(xy 71.487792 -372.160546) (xy 71.465942 -372.134869) (xy 71.427853 -372.079236) (xy 71.396703 -372.019442)
			(xy 71.372938 -371.956346) (xy 71.356902 -371.890859) (xy 71.348825 -371.823922) (xy 71.348824 -371.756499)
			(xy 71.356898 -371.689562) (xy 71.372932 -371.624074) (xy 71.396694 -371.560978) (xy 71.427843 -371.501182)
			(xy 71.465929 -371.445547) (xy 71.487792 -371.419882) (xy 71.493578 -371.412729) (xy 71.500099 -371.395545)
			(xy 71.500492 -371.386354) (xy 71.500492 -370.893848) (xy 71.500061 -370.884663) (xy 71.493562 -370.867478)
			(xy 71.487792 -370.86032) (xy 71.465917 -370.834664) (xy 71.427829 -370.779028) (xy 71.396679 -370.719231)
			(xy 71.372916 -370.656133) (xy 71.356881 -370.590642) (xy 71.348807 -370.523703) (xy 58.103008 -370.523703)
			(xy 58.103008 -371.310662) (xy 58.102522 -371.337931) (xy 58.09476 -371.391915) (xy 58.079395 -371.444245)
			(xy 58.056738 -371.493855) (xy 58.027252 -371.539736) (xy 57.991537 -371.580953) (xy 57.95032 -371.616668)
			(xy 57.904439 -371.646154) (xy 57.854829 -371.668811) (xy 57.802499 -371.684176) (xy 57.748515 -371.691938)
			(xy 57.693977 -371.691938) (xy 57.639993 -371.684176) (xy 57.587663 -371.668811) (xy 57.538053 -371.646154)
			(xy 57.492172 -371.616668) (xy 57.450955 -371.580953) (xy 57.41524 -371.539736) (xy 57.385754 -371.493855)
			(xy 57.363097 -371.444245) (xy 57.347732 -371.391915) (xy 57.33997 -371.337931) (xy 57.339484 -371.310662)
			(xy 54.729888 -371.310662) (xy 54.729402 -371.337931) (xy 54.72164 -371.391915) (xy 54.706275 -371.444245)
			(xy 54.683618 -371.493855) (xy 54.654132 -371.539736) (xy 54.618417 -371.580953) (xy 54.5772 -371.616668)
			(xy 54.531319 -371.646154) (xy 54.481709 -371.668811) (xy 54.429379 -371.684176) (xy 54.375395 -371.691938)
			(xy 54.320857 -371.691938) (xy 54.266873 -371.684176) (xy 54.214543 -371.668811) (xy 54.164933 -371.646154)
			(xy 54.119052 -371.616668) (xy 54.077835 -371.580953) (xy 54.04212 -371.539736) (xy 54.012634 -371.493855)
			(xy 53.989977 -371.444245) (xy 53.974612 -371.391915) (xy 53.96685 -371.337931) (xy 53.966364 -371.310662)
			(xy 48.196948 -371.310662) (xy 48.223223 -371.361224) (xy 48.246896 -371.424224) (xy 48.262871 -371.489602)
			(xy 48.270918 -371.556421) (xy 48.270921 -371.623722) (xy 48.262881 -371.690542) (xy 48.246913 -371.755921)
			(xy 48.223246 -371.818924) (xy 48.192219 -371.878647) (xy 48.154277 -371.934234) (xy 48.132492 -371.959886)
			(xy 48.126675 -371.967017) (xy 48.120173 -371.984218) (xy 48.119792 -371.993414) (xy 48.119792 -372.486682)
			(xy 48.120213 -372.495868) (xy 48.126719 -372.513052) (xy 48.132492 -372.52021) (xy 48.154312 -372.545835)
			(xy 48.192258 -372.601426) (xy 48.223288 -372.661154) (xy 48.246958 -372.724162) (xy 48.262927 -372.789547)
			(xy 48.270968 -372.856372) (xy 48.270965 -372.923679) (xy 48.262918 -372.990504) (xy 48.246942 -373.055887)
			(xy 48.223267 -373.118893) (xy 48.192232 -373.178618) (xy 48.154281 -373.234205) (xy 48.132492 -373.259858)
			(xy 48.126687 -373.266997) (xy 48.120178 -373.284192) (xy 48.119792 -373.293386) (xy 48.119792 -373.451374)
			(xy 48.119246 -373.461526) (xy 48.111486 -373.480289) (xy 48.097136 -373.494655) (xy 48.078382 -373.502435)
			(xy 48.06823 -373.502936) (xy 47.35195 -373.502936) (xy 47.341778 -373.502495) (xy 47.32298 -373.494721)
			(xy 47.308592 -373.48034) (xy 47.30081 -373.461545) (xy 47.300388 -373.451374) (xy 47.300388 -373.293386)
			(xy 47.299987 -373.284198) (xy 47.293467 -373.267013) (xy 47.287688 -373.259858) (xy 47.265932 -373.234179)
			(xy 47.227979 -373.178598) (xy 47.196942 -373.118878) (xy 47.173265 -373.055877) (xy 47.157288 -372.990498)
			(xy 47.14924 -372.923677) (xy 47.149237 -372.856374) (xy 47.157279 -372.789553) (xy 47.17325 -372.724172)
			(xy 47.196921 -372.661169) (xy 47.227953 -372.601446) (xy 47.265901 -372.545861) (xy 47.287688 -372.52021)
			(xy 47.293504 -372.513078) (xy 47.300007 -372.495878) (xy 47.300388 -372.486682) (xy 47.300388 -371.993414)
			(xy 47.299974 -371.984227) (xy 47.293463 -371.967043) (xy 47.287688 -371.959886) (xy 47.265861 -371.934265)
			(xy 47.227911 -371.878675) (xy 47.196876 -371.818948) (xy 47.173204 -371.755939) (xy 47.157232 -371.690553)
			(xy 47.14919 -371.623726) (xy 46.046568 -371.623726) (xy 46.046802 -371.624349) (xy 46.062775 -371.689733)
			(xy 46.070818 -371.756557) (xy 46.070817 -371.823864) (xy 46.062771 -371.890688) (xy 46.046796 -371.956071)
			(xy 46.023121 -372.019076) (xy 45.992085 -372.0788) (xy 45.954133 -372.134386) (xy 45.932344 -372.160038)
			(xy 45.926542 -372.167179) (xy 45.920032 -372.184373) (xy 45.919644 -372.193566) (xy 45.919644 -372.351554)
			(xy 45.919198 -372.361725) (xy 45.911425 -372.380522) (xy 45.897046 -372.394909) (xy 45.878253 -372.402693)
			(xy 45.868082 -372.403116) (xy 45.151802 -372.403116) (xy 45.141625 -372.402733) (xy 45.122821 -372.394941)
			(xy 45.108435 -372.380542) (xy 45.100658 -372.361732) (xy 45.10024 -372.351554) (xy 45.10024 -372.193566)
			(xy 45.099837 -372.184378) (xy 45.093317 -372.167194) (xy 45.08754 -372.160038) (xy 45.065766 -372.134374)
			(xy 45.027817 -372.07879) (xy 44.996783 -372.019068) (xy 44.973109 -371.956065) (xy 44.957135 -371.890684)
			(xy 44.94909 -371.823862) (xy 44.949089 -371.756559) (xy 44.957132 -371.689737) (xy 44.973103 -371.624356)
			(xy 44.996774 -371.561352) (xy 45.027806 -371.501628) (xy 45.065753 -371.446042) (xy 45.08754 -371.42039)
			(xy 45.093328 -371.413239) (xy 45.099847 -371.396053) (xy 45.10024 -371.386862) (xy 45.10024 -370.89334)
			(xy 45.099801 -370.884156) (xy 45.093306 -370.866972) (xy 45.08754 -370.859812) (xy 45.06574 -370.83417)
			(xy 45.027792 -370.778582) (xy 44.996759 -370.718857) (xy 44.973087 -370.655851) (xy 44.957115 -370.590468)
			(xy 44.949071 -370.523644) (xy 41.671032 -370.523644) (xy 41.671032 -370.523703) (xy 41.662957 -370.590641)
			(xy 41.646921 -370.65613) (xy 41.623156 -370.719227) (xy 41.592004 -370.779022) (xy 41.553913 -370.834656)
			(xy 41.532048 -370.86032) (xy 41.526254 -370.867467) (xy 41.519739 -370.884656) (xy 41.519348 -370.893848)
			(xy 41.519348 -371.386354) (xy 41.519792 -371.395537) (xy 41.526284 -371.412721) (xy 41.532048 -371.419882)
			(xy 41.553928 -371.445535) (xy 41.592019 -371.50117) (xy 41.623172 -371.560967) (xy 41.646832 -371.623785)
			(xy 42.748894 -371.623785) (xy 42.748898 -371.556358) (xy 42.756977 -371.489417) (xy 42.773017 -371.423926)
			(xy 42.796785 -371.360828) (xy 42.827941 -371.30103) (xy 42.866034 -371.245395) (xy 42.8879 -371.21973)
			(xy 42.893709 -371.212593) (xy 42.900216 -371.195396) (xy 42.9006 -371.186202) (xy 42.9006 -371.028722)
			(xy 42.901143 -371.018602) (xy 42.908856 -370.999888) (xy 42.923125 -370.985533) (xy 42.941791 -370.977706)
			(xy 42.951908 -370.97716) (xy 43.668188 -370.97716) (xy 43.678336 -370.977631) (xy 43.697081 -370.985415)
			(xy 43.711403 -370.999796) (xy 43.71911 -371.018572) (xy 43.719496 -371.028722) (xy 43.719496 -371.186202)
			(xy 43.719906 -371.195389) (xy 43.72642 -371.212573) (xy 43.732196 -371.21973) (xy 43.754023 -371.245426)
			(xy 43.792113 -371.301056) (xy 43.823265 -371.360848) (xy 43.847032 -371.423941) (xy 43.86307 -371.489426)
			(xy 43.871149 -371.556361) (xy 43.871153 -371.623782) (xy 43.86308 -371.690718) (xy 43.847049 -371.756205)
			(xy 43.823289 -371.8193) (xy 43.792142 -371.879095) (xy 43.754058 -371.934729) (xy 43.732196 -371.960394)
			(xy 43.726419 -371.967553) (xy 43.719893 -371.984733) (xy 43.719496 -371.993922) (xy 43.719496 -372.486174)
			(xy 43.71992 -372.49536) (xy 43.726424 -372.512544) (xy 43.732196 -372.519702) (xy 43.754094 -372.54534)
			(xy 43.792181 -372.600978) (xy 43.823331 -372.660778) (xy 43.847093 -372.723878) (xy 43.863127 -372.789371)
			(xy 43.8712 -372.856312) (xy 43.871197 -372.923739) (xy 43.863117 -372.990679) (xy 43.847078 -373.05617)
			(xy 43.82331 -373.119269) (xy 43.792155 -373.179066) (xy 43.754062 -373.234701) (xy 43.732196 -373.260366)
			(xy 43.726388 -373.267503) (xy 43.71988 -373.2847) (xy 43.719496 -373.293894) (xy 43.719496 -373.451374)
			(xy 43.718953 -373.461495) (xy 43.711241 -373.480208) (xy 43.696972 -373.494564) (xy 43.678306 -373.502391)
			(xy 43.668188 -373.502936) (xy 42.951908 -373.502936) (xy 42.941759 -373.502473) (xy 42.923014 -373.494686)
			(xy 42.908691 -373.480303) (xy 42.900985 -373.461525) (xy 42.9006 -373.451374) (xy 42.9006 -373.293894)
			(xy 42.900193 -373.284707) (xy 42.893677 -373.267522) (xy 42.8879 -373.260366) (xy 42.866069 -373.234673)
			(xy 42.82798 -373.179043) (xy 42.796828 -373.11925) (xy 42.773061 -373.056157) (xy 42.757024 -372.990671)
			(xy 42.748945 -372.923736) (xy 42.748942 -372.856315) (xy 42.757014 -372.789379) (xy 42.773046 -372.723892)
			(xy 42.796807 -372.660796) (xy 42.827953 -372.601001) (xy 42.866038 -372.545367) (xy 42.8879 -372.519702)
			(xy 42.893678 -372.512544) (xy 42.900204 -372.495363) (xy 42.9006 -372.486174) (xy 42.9006 -371.993922)
			(xy 42.900179 -371.984736) (xy 42.893673 -371.967551) (xy 42.8879 -371.960394) (xy 42.865999 -371.93476)
			(xy 42.827911 -371.879121) (xy 42.796762 -371.81932) (xy 42.773 -371.756219) (xy 42.756967 -371.690726)
			(xy 42.748894 -371.623785) (xy 41.646832 -371.623785) (xy 41.646938 -371.624066) (xy 41.662974 -371.689557)
			(xy 41.67105 -371.756498) (xy 41.671048 -371.823923) (xy 41.66297 -371.890864) (xy 41.646932 -371.956354)
			(xy 41.623164 -372.019452) (xy 41.592008 -372.079248) (xy 41.553915 -372.134882) (xy 41.532048 -372.160546)
			(xy 41.526243 -372.167685) (xy 41.519735 -372.18488) (xy 41.519348 -372.194074) (xy 41.519348 -372.351554)
			(xy 41.518835 -372.361679) (xy 41.51112 -372.380402) (xy 41.496842 -372.39476) (xy 41.478162 -372.402579)
			(xy 41.46804 -372.403116) (xy 40.75176 -372.403116) (xy 40.741605 -372.402711) (xy 40.722855 -372.394906)
			(xy 40.708534 -372.380504) (xy 40.700833 -372.361711) (xy 40.700452 -372.351554) (xy 40.700452 -372.194074)
			(xy 40.700043 -372.184887) (xy 40.693527 -372.167703) (xy 40.687752 -372.160546) (xy 40.6659 -372.13487)
			(xy 40.627807 -372.079238) (xy 40.596653 -372.019444) (xy 40.572886 -371.956349) (xy 40.556848 -371.89086)
			(xy 40.54877 -371.823922) (xy 40.548769 -371.756499) (xy 40.556844 -371.68956) (xy 40.57288 -371.624072)
			(xy 40.596645 -371.560975) (xy 40.627797 -371.50118) (xy 40.665887 -371.445546) (xy 40.687752 -371.419882)
			(xy 40.693545 -371.412735) (xy 40.70006 -371.395546) (xy 40.700452 -371.386354) (xy 40.700452 -370.893848)
			(xy 40.700007 -370.884665) (xy 40.693516 -370.867481) (xy 40.687752 -370.86032) (xy 40.665874 -370.834665)
			(xy 40.627783 -370.779031) (xy 40.59663 -370.719233) (xy 40.572864 -370.656135) (xy 40.556828 -370.590644)
			(xy 40.548752 -370.523704) (xy 37.271241 -370.523704) (xy 37.263166 -370.590641) (xy 37.247131 -370.65613)
			(xy 37.223366 -370.719226) (xy 37.192215 -370.779022) (xy 37.154125 -370.834655) (xy 37.13226 -370.86032)
			(xy 37.126467 -370.867468) (xy 37.119951 -370.884656) (xy 37.11956 -370.893848) (xy 37.11956 -371.386354)
			(xy 37.120001 -371.395538) (xy 37.126494 -371.412722) (xy 37.13226 -371.419882) (xy 37.154139 -371.445535)
			(xy 37.19223 -371.501171) (xy 37.223382 -371.560968) (xy 37.247019 -371.623725) (xy 38.349126 -371.623725)
			(xy 38.349129 -371.556418) (xy 38.357177 -371.489593) (xy 38.373153 -371.424209) (xy 38.396828 -371.361203)
			(xy 38.427864 -371.301478) (xy 38.465815 -371.245891) (xy 38.487604 -371.220238) (xy 38.49341 -371.213099)
			(xy 38.499919 -371.195904) (xy 38.500304 -371.18671) (xy 38.500304 -371.028722) (xy 38.50085 -371.01857)
			(xy 38.508611 -370.999808) (xy 38.522961 -370.985443) (xy 38.541714 -370.977661) (xy 38.551866 -370.97716)
			(xy 39.268146 -370.97716) (xy 39.278309 -370.977596) (xy 39.297084 -370.98539) (xy 39.311448 -370.999773)
			(xy 39.319217 -371.018558) (xy 39.319708 -371.028722) (xy 39.319708 -371.18671) (xy 39.320112 -371.195898)
			(xy 39.32663 -371.213082) (xy 39.332408 -371.220238) (xy 39.35416 -371.24592) (xy 39.392113 -371.301501)
			(xy 39.423151 -371.36122) (xy 39.446829 -371.424221) (xy 39.462806 -371.4896) (xy 39.470854 -371.55642)
			(xy 39.470857 -371.623723) (xy 39.462816 -371.690544) (xy 39.446845 -371.755925) (xy 39.423175 -371.818928)
			(xy 39.392143 -371.87865) (xy 39.354195 -371.934235) (xy 39.332408 -371.959886) (xy 39.326593 -371.967018)
			(xy 39.320089 -371.984219) (xy 39.319708 -371.993414) (xy 39.319708 -372.486682) (xy 39.320125 -372.495868)
			(xy 39.326634 -372.513053) (xy 39.332408 -372.52021) (xy 39.354231 -372.545834) (xy 39.392182 -372.601423)
			(xy 39.423217 -372.66115) (xy 39.44689 -372.724158) (xy 39.462862 -372.789545) (xy 39.470904 -372.856371)
			(xy 39.470901 -372.92368) (xy 39.462853 -372.990506) (xy 39.446875 -373.05589) (xy 39.423196 -373.118897)
			(xy 39.392156 -373.178621) (xy 39.354199 -373.234207) (xy 39.332408 -373.259858) (xy 39.326605 -373.266999)
			(xy 39.320094 -373.284193) (xy 39.319708 -373.293386) (xy 39.319708 -373.451374) (xy 39.319147 -373.461525)
			(xy 39.311389 -373.480284) (xy 39.297045 -373.494649) (xy 39.278296 -373.502432) (xy 39.268146 -373.502936)
			(xy 38.551866 -373.502936) (xy 38.541703 -373.502494) (xy 38.522928 -373.494703) (xy 38.508563 -373.480322)
			(xy 38.500794 -373.461538) (xy 38.500304 -373.451374) (xy 38.500304 -373.293386) (xy 38.4999 -373.284198)
			(xy 38.493382 -373.267014) (xy 38.487604 -373.259858) (xy 38.465851 -373.234178) (xy 38.427903 -373.178595)
			(xy 38.39687 -373.118875) (xy 38.373197 -373.055874) (xy 38.357223 -372.990495) (xy 38.349177 -372.923676)
			(xy 38.349174 -372.856375) (xy 38.357214 -372.789555) (xy 38.373182 -372.724175) (xy 38.396849 -372.661172)
			(xy 38.427877 -372.601449) (xy 38.465819 -372.545863) (xy 38.487604 -372.52021) (xy 38.493422 -372.51308)
			(xy 38.499924 -372.495878) (xy 38.500304 -372.486682) (xy 38.500304 -371.993414) (xy 38.499886 -371.984228)
			(xy 38.493378 -371.967043) (xy 38.487604 -371.959886) (xy 38.46578 -371.934264) (xy 38.427835 -371.878672)
			(xy 38.396805 -371.818944) (xy 38.373136 -371.755936) (xy 38.357167 -371.69055) (xy 38.349126 -371.623725)
			(xy 37.247019 -371.623725) (xy 37.247148 -371.624067) (xy 37.263183 -371.689557) (xy 37.271259 -371.756498)
			(xy 37.271257 -371.823923) (xy 37.263179 -371.890863) (xy 37.247141 -371.956354) (xy 37.223374 -372.019451)
			(xy 37.192219 -372.079248) (xy 37.154126 -372.134881) (xy 37.13226 -372.160546) (xy 37.126456 -372.167686)
			(xy 37.119947 -372.184881) (xy 37.11956 -372.194074) (xy 37.11956 -372.351554) (xy 37.119036 -372.361678)
			(xy 37.111323 -372.380398) (xy 37.097048 -372.394756) (xy 37.078373 -372.402576) (xy 37.068252 -372.403116)
			(xy 36.351972 -372.403116) (xy 36.341818 -372.402702) (xy 36.323068 -372.3949) (xy 36.308746 -372.380501)
			(xy 36.301045 -372.36171) (xy 36.300664 -372.351554) (xy 36.300664 -372.194074) (xy 36.300252 -372.184887)
			(xy 36.293738 -372.167704) (xy 36.287964 -372.160546) (xy 36.266115 -372.134869) (xy 36.228028 -372.079235)
			(xy 36.196879 -372.01944) (xy 36.173116 -371.956345) (xy 36.15708 -371.890858) (xy 36.149004 -371.823921)
			(xy 36.149003 -371.7565) (xy 36.157076 -371.689563) (xy 36.173109 -371.624075) (xy 36.19687 -371.560979)
			(xy 36.228017 -371.501183) (xy 36.266102 -371.445548) (xy 36.287964 -371.419882) (xy 36.293759 -371.412736)
			(xy 36.300273 -371.395546) (xy 36.300664 -371.386354) (xy 36.300664 -370.893848) (xy 36.300217 -370.884665)
			(xy 36.293727 -370.867481) (xy 36.287964 -370.86032) (xy 36.26609 -370.834664) (xy 36.228004 -370.779027)
			(xy 36.196855 -370.719229) (xy 36.173093 -370.656131) (xy 36.15706 -370.590642) (xy 36.148986 -370.523703)
			(xy 32.870915 -370.523703) (xy 32.862879 -370.590465) (xy 32.846908 -370.655846) (xy 32.823237 -370.71885)
			(xy 32.792205 -370.778573) (xy 32.754259 -370.83416) (xy 32.732472 -370.859812) (xy 32.726684 -370.866963)
			(xy 32.720165 -370.884149) (xy 32.719772 -370.89334) (xy 32.719772 -371.386862) (xy 32.720207 -371.396046)
			(xy 32.726704 -371.413231) (xy 32.732472 -371.42039) (xy 32.754273 -371.446031) (xy 32.792221 -371.501619)
			(xy 32.823253 -371.561344) (xy 32.846713 -371.623785) (xy 33.948806 -371.623785) (xy 33.94881 -371.556358)
			(xy 33.95689 -371.489417) (xy 33.97293 -371.423925) (xy 33.996699 -371.360827) (xy 34.027855 -371.30103)
			(xy 34.065949 -371.245395) (xy 34.087816 -371.21973) (xy 34.093627 -371.212595) (xy 34.100132 -371.195397)
			(xy 34.100516 -371.186202) (xy 34.100516 -371.028722) (xy 34.101044 -371.0186) (xy 34.10876 -370.999883)
			(xy 34.123033 -370.985527) (xy 34.141705 -370.977703) (xy 34.151824 -370.97716) (xy 34.868104 -370.97716)
			(xy 34.878253 -370.977618) (xy 34.896998 -370.985407) (xy 34.91132 -370.999792) (xy 34.919027 -371.018571)
			(xy 34.919412 -371.028722) (xy 34.919412 -371.186202) (xy 34.919819 -371.19539) (xy 34.926334 -371.212574)
			(xy 34.932112 -371.21973) (xy 34.953938 -371.245426) (xy 34.992027 -371.301057) (xy 35.023179 -371.360849)
			(xy 35.046945 -371.423941) (xy 35.062982 -371.489427) (xy 35.071061 -371.556361) (xy 35.071065 -371.623782)
			(xy 35.062993 -371.690717) (xy 35.046962 -371.756204) (xy 35.023202 -371.819299) (xy 34.992057 -371.879094)
			(xy 34.953973 -371.934729) (xy 34.932112 -371.960394) (xy 34.926337 -371.967555) (xy 34.919809 -371.984733)
			(xy 34.919412 -371.993922) (xy 34.919412 -372.486174) (xy 34.919832 -372.49536) (xy 34.926338 -372.512545)
			(xy 34.932112 -372.519702) (xy 34.954009 -372.54534) (xy 34.992096 -372.600979) (xy 35.023244 -372.660779)
			(xy 35.047006 -372.723879) (xy 35.063039 -372.789371) (xy 35.071112 -372.856312) (xy 35.071109 -372.923739)
			(xy 35.06303 -372.990679) (xy 35.046991 -373.05617) (xy 35.023224 -373.119268) (xy 34.99207 -373.179065)
			(xy 34.953978 -373.234701) (xy 34.932112 -373.260366) (xy 34.926306 -373.267505) (xy 34.919797 -373.2847)
			(xy 34.919412 -373.293894) (xy 34.919412 -373.451374) (xy 34.918854 -373.461493) (xy 34.911144 -373.480203)
			(xy 34.89688 -373.494559) (xy 34.878219 -373.502388) (xy 34.868104 -373.502936) (xy 34.151824 -373.502936)
			(xy 34.141676 -373.50246) (xy 34.122931 -373.494679) (xy 34.108608 -373.480299) (xy 34.100901 -373.461524)
			(xy 34.100516 -373.451374) (xy 34.100516 -373.293894) (xy 34.100105 -373.284707) (xy 34.093592 -373.267523)
			(xy 34.087816 -373.260366) (xy 34.065985 -373.234673) (xy 34.027894 -373.179043) (xy 33.996741 -373.119251)
			(xy 33.972974 -373.056158) (xy 33.956936 -372.990672) (xy 33.948857 -372.923736) (xy 33.948854 -372.856315)
			(xy 33.956927 -372.789379) (xy 33.972959 -372.723891) (xy 33.99672 -372.660796) (xy 34.027868 -372.601001)
			(xy 34.065953 -372.545367) (xy 34.087816 -372.519702) (xy 34.093596 -372.512545) (xy 34.10012 -372.495364)
			(xy 34.100516 -372.486174) (xy 34.100516 -371.993922) (xy 34.100092 -371.984736) (xy 34.093587 -371.967552)
			(xy 34.087816 -371.960394) (xy 34.065914 -371.93476) (xy 34.027826 -371.879121) (xy 33.996676 -371.819321)
			(xy 33.972913 -371.75622) (xy 33.956879 -371.690727) (xy 33.948806 -371.623785) (xy 32.846713 -371.623785)
			(xy 32.846925 -371.62435) (xy 32.862896 -371.689734) (xy 32.870939 -371.756558) (xy 32.870938 -371.823864)
			(xy 32.862892 -371.890687) (xy 32.846918 -371.95607) (xy 32.823244 -372.019075) (xy 32.79221 -372.078799)
			(xy 32.75426 -372.134386) (xy 32.732472 -372.160038) (xy 32.726673 -372.167181) (xy 32.72016 -372.184373)
			(xy 32.719772 -372.193566) (xy 32.719772 -372.351554) (xy 32.719299 -372.361721) (xy 32.711531 -372.380513)
			(xy 32.69716 -372.394899) (xy 32.678377 -372.402688) (xy 32.66821 -372.403116) (xy 31.95193 -372.403116)
			(xy 31.941755 -372.40271) (xy 31.922952 -372.394927) (xy 31.908564 -372.380535) (xy 31.900787 -372.361729)
			(xy 31.900368 -372.351554) (xy 31.900368 -372.193566) (xy 31.899959 -372.184379) (xy 31.893443 -372.167195)
			(xy 31.887668 -372.160038) (xy 31.865893 -372.134375) (xy 31.827942 -372.078791) (xy 31.796907 -372.019069)
			(xy 31.773232 -371.956066) (xy 31.757257 -371.890685) (xy 31.749211 -371.823863) (xy 31.74921 -371.756558)
			(xy 31.757253 -371.689736) (xy 31.773226 -371.624354) (xy 31.796898 -371.56135) (xy 31.827931 -371.501627)
			(xy 31.86588 -371.446042) (xy 31.887668 -371.42039) (xy 31.89346 -371.413242) (xy 31.899975 -371.396053)
			(xy 31.900368 -371.386862) (xy 31.900368 -370.89334) (xy 31.899923 -370.884157) (xy 31.893432 -370.866973)
			(xy 31.887668 -370.859812) (xy 31.865868 -370.83417) (xy 31.827917 -370.778583) (xy 31.796883 -370.718858)
			(xy 31.77321 -370.655852) (xy 31.757237 -370.590468) (xy 31.749193 -370.523644) (xy 28.471153 -370.523644)
			(xy 28.471153 -370.523703) (xy 28.463078 -370.59064) (xy 28.447043 -370.656129) (xy 28.42328 -370.719226)
			(xy 28.392129 -370.779021) (xy 28.35404 -370.834655) (xy 28.332176 -370.86032) (xy 28.326386 -370.867469)
			(xy 28.319868 -370.884657) (xy 28.319476 -370.893848) (xy 28.319476 -371.386354) (xy 28.319914 -371.395538)
			(xy 28.326409 -371.412722) (xy 28.332176 -371.419882) (xy 28.354055 -371.445535) (xy 28.392144 -371.501171)
			(xy 28.423296 -371.560969) (xy 28.446931 -371.623725) (xy 29.549038 -371.623725) (xy 29.549042 -371.556418)
			(xy 29.557089 -371.489593) (xy 29.573066 -371.424209) (xy 29.596742 -371.361203) (xy 29.627778 -371.301478)
			(xy 29.665731 -371.24589) (xy 29.68752 -371.220238) (xy 29.693328 -371.213101) (xy 29.699835 -371.195904)
			(xy 29.70022 -371.18671) (xy 29.70022 -371.028722) (xy 29.700682 -371.018554) (xy 29.708456 -370.999763)
			(xy 29.72283 -370.985378) (xy 29.741614 -370.97759) (xy 29.751782 -370.97716) (xy 30.468062 -370.97716)
			(xy 30.478234 -370.977596) (xy 30.497032 -370.985372) (xy 30.511419 -370.999755) (xy 30.519201 -371.01855)
			(xy 30.519624 -371.028722) (xy 30.519624 -371.18671) (xy 30.520024 -371.195898) (xy 30.526544 -371.213083)
			(xy 30.532324 -371.220238) (xy 30.554075 -371.24592) (xy 30.592028 -371.301502) (xy 30.623065 -371.361221)
			(xy 30.646741 -371.424221) (xy 30.662718 -371.4896) (xy 30.670766 -371.55642) (xy 30.670769 -371.623723)
			(xy 30.662728 -371.690543) (xy 30.646758 -371.755924) (xy 30.623088 -371.818927) (xy 30.592057 -371.878649)
			(xy 30.554111 -371.934234) (xy 30.532324 -371.959886) (xy 30.526511 -371.96702) (xy 30.520005 -371.984219)
			(xy 30.519624 -371.993414) (xy 30.519624 -372.486682) (xy 30.520037 -372.495869) (xy 30.526548 -372.513054)
			(xy 30.532324 -372.52021) (xy 30.554146 -372.545834) (xy 30.592096 -372.601424) (xy 30.62313 -372.661151)
			(xy 30.646803 -372.724159) (xy 30.662774 -372.789545) (xy 30.670816 -372.856371) (xy 30.670813 -372.92368)
			(xy 30.662765 -372.990505) (xy 30.646788 -373.05589) (xy 30.623109 -373.118896) (xy 30.59207 -373.17862)
			(xy 30.554115 -373.234206) (xy 30.532324 -373.259858) (xy 30.526523 -373.267) (xy 30.52001 -373.284193)
			(xy 30.519624 -373.293386) (xy 30.519624 -373.451374) (xy 30.519214 -373.461549) (xy 30.51143 -373.48035)
			(xy 30.49704 -373.494737) (xy 30.478237 -373.502516) (xy 30.468062 -373.502936) (xy 29.751782 -373.502936)
			(xy 29.741606 -373.50255) (xy 29.722806 -373.494754) (xy 29.708421 -373.480357) (xy 29.700641 -373.46155)
			(xy 29.70022 -373.451374) (xy 29.70022 -373.293386) (xy 29.699812 -373.284199) (xy 29.693297 -373.267015)
			(xy 29.68752 -373.259858) (xy 29.665767 -373.234178) (xy 29.627818 -373.178595) (xy 29.596784 -373.118875)
			(xy 29.57311 -373.055874) (xy 29.557136 -372.990496) (xy 29.549089 -372.923677) (xy 29.549086 -372.856375)
			(xy 29.557127 -372.789555) (xy 29.573095 -372.724175) (xy 29.596763 -372.661172) (xy 29.627792 -372.601449)
			(xy 29.665735 -372.545863) (xy 29.68752 -372.52021) (xy 29.69334 -372.513081) (xy 29.69984 -372.495878)
			(xy 29.70022 -372.486682) (xy 29.70022 -371.993414) (xy 29.699798 -371.984228) (xy 29.693292 -371.967044)
			(xy 29.68752 -371.959886) (xy 29.665695 -371.934264) (xy 29.627749 -371.878673) (xy 29.596718 -371.818945)
			(xy 29.573049 -371.755937) (xy 29.557079 -371.690551) (xy 29.549038 -371.623725) (xy 28.446931 -371.623725)
			(xy 28.44706 -371.624067) (xy 28.463096 -371.689558) (xy 28.471171 -371.756498) (xy 28.471169 -371.823923)
			(xy 28.463092 -371.890863) (xy 28.447054 -371.956353) (xy 28.423287 -372.01945) (xy 28.392134 -372.079247)
			(xy 28.354042 -372.134881) (xy 28.332176 -372.160546) (xy 28.326375 -372.167688) (xy 28.319864 -372.184881)
			(xy 28.319476 -372.194074) (xy 28.319476 -372.351554) (xy 28.318936 -372.361676) (xy 28.311226 -372.380393)
			(xy 28.296956 -372.39475) (xy 28.278287 -372.402574) (xy 28.268168 -372.403116) (xy 27.551888 -372.403116)
			(xy 27.541735 -372.402689) (xy 27.522985 -372.394892) (xy 27.508663 -372.380498) (xy 27.500961 -372.361709)
			(xy 27.50058 -372.351554) (xy 27.50058 -372.194074) (xy 27.500187 -372.184885) (xy 27.493662 -372.167701)
			(xy 27.48788 -372.160546) (xy 27.46603 -372.134869) (xy 27.427943 -372.079236) (xy 27.396792 -372.019441)
			(xy 27.373028 -371.956346) (xy 27.356993 -371.890858) (xy 27.348916 -371.823922) (xy 27.348915 -371.756499)
			(xy 27.356989 -371.689562) (xy 27.373022 -371.624074) (xy 27.396784 -371.560978) (xy 27.427932 -371.501182)
			(xy 27.466018 -371.445548) (xy 27.48788 -371.419882) (xy 27.493664 -371.412728) (xy 27.500187 -371.395544)
			(xy 27.50058 -371.386354) (xy 27.50058 -370.893848) (xy 27.500151 -370.884663) (xy 27.493651 -370.867478)
			(xy 27.48788 -370.86032) (xy 27.466005 -370.834664) (xy 27.427918 -370.779028) (xy 27.396769 -370.71923)
			(xy 27.373006 -370.656132) (xy 27.356972 -370.590642) (xy 27.348898 -370.523703) (xy 1.524 -370.523703)
			(xy 1.524 -372.100847) (xy 8.642336 -372.100847) (xy 8.642336 -372.040913) (xy 8.650159 -371.981491)
			(xy 8.665671 -371.923598) (xy 8.688607 -371.868226) (xy 8.718575 -371.81632) (xy 8.755061 -371.768771)
			(xy 8.797441 -371.726391) (xy 8.84499 -371.689905) (xy 8.896896 -371.659937) (xy 8.952268 -371.637001)
			(xy 9.010161 -371.621489) (xy 9.069583 -371.613666) (xy 9.09955 -371.613176) (xy 9.96315 -371.613176)
			(xy 9.993118 -371.613658) (xy 10.052541 -371.621481) (xy 10.110435 -371.636994) (xy 10.165808 -371.65993)
			(xy 10.217714 -371.689898) (xy 10.265264 -371.726385) (xy 10.307645 -371.768766) (xy 10.344132 -371.816316)
			(xy 10.3741 -371.868222) (xy 10.397036 -371.923595) (xy 10.412549 -371.981489) (xy 10.420372 -372.040912)
			(xy 10.420372 -372.100848) (xy 10.412549 -372.160271) (xy 10.397036 -372.218165) (xy 10.3741 -372.273538)
			(xy 10.344132 -372.325444) (xy 10.307645 -372.372994) (xy 10.265264 -372.415375) (xy 10.217714 -372.451862)
			(xy 10.165808 -372.48183) (xy 10.110435 -372.504766) (xy 10.052541 -372.520279) (xy 9.993118 -372.528102)
			(xy 9.96315 -372.528592) (xy 9.09955 -372.528592) (xy 9.069583 -372.528094) (xy 9.010161 -372.520271)
			(xy 8.952268 -372.504759) (xy 8.896896 -372.481823) (xy 8.84499 -372.451855) (xy 8.797441 -372.415369)
			(xy 8.755061 -372.372989) (xy 8.718575 -372.32544) (xy 8.688607 -372.273534) (xy 8.665671 -372.218162)
			(xy 8.650159 -372.160269) (xy 8.642336 -372.100847) (xy 1.524 -372.100847) (xy 1.524 -374.423871)
			(xy 27.348897 -374.423871) (xy 27.348897 -374.356446) (xy 27.356974 -374.289508) (xy 27.37301 -374.224019)
			(xy 27.396774 -374.160922) (xy 27.427926 -374.101125) (xy 27.466016 -374.045491) (xy 27.48788 -374.019826)
			(xy 27.493688 -374.012689) (xy 27.500197 -373.995492) (xy 27.50058 -373.986298) (xy 27.50058 -373.828818)
			(xy 27.501042 -373.818688) (xy 27.508772 -373.799959) (xy 27.523066 -373.785601) (xy 27.54176 -373.777788)
			(xy 27.551888 -373.777256) (xy 28.268168 -373.777256) (xy 28.278315 -373.777747) (xy 28.297058 -373.785523)
			(xy 28.311381 -373.799899) (xy 28.31909 -373.81867) (xy 28.319476 -373.828818) (xy 28.319476 -373.986298)
			(xy 28.319892 -373.995484) (xy 28.326402 -374.012669) (xy 28.332176 -374.019826) (xy 28.354038 -374.045493)
			(xy 28.392127 -374.101127) (xy 28.423278 -374.160923) (xy 28.447043 -374.22402) (xy 28.463078 -374.289509)
			(xy 28.471154 -374.356447) (xy 28.471155 -374.423823) (xy 31.749171 -374.423823) (xy 31.749175 -374.356514)
			(xy 31.757224 -374.289688) (xy 31.773202 -374.224303) (xy 31.796881 -374.161297) (xy 31.827921 -374.101572)
			(xy 31.865877 -374.045986) (xy 31.887668 -374.020334) (xy 31.893483 -374.013202) (xy 31.899985 -373.996001)
			(xy 31.900368 -373.986806) (xy 31.900368 -373.828818) (xy 31.900779 -373.818644) (xy 31.908564 -373.799844)
			(xy 31.922954 -373.785457) (xy 31.941756 -373.777677) (xy 31.95193 -373.777256) (xy 32.66821 -373.777256)
			(xy 32.678384 -373.777656) (xy 32.697183 -373.785448) (xy 32.711568 -373.799841) (xy 32.719349 -373.818643)
			(xy 32.719772 -373.828818) (xy 32.719772 -373.986806) (xy 32.720185 -373.995993) (xy 32.726697 -374.013177)
			(xy 32.732472 -374.020334) (xy 32.754218 -374.04602) (xy 32.792167 -374.101602) (xy 32.823202 -374.161321)
			(xy 32.846876 -374.224321) (xy 32.862852 -374.289699) (xy 32.870899 -374.356518) (xy 32.870903 -374.423819)
			(xy 32.870895 -374.423882) (xy 36.148964 -374.423882) (xy 36.148968 -374.356455) (xy 36.157048 -374.289515)
			(xy 36.173087 -374.224024) (xy 36.196854 -374.160925) (xy 36.228007 -374.101128) (xy 36.266099 -374.045492)
			(xy 36.287964 -374.019826) (xy 36.293782 -374.012697) (xy 36.300282 -373.995494) (xy 36.300664 -373.986298)
			(xy 36.300664 -373.828818) (xy 36.301142 -373.818689) (xy 36.308868 -373.799964) (xy 36.323158 -373.785606)
			(xy 36.341846 -373.777791) (xy 36.351972 -373.777256) (xy 37.068252 -373.777256) (xy 37.078398 -373.77776)
			(xy 37.09714 -373.785532) (xy 37.111464 -373.799903) (xy 37.119173 -373.818671) (xy 37.11956 -373.828818)
			(xy 37.11956 -373.986298) (xy 37.11998 -373.995484) (xy 37.126488 -374.012668) (xy 37.13226 -374.019826)
			(xy 37.154084 -374.045525) (xy 37.192177 -374.101153) (xy 37.223331 -374.160945) (xy 37.2471 -374.224037)
			(xy 37.263139 -374.289523) (xy 37.271219 -374.356458) (xy 37.271223 -374.423879) (xy 37.271223 -374.423882)
			(xy 40.548731 -374.423882) (xy 40.548735 -374.356454) (xy 40.556815 -374.289512) (xy 40.572857 -374.22402)
			(xy 40.596628 -374.160921) (xy 40.627787 -374.101124) (xy 40.665884 -374.04549) (xy 40.687752 -374.019826)
			(xy 40.693569 -374.012695) (xy 40.70007 -373.995494) (xy 40.700452 -373.986298) (xy 40.700452 -373.828818)
			(xy 40.700942 -373.818691) (xy 40.708666 -373.799968) (xy 40.722951 -373.785611) (xy 40.741636 -373.777793)
			(xy 40.75176 -373.777256) (xy 41.46804 -373.777256) (xy 41.478191 -373.777688) (xy 41.496936 -373.785489)
			(xy 41.511256 -373.799881) (xy 41.518963 -373.818665) (xy 41.519348 -373.828818) (xy 41.519348 -373.986298)
			(xy 41.519771 -373.995484) (xy 41.526277 -374.012667) (xy 41.532048 -374.019826) (xy 41.553873 -374.045524)
			(xy 41.591966 -374.101153) (xy 41.623121 -374.160944) (xy 41.64689 -374.224037) (xy 41.66293 -374.289522)
			(xy 41.67101 -374.356458) (xy 41.671014 -374.423823) (xy 44.94905 -374.423823) (xy 44.949054 -374.356514)
			(xy 44.957102 -374.289689) (xy 44.97308 -374.224304) (xy 44.996757 -374.161298) (xy 45.027796 -374.101573)
			(xy 45.06575 -374.045986) (xy 45.08754 -374.020334) (xy 45.093352 -374.0132) (xy 45.099857 -373.996001)
			(xy 45.10024 -373.986806) (xy 45.10024 -373.828818) (xy 45.100678 -373.818647) (xy 45.108458 -373.799853)
			(xy 45.122839 -373.785467) (xy 45.141631 -373.777682) (xy 45.151802 -373.777256) (xy 45.868082 -373.777256)
			(xy 45.878255 -373.777679) (xy 45.897053 -373.785461) (xy 45.911439 -373.799847) (xy 45.919221 -373.818645)
			(xy 45.919644 -373.828818) (xy 45.919644 -373.986806) (xy 45.920064 -373.995992) (xy 45.926572 -374.013176)
			(xy 45.932344 -374.020334) (xy 45.954091 -374.04602) (xy 45.992042 -374.101601) (xy 46.023078 -374.16132)
			(xy 46.046754 -374.22432) (xy 46.06273 -374.289698) (xy 46.070778 -374.356517) (xy 46.070782 -374.423819)
			(xy 46.070774 -374.423882) (xy 71.348786 -374.423882) (xy 71.348789 -374.356455) (xy 71.356869 -374.289514)
			(xy 71.372909 -374.224023) (xy 71.396677 -374.160924) (xy 71.427833 -374.101127) (xy 71.465926 -374.045491)
			(xy 71.487792 -374.019826) (xy 71.493602 -374.01269) (xy 71.500109 -373.995492) (xy 71.500492 -373.986298)
			(xy 71.500492 -373.828818) (xy 71.50104 -373.818698) (xy 71.508753 -373.799987) (xy 71.52302 -373.785631)
			(xy 71.541684 -373.777803) (xy 71.5518 -373.777256) (xy 72.26808 -373.777256) (xy 72.278227 -373.777737)
			(xy 72.296971 -373.785518) (xy 72.311293 -373.799896) (xy 72.319002 -373.818669) (xy 72.319388 -373.828818)
			(xy 72.319388 -373.986298) (xy 72.319802 -373.995485) (xy 72.326313 -374.012669) (xy 72.332088 -374.019826)
			(xy 72.353911 -374.045525) (xy 72.392002 -374.101154) (xy 72.423155 -374.160946) (xy 72.446922 -374.224038)
			(xy 72.462961 -374.289523) (xy 72.47104 -374.356458) (xy 72.471044 -374.423823) (xy 75.749081 -374.423823)
			(xy 75.749084 -374.356514) (xy 75.757133 -374.289688) (xy 75.773112 -374.224303) (xy 75.796791 -374.161296)
			(xy 75.827832 -374.101572) (xy 75.865788 -374.045985) (xy 75.88758 -374.020334) (xy 75.893385 -374.013194)
			(xy 75.899895 -373.996) (xy 75.90028 -373.986806) (xy 75.90028 -373.828818) (xy 75.900679 -373.818642)
			(xy 75.908466 -373.79984) (xy 75.92286 -373.785453) (xy 75.941666 -373.777675) (xy 75.951842 -373.777256)
			(xy 76.668122 -373.777256) (xy 76.678283 -373.777716) (xy 76.697057 -373.785501) (xy 76.711422 -373.799877)
			(xy 76.719192 -373.818656) (xy 76.719684 -373.828818) (xy 76.719684 -373.986806) (xy 76.720095 -373.995993)
			(xy 76.726608 -374.013177) (xy 76.732384 -374.020334) (xy 76.754129 -374.046021) (xy 76.792078 -374.101603)
			(xy 76.823112 -374.161322) (xy 76.846786 -374.224322) (xy 76.862761 -374.289699) (xy 76.870808 -374.356518)
			(xy 76.870812 -374.423819) (xy 76.870804 -374.423882) (xy 80.148873 -374.423882) (xy 80.148877 -374.356455)
			(xy 80.156957 -374.289515) (xy 80.172996 -374.224023) (xy 80.196764 -374.160925) (xy 80.227918 -374.101127)
			(xy 80.26601 -374.045492) (xy 80.287876 -374.019826) (xy 80.293684 -374.012689) (xy 80.300193 -373.995492)
			(xy 80.300576 -373.986298) (xy 80.300576 -373.828818) (xy 80.301042 -373.818688) (xy 80.308771 -373.79996)
			(xy 80.323064 -373.785602) (xy 80.341756 -373.777789) (xy 80.351884 -373.777256) (xy 81.068164 -373.777256)
			(xy 81.07831 -373.77775) (xy 81.097053 -373.785526) (xy 81.111376 -373.7999) (xy 81.119085 -373.81867)
			(xy 81.119472 -373.828818) (xy 81.119472 -373.986298) (xy 81.119889 -373.995484) (xy 81.126399 -374.012668)
			(xy 81.132172 -374.019826) (xy 81.153996 -374.045525) (xy 81.192087 -374.101154) (xy 81.223242 -374.160945)
			(xy 81.247009 -374.224038) (xy 81.263049 -374.289523) (xy 81.271128 -374.356458) (xy 81.271132 -374.423879)
			(xy 81.271132 -374.423882) (xy 84.548664 -374.423882) (xy 84.548668 -374.356455) (xy 84.556748 -374.289515)
			(xy 84.572787 -374.224024) (xy 84.596554 -374.160925) (xy 84.627707 -374.101128) (xy 84.665799 -374.045492)
			(xy 84.687664 -374.019826) (xy 84.693482 -374.012697) (xy 84.699982 -373.995494) (xy 84.700364 -373.986298)
			(xy 84.700364 -373.828818) (xy 84.700842 -373.818689) (xy 84.708568 -373.799964) (xy 84.722858 -373.785606)
			(xy 84.741546 -373.777791) (xy 84.751672 -373.777256) (xy 85.467952 -373.777256) (xy 85.478098 -373.77776)
			(xy 85.49684 -373.785532) (xy 85.511164 -373.799903) (xy 85.518873 -373.818671) (xy 85.51926 -373.828818)
			(xy 85.51926 -373.986298) (xy 85.51968 -373.995484) (xy 85.526188 -374.012668) (xy 85.53196 -374.019826)
			(xy 85.553784 -374.045525) (xy 85.591877 -374.101153) (xy 85.623031 -374.160945) (xy 85.6468 -374.224037)
			(xy 85.662839 -374.289523) (xy 85.670919 -374.356458) (xy 85.670923 -374.423822) (xy 115.349223 -374.423822)
			(xy 115.349227 -374.356515) (xy 115.357275 -374.28969) (xy 115.373251 -374.224306) (xy 115.396927 -374.1613)
			(xy 115.427963 -374.101574) (xy 115.465915 -374.045987) (xy 115.487704 -374.020334) (xy 115.493512 -374.013197)
			(xy 115.50002 -373.996) (xy 115.500404 -373.986806) (xy 115.500404 -373.828818) (xy 115.500947 -373.818666)
			(xy 115.508709 -373.799903) (xy 115.52306 -373.785539) (xy 115.541814 -373.777757) (xy 115.551966 -373.777256)
			(xy 116.268246 -373.777256) (xy 116.278409 -373.777696) (xy 116.297183 -373.785489) (xy 116.311547 -373.799871)
			(xy 116.319316 -373.818654) (xy 116.319808 -373.828818) (xy 116.319808 -373.986806) (xy 116.320214 -373.995994)
			(xy 116.32673 -374.013178) (xy 116.332508 -374.020334) (xy 116.354256 -374.046019) (xy 116.39221 -374.1016)
			(xy 116.423248 -374.161318) (xy 116.446925 -374.224319) (xy 116.462903 -374.289697) (xy 116.470951 -374.356517)
			(xy 116.470955 -374.42382) (xy 116.470948 -374.423882) (xy 119.748992 -374.423882) (xy 119.748995 -374.356455)
			(xy 119.757075 -374.289514) (xy 119.773115 -374.224022) (xy 119.796884 -374.160924) (xy 119.82804 -374.101126)
			(xy 119.866134 -374.045491) (xy 119.888 -374.019826) (xy 119.89381 -374.012691) (xy 119.900317 -373.995493)
			(xy 119.9007 -373.986298) (xy 119.9007 -373.828818) (xy 119.90124 -373.818697) (xy 119.908955 -373.799984)
			(xy 119.923224 -373.785629) (xy 119.94189 -373.777802) (xy 119.952008 -373.777256) (xy 120.668288 -373.777256)
			(xy 120.678436 -373.777731) (xy 120.69718 -373.785514) (xy 120.711502 -373.799894) (xy 120.71921 -373.818669)
			(xy 120.719596 -373.828818) (xy 120.719596 -373.986298) (xy 120.720008 -373.995485) (xy 120.726521 -374.012669)
			(xy 120.732296 -374.019826) (xy 120.754119 -374.045525) (xy 120.792209 -374.101155) (xy 120.823362 -374.160946)
			(xy 120.847129 -374.224039) (xy 120.863167 -374.289524) (xy 120.871246 -374.356458) (xy 120.87125 -374.423823)
			(xy 124.149287 -374.423823) (xy 124.149291 -374.356514) (xy 124.15734 -374.289688) (xy 124.173319 -374.224302)
			(xy 124.196998 -374.161296) (xy 124.228039 -374.101572) (xy 124.265996 -374.045986) (xy 124.287788 -374.020334)
			(xy 124.293594 -374.013195) (xy 124.300103 -373.996) (xy 124.300488 -373.986806) (xy 124.300488 -373.828818)
			(xy 124.30088 -373.818641) (xy 124.308668 -373.799837) (xy 124.323064 -373.78545) (xy 124.341873 -373.777673)
			(xy 124.35205 -373.777256) (xy 125.06833 -373.777256) (xy 125.078492 -373.777709) (xy 125.097265 -373.785497)
			(xy 125.11163 -373.799875) (xy 125.1194 -373.818656) (xy 125.119892 -373.828818) (xy 125.119892 -373.986806)
			(xy 125.120301 -373.995993) (xy 125.126816 -374.013177) (xy 125.132592 -374.020334) (xy 125.154338 -374.04602)
			(xy 125.192286 -374.101603) (xy 125.223319 -374.161322) (xy 125.246993 -374.224322) (xy 125.262968 -374.2897)
			(xy 125.271015 -374.356518) (xy 125.271019 -374.423819) (xy 125.271019 -374.423823) (xy 128.549078 -374.423823)
			(xy 128.549081 -374.356514) (xy 128.55713 -374.289688) (xy 128.573109 -374.224303) (xy 128.596788 -374.161296)
			(xy 128.627828 -374.101572) (xy 128.665784 -374.045985) (xy 128.687576 -374.020334) (xy 128.69338 -374.013194)
			(xy 128.699891 -373.996) (xy 128.700276 -373.986806) (xy 128.700276 -373.828818) (xy 128.700679 -373.818643)
			(xy 128.708465 -373.799841) (xy 128.722858 -373.785454) (xy 128.741663 -373.777675) (xy 128.751838 -373.777256)
			(xy 129.468118 -373.777256) (xy 129.478279 -373.777719) (xy 129.497052 -373.785503) (xy 129.511418 -373.799878)
			(xy 129.519188 -373.818656) (xy 129.51968 -373.828818) (xy 129.51968 -373.986806) (xy 129.520092 -373.995993)
			(xy 129.526605 -374.013177) (xy 129.53238 -374.020334) (xy 129.554126 -374.046021) (xy 129.592074 -374.101603)
			(xy 129.623108 -374.161322) (xy 129.646783 -374.224321) (xy 129.662758 -374.289699) (xy 129.670805 -374.356518)
			(xy 129.670809 -374.423819) (xy 129.670809 -374.423822) (xy 159.349132 -374.423822) (xy 159.349136 -374.356514)
			(xy 159.357184 -374.289689) (xy 159.373161 -374.224305) (xy 159.396837 -374.161299) (xy 159.427874 -374.101574)
			(xy 159.465826 -374.045986) (xy 159.487616 -374.020334) (xy 159.493425 -374.013198) (xy 159.499932 -373.996)
			(xy 159.500316 -373.986806) (xy 159.500316 -373.828818) (xy 159.500847 -373.818664) (xy 159.508612 -373.799899)
			(xy 159.522966 -373.785534) (xy 159.541724 -373.777755) (xy 159.551878 -373.777256) (xy 160.268158 -373.777256)
			(xy 160.278329 -373.777699) (xy 160.297126 -373.785473) (xy 160.311513 -373.799854) (xy 160.319297 -373.818647)
			(xy 160.31972 -373.828818) (xy 160.31972 -373.986806) (xy 160.320123 -373.995994) (xy 160.326641 -374.013179)
			(xy 160.33242 -374.020334) (xy 160.354168 -374.04602) (xy 160.39212 -374.1016) (xy 160.423158 -374.161319)
			(xy 160.446835 -374.224319) (xy 160.462812 -374.289698) (xy 160.47086 -374.356517) (xy 160.470864 -374.42382)
			(xy 160.470857 -374.423882) (xy 163.748901 -374.423882) (xy 163.748904 -374.356455) (xy 163.756985 -374.289514)
			(xy 163.773025 -374.224022) (xy 163.796794 -374.160923) (xy 163.827951 -374.101126) (xy 163.866045 -374.045491)
			(xy 163.887912 -374.019826) (xy 163.893724 -374.012692) (xy 163.900229 -373.995493) (xy 163.900612 -373.986298)
			(xy 163.900612 -373.828818) (xy 163.90114 -373.818696) (xy 163.908857 -373.79998) (xy 163.92313 -373.785624)
			(xy 163.941801 -373.7778) (xy 163.95192 -373.777256) (xy 164.6682 -373.777256) (xy 164.678349 -373.777721)
			(xy 164.697092 -373.785508) (xy 164.711414 -373.799891) (xy 164.719122 -373.818668) (xy 164.719508 -373.828818)
			(xy 164.719508 -373.986298) (xy 164.719917 -373.995485) (xy 164.726431 -374.01267) (xy 164.732208 -374.019826)
			(xy 164.75403 -374.045525) (xy 164.79212 -374.101155) (xy 164.823272 -374.160947) (xy 164.847038 -374.224039)
			(xy 164.863076 -374.289524) (xy 164.871155 -374.356458) (xy 164.871159 -374.423822) (xy 168.14922 -374.423822)
			(xy 168.149224 -374.356515) (xy 168.157272 -374.28969) (xy 168.173248 -374.224306) (xy 168.196924 -374.1613)
			(xy 168.22796 -374.101575) (xy 168.265911 -374.045987) (xy 168.2877 -374.020334) (xy 168.293507 -374.013196)
			(xy 168.300015 -373.996) (xy 168.3004 -373.986806) (xy 168.3004 -373.828818) (xy 168.300947 -373.818666)
			(xy 168.308709 -373.799905) (xy 168.323058 -373.78554) (xy 168.341811 -373.777758) (xy 168.351962 -373.777256)
			(xy 169.068242 -373.777256) (xy 169.078405 -373.777699) (xy 169.097178 -373.785491) (xy 169.111543 -373.799872)
			(xy 169.119312 -373.818655) (xy 169.119804 -373.828818) (xy 169.119804 -373.986806) (xy 169.120211 -373.995994)
			(xy 169.126727 -374.013178) (xy 169.132504 -374.020334) (xy 169.154249 -374.046021) (xy 169.192196 -374.101603)
			(xy 169.223229 -374.161322) (xy 169.246902 -374.224322) (xy 169.262877 -374.2897) (xy 169.270924 -374.356518)
			(xy 169.270928 -374.423819) (xy 169.270928 -374.423823) (xy 172.548987 -374.423823) (xy 172.548991 -374.356514)
			(xy 172.55704 -374.289688) (xy 172.573019 -374.224302) (xy 172.596698 -374.161296) (xy 172.627739 -374.101572)
			(xy 172.665696 -374.045986) (xy 172.687488 -374.020334) (xy 172.693294 -374.013195) (xy 172.699803 -373.996)
			(xy 172.700188 -373.986806) (xy 172.700188 -373.828818) (xy 172.70058 -373.818641) (xy 172.708368 -373.799837)
			(xy 172.722764 -373.78545) (xy 172.741573 -373.777673) (xy 172.75175 -373.777256) (xy 173.46803 -373.777256)
			(xy 173.478192 -373.777709) (xy 173.496965 -373.785497) (xy 173.51133 -373.799875) (xy 173.5191 -373.818656)
			(xy 173.519592 -373.828818) (xy 173.519592 -373.986806) (xy 173.520001 -373.995993) (xy 173.526516 -374.013177)
			(xy 173.532292 -374.020334) (xy 173.554038 -374.04602) (xy 173.591986 -374.101603) (xy 173.623019 -374.161322)
			(xy 173.646693 -374.224322) (xy 173.662668 -374.2897) (xy 173.670715 -374.356518) (xy 173.670719 -374.423819)
			(xy 173.662679 -374.490638) (xy 173.646712 -374.556018) (xy 173.623045 -374.61902) (xy 173.592018 -374.678743)
			(xy 173.554076 -374.73433) (xy 173.532292 -374.759982) (xy 173.526477 -374.767114) (xy 173.519974 -374.784315)
			(xy 173.519592 -374.79351) (xy 173.519592 -375.286778) (xy 173.520015 -375.295964) (xy 173.52652 -375.313148)
			(xy 173.532292 -375.320306) (xy 173.554108 -375.345934) (xy 173.592054 -375.401525) (xy 173.623084 -375.461252)
			(xy 173.646754 -375.52426) (xy 173.662724 -375.589644) (xy 173.670765 -375.656469) (xy 173.670763 -375.723776)
			(xy 173.662716 -375.7906) (xy 173.646741 -375.855984) (xy 173.623066 -375.918989) (xy 173.592031 -375.978714)
			(xy 173.554081 -376.034301) (xy 173.532292 -376.059954) (xy 173.526489 -376.067095) (xy 173.519978 -376.084289)
			(xy 173.519592 -376.093482) (xy 173.519592 -376.25147) (xy 173.519043 -376.261622) (xy 173.511284 -376.280385)
			(xy 173.496935 -376.29475) (xy 173.478182 -376.302531) (xy 173.46803 -376.303032) (xy 172.75175 -376.303032)
			(xy 172.741578 -376.302595) (xy 172.722779 -376.29482) (xy 172.708391 -376.280438) (xy 172.700609 -376.261642)
			(xy 172.700188 -376.25147) (xy 172.700188 -376.093482) (xy 172.699789 -376.084294) (xy 172.693268 -376.067109)
			(xy 172.687488 -376.059954) (xy 172.665728 -376.034278) (xy 172.627775 -375.978696) (xy 172.596738 -375.918976)
			(xy 172.573061 -375.855975) (xy 172.557085 -375.790595) (xy 172.549038 -375.723774) (xy 172.549035 -375.656471)
			(xy 172.557077 -375.589649) (xy 172.573048 -375.524268) (xy 172.59672 -375.461265) (xy 172.627752 -375.401542)
			(xy 172.665701 -375.345957) (xy 172.687488 -375.320306) (xy 172.693263 -375.313145) (xy 172.699791 -375.295967)
			(xy 172.700188 -375.286778) (xy 172.700188 -374.79351) (xy 172.699776 -374.784323) (xy 172.693264 -374.767138)
			(xy 172.687488 -374.759982) (xy 172.665658 -374.734364) (xy 172.627707 -374.678774) (xy 172.596673 -374.619046)
			(xy 172.573 -374.556037) (xy 172.557029 -374.49065) (xy 172.548987 -374.423823) (xy 169.270928 -374.423823)
			(xy 169.262888 -374.490638) (xy 169.246921 -374.556017) (xy 169.223255 -374.61902) (xy 169.192229 -374.678743)
			(xy 169.154288 -374.734329) (xy 169.132504 -374.759982) (xy 169.126691 -374.767115) (xy 169.120186 -374.784315)
			(xy 169.119804 -374.79351) (xy 169.119804 -375.286778) (xy 169.120224 -375.295964) (xy 169.126731 -375.313149)
			(xy 169.132504 -375.320306) (xy 169.15432 -375.345935) (xy 169.192265 -375.401525) (xy 169.223295 -375.461253)
			(xy 169.246964 -375.52426) (xy 169.262933 -375.589645) (xy 169.270974 -375.656469) (xy 169.270972 -375.723776)
			(xy 169.262925 -375.7906) (xy 169.24695 -375.855983) (xy 169.223276 -375.918989) (xy 169.192242 -375.978713)
			(xy 169.154292 -376.034301) (xy 169.132504 -376.059954) (xy 169.126702 -376.067096) (xy 169.120191 -376.084289)
			(xy 169.119804 -376.093482) (xy 169.119804 -376.25147) (xy 169.119243 -376.261621) (xy 169.111487 -376.280381)
			(xy 169.097142 -376.294746) (xy 169.078392 -376.302529) (xy 169.068242 -376.303032) (xy 168.351962 -376.303032)
			(xy 168.341798 -376.302597) (xy 168.323022 -376.294804) (xy 168.308657 -376.280421) (xy 168.30089 -376.261635)
			(xy 168.3004 -376.25147) (xy 168.3004 -376.093482) (xy 168.299998 -376.084294) (xy 168.293479 -376.06711)
			(xy 168.2877 -376.059954) (xy 168.265943 -376.034277) (xy 168.227996 -375.978693) (xy 168.196963 -375.918973)
			(xy 168.173291 -375.855972) (xy 168.157317 -375.790593) (xy 168.149271 -375.723774) (xy 168.149268 -375.656472)
			(xy 168.157309 -375.589652) (xy 168.173277 -375.524272) (xy 168.196945 -375.461269) (xy 168.227973 -375.401546)
			(xy 168.265915 -375.345959) (xy 168.2877 -375.320306) (xy 168.293477 -375.313147) (xy 168.300003 -375.295967)
			(xy 168.3004 -375.286778) (xy 168.3004 -374.79351) (xy 168.299985 -374.784323) (xy 168.293475 -374.767139)
			(xy 168.2877 -374.759982) (xy 168.265872 -374.734363) (xy 168.227927 -374.678771) (xy 168.196898 -374.619043)
			(xy 168.173229 -374.556034) (xy 168.15726 -374.490648) (xy 168.14922 -374.423822) (xy 164.871159 -374.423822)
			(xy 164.871159 -374.423879) (xy 164.863088 -374.490814) (xy 164.847057 -374.5563) (xy 164.823298 -374.619396)
			(xy 164.792152 -374.679191) (xy 164.754069 -374.734825) (xy 164.732208 -374.76049) (xy 164.726392 -374.767621)
			(xy 164.719889 -374.784822) (xy 164.719508 -374.794018) (xy 164.719508 -375.28627) (xy 164.719931 -375.295456)
			(xy 164.726435 -375.31264) (xy 164.732208 -375.319798) (xy 164.754101 -375.345439) (xy 164.792188 -375.401077)
			(xy 164.823337 -375.460877) (xy 164.8471 -375.523977) (xy 164.863133 -375.589469) (xy 164.871206 -375.65641)
			(xy 164.871203 -375.723835) (xy 164.863125 -375.790776) (xy 164.847086 -375.856266) (xy 164.823319 -375.919364)
			(xy 164.792165 -375.979161) (xy 164.754073 -376.034797) (xy 164.732208 -376.060462) (xy 164.726404 -376.067602)
			(xy 164.719893 -376.084796) (xy 164.719508 -376.09399) (xy 164.719508 -376.25147) (xy 164.71895 -376.261589)
			(xy 164.711241 -376.2803) (xy 164.696977 -376.294656) (xy 164.678316 -376.302485) (xy 164.6682 -376.303032)
			(xy 163.95192 -376.303032) (xy 163.941771 -376.302563) (xy 163.923025 -376.29478) (xy 163.908702 -376.280398)
			(xy 163.900996 -376.26162) (xy 163.900612 -376.25147) (xy 163.900612 -376.09399) (xy 163.900204 -376.084803)
			(xy 163.893689 -376.067618) (xy 163.887912 -376.060462) (xy 163.866077 -376.034773) (xy 163.827987 -375.979142)
			(xy 163.796834 -375.919349) (xy 163.773068 -375.856255) (xy 163.75703 -375.790769) (xy 163.748951 -375.723833)
			(xy 163.748949 -375.656412) (xy 163.757022 -375.589475) (xy 163.773054 -375.523988) (xy 163.796816 -375.460892)
			(xy 163.827963 -375.401097) (xy 163.866049 -375.345463) (xy 163.887912 -375.319798) (xy 163.893693 -375.312642)
			(xy 163.900217 -375.29546) (xy 163.900612 -375.28627) (xy 163.900612 -374.794018) (xy 163.90019 -374.784832)
			(xy 163.893684 -374.767648) (xy 163.887912 -374.76049) (xy 163.866006 -374.734859) (xy 163.827918 -374.67922)
			(xy 163.796769 -374.619419) (xy 163.773006 -374.556318) (xy 163.756973 -374.490824) (xy 163.748901 -374.423882)
			(xy 160.470857 -374.423882) (xy 160.462823 -374.49064) (xy 160.446853 -374.556021) (xy 160.423184 -374.619023)
			(xy 160.392153 -374.678745) (xy 160.354206 -374.73433) (xy 160.33242 -374.759982) (xy 160.326608 -374.767117)
			(xy 160.320102 -374.784315) (xy 160.31972 -374.79351) (xy 160.31972 -375.286778) (xy 160.320136 -375.295965)
			(xy 160.326645 -375.313149) (xy 160.33242 -375.320306) (xy 160.354238 -375.345933) (xy 160.392189 -375.401522)
			(xy 160.423223 -375.461249) (xy 160.446896 -375.524257) (xy 160.462868 -375.589643) (xy 160.470911 -375.656468)
			(xy 160.470908 -375.723777) (xy 160.46286 -375.790602) (xy 160.446883 -375.855986) (xy 160.423205 -375.918992)
			(xy 160.392166 -375.978716) (xy 160.354211 -376.034302) (xy 160.33242 -376.059954) (xy 160.32662 -376.067097)
			(xy 160.320107 -376.084289) (xy 160.31972 -376.093482) (xy 160.31972 -376.25147) (xy 160.31931 -376.261645)
			(xy 160.311528 -376.280447) (xy 160.297137 -376.294834) (xy 160.278333 -376.302613) (xy 160.268158 -376.303032)
			(xy 159.551878 -376.303032) (xy 159.541701 -376.302653) (xy 159.5229 -376.294855) (xy 159.508515 -376.280456)
			(xy 159.500737 -376.261647) (xy 159.500316 -376.25147) (xy 159.500316 -376.093482) (xy 159.499911 -376.084294)
			(xy 159.493393 -376.06711) (xy 159.487616 -376.059954) (xy 159.465858 -376.034277) (xy 159.42791 -375.978694)
			(xy 159.396877 -375.918973) (xy 159.373203 -375.855972) (xy 159.357229 -375.790593) (xy 159.349183 -375.723774)
			(xy 159.34918 -375.656471) (xy 159.357221 -375.589651) (xy 159.37319 -375.524271) (xy 159.396858 -375.461268)
			(xy 159.427887 -375.401545) (xy 159.465831 -375.345958) (xy 159.487616 -375.320306) (xy 159.493394 -375.313148)
			(xy 159.499919 -375.295967) (xy 159.500316 -375.286778) (xy 159.500316 -374.79351) (xy 159.499897 -374.784324)
			(xy 159.493389 -374.76714) (xy 159.487616 -374.759982) (xy 159.465788 -374.734364) (xy 159.427842 -374.678772)
			(xy 159.396811 -374.619043) (xy 159.373142 -374.556034) (xy 159.357173 -374.490648) (xy 159.349132 -374.423822)
			(xy 129.670809 -374.423822) (xy 129.662769 -374.490638) (xy 129.646801 -374.556018) (xy 129.623134 -374.619021)
			(xy 129.592107 -374.678743) (xy 129.554164 -374.734329) (xy 129.53238 -374.759982) (xy 129.526564 -374.767113)
			(xy 129.520062 -374.784315) (xy 129.51968 -374.79351) (xy 129.51968 -375.286778) (xy 129.520105 -375.295963)
			(xy 129.526609 -375.313148) (xy 129.53238 -375.320306) (xy 129.554197 -375.345934) (xy 129.592143 -375.401524)
			(xy 129.623174 -375.461252) (xy 129.646845 -375.524259) (xy 129.662815 -375.589644) (xy 129.670856 -375.656469)
			(xy 129.670854 -375.723776) (xy 129.662807 -375.7906) (xy 129.646831 -375.855984) (xy 129.623156 -375.91899)
			(xy 129.59212 -375.978714) (xy 129.554169 -376.034302) (xy 129.53238 -376.059954) (xy 129.526576 -376.067094)
			(xy 129.520066 -376.084288) (xy 129.51968 -376.093482) (xy 129.51968 -376.25147) (xy 129.519212 -376.261637)
			(xy 129.51144 -376.280428) (xy 129.497068 -376.294813) (xy 129.478285 -376.302602) (xy 129.468118 -376.303032)
			(xy 128.751838 -376.303032) (xy 128.741665 -376.302604) (xy 128.722866 -376.294826) (xy 128.708478 -376.280441)
			(xy 128.700697 -376.261643) (xy 128.700276 -376.25147) (xy 128.700276 -376.093482) (xy 128.69988 -376.084293)
			(xy 128.693357 -376.067109) (xy 128.687576 -376.059954) (xy 128.665817 -376.034278) (xy 128.627865 -375.978696)
			(xy 128.596828 -375.918976) (xy 128.573152 -375.855974) (xy 128.557176 -375.790595) (xy 128.549129 -375.723774)
			(xy 128.549126 -375.656471) (xy 128.557168 -375.58965) (xy 128.573138 -375.524269) (xy 128.59681 -375.461265)
			(xy 128.627841 -375.401543) (xy 128.665789 -375.345958) (xy 128.687576 -375.320306) (xy 128.69335 -375.313144)
			(xy 128.699879 -375.295967) (xy 128.700276 -375.286778) (xy 128.700276 -374.79351) (xy 128.699866 -374.784323)
			(xy 128.693353 -374.767138) (xy 128.687576 -374.759982) (xy 128.665746 -374.734365) (xy 128.627796 -374.678774)
			(xy 128.596762 -374.619046) (xy 128.57309 -374.556037) (xy 128.557119 -374.49065) (xy 128.549078 -374.423823)
			(xy 125.271019 -374.423823) (xy 125.262979 -374.490638) (xy 125.247012 -374.556018) (xy 125.223345 -374.61902)
			(xy 125.192318 -374.678743) (xy 125.154376 -374.73433) (xy 125.132592 -374.759982) (xy 125.126777 -374.767114)
			(xy 125.120274 -374.784315) (xy 125.119892 -374.79351) (xy 125.119892 -375.286778) (xy 125.120315 -375.295964)
			(xy 125.12682 -375.313148) (xy 125.132592 -375.320306) (xy 125.154408 -375.345934) (xy 125.192354 -375.401525)
			(xy 125.223384 -375.461252) (xy 125.247054 -375.52426) (xy 125.263024 -375.589644) (xy 125.271065 -375.656469)
			(xy 125.271063 -375.723776) (xy 125.263016 -375.7906) (xy 125.247041 -375.855984) (xy 125.223366 -375.918989)
			(xy 125.192331 -375.978714) (xy 125.154381 -376.034301) (xy 125.132592 -376.059954) (xy 125.126789 -376.067095)
			(xy 125.120278 -376.084289) (xy 125.119892 -376.093482) (xy 125.119892 -376.25147) (xy 125.119343 -376.261622)
			(xy 125.111584 -376.280385) (xy 125.097235 -376.29475) (xy 125.078482 -376.302531) (xy 125.06833 -376.303032)
			(xy 124.35205 -376.303032) (xy 124.341878 -376.302595) (xy 124.323079 -376.29482) (xy 124.308691 -376.280438)
			(xy 124.300909 -376.261642) (xy 124.300488 -376.25147) (xy 124.300488 -376.093482) (xy 124.300089 -376.084294)
			(xy 124.293568 -376.067109) (xy 124.287788 -376.059954) (xy 124.266028 -376.034278) (xy 124.228075 -375.978696)
			(xy 124.197038 -375.918976) (xy 124.173361 -375.855975) (xy 124.157385 -375.790595) (xy 124.149338 -375.723774)
			(xy 124.149335 -375.656471) (xy 124.157377 -375.589649) (xy 124.173348 -375.524268) (xy 124.19702 -375.461265)
			(xy 124.228052 -375.401542) (xy 124.266001 -375.345957) (xy 124.287788 -375.320306) (xy 124.293563 -375.313145)
			(xy 124.300091 -375.295967) (xy 124.300488 -375.286778) (xy 124.300488 -374.79351) (xy 124.300076 -374.784323)
			(xy 124.293564 -374.767138) (xy 124.287788 -374.759982) (xy 124.265958 -374.734364) (xy 124.228007 -374.678774)
			(xy 124.196973 -374.619046) (xy 124.1733 -374.556037) (xy 124.157329 -374.49065) (xy 124.149287 -374.423823)
			(xy 120.87125 -374.423823) (xy 120.87125 -374.423879) (xy 120.863178 -374.490814) (xy 120.847147 -374.556301)
			(xy 120.823388 -374.619396) (xy 120.792242 -374.679191) (xy 120.754158 -374.734825) (xy 120.732296 -374.76049)
			(xy 120.726478 -374.76762) (xy 120.719976 -374.784822) (xy 120.719596 -374.794018) (xy 120.719596 -375.28627)
			(xy 120.720022 -375.295456) (xy 120.726525 -375.31264) (xy 120.732296 -375.319798) (xy 120.75419 -375.345439)
			(xy 120.792278 -375.401077) (xy 120.823427 -375.460876) (xy 120.84719 -375.523976) (xy 120.863223 -375.589468)
			(xy 120.871297 -375.656409) (xy 120.871294 -375.723836) (xy 120.863215 -375.790776) (xy 120.847177 -375.856267)
			(xy 120.823409 -375.919365) (xy 120.792254 -375.979162) (xy 120.754162 -376.034797) (xy 120.732296 -376.060462)
			(xy 120.72649 -376.067601) (xy 120.719981 -376.084796) (xy 120.719596 -376.09399) (xy 120.719596 -376.25147)
			(xy 120.71905 -376.26159) (xy 120.711339 -376.280304) (xy 120.697071 -376.29466) (xy 120.678405 -376.302487)
			(xy 120.668288 -376.303032) (xy 119.952008 -376.303032) (xy 119.941858 -376.302572) (xy 119.923112 -376.294786)
			(xy 119.90879 -376.280401) (xy 119.901084 -376.261621) (xy 119.9007 -376.25147) (xy 119.9007 -376.09399)
			(xy 119.900294 -376.084802) (xy 119.893777 -376.067618) (xy 119.888 -376.060462) (xy 119.866166 -376.034772)
			(xy 119.828076 -375.979141) (xy 119.796924 -375.919349) (xy 119.773158 -375.856255) (xy 119.75712 -375.790769)
			(xy 119.749042 -375.723833) (xy 119.749039 -375.656412) (xy 119.757112 -375.589476) (xy 119.773145 -375.523988)
			(xy 119.796905 -375.460893) (xy 119.828053 -375.401097) (xy 119.866138 -375.345463) (xy 119.888 -375.319798)
			(xy 119.89378 -375.312641) (xy 119.900305 -375.29546) (xy 119.9007 -375.28627) (xy 119.9007 -374.794018)
			(xy 119.900281 -374.784832) (xy 119.893773 -374.767647) (xy 119.888 -374.76049) (xy 119.866095 -374.734859)
			(xy 119.828007 -374.679219) (xy 119.796858 -374.619418) (xy 119.773097 -374.556317) (xy 119.757064 -374.490824)
			(xy 119.748992 -374.423882) (xy 116.470948 -374.423882) (xy 116.462914 -374.49064) (xy 116.446944 -374.556021)
			(xy 116.423273 -374.619024) (xy 116.392242 -374.678746) (xy 116.354295 -374.734331) (xy 116.332508 -374.759982)
			(xy 116.326695 -374.767116) (xy 116.32019 -374.784315) (xy 116.319808 -374.79351) (xy 116.319808 -375.286778)
			(xy 116.320227 -375.295964) (xy 116.326734 -375.313149) (xy 116.332508 -375.320306) (xy 116.354327 -375.345933)
			(xy 116.392278 -375.401522) (xy 116.423313 -375.461249) (xy 116.446986 -375.524256) (xy 116.462959 -375.589642)
			(xy 116.471001 -375.656468) (xy 116.470999 -375.723777) (xy 116.462951 -375.790602) (xy 116.446973 -375.855987)
			(xy 116.423295 -375.918993) (xy 116.392255 -375.978717) (xy 116.354299 -376.034303) (xy 116.332508 -376.059954)
			(xy 116.326707 -376.067096) (xy 116.320195 -376.084289) (xy 116.319808 -376.093482) (xy 116.319808 -376.25147)
			(xy 116.319243 -376.26162) (xy 116.311487 -376.28038) (xy 116.297144 -376.294745) (xy 116.278395 -376.302528)
			(xy 116.268246 -376.303032) (xy 115.551966 -376.303032) (xy 115.541802 -376.302594) (xy 115.523027 -376.294803)
			(xy 115.508662 -376.28042) (xy 115.500894 -376.261634) (xy 115.500404 -376.25147) (xy 115.500404 -376.093482)
			(xy 115.500002 -376.084294) (xy 115.493483 -376.06711) (xy 115.487704 -376.059954) (xy 115.465947 -376.034277)
			(xy 115.427999 -375.978693) (xy 115.396967 -375.918973) (xy 115.373294 -375.855972) (xy 115.35732 -375.790593)
			(xy 115.349274 -375.723774) (xy 115.349271 -375.656472) (xy 115.357312 -375.589652) (xy 115.37328 -375.524271)
			(xy 115.396948 -375.461268) (xy 115.427976 -375.401545) (xy 115.465919 -375.345959) (xy 115.487704 -375.320306)
			(xy 115.493481 -375.313147) (xy 115.500007 -375.295967) (xy 115.500404 -375.286778) (xy 115.500404 -374.79351)
			(xy 115.499988 -374.784323) (xy 115.493478 -374.767139) (xy 115.487704 -374.759982) (xy 115.465876 -374.734363)
			(xy 115.427931 -374.678771) (xy 115.396901 -374.619043) (xy 115.373232 -374.556034) (xy 115.357263 -374.490648)
			(xy 115.349223 -374.423822) (xy 85.670923 -374.423822) (xy 85.670923 -374.423879) (xy 85.662851 -374.490815)
			(xy 85.646818 -374.556302) (xy 85.623057 -374.619398) (xy 85.591909 -374.679192) (xy 85.553823 -374.734826)
			(xy 85.53196 -374.76049) (xy 85.526138 -374.767617) (xy 85.519639 -374.784822) (xy 85.51926 -374.794018)
			(xy 85.51926 -375.28627) (xy 85.519694 -375.295454) (xy 85.526192 -375.312639) (xy 85.53196 -375.319798)
			(xy 85.553855 -375.345438) (xy 85.591945 -375.401075) (xy 85.623097 -375.460875) (xy 85.646861 -375.523975)
			(xy 85.662896 -375.589467) (xy 85.67097 -375.656409) (xy 85.670967 -375.723836) (xy 85.662888 -375.790777)
			(xy 85.646848 -375.856268) (xy 85.623079 -375.919367) (xy 85.591922 -375.979163) (xy 85.553827 -376.034797)
			(xy 85.53196 -376.060462) (xy 85.52615 -376.067597) (xy 85.519644 -376.084796) (xy 85.51926 -376.09399)
			(xy 85.51926 -376.25147) (xy 85.518749 -376.261595) (xy 85.511031 -376.280315) (xy 85.496752 -376.294673)
			(xy 85.478074 -376.302493) (xy 85.467952 -376.303032) (xy 84.751672 -376.303032) (xy 84.74152 -376.302602)
			(xy 84.722773 -376.294803) (xy 84.708452 -376.28041) (xy 84.700747 -376.261624) (xy 84.700364 -376.25147)
			(xy 84.700364 -376.09399) (xy 84.699944 -376.084804) (xy 84.693436 -376.06762) (xy 84.687664 -376.060462)
			(xy 84.665831 -376.034772) (xy 84.627744 -375.97914) (xy 84.596594 -375.919347) (xy 84.572829 -375.856253)
			(xy 84.556793 -375.790768) (xy 84.548715 -375.723833) (xy 84.548712 -375.656412) (xy 84.556785 -375.589477)
			(xy 84.572816 -375.52399) (xy 84.596575 -375.460894) (xy 84.62772 -375.401099) (xy 84.665803 -375.345464)
			(xy 84.687664 -375.319798) (xy 84.693452 -375.312647) (xy 84.69997 -375.295461) (xy 84.700364 -375.28627)
			(xy 84.700364 -374.794018) (xy 84.699931 -374.784834) (xy 84.693432 -374.76765) (xy 84.687664 -374.76049)
			(xy 84.66576 -374.734858) (xy 84.627675 -374.679218) (xy 84.596528 -374.619417) (xy 84.572768 -374.556316)
			(xy 84.556736 -374.490823) (xy 84.548664 -374.423882) (xy 81.271132 -374.423882) (xy 81.26306 -374.490815)
			(xy 81.247028 -374.556302) (xy 81.223267 -374.619397) (xy 81.19212 -374.679192) (xy 81.154034 -374.734825)
			(xy 81.132172 -374.76049) (xy 81.126351 -374.767618) (xy 81.119852 -374.784822) (xy 81.119472 -374.794018)
			(xy 81.119472 -375.28627) (xy 81.119903 -375.295455) (xy 81.126403 -375.312639) (xy 81.132172 -375.319798)
			(xy 81.154066 -375.345438) (xy 81.192156 -375.401076) (xy 81.223307 -375.460875) (xy 81.247071 -375.523975)
			(xy 81.263105 -375.589468) (xy 81.271179 -375.656409) (xy 81.271176 -375.723836) (xy 81.263097 -375.790777)
			(xy 81.247057 -375.856268) (xy 81.223289 -375.919366) (xy 81.192133 -375.979163) (xy 81.154039 -376.034797)
			(xy 81.132172 -376.060462) (xy 81.126363 -376.067598) (xy 81.119856 -376.084796) (xy 81.119472 -376.09399)
			(xy 81.119472 -376.25147) (xy 81.118949 -376.261593) (xy 81.111234 -376.280312) (xy 81.096958 -376.294669)
			(xy 81.078284 -376.302491) (xy 81.068164 -376.303032) (xy 80.351884 -376.303032) (xy 80.341733 -376.302592)
			(xy 80.322986 -376.294797) (xy 80.308664 -376.280407) (xy 80.300959 -376.261623) (xy 80.300576 -376.25147)
			(xy 80.300576 -376.09399) (xy 80.300176 -376.084802) (xy 80.293656 -376.067617) (xy 80.287876 -376.060462)
			(xy 80.266042 -376.034772) (xy 80.227954 -375.97914) (xy 80.196804 -375.919347) (xy 80.173039 -375.856254)
			(xy 80.157002 -375.790768) (xy 80.148924 -375.723833) (xy 80.148921 -375.656412) (xy 80.156994 -375.589476)
			(xy 80.173025 -375.523989) (xy 80.196785 -375.460894) (xy 80.227931 -375.401098) (xy 80.266015 -375.345464)
			(xy 80.287876 -375.319798) (xy 80.293653 -375.312639) (xy 80.30018 -375.295459) (xy 80.300576 -375.28627)
			(xy 80.300576 -374.794018) (xy 80.300163 -374.784831) (xy 80.293652 -374.767646) (xy 80.287876 -374.76049)
			(xy 80.265972 -374.734858) (xy 80.227886 -374.679218) (xy 80.196738 -374.619417) (xy 80.172977 -374.556316)
			(xy 80.156946 -374.490823) (xy 80.148873 -374.423882) (xy 76.870804 -374.423882) (xy 76.862772 -374.490638)
			(xy 76.846805 -374.556018) (xy 76.823138 -374.619021) (xy 76.79211 -374.678743) (xy 76.754168 -374.734329)
			(xy 76.732384 -374.759982) (xy 76.726568 -374.767114) (xy 76.720066 -374.784315) (xy 76.719684 -374.79351)
			(xy 76.719684 -375.286778) (xy 76.720108 -375.295964) (xy 76.726613 -375.313148) (xy 76.732384 -375.320306)
			(xy 76.754201 -375.345934) (xy 76.792147 -375.401525) (xy 76.823178 -375.461252) (xy 76.846848 -375.524259)
			(xy 76.862818 -375.589644) (xy 76.870859 -375.656469) (xy 76.870857 -375.723776) (xy 76.86281 -375.7906)
			(xy 76.846834 -375.855984) (xy 76.823159 -375.91899) (xy 76.792124 -375.978714) (xy 76.754173 -376.034302)
			(xy 76.732384 -376.059954) (xy 76.72658 -376.067094) (xy 76.72007 -376.084289) (xy 76.719684 -376.093482)
			(xy 76.719684 -376.25147) (xy 76.719212 -376.261637) (xy 76.711441 -376.280427) (xy 76.69707 -376.294812)
			(xy 76.678288 -376.302602) (xy 76.668122 -376.303032) (xy 75.951842 -376.303032) (xy 75.941669 -376.302601)
			(xy 75.92287 -376.294824) (xy 75.908482 -376.28044) (xy 75.900701 -376.261643) (xy 75.90028 -376.25147)
			(xy 75.90028 -376.093482) (xy 75.899883 -376.084293) (xy 75.893361 -376.067109) (xy 75.88758 -376.059954)
			(xy 75.865821 -376.034278) (xy 75.827868 -375.978696) (xy 75.796831 -375.918976) (xy 75.773155 -375.855975)
			(xy 75.757179 -375.790595) (xy 75.749132 -375.723774) (xy 75.749129 -375.656471) (xy 75.757171 -375.58965)
			(xy 75.773142 -375.524269) (xy 75.796813 -375.461265) (xy 75.827845 -375.401543) (xy 75.865793 -375.345958)
			(xy 75.88758 -375.320306) (xy 75.893354 -375.313145) (xy 75.899883 -375.295967) (xy 75.90028 -375.286778)
			(xy 75.90028 -374.79351) (xy 75.89987 -374.784323) (xy 75.893357 -374.767138) (xy 75.88758 -374.759982)
			(xy 75.865749 -374.734365) (xy 75.827799 -374.678774) (xy 75.796765 -374.619046) (xy 75.773093 -374.556037)
			(xy 75.757122 -374.49065) (xy 75.749081 -374.423823) (xy 72.471044 -374.423823) (xy 72.471044 -374.423879)
			(xy 72.462972 -374.490814) (xy 72.446941 -374.556301) (xy 72.423181 -374.619396) (xy 72.392034 -374.679191)
			(xy 72.35395 -374.734825) (xy 72.332088 -374.76049) (xy 72.326269 -374.76762) (xy 72.319768 -374.784822)
			(xy 72.319388 -374.794018) (xy 72.319388 -375.28627) (xy 72.319815 -375.295455) (xy 72.326317 -375.31264)
			(xy 72.332088 -375.319798) (xy 72.353982 -375.345439) (xy 72.39207 -375.401076) (xy 72.423221 -375.460876)
			(xy 72.446984 -375.523976) (xy 72.463017 -375.589468) (xy 72.471091 -375.656409) (xy 72.471088 -375.723836)
			(xy 72.463009 -375.790776) (xy 72.44697 -375.856267) (xy 72.423202 -375.919365) (xy 72.392047 -375.979162)
			(xy 72.353954 -376.034797) (xy 72.332088 -376.060462) (xy 72.326281 -376.0676) (xy 72.319773 -376.084796)
			(xy 72.319388 -376.09399) (xy 72.319388 -376.25147) (xy 72.31885 -376.261591) (xy 72.311137 -376.280307)
			(xy 72.296867 -376.294663) (xy 72.278198 -376.302488) (xy 72.26808 -376.303032) (xy 71.5518 -376.303032)
			(xy 71.54165 -376.302579) (xy 71.522904 -376.294789) (xy 71.508582 -376.280403) (xy 71.500876 -376.261622)
			(xy 71.500492 -376.25147) (xy 71.500492 -376.09399) (xy 71.500088 -376.084802) (xy 71.49357 -376.067618)
			(xy 71.487792 -376.060462) (xy 71.465958 -376.034772) (xy 71.427869 -375.979141) (xy 71.396717 -375.919348)
			(xy 71.372952 -375.856255) (xy 71.356914 -375.790769) (xy 71.348836 -375.723833) (xy 71.348833 -375.656412)
			(xy 71.356906 -375.589476) (xy 71.372938 -375.523989) (xy 71.396699 -375.460893) (xy 71.427845 -375.401098)
			(xy 71.46593 -375.345463) (xy 71.487792 -375.319798) (xy 71.493571 -375.31264) (xy 71.500096 -375.295459)
			(xy 71.500492 -375.28627) (xy 71.500492 -374.794018) (xy 71.500075 -374.784832) (xy 71.493566 -374.767647)
			(xy 71.487792 -374.76049) (xy 71.465887 -374.734859) (xy 71.4278 -374.679219) (xy 71.396652 -374.619418)
			(xy 71.37289 -374.556317) (xy 71.356858 -374.490824) (xy 71.348786 -374.423882) (xy 46.070774 -374.423882)
			(xy 46.062742 -374.490639) (xy 46.046773 -374.55602) (xy 46.023104 -374.619022) (xy 45.992075 -374.678745)
			(xy 45.95413 -374.73433) (xy 45.932344 -374.759982) (xy 45.926523 -374.76711) (xy 45.920025 -374.784314)
			(xy 45.919644 -374.79351) (xy 45.919644 -375.286778) (xy 45.920077 -375.295962) (xy 45.926576 -375.313146)
			(xy 45.932344 -375.320306) (xy 45.954162 -375.345934) (xy 45.992111 -375.401523) (xy 46.023144 -375.46125)
			(xy 46.046816 -375.524258) (xy 46.062787 -375.589643) (xy 46.070829 -375.656469) (xy 46.070826 -375.723776)
			(xy 46.062779 -375.790601) (xy 46.046802 -375.855985) (xy 46.023125 -375.918991) (xy 45.992088 -375.978716)
			(xy 45.954134 -376.034302) (xy 45.932344 -376.059954) (xy 45.926535 -376.06709) (xy 45.920029 -376.084288)
			(xy 45.919644 -376.093482) (xy 45.919644 -376.25147) (xy 45.919211 -376.261642) (xy 45.911433 -376.280439)
			(xy 45.897049 -376.294826) (xy 45.878254 -376.302609) (xy 45.868082 -376.303032) (xy 45.151802 -376.303032)
			(xy 45.141627 -376.302634) (xy 45.122826 -376.294844) (xy 45.10844 -376.28045) (xy 45.100661 -376.261645)
			(xy 45.10024 -376.25147) (xy 45.10024 -376.093482) (xy 45.09983 -376.084295) (xy 45.093315 -376.067111)
			(xy 45.08754 -376.059954) (xy 45.065782 -376.034277) (xy 45.027832 -375.978695) (xy 44.996798 -375.918974)
			(xy 44.973123 -375.855973) (xy 44.957148 -375.790594) (xy 44.949101 -375.723774) (xy 44.949099 -375.656471)
			(xy 44.95714 -375.589651) (xy 44.97311 -375.52427) (xy 44.996779 -375.461267) (xy 45.027809 -375.401544)
			(xy 45.065754 -375.345958) (xy 45.08754 -375.320306) (xy 45.093322 -375.31315) (xy 45.099844 -375.295968)
			(xy 45.10024 -375.286778) (xy 45.10024 -374.79351) (xy 45.099816 -374.784324) (xy 45.093311 -374.76714)
			(xy 45.08754 -374.759982) (xy 45.065711 -374.734364) (xy 45.027763 -374.678773) (xy 44.996732 -374.619044)
			(xy 44.973061 -374.556035) (xy 44.957091 -374.490649) (xy 44.94905 -374.423823) (xy 41.671014 -374.423823)
			(xy 41.671014 -374.423879) (xy 41.662941 -374.490816) (xy 41.646909 -374.556303) (xy 41.623147 -374.619398)
			(xy 41.591998 -374.679193) (xy 41.553911 -374.734826) (xy 41.532048 -374.76049) (xy 41.526224 -374.767616)
			(xy 41.519727 -374.784821) (xy 41.519348 -374.794018) (xy 41.519348 -375.28627) (xy 41.519784 -375.295454)
			(xy 41.526281 -375.312638) (xy 41.532048 -375.319798) (xy 41.553943 -375.345438) (xy 41.592035 -375.401075)
			(xy 41.623187 -375.460874) (xy 41.646952 -375.523974) (xy 41.662987 -375.589467) (xy 41.671061 -375.656409)
			(xy 41.671058 -375.723836) (xy 41.662978 -375.790777) (xy 41.646938 -375.856269) (xy 41.623168 -375.919367)
			(xy 41.592011 -375.979164) (xy 41.553916 -376.034798) (xy 41.532048 -376.060462) (xy 41.526236 -376.067596)
			(xy 41.519732 -376.084795) (xy 41.519348 -376.09399) (xy 41.519348 -376.25147) (xy 41.518849 -376.261596)
			(xy 41.511129 -376.280319) (xy 41.496846 -376.294677) (xy 41.478164 -376.302495) (xy 41.46804 -376.303032)
			(xy 40.75176 -376.303032) (xy 40.741607 -376.302612) (xy 40.72286 -376.294809) (xy 40.708539 -376.280413)
			(xy 40.700835 -376.261625) (xy 40.700452 -376.25147) (xy 40.700452 -376.09399) (xy 40.700035 -376.084804)
			(xy 40.693525 -376.06762) (xy 40.687752 -376.060462) (xy 40.665916 -376.034773) (xy 40.627823 -375.979143)
			(xy 40.596668 -375.919351) (xy 40.5729 -375.856257) (xy 40.55686 -375.79077) (xy 40.548781 -375.723834)
			(xy 40.548779 -375.656411) (xy 40.556852 -375.589474) (xy 40.572886 -375.523986) (xy 40.596649 -375.46089)
			(xy 40.627799 -375.401095) (xy 40.665888 -375.345462) (xy 40.687752 -375.319798) (xy 40.693538 -375.312646)
			(xy 40.700058 -375.29546) (xy 40.700452 -375.28627) (xy 40.700452 -374.794018) (xy 40.700022 -374.784833)
			(xy 40.693521 -374.767649) (xy 40.687752 -374.76049) (xy 40.665845 -374.73486) (xy 40.627754 -374.679221)
			(xy 40.596602 -374.619421) (xy 40.572838 -374.556319) (xy 40.556804 -374.490825) (xy 40.548731 -374.423882)
			(xy 37.271223 -374.423882) (xy 37.263151 -374.490815) (xy 37.247118 -374.556302) (xy 37.223357 -374.619398)
			(xy 37.192209 -374.679192) (xy 37.154123 -374.734826) (xy 37.13226 -374.76049) (xy 37.126438 -374.767617)
			(xy 37.119939 -374.784822) (xy 37.11956 -374.794018) (xy 37.11956 -375.28627) (xy 37.119994 -375.295454)
			(xy 37.126492 -375.312639) (xy 37.13226 -375.319798) (xy 37.154155 -375.345438) (xy 37.192245 -375.401075)
			(xy 37.223397 -375.460875) (xy 37.247161 -375.523975) (xy 37.263196 -375.589467) (xy 37.27127 -375.656409)
			(xy 37.271267 -375.723836) (xy 37.263188 -375.790777) (xy 37.247148 -375.856268) (xy 37.223379 -375.919367)
			(xy 37.192222 -375.979163) (xy 37.154127 -376.034797) (xy 37.13226 -376.060462) (xy 37.12645 -376.067597)
			(xy 37.119944 -376.084796) (xy 37.11956 -376.09399) (xy 37.11956 -376.25147) (xy 37.119049 -376.261595)
			(xy 37.111331 -376.280315) (xy 37.097052 -376.294673) (xy 37.078374 -376.302493) (xy 37.068252 -376.303032)
			(xy 36.351972 -376.303032) (xy 36.34182 -376.302602) (xy 36.323073 -376.294803) (xy 36.308752 -376.28041)
			(xy 36.301047 -376.261624) (xy 36.300664 -376.25147) (xy 36.300664 -376.09399) (xy 36.300244 -376.084804)
			(xy 36.293736 -376.06762) (xy 36.287964 -376.060462) (xy 36.266131 -376.034772) (xy 36.228044 -375.97914)
			(xy 36.196894 -375.919347) (xy 36.173129 -375.856253) (xy 36.157093 -375.790768) (xy 36.149015 -375.723833)
			(xy 36.149012 -375.656412) (xy 36.157085 -375.589477) (xy 36.173116 -375.52399) (xy 36.196875 -375.460894)
			(xy 36.22802 -375.401099) (xy 36.266103 -375.345464) (xy 36.287964 -375.319798) (xy 36.293752 -375.312647)
			(xy 36.30027 -375.295461) (xy 36.300664 -375.28627) (xy 36.300664 -374.794018) (xy 36.300231 -374.784834)
			(xy 36.293732 -374.76765) (xy 36.287964 -374.76049) (xy 36.26606 -374.734858) (xy 36.227975 -374.679218)
			(xy 36.196828 -374.619417) (xy 36.173068 -374.556316) (xy 36.157036 -374.490823) (xy 36.148964 -374.423882)
			(xy 32.870895 -374.423882) (xy 32.862863 -374.490639) (xy 32.846895 -374.556018) (xy 32.823227 -374.619021)
			(xy 32.7922 -374.678743) (xy 32.754257 -374.73433) (xy 32.732472 -374.759982) (xy 32.726654 -374.767112)
			(xy 32.720153 -374.784314) (xy 32.719772 -374.79351) (xy 32.719772 -375.286778) (xy 32.720199 -375.295963)
			(xy 32.726702 -375.313147) (xy 32.732472 -375.320306) (xy 32.754289 -375.345934) (xy 32.792236 -375.401524)
			(xy 32.823268 -375.461251) (xy 32.846938 -375.524259) (xy 32.862909 -375.589644) (xy 32.87095 -375.656469)
			(xy 32.870948 -375.723776) (xy 32.862901 -375.790601) (xy 32.846925 -375.855984) (xy 32.823249 -375.91899)
			(xy 32.792213 -375.978715) (xy 32.754261 -376.034302) (xy 32.732472 -376.059954) (xy 32.726666 -376.067093)
			(xy 32.720158 -376.084288) (xy 32.719772 -376.093482) (xy 32.719772 -376.25147) (xy 32.719312 -376.261638)
			(xy 32.711538 -376.28043) (xy 32.697164 -376.294816) (xy 32.678378 -376.302604) (xy 32.66821 -376.303032)
			(xy 31.95193 -376.303032) (xy 31.941757 -376.302611) (xy 31.922957 -376.29483) (xy 31.90857 -376.280443)
			(xy 31.900789 -376.261643) (xy 31.900368 -376.25147) (xy 31.900368 -376.093482) (xy 31.899951 -376.084296)
			(xy 31.89344 -376.067112) (xy 31.887668 -376.059954) (xy 31.865909 -376.034278) (xy 31.827957 -375.978696)
			(xy 31.796921 -375.918976) (xy 31.773245 -375.855974) (xy 31.75727 -375.790595) (xy 31.749223 -375.723774)
			(xy 31.74922 -375.656471) (xy 31.757261 -375.58965) (xy 31.773232 -375.524269) (xy 31.796903 -375.461266)
			(xy 31.827934 -375.401543) (xy 31.865881 -375.345958) (xy 31.887668 -375.320306) (xy 31.893453 -375.313153)
			(xy 31.899973 -375.295968) (xy 31.900368 -375.286778) (xy 31.900368 -374.79351) (xy 31.899938 -374.784325)
			(xy 31.893436 -374.767142) (xy 31.887668 -374.759982) (xy 31.865838 -374.734364) (xy 31.827888 -374.678774)
			(xy 31.796855 -374.619046) (xy 31.773184 -374.556036) (xy 31.757213 -374.49065) (xy 31.749171 -374.423823)
			(xy 28.471155 -374.423823) (xy 28.471155 -374.42387) (xy 28.463079 -374.490809) (xy 28.447044 -374.556297)
			(xy 28.423279 -374.619394) (xy 28.392129 -374.67919) (xy 28.35404 -374.734825) (xy 28.332176 -374.76049)
			(xy 28.326356 -374.767618) (xy 28.319856 -374.784822) (xy 28.319476 -374.794018) (xy 28.319476 -375.28627)
			(xy 28.319906 -375.295455) (xy 28.326407 -375.312639) (xy 28.332176 -375.319798) (xy 28.35407 -375.345439)
			(xy 28.39216 -375.401076) (xy 28.42331 -375.460875) (xy 28.447074 -375.523976) (xy 28.463108 -375.589468)
			(xy 28.471182 -375.656409) (xy 28.471179 -375.723836) (xy 28.4631 -375.790777) (xy 28.447061 -375.856268)
			(xy 28.423292 -375.919366) (xy 28.392136 -375.979163) (xy 28.354043 -376.034797) (xy 28.332176 -376.060462)
			(xy 28.326368 -376.067599) (xy 28.319861 -376.084796) (xy 28.319476 -376.09399) (xy 28.319476 -376.25147)
			(xy 28.31895 -376.261593) (xy 28.311235 -376.28031) (xy 28.29696 -376.294667) (xy 28.278288 -376.30249)
			(xy 28.268168 -376.303032) (xy 27.551888 -376.303032) (xy 27.541737 -376.302589) (xy 27.52299 -376.294796)
			(xy 27.508669 -376.280406) (xy 27.500964 -376.261623) (xy 27.50058 -376.25147) (xy 27.50058 -376.09399)
			(xy 27.500179 -376.084802) (xy 27.493659 -376.067617) (xy 27.48788 -376.060462) (xy 27.466046 -376.034772)
			(xy 27.427958 -375.979141) (xy 27.396807 -375.919348) (xy 27.373042 -375.856254) (xy 27.357005 -375.790768)
			(xy 27.348927 -375.723833) (xy 27.348924 -375.656412) (xy 27.356997 -375.589476) (xy 27.373029 -375.523989)
			(xy 27.396789 -375.460894) (xy 27.427935 -375.401098) (xy 27.466019 -375.345464) (xy 27.48788 -375.319798)
			(xy 27.493658 -375.312639) (xy 27.500184 -375.295459) (xy 27.50058 -375.28627) (xy 27.50058 -374.794018)
			(xy 27.500166 -374.784831) (xy 27.493655 -374.767646) (xy 27.48788 -374.76049) (xy 27.466014 -374.734827)
			(xy 27.427924 -374.679192) (xy 27.396773 -374.619396) (xy 27.373009 -374.556299) (xy 27.356973 -374.490809)
			(xy 27.348897 -374.423871) (xy 1.524 -374.423871) (xy 1.524 -376.756551) (xy 29.549067 -376.756551)
			(xy 29.557111 -376.689729) (xy 29.573083 -376.624347) (xy 29.596754 -376.561343) (xy 29.627786 -376.501619)
			(xy 29.665733 -376.446032) (xy 29.68752 -376.42038) (xy 29.69331 -376.41323) (xy 29.699828 -376.396043)
			(xy 29.70022 -376.386852) (xy 29.70022 -375.893584) (xy 29.699813 -375.884397) (xy 29.693297 -375.867212)
			(xy 29.68752 -375.860056) (xy 29.665765 -375.834378) (xy 29.627816 -375.778794) (xy 29.596782 -375.719074)
			(xy 29.573109 -375.656073) (xy 29.557134 -375.590694) (xy 29.549088 -375.523875) (xy 29.549085 -375.456573)
			(xy 29.557126 -375.389753) (xy 29.573095 -375.324373) (xy 29.596763 -375.26137) (xy 29.627791 -375.201647)
			(xy 29.665735 -375.146061) (xy 29.68752 -375.120408) (xy 29.693298 -375.11325) (xy 29.699823 -375.096069)
			(xy 29.70022 -375.08688) (xy 29.70022 -374.928638) (xy 29.700695 -374.918471) (xy 29.708464 -374.899681)
			(xy 29.722834 -374.885295) (xy 29.741616 -374.877506) (xy 29.751782 -374.877076) (xy 30.468062 -374.877076)
			(xy 30.478236 -374.877496) (xy 30.497037 -374.885276) (xy 30.511424 -374.899663) (xy 30.519204 -374.918464)
			(xy 30.519624 -374.928638) (xy 30.519624 -375.08688) (xy 30.520038 -375.096067) (xy 30.526548 -375.113252)
			(xy 30.532324 -375.120408) (xy 30.554144 -375.146034) (xy 30.592094 -375.201623) (xy 30.623128 -375.26135)
			(xy 30.646801 -375.324358) (xy 30.662773 -375.389744) (xy 30.670815 -375.45657) (xy 30.670812 -375.523878)
			(xy 30.662764 -375.590704) (xy 30.646787 -375.656088) (xy 30.623109 -375.719094) (xy 30.59207 -375.778818)
			(xy 30.554115 -375.834404) (xy 30.532324 -375.860056) (xy 30.526524 -375.867199) (xy 30.520011 -375.884391)
			(xy 30.519624 -375.893584) (xy 30.519624 -376.386852) (xy 30.520052 -376.396037) (xy 30.526553 -376.413222)
			(xy 30.532324 -376.42038) (xy 30.554117 -376.446028) (xy 30.592068 -376.501615) (xy 30.623103 -376.561338)
			(xy 30.646777 -376.624343) (xy 30.662751 -376.689726) (xy 30.670795 -376.75655) (xy 30.670795 -376.823856)
			(xy 30.670788 -376.823915) (xy 33.948836 -376.823915) (xy 33.948836 -376.756491) (xy 33.956911 -376.689553)
			(xy 33.972947 -376.624064) (xy 33.996711 -376.560967) (xy 34.027862 -376.501171) (xy 34.065952 -376.445537)
			(xy 34.087816 -376.419872) (xy 34.093609 -376.412724) (xy 34.100125 -376.395536) (xy 34.100516 -376.386344)
			(xy 34.100516 -375.894092) (xy 34.100106 -375.884905) (xy 34.093592 -375.867721) (xy 34.087816 -375.860564)
			(xy 34.065983 -375.834873) (xy 34.027892 -375.779243) (xy 33.996739 -375.71945) (xy 33.972973 -375.656357)
			(xy 33.956934 -375.59087) (xy 33.948856 -375.523935) (xy 33.948853 -375.456513) (xy 33.956926 -375.389577)
			(xy 33.972958 -375.324089) (xy 33.99672 -375.260994) (xy 34.027867 -375.201199) (xy 34.065953 -375.145565)
			(xy 34.087816 -375.1199) (xy 34.093597 -375.112744) (xy 34.10012 -375.095562) (xy 34.100516 -375.086372)
			(xy 34.100516 -374.928638) (xy 34.101057 -374.918517) (xy 34.108768 -374.899801) (xy 34.123038 -374.885444)
			(xy 34.141706 -374.87762) (xy 34.151824 -374.877076) (xy 34.868104 -374.877076) (xy 34.878255 -374.877518)
			(xy 34.897003 -374.88531) (xy 34.911325 -374.8997) (xy 34.919029 -374.918485) (xy 34.919412 -374.928638)
			(xy 34.919412 -375.086372) (xy 34.919833 -375.095558) (xy 34.926339 -375.112743) (xy 34.932112 -375.1199)
			(xy 34.954007 -375.14554) (xy 34.992094 -375.201178) (xy 35.023243 -375.260978) (xy 35.047004 -375.324078)
			(xy 35.063037 -375.38957) (xy 35.07111 -375.456511) (xy 35.071108 -375.523937) (xy 35.063029 -375.590877)
			(xy 35.04699 -375.656368) (xy 35.023223 -375.719466) (xy 34.992069 -375.779263) (xy 34.953977 -375.834899)
			(xy 34.932112 -375.860564) (xy 34.926307 -375.867703) (xy 34.919797 -375.884898) (xy 34.919412 -375.894092)
			(xy 34.919412 -376.386344) (xy 34.919798 -376.395534) (xy 34.926328 -376.412718) (xy 34.932112 -376.419872)
			(xy 34.953979 -376.445534) (xy 34.992067 -376.501169) (xy 35.023217 -376.560966) (xy 35.046981 -376.624063)
			(xy 35.063015 -376.689553) (xy 35.071091 -376.756491) (xy 35.071091 -376.756551) (xy 38.349155 -376.756551)
			(xy 38.357198 -376.689729) (xy 38.37317 -376.624348) (xy 38.396841 -376.561343) (xy 38.427872 -376.50162)
			(xy 38.465818 -376.446033) (xy 38.487604 -376.42038) (xy 38.493392 -376.413229) (xy 38.499912 -376.396043)
			(xy 38.500304 -376.386852) (xy 38.500304 -375.893584) (xy 38.499901 -375.884396) (xy 38.493382 -375.867212)
			(xy 38.487604 -375.860056) (xy 38.465849 -375.834378) (xy 38.427901 -375.778794) (xy 38.396869 -375.719074)
			(xy 38.373195 -375.656073) (xy 38.357221 -375.590694) (xy 38.349175 -375.523875) (xy 38.349172 -375.456573)
			(xy 38.357213 -375.389753) (xy 38.373181 -375.324373) (xy 38.396849 -375.26137) (xy 38.427876 -375.201647)
			(xy 38.465819 -375.146061) (xy 38.487604 -375.120408) (xy 38.49338 -375.113248) (xy 38.499907 -375.096069)
			(xy 38.500304 -375.08688) (xy 38.500304 -374.928638) (xy 38.500794 -374.918473) (xy 38.50856 -374.899686)
			(xy 38.522925 -374.885301) (xy 38.541702 -374.877508) (xy 38.551866 -374.877076) (xy 39.268146 -374.877076)
			(xy 39.278311 -374.877497) (xy 39.297089 -374.885293) (xy 39.311454 -374.899682) (xy 39.31922 -374.918472)
			(xy 39.319708 -374.928638) (xy 39.319708 -375.08688) (xy 39.320126 -375.096066) (xy 39.326634 -375.113251)
			(xy 39.332408 -375.120408) (xy 39.354229 -375.146034) (xy 39.39218 -375.201623) (xy 39.423215 -375.261349)
			(xy 39.446888 -375.324357) (xy 39.462861 -375.389743) (xy 39.470903 -375.45657) (xy 39.4709 -375.523878)
			(xy 39.462852 -375.590704) (xy 39.446874 -375.656089) (xy 39.423195 -375.719095) (xy 39.392155 -375.778819)
			(xy 39.354199 -375.834405) (xy 39.332408 -375.860056) (xy 39.326606 -375.867197) (xy 39.320094 -375.884391)
			(xy 39.319708 -375.893584) (xy 39.319708 -376.386852) (xy 39.320139 -376.396037) (xy 39.326638 -376.413222)
			(xy 39.332408 -376.42038) (xy 39.354201 -376.446028) (xy 39.392153 -376.501614) (xy 39.423189 -376.561338)
			(xy 39.446864 -376.624343) (xy 39.462839 -376.689726) (xy 39.470883 -376.75655) (xy 39.470883 -376.823856)
			(xy 39.470876 -376.823915) (xy 42.748924 -376.823915) (xy 42.748924 -376.756491) (xy 42.756999 -376.689553)
			(xy 42.773034 -376.624064) (xy 42.796798 -376.560968) (xy 42.827948 -376.501172) (xy 42.866036 -376.445537)
			(xy 42.8879 -376.419872) (xy 42.893691 -376.412723) (xy 42.900209 -376.395535) (xy 42.9006 -376.386344)
			(xy 42.9006 -375.894092) (xy 42.900194 -375.884904) (xy 42.893677 -375.86772) (xy 42.8879 -375.860564)
			(xy 42.866067 -375.834873) (xy 42.827978 -375.779242) (xy 42.796826 -375.719449) (xy 42.77306 -375.656356)
			(xy 42.757022 -375.59087) (xy 42.748944 -375.523935) (xy 42.748941 -375.456513) (xy 42.757013 -375.389577)
			(xy 42.773045 -375.32409) (xy 42.796806 -375.260995) (xy 42.827953 -375.201199) (xy 42.866038 -375.145565)
			(xy 42.8879 -375.1199) (xy 42.893679 -375.112742) (xy 42.900204 -375.095561) (xy 42.9006 -375.086372)
			(xy 42.9006 -374.928638) (xy 42.901157 -374.918519) (xy 42.908865 -374.899806) (xy 42.923129 -374.88545)
			(xy 42.941792 -374.877622) (xy 42.951908 -374.877076) (xy 43.668188 -374.877076) (xy 43.678338 -374.877531)
			(xy 43.697086 -374.885318) (xy 43.711409 -374.899704) (xy 43.719113 -374.918486) (xy 43.719496 -374.928638)
			(xy 43.719496 -375.086372) (xy 43.719921 -375.095558) (xy 43.726424 -375.112742) (xy 43.732196 -375.1199)
			(xy 43.754092 -375.145539) (xy 43.79218 -375.201177) (xy 43.823329 -375.260977) (xy 43.847092 -375.324077)
			(xy 43.863125 -375.38957) (xy 43.871198 -375.456511) (xy 43.871196 -375.523937) (xy 43.863116 -375.590878)
			(xy 43.847077 -375.656369) (xy 43.823309 -375.719467) (xy 43.792155 -375.779264) (xy 43.754062 -375.834899)
			(xy 43.732196 -375.860564) (xy 43.726389 -375.867702) (xy 43.719881 -375.884898) (xy 43.719496 -375.894092)
			(xy 43.719496 -376.386344) (xy 43.719886 -376.395533) (xy 43.726414 -376.412717) (xy 43.732196 -376.419872)
			(xy 43.754064 -376.445534) (xy 43.792153 -376.501169) (xy 43.823304 -376.560965) (xy 43.847068 -376.624063)
			(xy 43.863103 -376.689552) (xy 43.871179 -376.756491) (xy 43.871178 -376.823856) (xy 47.149219 -376.823856)
			(xy 47.149219 -376.75655) (xy 47.157264 -376.689727) (xy 47.173238 -376.624344) (xy 47.196912 -376.56134)
			(xy 47.227948 -376.501617) (xy 47.265899 -376.446031) (xy 47.287688 -376.42038) (xy 47.293474 -376.413227)
			(xy 47.299995 -376.396043) (xy 47.300388 -376.386852) (xy 47.300388 -375.893584) (xy 47.299988 -375.884396)
			(xy 47.293468 -375.867211) (xy 47.287688 -375.860056) (xy 47.26593 -375.834379) (xy 47.227977 -375.778797)
			(xy 47.19694 -375.719077) (xy 47.173263 -375.656076) (xy 47.157287 -375.590696) (xy 47.149239 -375.523876)
			(xy 47.149236 -375.456572) (xy 47.157278 -375.389751) (xy 47.173249 -375.32437) (xy 47.19692 -375.261367)
			(xy 47.227952 -375.201644) (xy 47.265901 -375.146059) (xy 47.287688 -375.120408) (xy 47.293462 -375.113247)
			(xy 47.299991 -375.096069) (xy 47.300388 -375.08688) (xy 47.300388 -374.928892) (xy 47.300815 -374.918739)
			(xy 47.308611 -374.899989) (xy 47.323006 -374.885666) (xy 47.341795 -374.877965) (xy 47.35195 -374.877584)
			(xy 48.06823 -374.877584) (xy 48.078364 -374.878003) (xy 48.097094 -374.885749) (xy 48.111451 -374.900056)
			(xy 48.119261 -374.91876) (xy 48.119792 -374.928892) (xy 48.119792 -375.08688) (xy 48.120214 -375.096066)
			(xy 48.12672 -375.11325) (xy 48.132492 -375.120408) (xy 48.15431 -375.146035) (xy 48.192256 -375.201626)
			(xy 48.223286 -375.261353) (xy 48.246956 -375.324361) (xy 48.262926 -375.389746) (xy 48.270967 -375.456571)
			(xy 48.270964 -375.523878) (xy 48.262917 -375.590702) (xy 48.246942 -375.656085) (xy 48.223267 -375.719091)
			(xy 48.192231 -375.778816) (xy 48.154281 -375.834403) (xy 48.132492 -375.860056) (xy 48.126688 -375.867196)
			(xy 48.120178 -375.884391) (xy 48.119792 -375.893584) (xy 48.119792 -376.386852) (xy 48.120227 -376.396037)
			(xy 48.126724 -376.413221) (xy 48.132492 -376.42038) (xy 48.154283 -376.446029) (xy 48.192229 -376.501617)
			(xy 48.223261 -376.561341) (xy 48.246932 -376.624346) (xy 48.262904 -376.689728) (xy 48.270947 -376.756551)
			(xy 73.548976 -376.756551) (xy 73.55702 -376.689728) (xy 73.572992 -376.624347) (xy 73.596664 -376.561342)
			(xy 73.627697 -376.501619) (xy 73.665645 -376.446032) (xy 73.687432 -376.42038) (xy 73.693224 -376.413231)
			(xy 73.699741 -376.396043) (xy 73.700132 -376.386852) (xy 73.700132 -375.893584) (xy 73.699722 -375.884397)
			(xy 73.693208 -375.867213) (xy 73.687432 -375.860056) (xy 73.665676 -375.834378) (xy 73.627727 -375.778795)
			(xy 73.596693 -375.719075) (xy 73.573018 -375.656074) (xy 73.557043 -375.590695) (xy 73.548997 -375.523875)
			(xy 73.548994 -375.456573) (xy 73.557035 -375.389753) (xy 73.573004 -375.324372) (xy 73.596673 -375.261369)
			(xy 73.627702 -375.201647) (xy 73.665647 -375.14606) (xy 73.687432 -375.120408) (xy 73.693212 -375.113251)
			(xy 73.699736 -375.096069) (xy 73.700132 -375.08688) (xy 73.700132 -374.928638) (xy 73.700595 -374.91847)
			(xy 73.708366 -374.899677) (xy 73.72274 -374.885291) (xy 73.741526 -374.877504) (xy 73.751694 -374.877076)
			(xy 74.467974 -374.877076) (xy 74.478149 -374.877486) (xy 74.49695 -374.88527) (xy 74.511337 -374.89966)
			(xy 74.519116 -374.918463) (xy 74.519536 -374.928638) (xy 74.519536 -375.08688) (xy 74.51997 -375.096064)
			(xy 74.526469 -375.113248) (xy 74.532236 -375.120408) (xy 74.554056 -375.146034) (xy 74.592006 -375.201623)
			(xy 74.623039 -375.26135) (xy 74.646711 -375.324358) (xy 74.662683 -375.389744) (xy 74.670725 -375.45657)
			(xy 74.670722 -375.523878) (xy 74.662674 -375.590703) (xy 74.646697 -375.656088) (xy 74.623019 -375.719094)
			(xy 74.591981 -375.778818) (xy 74.554027 -375.834404) (xy 74.532236 -375.860056) (xy 74.526425 -375.867191)
			(xy 74.519921 -375.88439) (xy 74.519536 -375.893584) (xy 74.519536 -376.386852) (xy 74.519983 -376.396035)
			(xy 74.526473 -376.413219) (xy 74.532236 -376.42038) (xy 74.554028 -376.446029) (xy 74.591979 -376.501615)
			(xy 74.623013 -376.561339) (xy 74.646687 -376.624344) (xy 74.66266 -376.689727) (xy 74.670704 -376.75655)
			(xy 74.670704 -376.823856) (xy 74.670697 -376.823915) (xy 77.948745 -376.823915) (xy 77.948745 -376.756491)
			(xy 77.956821 -376.689553) (xy 77.972856 -376.624063) (xy 77.996621 -376.560967) (xy 78.027773 -376.501171)
			(xy 78.065863 -376.445537) (xy 78.087728 -376.419872) (xy 78.093523 -376.412726) (xy 78.100038 -376.395536)
			(xy 78.100428 -376.386344) (xy 78.100428 -375.894092) (xy 78.100016 -375.884905) (xy 78.093503 -375.867721)
			(xy 78.087728 -375.860564) (xy 78.065894 -375.834873) (xy 78.027803 -375.779243) (xy 77.996649 -375.719451)
			(xy 77.972882 -375.656357) (xy 77.956844 -375.590871) (xy 77.948765 -375.523935) (xy 77.948762 -375.456513)
			(xy 77.956835 -375.389577) (xy 77.972868 -375.324089) (xy 77.99663 -375.260993) (xy 78.027778 -375.201198)
			(xy 78.065865 -375.145565) (xy 78.087728 -375.1199) (xy 78.093511 -375.112745) (xy 78.100033 -375.095562)
			(xy 78.100428 -375.086372) (xy 78.100428 -374.928638) (xy 78.100958 -374.918515) (xy 78.108671 -374.899797)
			(xy 78.122944 -374.88544) (xy 78.141616 -374.877618) (xy 78.151736 -374.877076) (xy 78.868016 -374.877076)
			(xy 78.878168 -374.877508) (xy 78.896916 -374.885304) (xy 78.911238 -374.899697) (xy 78.918942 -374.918484)
			(xy 78.919324 -374.928638) (xy 78.919324 -375.086372) (xy 78.919742 -375.095558) (xy 78.92625 -375.112743)
			(xy 78.932024 -375.1199) (xy 78.953919 -375.14554) (xy 78.992005 -375.201178) (xy 79.023153 -375.260978)
			(xy 79.046914 -375.324079) (xy 79.062947 -375.38957) (xy 79.07102 -375.456511) (xy 79.071017 -375.523937)
			(xy 79.062938 -375.590877) (xy 79.0469 -375.656367) (xy 79.023133 -375.719466) (xy 78.99198 -375.779263)
			(xy 78.953889 -375.834898) (xy 78.932024 -375.860564) (xy 78.926221 -375.867704) (xy 78.919709 -375.884898)
			(xy 78.919324 -375.894092) (xy 78.919324 -376.386344) (xy 78.919708 -376.395534) (xy 78.926239 -376.412718)
			(xy 78.932024 -376.419872) (xy 78.953891 -376.445534) (xy 78.991978 -376.50117) (xy 79.023127 -376.560967)
			(xy 79.04689 -376.624064) (xy 79.062925 -376.689553) (xy 79.071 -376.756491) (xy 79.071 -376.756551)
			(xy 82.349064 -376.756551) (xy 82.357108 -376.689729) (xy 82.373079 -376.624347) (xy 82.396751 -376.561343)
			(xy 82.427782 -376.501619) (xy 82.465729 -376.446032) (xy 82.487516 -376.42038) (xy 82.493305 -376.41323)
			(xy 82.499824 -376.396043) (xy 82.500216 -376.386852) (xy 82.500216 -375.893584) (xy 82.49981 -375.884396)
			(xy 82.493293 -375.867212) (xy 82.487516 -375.860056) (xy 82.46576 -375.834378) (xy 82.427812 -375.778795)
			(xy 82.396779 -375.719074) (xy 82.373105 -375.656073) (xy 82.357131 -375.590694) (xy 82.349084 -375.523875)
			(xy 82.349081 -375.456573) (xy 82.357122 -375.389753) (xy 82.373091 -375.324373) (xy 82.396759 -375.26137)
			(xy 82.427787 -375.201647) (xy 82.465731 -375.14606) (xy 82.487516 -375.120408) (xy 82.493294 -375.113249)
			(xy 82.499819 -375.096069) (xy 82.500216 -375.08688) (xy 82.500216 -374.928638) (xy 82.500694 -374.918472)
			(xy 82.508463 -374.899682) (xy 82.522832 -374.885297) (xy 82.541612 -374.877506) (xy 82.551778 -374.877076)
			(xy 83.268058 -374.877076) (xy 83.278232 -374.877499) (xy 83.297033 -374.885277) (xy 83.31142 -374.899664)
			(xy 83.3192 -374.918464) (xy 83.31962 -374.928638) (xy 83.31962 -375.08688) (xy 83.320035 -375.096067)
			(xy 83.326545 -375.113251) (xy 83.33232 -375.120408) (xy 83.35414 -375.146034) (xy 83.392091 -375.201623)
			(xy 83.423125 -375.26135) (xy 83.446798 -375.324358) (xy 83.46277 -375.389744) (xy 83.470812 -375.45657)
			(xy 83.470809 -375.523878) (xy 83.462761 -375.590704) (xy 83.446784 -375.656088) (xy 83.423105 -375.719094)
			(xy 83.392066 -375.778818) (xy 83.354111 -375.834404) (xy 83.33232 -375.860056) (xy 83.326519 -375.867199)
			(xy 83.320007 -375.884391) (xy 83.31962 -375.893584) (xy 83.31962 -376.386852) (xy 83.320049 -376.396037)
			(xy 83.326549 -376.413222) (xy 83.33232 -376.42038) (xy 83.354113 -376.446028) (xy 83.392064 -376.501614)
			(xy 83.4231 -376.561338) (xy 83.446774 -376.624343) (xy 83.462748 -376.689726) (xy 83.470792 -376.75655)
			(xy 83.470792 -376.823856) (xy 83.470785 -376.823915) (xy 86.748833 -376.823915) (xy 86.748833 -376.756491)
			(xy 86.756908 -376.689553) (xy 86.772944 -376.624064) (xy 86.796708 -376.560967) (xy 86.827859 -376.501171)
			(xy 86.865948 -376.445537) (xy 86.887812 -376.419872) (xy 86.893604 -376.412724) (xy 86.900121 -376.395536)
			(xy 86.900512 -376.386344) (xy 86.900512 -375.894092) (xy 86.900103 -375.884905) (xy 86.893588 -375.86772)
			(xy 86.887812 -375.860564) (xy 86.865979 -375.834873) (xy 86.827889 -375.779242) (xy 86.796736 -375.71945)
			(xy 86.772969 -375.656356) (xy 86.756931 -375.59087) (xy 86.748853 -375.523935) (xy 86.74885 -375.456513)
			(xy 86.756923 -375.389577) (xy 86.772955 -375.32409) (xy 86.796716 -375.260994) (xy 86.827864 -375.201199)
			(xy 86.86595 -375.145565) (xy 86.887812 -375.1199) (xy 86.893592 -375.112743) (xy 86.900116 -375.095562)
			(xy 86.900512 -375.086372) (xy 86.900512 -374.928638) (xy 86.901057 -374.918517) (xy 86.908767 -374.899802)
			(xy 86.923035 -374.885446) (xy 86.941702 -374.87762) (xy 86.95182 -374.877076) (xy 87.6681 -374.877076)
			(xy 87.678251 -374.877521) (xy 87.696999 -374.885312) (xy 87.711321 -374.899701) (xy 87.719025 -374.918485)
			(xy 87.719408 -374.928638) (xy 87.719408 -375.086372) (xy 87.71983 -375.095558) (xy 87.726335 -375.112743)
			(xy 87.732108 -375.1199) (xy 87.754003 -375.145539) (xy 87.79209 -375.201178) (xy 87.798441 -375.213371)
			(xy 104.681961 -375.213371) (xy 104.681961 -375.153429) (xy 104.689785 -375.094001) (xy 104.7053 -375.036103)
			(xy 104.72824 -374.980725) (xy 104.758212 -374.928815) (xy 104.794703 -374.881262) (xy 104.837089 -374.838879)
			(xy 104.884645 -374.802391) (xy 104.936557 -374.772424) (xy 104.991937 -374.749489) (xy 105.049837 -374.733978)
			(xy 105.109265 -374.726159) (xy 105.139236 -374.725692) (xy 106.002836 -374.725692) (xy 106.032802 -374.726184)
			(xy 106.092221 -374.734011) (xy 106.15011 -374.749527) (xy 106.205479 -374.772465) (xy 106.25738 -374.802434)
			(xy 106.304926 -374.838921) (xy 106.347303 -374.881301) (xy 106.383786 -374.92885) (xy 106.413751 -374.980753)
			(xy 106.436685 -375.036124) (xy 106.452196 -375.094014) (xy 106.460018 -375.153434) (xy 106.460018 -375.213366)
			(xy 106.452196 -375.272786) (xy 106.436685 -375.330676) (xy 106.413751 -375.386047) (xy 106.383786 -375.43795)
			(xy 106.347303 -375.485499) (xy 106.304926 -375.527879) (xy 106.25738 -375.564366) (xy 106.205479 -375.594335)
			(xy 106.15011 -375.617273) (xy 106.092221 -375.632789) (xy 106.032802 -375.640616) (xy 106.002836 -375.641108)
			(xy 105.139236 -375.641108) (xy 105.109265 -375.640641) (xy 105.049837 -375.632822) (xy 104.991937 -375.617311)
			(xy 104.936557 -375.594376) (xy 104.884645 -375.564409) (xy 104.837089 -375.527921) (xy 104.794703 -375.485538)
			(xy 104.758212 -375.437985) (xy 104.72824 -375.386075) (xy 104.7053 -375.330697) (xy 104.689785 -375.272799)
			(xy 104.681961 -375.213371) (xy 87.798441 -375.213371) (xy 87.823239 -375.260978) (xy 87.847001 -375.324078)
			(xy 87.863034 -375.38957) (xy 87.871107 -375.456511) (xy 87.871105 -375.523937) (xy 87.863026 -375.590877)
			(xy 87.846987 -375.656368) (xy 87.82322 -375.719466) (xy 87.792066 -375.779263) (xy 87.753974 -375.834899)
			(xy 87.732108 -375.860564) (xy 87.726303 -375.867703) (xy 87.719793 -375.884898) (xy 87.719408 -375.894092)
			(xy 87.719408 -376.386344) (xy 87.719795 -376.395534) (xy 87.726324 -376.412718) (xy 87.732108 -376.419872)
			(xy 87.753976 -376.445534) (xy 87.792064 -376.501169) (xy 87.823214 -376.560966) (xy 87.846977 -376.624063)
			(xy 87.863012 -376.689553) (xy 87.871088 -376.756491) (xy 87.871087 -376.823915) (xy 117.548863 -376.823915)
			(xy 117.548863 -376.756491) (xy 117.556939 -376.689552) (xy 117.572976 -376.624062) (xy 117.596742 -376.560965)
			(xy 117.627895 -376.50117) (xy 117.665986 -376.445536) (xy 117.687852 -376.419872) (xy 117.693649 -376.412728)
			(xy 117.700162 -376.395536) (xy 117.700552 -376.386344) (xy 117.700552 -375.894092) (xy 117.700134 -375.884906)
			(xy 117.693625 -375.867722) (xy 117.687852 -375.860564) (xy 117.666018 -375.834874) (xy 117.627925 -375.779244)
			(xy 117.59677 -375.719452) (xy 117.573001 -375.656358) (xy 117.556962 -375.590871) (xy 117.548883 -375.523935)
			(xy 117.54888 -375.456513) (xy 117.556953 -375.389576) (xy 117.572987 -375.324088) (xy 117.59675 -375.260992)
			(xy 117.6279 -375.201197) (xy 117.665988 -375.145564) (xy 117.687852 -375.1199) (xy 117.693638 -375.112747)
			(xy 117.700157 -375.095562) (xy 117.700552 -375.086372) (xy 117.700552 -374.928638) (xy 117.701058 -374.918512)
			(xy 117.708776 -374.89979) (xy 117.723056 -374.885432) (xy 117.741737 -374.877613) (xy 117.75186 -374.877076)
			(xy 118.46814 -374.877076) (xy 118.478294 -374.877488) (xy 118.497042 -374.885293) (xy 118.511363 -374.899691)
			(xy 118.519066 -374.918482) (xy 118.519448 -374.928638) (xy 118.519448 -375.086372) (xy 118.519883 -375.095556)
			(xy 118.526381 -375.11274) (xy 118.532148 -375.1199) (xy 118.554045 -375.145538) (xy 118.592136 -375.201176)
			(xy 118.623289 -375.260975) (xy 118.647053 -375.324075) (xy 118.663088 -375.389568) (xy 118.671162 -375.45651)
			(xy 118.671159 -375.523938) (xy 118.66308 -375.590879) (xy 118.647039 -375.656371) (xy 118.623269 -375.719469)
			(xy 118.592112 -375.779266) (xy 118.554016 -375.8349) (xy 118.532148 -375.860564) (xy 118.526335 -375.867698)
			(xy 118.519832 -375.884897) (xy 118.519448 -375.894092) (xy 118.519448 -376.386344) (xy 118.519849 -376.395532)
			(xy 118.52637 -376.412715) (xy 118.532148 -376.419872) (xy 118.554018 -376.445533) (xy 118.59211 -376.501167)
			(xy 118.623263 -376.560963) (xy 118.647029 -376.624061) (xy 118.663066 -376.689551) (xy 118.671143 -376.75649)
			(xy 118.671143 -376.756551) (xy 121.949182 -376.756551) (xy 121.957226 -376.689728) (xy 121.973199 -376.624346)
			(xy 121.996871 -376.561342) (xy 122.027904 -376.501618) (xy 122.065852 -376.446032) (xy 122.08764 -376.42038)
			(xy 122.093433 -376.413232) (xy 122.099949 -376.396044) (xy 122.10034 -376.386852) (xy 122.10034 -375.893584)
			(xy 122.099929 -375.884397) (xy 122.093415 -375.867213) (xy 122.08764 -375.860056) (xy 122.065884 -375.834378)
			(xy 122.027934 -375.778795) (xy 121.996899 -375.719075) (xy 121.973225 -375.656074) (xy 121.95725 -375.590695)
			(xy 121.949203 -375.523875) (xy 121.9492 -375.456573) (xy 121.957241 -375.389752) (xy 121.973211 -375.324372)
			(xy 121.99688 -375.261369) (xy 122.027909 -375.201646) (xy 122.065854 -375.14606) (xy 122.08764 -375.120408)
			(xy 122.093421 -375.113252) (xy 122.099944 -375.09607) (xy 122.10034 -375.08688) (xy 122.10034 -374.928638)
			(xy 122.100795 -374.918469) (xy 122.108568 -374.899674) (xy 122.122944 -374.885288) (xy 122.141733 -374.877502)
			(xy 122.151902 -374.877076) (xy 122.868182 -374.877076) (xy 122.878357 -374.877479) (xy 122.897159 -374.885265)
			(xy 122.911546 -374.899658) (xy 122.919325 -374.918463) (xy 122.919744 -374.928638) (xy 122.919744 -375.08688)
			(xy 122.920176 -375.096065) (xy 122.926676 -375.113249) (xy 122.932444 -375.120408) (xy 122.954264 -375.146034)
			(xy 122.992213 -375.201624) (xy 123.023246 -375.261351) (xy 123.046917 -375.324359) (xy 123.062889 -375.389744)
			(xy 123.070931 -375.45657) (xy 123.070928 -375.523878) (xy 123.06288 -375.590703) (xy 123.046903 -375.656087)
			(xy 123.023226 -375.719093) (xy 122.992188 -375.778818) (xy 122.954234 -375.834404) (xy 122.932444 -375.860056)
			(xy 122.926634 -375.867192) (xy 122.920129 -375.88439) (xy 122.919744 -375.893584) (xy 122.919744 -376.386852)
			(xy 122.92019 -376.396035) (xy 122.92668 -376.413219) (xy 122.932444 -376.42038) (xy 122.954236 -376.446029)
			(xy 122.992186 -376.501615) (xy 123.02322 -376.561339) (xy 123.046893 -376.624344) (xy 123.062866 -376.689727)
			(xy 123.07091 -376.75655) (xy 123.07091 -376.823856) (xy 123.070903 -376.823915) (xy 126.348951 -376.823915)
			(xy 126.348951 -376.756491) (xy 126.357027 -376.689552) (xy 126.373063 -376.624063) (xy 126.396828 -376.560966)
			(xy 126.42798 -376.50117) (xy 126.466071 -376.445537) (xy 126.487936 -376.419872) (xy 126.493732 -376.412726)
			(xy 126.500246 -376.395536) (xy 126.500636 -376.386344) (xy 126.500636 -375.894092) (xy 126.500222 -375.884905)
			(xy 126.49371 -375.867721) (xy 126.487936 -375.860564) (xy 126.466102 -375.834873) (xy 126.42801 -375.779243)
			(xy 126.396856 -375.719451) (xy 126.373088 -375.656357) (xy 126.35705 -375.590871) (xy 126.348971 -375.523935)
			(xy 126.348968 -375.456513) (xy 126.357041 -375.389576) (xy 126.373074 -375.324089) (xy 126.396836 -375.260993)
			(xy 126.427985 -375.201198) (xy 126.466073 -375.145565) (xy 126.487936 -375.1199) (xy 126.49372 -375.112746)
			(xy 126.500241 -375.095562) (xy 126.500636 -375.086372) (xy 126.500636 -374.928638) (xy 126.501158 -374.918514)
			(xy 126.508872 -374.899795) (xy 126.523148 -374.885437) (xy 126.541823 -374.877616) (xy 126.551944 -374.877076)
			(xy 127.268224 -374.877076) (xy 127.278377 -374.877501) (xy 127.297125 -374.8853) (xy 127.311447 -374.899695)
			(xy 127.31915 -374.918483) (xy 127.319532 -374.928638) (xy 127.319532 -375.086372) (xy 127.319971 -375.095556)
			(xy 127.326466 -375.11274) (xy 127.332232 -375.1199) (xy 127.354126 -375.14554) (xy 127.392212 -375.201179)
			(xy 127.423359 -375.260979) (xy 127.44712 -375.324079) (xy 127.463153 -375.389571) (xy 127.471226 -375.456511)
			(xy 127.471223 -375.523937) (xy 127.463144 -375.590877) (xy 127.447106 -375.656367) (xy 127.42334 -375.719465)
			(xy 127.392187 -375.779263) (xy 127.354097 -375.834898) (xy 127.332232 -375.860564) (xy 127.326417 -375.867696)
			(xy 127.319915 -375.884897) (xy 127.319532 -375.894092) (xy 127.319532 -376.386344) (xy 127.319936 -376.395532)
			(xy 127.326456 -376.412715) (xy 127.332232 -376.419872) (xy 127.354099 -376.445535) (xy 127.392185 -376.50117)
			(xy 127.423334 -376.560967) (xy 127.447097 -376.624064) (xy 127.463131 -376.689553) (xy 127.471206 -376.756491)
			(xy 127.471206 -376.756551) (xy 130.74927 -376.756551) (xy 130.757314 -376.689729) (xy 130.773286 -376.624347)
			(xy 130.796958 -376.561343) (xy 130.827989 -376.501619) (xy 130.865937 -376.446032) (xy 130.887724 -376.42038)
			(xy 130.893514 -376.413231) (xy 130.900032 -376.396043) (xy 130.900424 -376.386852) (xy 130.900424 -375.893584)
			(xy 130.900016 -375.884397) (xy 130.8935 -375.867213) (xy 130.887724 -375.860056) (xy 130.865968 -375.834378)
			(xy 130.82802 -375.778795) (xy 130.796986 -375.719074) (xy 130.773312 -375.656073) (xy 130.757337 -375.590695)
			(xy 130.749291 -375.523875) (xy 130.749288 -375.456573) (xy 130.757329 -375.389753) (xy 130.773298 -375.324373)
			(xy 130.796966 -375.26137) (xy 130.827995 -375.201647) (xy 130.865939 -375.146061) (xy 130.887724 -375.120408)
			(xy 130.893502 -375.11325) (xy 130.900027 -375.096069) (xy 130.900424 -375.08688) (xy 130.900424 -374.928638)
			(xy 130.900895 -374.918471) (xy 130.908665 -374.899679) (xy 130.923036 -374.885294) (xy 130.941819 -374.877505)
			(xy 130.951986 -374.877076) (xy 131.668266 -374.877076) (xy 131.67844 -374.877493) (xy 131.697241 -374.885274)
			(xy 131.711629 -374.899662) (xy 131.719408 -374.918464) (xy 131.719828 -374.928638) (xy 131.719828 -375.08688)
			(xy 131.720241 -375.096067) (xy 131.726752 -375.113252) (xy 131.732528 -375.120408) (xy 131.754348 -375.146034)
			(xy 131.792298 -375.201623) (xy 131.823332 -375.26135) (xy 131.847005 -375.324358) (xy 131.862976 -375.389744)
			(xy 131.871018 -375.45657) (xy 131.871016 -375.523878) (xy 131.862968 -375.590704) (xy 131.84699 -375.656088)
			(xy 131.823313 -375.719094) (xy 131.792274 -375.778818) (xy 131.754319 -375.834404) (xy 131.732528 -375.860056)
			(xy 131.726716 -375.86719) (xy 131.720213 -375.884389) (xy 131.719828 -375.893584) (xy 131.719828 -376.386852)
			(xy 131.720255 -376.396037) (xy 131.726756 -376.413222) (xy 131.732528 -376.42038) (xy 131.754321 -376.446029)
			(xy 131.792271 -376.501615) (xy 131.823306 -376.561338) (xy 131.84698 -376.624344) (xy 131.862954 -376.689727)
			(xy 131.870991 -376.756492) (xy 161.548796 -376.756492) (xy 161.556871 -376.689554) (xy 161.572905 -376.624066)
			(xy 161.596667 -376.560969) (xy 161.627816 -376.501173) (xy 161.665902 -376.445538) (xy 161.687764 -376.419872)
			(xy 161.693563 -376.412729) (xy 161.700074 -376.395536) (xy 161.700464 -376.386344) (xy 161.700464 -375.894092)
			(xy 161.700043 -375.884906) (xy 161.693535 -375.867723) (xy 161.687764 -375.860564) (xy 161.665933 -375.834872)
			(xy 161.627845 -375.779241) (xy 161.596695 -375.719448) (xy 161.572931 -375.656354) (xy 161.556894 -375.590869)
			(xy 161.548816 -375.523934) (xy 161.548814 -375.456514) (xy 161.556886 -375.389578) (xy 161.572917 -375.324092)
			(xy 161.596676 -375.260996) (xy 161.627821 -375.201201) (xy 161.665903 -375.145566) (xy 161.687764 -375.1199)
			(xy 161.693551 -375.112748) (xy 161.70007 -375.095562) (xy 161.700464 -375.086372) (xy 161.700464 -374.928638)
			(xy 161.700959 -374.918511) (xy 161.708678 -374.899786) (xy 161.722963 -374.885428) (xy 161.741647 -374.877611)
			(xy 161.751772 -374.877076) (xy 162.468052 -374.877076) (xy 162.4782 -374.877561) (xy 162.496947 -374.885336)
			(xy 162.511271 -374.899713) (xy 162.518977 -374.918489) (xy 162.51936 -374.928638) (xy 162.51936 -375.086372)
			(xy 162.519793 -375.095557) (xy 162.526292 -375.112741) (xy 162.53206 -375.1199) (xy 162.553957 -375.145539)
			(xy 162.592047 -375.201176) (xy 162.623199 -375.260976) (xy 162.646963 -375.324076) (xy 162.662997 -375.389569)
			(xy 162.671071 -375.456511) (xy 162.671068 -375.523938) (xy 162.662989 -375.590879) (xy 162.646949 -375.65637)
			(xy 162.623179 -375.719468) (xy 162.592022 -375.779265) (xy 162.553927 -375.834899) (xy 162.53206 -375.860564)
			(xy 162.526249 -375.867699) (xy 162.519744 -375.884897) (xy 162.51936 -375.894092) (xy 162.51936 -376.386344)
			(xy 162.519758 -376.395532) (xy 162.526281 -376.412716) (xy 162.53206 -376.419872) (xy 162.553929 -376.445533)
			(xy 162.592021 -376.501167) (xy 162.623173 -376.560964) (xy 162.646939 -376.624061) (xy 162.662975 -376.689551)
			(xy 162.671052 -376.756491) (xy 162.671051 -376.823855) (xy 165.949092 -376.823855) (xy 165.949092 -376.756551)
			(xy 165.957136 -376.689728) (xy 165.973109 -376.624346) (xy 165.996782 -376.561342) (xy 166.027815 -376.501618)
			(xy 166.065764 -376.446032) (xy 166.087552 -376.42038) (xy 166.093346 -376.413233) (xy 166.099861 -376.396044)
			(xy 166.100252 -376.386852) (xy 166.100252 -375.893584) (xy 166.099838 -375.884397) (xy 166.093326 -375.867214)
			(xy 166.087552 -375.860056) (xy 166.065795 -375.834378) (xy 166.027845 -375.778796) (xy 165.996809 -375.719076)
			(xy 165.973134 -375.656075) (xy 165.957159 -375.590695) (xy 165.949112 -375.523875) (xy 165.949109 -375.456573)
			(xy 165.95715 -375.389752) (xy 165.97312 -375.324371) (xy 165.99679 -375.261368) (xy 166.02782 -375.201646)
			(xy 166.065766 -375.14606) (xy 166.087552 -375.120408) (xy 166.093334 -375.113253) (xy 166.099856 -375.09607)
			(xy 166.100252 -375.08688) (xy 166.100252 -374.928638) (xy 166.100695 -374.918467) (xy 166.10847 -374.899671)
			(xy 166.12285 -374.885284) (xy 166.141643 -374.8775) (xy 166.151814 -374.877076) (xy 166.868094 -374.877076)
			(xy 166.87827 -374.87747) (xy 166.897072 -374.88526) (xy 166.911458 -374.899655) (xy 166.919237 -374.918462)
			(xy 166.919656 -374.928638) (xy 166.919656 -375.08688) (xy 166.920085 -375.096065) (xy 166.926587 -375.113249)
			(xy 166.932356 -375.120408) (xy 166.954175 -375.146034) (xy 166.992124 -375.201624) (xy 167.023156 -375.261351)
			(xy 167.046827 -375.324359) (xy 167.062798 -375.389745) (xy 167.07084 -375.45657) (xy 167.070837 -375.523878)
			(xy 167.062789 -375.590703) (xy 167.046813 -375.656087) (xy 167.023136 -375.719093) (xy 166.992099 -375.778817)
			(xy 166.954146 -375.834404) (xy 166.932356 -375.860056) (xy 166.926548 -375.867193) (xy 166.920041 -375.88439)
			(xy 166.919656 -375.893584) (xy 166.919656 -376.386852) (xy 166.920099 -376.396035) (xy 166.926591 -376.41322)
			(xy 166.932356 -376.42038) (xy 166.954148 -376.446029) (xy 166.992097 -376.501616) (xy 167.02313 -376.56134)
			(xy 167.046803 -376.624345) (xy 167.062776 -376.689727) (xy 167.07082 -376.75655) (xy 167.07082 -376.823856)
			(xy 167.070813 -376.823915) (xy 170.34886 -376.823915) (xy 170.34886 -376.756491) (xy 170.356936 -376.689552)
			(xy 170.372972 -376.624063) (xy 170.396738 -376.560966) (xy 170.427891 -376.50117) (xy 170.465983 -376.445536)
			(xy 170.487848 -376.419872) (xy 170.493645 -376.412727) (xy 170.500158 -376.395536) (xy 170.500548 -376.386344)
			(xy 170.500548 -375.894092) (xy 170.500131 -375.884906) (xy 170.493621 -375.867722) (xy 170.487848 -375.860564)
			(xy 170.466014 -375.834874) (xy 170.427921 -375.779244) (xy 170.396766 -375.719452) (xy 170.372998 -375.656358)
			(xy 170.356959 -375.590871) (xy 170.34888 -375.523935) (xy 170.348877 -375.456513) (xy 170.35695 -375.389576)
			(xy 170.372984 -375.324088) (xy 170.396747 -375.260992) (xy 170.427896 -375.201197) (xy 170.465984 -375.145564)
			(xy 170.487848 -375.1199) (xy 170.493633 -375.112747) (xy 170.500153 -375.095562) (xy 170.500548 -375.086372)
			(xy 170.500548 -374.928638) (xy 170.501058 -374.918513) (xy 170.508775 -374.899791) (xy 170.523054 -374.885433)
			(xy 170.541734 -374.877614) (xy 170.551856 -374.877076) (xy 171.268136 -374.877076) (xy 171.278289 -374.877492)
			(xy 171.297038 -374.885295) (xy 171.311359 -374.899692) (xy 171.319062 -374.918482) (xy 171.319444 -374.928638)
			(xy 171.319444 -375.086372) (xy 171.31988 -375.095556) (xy 171.326377 -375.11274) (xy 171.332144 -375.1199)
			(xy 171.354041 -375.145538) (xy 171.392133 -375.201175) (xy 171.423285 -375.260975) (xy 171.44705 -375.324075)
			(xy 171.463085 -375.389568) (xy 171.471159 -375.45651) (xy 171.471156 -375.523938) (xy 171.463076 -375.590879)
			(xy 171.447036 -375.656371) (xy 171.423266 -375.719469) (xy 171.392108 -375.779266) (xy 171.354012 -375.8349)
			(xy 171.332144 -375.860564) (xy 171.326331 -375.867697) (xy 171.319828 -375.884897) (xy 171.319444 -375.894092)
			(xy 171.319444 -376.386344) (xy 171.319845 -376.395532) (xy 171.326366 -376.412716) (xy 171.332144 -376.419872)
			(xy 171.354014 -376.445533) (xy 171.392106 -376.501167) (xy 171.42326 -376.560963) (xy 171.447026 -376.624061)
			(xy 171.463063 -376.689551) (xy 171.47114 -376.75649) (xy 171.47114 -376.756551) (xy 174.749179 -376.756551)
			(xy 174.757223 -376.689728) (xy 174.773195 -376.624346) (xy 174.796868 -376.561342) (xy 174.8279 -376.501619)
			(xy 174.865848 -376.446032) (xy 174.887636 -376.42038) (xy 174.893428 -376.413232) (xy 174.899945 -376.396043)
			(xy 174.900336 -376.386852) (xy 174.900336 -375.893584) (xy 174.899926 -375.884397) (xy 174.893411 -375.867213)
			(xy 174.887636 -375.860056) (xy 174.86588 -375.834378) (xy 174.82793 -375.778795) (xy 174.796896 -375.719075)
			(xy 174.773222 -375.656074) (xy 174.757246 -375.590695) (xy 174.7492 -375.523875) (xy 174.749197 -375.456573)
			(xy 174.757238 -375.389752) (xy 174.773207 -375.324372) (xy 174.796876 -375.261369) (xy 174.827906 -375.201646)
			(xy 174.865851 -375.14606) (xy 174.887636 -375.120408) (xy 174.893416 -375.113251) (xy 174.89994 -375.096069)
			(xy 174.900336 -375.08688) (xy 174.900336 -374.928638) (xy 174.900795 -374.918469) (xy 174.908567 -374.899676)
			(xy 174.922942 -374.88529) (xy 174.941729 -374.877503) (xy 174.951898 -374.877076) (xy 175.668178 -374.877076)
			(xy 175.678353 -374.877483) (xy 175.697154 -374.885268) (xy 175.711541 -374.899659) (xy 175.71932 -374.918463)
			(xy 175.71974 -374.928638) (xy 175.71974 -375.08688) (xy 175.720173 -375.096064) (xy 175.726672 -375.113248)
			(xy 175.73244 -375.120408) (xy 175.75426 -375.146034) (xy 175.792209 -375.201624) (xy 175.823242 -375.261351)
			(xy 175.846914 -375.324359) (xy 175.862886 -375.389744) (xy 175.870928 -375.45657) (xy 175.870925 -375.523878)
			(xy 175.862877 -375.590703) (xy 175.8469 -375.656087) (xy 175.823223 -375.719093) (xy 175.792185 -375.778818)
			(xy 175.754231 -375.834404) (xy 175.73244 -375.860056) (xy 175.72663 -375.867191) (xy 175.720125 -375.88439)
			(xy 175.71974 -375.893584) (xy 175.71974 -376.386852) (xy 175.720186 -376.396035) (xy 175.726676 -376.413219)
			(xy 175.73244 -376.42038) (xy 175.754232 -376.446029) (xy 175.792182 -376.501615) (xy 175.823216 -376.561339)
			(xy 175.84689 -376.624344) (xy 175.862863 -376.689727) (xy 175.870907 -376.75655) (xy 175.870907 -376.823856)
			(xy 175.862862 -376.890679) (xy 175.846888 -376.956062) (xy 175.823214 -377.019066) (xy 175.792179 -377.07879)
			(xy 175.754228 -377.134376) (xy 175.73244 -377.160028) (xy 175.726642 -377.167172) (xy 175.72013 -377.184364)
			(xy 175.71974 -377.193556) (xy 175.71974 -377.35129) (xy 175.719328 -377.361464) (xy 175.711542 -377.380262)
			(xy 175.697152 -377.394648) (xy 175.678352 -377.40243) (xy 175.668178 -377.402852) (xy 174.951898 -377.402852)
			(xy 174.941725 -377.402438) (xy 174.922928 -377.39465) (xy 174.908543 -377.380262) (xy 174.90076 -377.361463)
			(xy 174.900336 -377.35129) (xy 174.900336 -377.193556) (xy 174.899939 -377.184368) (xy 174.893415 -377.167184)
			(xy 174.887636 -377.160028) (xy 174.865852 -377.134373) (xy 174.827903 -377.078787) (xy 174.79687 -377.019063)
			(xy 174.773197 -376.956059) (xy 174.757224 -376.890678) (xy 174.74918 -376.823855) (xy 174.749179 -376.756551)
			(xy 171.47114 -376.756551) (xy 171.471139 -376.823916) (xy 171.463062 -376.890855) (xy 171.447024 -376.956345)
			(xy 171.423257 -377.019442) (xy 171.392103 -377.079238) (xy 171.35401 -377.134872) (xy 171.332144 -377.160536)
			(xy 171.326343 -377.167678) (xy 171.319832 -377.184871) (xy 171.319444 -377.194064) (xy 171.319444 -377.35129)
			(xy 171.318965 -377.361418) (xy 171.311237 -377.380142) (xy 171.296948 -377.394499) (xy 171.278262 -377.402316)
			(xy 171.268136 -377.402852) (xy 170.551856 -377.402852) (xy 170.541706 -377.402415) (xy 170.522962 -377.394615)
			(xy 170.508642 -377.380224) (xy 170.500935 -377.361442) (xy 170.500548 -377.35129) (xy 170.500548 -377.194064)
			(xy 170.500144 -377.184876) (xy 170.493625 -377.167693) (xy 170.487848 -377.160536) (xy 170.465986 -377.134868)
			(xy 170.427894 -377.079235) (xy 170.396741 -377.01944) (xy 170.372974 -376.956343) (xy 170.356937 -376.890854)
			(xy 170.34886 -376.823915) (xy 167.070813 -376.823915) (xy 167.062775 -376.890679) (xy 167.046801 -376.956061)
			(xy 167.023128 -377.019066) (xy 166.992094 -377.07879) (xy 166.954144 -377.134376) (xy 166.932356 -377.160028)
			(xy 166.92656 -377.167173) (xy 166.920046 -377.184364) (xy 166.919656 -377.193556) (xy 166.919656 -377.35129)
			(xy 166.919228 -377.361462) (xy 166.911445 -377.380257) (xy 166.897061 -377.394643) (xy 166.878266 -377.402427)
			(xy 166.868094 -377.402852) (xy 166.151814 -377.402852) (xy 166.141642 -377.402425) (xy 166.122846 -377.394642)
			(xy 166.10846 -377.380258) (xy 166.100676 -377.361462) (xy 166.100252 -377.35129) (xy 166.100252 -377.193556)
			(xy 166.099851 -377.184368) (xy 166.09333 -377.167185) (xy 166.087552 -377.160028) (xy 166.065768 -377.134373)
			(xy 166.027818 -377.078787) (xy 165.996784 -377.019064) (xy 165.97311 -376.95606) (xy 165.957137 -376.890678)
			(xy 165.949092 -376.823855) (xy 162.671051 -376.823855) (xy 162.671051 -376.823915) (xy 162.662974 -376.890855)
			(xy 162.646937 -376.956344) (xy 162.623171 -377.019442) (xy 162.592017 -377.079238) (xy 162.553926 -377.134871)
			(xy 162.53206 -377.160536) (xy 162.526261 -377.167679) (xy 162.519749 -377.184871) (xy 162.51936 -377.194064)
			(xy 162.51936 -377.35129) (xy 162.518865 -377.361416) (xy 162.511141 -377.380137) (xy 162.496857 -377.394494)
			(xy 162.478175 -377.402313) (xy 162.468052 -377.402852) (xy 161.751772 -377.402852) (xy 161.741623 -377.402402)
			(xy 161.72288 -377.394607) (xy 161.708559 -377.38022) (xy 161.700851 -377.361441) (xy 161.700464 -377.35129)
			(xy 161.700464 -377.194064) (xy 161.700057 -377.184877) (xy 161.69354 -377.167693) (xy 161.687764 -377.160536)
			(xy 161.665905 -377.134867) (xy 161.627819 -377.079232) (xy 161.59667 -377.019436) (xy 161.572907 -376.95634)
			(xy 161.556872 -376.890852) (xy 161.548797 -376.823914) (xy 161.548796 -376.756492) (xy 131.870991 -376.756492)
			(xy 131.870998 -376.75655) (xy 131.870998 -376.823856) (xy 131.862953 -376.890679) (xy 131.846979 -376.956062)
			(xy 131.823304 -377.019067) (xy 131.792268 -377.07879) (xy 131.754317 -377.134376) (xy 131.732528 -377.160028)
			(xy 131.726728 -377.167171) (xy 131.720218 -377.184363) (xy 131.719828 -377.193556) (xy 131.719828 -377.35129)
			(xy 131.719427 -377.361465) (xy 131.711639 -377.380266) (xy 131.697246 -377.394653) (xy 131.678441 -377.402432)
			(xy 131.668266 -377.402852) (xy 130.951986 -377.402852) (xy 130.941826 -377.402378) (xy 130.923055 -377.394597)
			(xy 130.90869 -377.380225) (xy 130.900918 -377.36145) (xy 130.900424 -377.35129) (xy 130.900424 -377.193556)
			(xy 130.90003 -377.184367) (xy 130.893504 -377.167183) (xy 130.887724 -377.160028) (xy 130.865941 -377.134372)
			(xy 130.827993 -377.078786) (xy 130.79696 -377.019063) (xy 130.773288 -376.956059) (xy 130.757315 -376.890677)
			(xy 130.749271 -376.823855) (xy 130.74927 -376.756551) (xy 127.471206 -376.756551) (xy 127.471205 -376.823915)
			(xy 127.46313 -376.890853) (xy 127.447095 -376.956342) (xy 127.423332 -377.019438) (xy 127.392182 -377.079235)
			(xy 127.354095 -377.13487) (xy 127.332232 -377.160536) (xy 127.326429 -377.167677) (xy 127.31992 -377.184871)
			(xy 127.319532 -377.194064) (xy 127.319532 -377.35129) (xy 127.319064 -377.36142) (xy 127.311335 -377.380146)
			(xy 127.297042 -377.394503) (xy 127.278351 -377.402318) (xy 127.268224 -377.402852) (xy 126.551944 -377.402852)
			(xy 126.541799 -377.402343) (xy 126.523058 -377.394572) (xy 126.508735 -377.380202) (xy 126.501024 -377.361436)
			(xy 126.500636 -377.35129) (xy 126.500636 -377.194064) (xy 126.500235 -377.184876) (xy 126.493714 -377.167692)
			(xy 126.487936 -377.160536) (xy 126.466075 -377.134868) (xy 126.427984 -377.079235) (xy 126.396831 -377.019439)
			(xy 126.373065 -376.956343) (xy 126.357028 -376.890854) (xy 126.348951 -376.823915) (xy 123.070903 -376.823915)
			(xy 123.062865 -376.890679) (xy 123.046891 -376.956062) (xy 123.023217 -377.019066) (xy 122.992183 -377.07879)
			(xy 122.954232 -377.134376) (xy 122.932444 -377.160028) (xy 122.926646 -377.167172) (xy 122.920134 -377.184364)
			(xy 122.919744 -377.193556) (xy 122.919744 -377.35129) (xy 122.919328 -377.361463) (xy 122.911543 -377.380261)
			(xy 122.897154 -377.394647) (xy 122.878355 -377.402429) (xy 122.868182 -377.402852) (xy 122.151902 -377.402852)
			(xy 122.141729 -377.402434) (xy 122.122933 -377.394648) (xy 122.108547 -377.380261) (xy 122.100764 -377.361463)
			(xy 122.10034 -377.35129) (xy 122.10034 -377.193556) (xy 122.099942 -377.184368) (xy 122.093419 -377.167184)
			(xy 122.08764 -377.160028) (xy 122.065856 -377.134373) (xy 122.027907 -377.078787) (xy 121.996873 -377.019064)
			(xy 121.9732 -376.95606) (xy 121.957227 -376.890678) (xy 121.949183 -376.823855) (xy 121.949182 -376.756551)
			(xy 118.671143 -376.756551) (xy 118.671142 -376.823916) (xy 118.663065 -376.890855) (xy 118.647028 -376.956345)
			(xy 118.623261 -377.019442) (xy 118.592107 -377.079238) (xy 118.554014 -377.134872) (xy 118.532148 -377.160536)
			(xy 118.526347 -377.167678) (xy 118.519836 -377.184871) (xy 118.519448 -377.194064) (xy 118.519448 -377.35129)
			(xy 118.518965 -377.361418) (xy 118.511238 -377.380141) (xy 118.496951 -377.394498) (xy 118.478265 -377.402315)
			(xy 118.46814 -377.402852) (xy 117.75186 -377.402852) (xy 117.74171 -377.402412) (xy 117.722967 -377.394613)
			(xy 117.708647 -377.380223) (xy 117.700939 -377.361442) (xy 117.700552 -377.35129) (xy 117.700552 -377.194064)
			(xy 117.700147 -377.184876) (xy 117.693628 -377.167693) (xy 117.687852 -377.160536) (xy 117.66599 -377.134868)
			(xy 117.627898 -377.079235) (xy 117.596744 -377.01944) (xy 117.572977 -376.956343) (xy 117.55694 -376.890854)
			(xy 117.548863 -376.823915) (xy 87.871087 -376.823915) (xy 87.863011 -376.890853) (xy 87.846976 -376.956342)
			(xy 87.823211 -377.019439) (xy 87.792061 -377.079236) (xy 87.753972 -377.134871) (xy 87.732108 -377.160536)
			(xy 87.726315 -377.167684) (xy 87.719798 -377.184872) (xy 87.719408 -377.194064) (xy 87.719408 -377.35129)
			(xy 87.718867 -377.36141) (xy 87.711151 -377.380122) (xy 87.696882 -377.394477) (xy 87.678217 -377.402305)
			(xy 87.6681 -377.402852) (xy 86.95182 -377.402852) (xy 86.941674 -377.402363) (xy 86.922932 -377.394584)
			(xy 86.908609 -377.380209) (xy 86.9009 -377.361438) (xy 86.900512 -377.35129) (xy 86.900512 -377.194064)
			(xy 86.900117 -377.184875) (xy 86.893592 -377.167691) (xy 86.887812 -377.160536) (xy 86.865952 -377.134868)
			(xy 86.827862 -377.079234) (xy 86.79671 -377.019438) (xy 86.772945 -376.956342) (xy 86.756909 -376.890853)
			(xy 86.748833 -376.823915) (xy 83.470785 -376.823915) (xy 83.462747 -376.89068) (xy 83.446772 -376.956063)
			(xy 83.423097 -377.019067) (xy 83.392061 -377.078791) (xy 83.354109 -377.134376) (xy 83.33232 -377.160028)
			(xy 83.326531 -377.167179) (xy 83.320011 -377.184365) (xy 83.31962 -377.193556) (xy 83.31962 -377.35129)
			(xy 83.319227 -377.361466) (xy 83.311438 -377.380269) (xy 83.297042 -377.394655) (xy 83.278234 -377.402433)
			(xy 83.268058 -377.402852) (xy 82.551778 -377.402852) (xy 82.541618 -377.402385) (xy 82.522846 -377.394601)
			(xy 82.508481 -377.380227) (xy 82.500709 -377.361451) (xy 82.500216 -377.35129) (xy 82.500216 -377.193556)
			(xy 82.499823 -377.184367) (xy 82.493297 -377.167183) (xy 82.487516 -377.160028) (xy 82.465733 -377.134372)
			(xy 82.427785 -377.078786) (xy 82.396753 -377.019063) (xy 82.373081 -376.956059) (xy 82.357109 -376.890677)
			(xy 82.349065 -376.823855) (xy 82.349064 -376.756551) (xy 79.071 -376.756551) (xy 79.070999 -376.823915)
			(xy 79.062924 -376.890853) (xy 79.046888 -376.956342) (xy 79.023125 -377.019439) (xy 78.991975 -377.079235)
			(xy 78.953887 -377.13487) (xy 78.932024 -377.160536) (xy 78.926232 -377.167685) (xy 78.919714 -377.184872)
			(xy 78.919324 -377.194064) (xy 78.919324 -377.35129) (xy 78.918864 -377.36142) (xy 78.911133 -377.380148)
			(xy 78.896838 -377.394506) (xy 78.878144 -377.402319) (xy 78.868016 -377.402852) (xy 78.151736 -377.402852)
			(xy 78.141591 -377.40235) (xy 78.122849 -377.394576) (xy 78.108526 -377.380204) (xy 78.100816 -377.361437)
			(xy 78.100428 -377.35129) (xy 78.100428 -377.194064) (xy 78.100029 -377.184876) (xy 78.093507 -377.167692)
			(xy 78.087728 -377.160536) (xy 78.065867 -377.134868) (xy 78.027776 -377.079235) (xy 77.996624 -377.019439)
			(xy 77.972858 -376.956342) (xy 77.956822 -376.890853) (xy 77.948745 -376.823915) (xy 74.670697 -376.823915)
			(xy 74.662659 -376.890679) (xy 74.646685 -376.956062) (xy 74.623011 -377.019067) (xy 74.591976 -377.07879)
			(xy 74.554025 -377.134376) (xy 74.532236 -377.160028) (xy 74.526437 -377.167171) (xy 74.519926 -377.184364)
			(xy 74.519536 -377.193556) (xy 74.519536 -377.35129) (xy 74.519127 -377.361464) (xy 74.511341 -377.380264)
			(xy 74.49695 -377.39465) (xy 74.478148 -377.402431) (xy 74.467974 -377.402852) (xy 73.751694 -377.402852)
			(xy 73.741521 -377.402441) (xy 73.722724 -377.394652) (xy 73.708339 -377.380263) (xy 73.700556 -377.361463)
			(xy 73.700132 -377.35129) (xy 73.700132 -377.193556) (xy 73.699736 -377.184367) (xy 73.693212 -377.167184)
			(xy 73.687432 -377.160028) (xy 73.665648 -377.134373) (xy 73.6277 -377.078786) (xy 73.596667 -377.019063)
			(xy 73.572994 -376.956059) (xy 73.557021 -376.890677) (xy 73.548977 -376.823855) (xy 73.548976 -376.756551)
			(xy 48.270947 -376.756551) (xy 48.270947 -376.823855) (xy 48.262903 -376.890678) (xy 48.24693 -376.95606)
			(xy 48.223258 -377.019064) (xy 48.192226 -377.078788) (xy 48.154279 -377.134375) (xy 48.132492 -377.160028)
			(xy 48.1267 -377.167176) (xy 48.120183 -377.184365) (xy 48.119792 -377.193556) (xy 48.119792 -377.351544)
			(xy 48.119414 -377.361702) (xy 48.111603 -377.380457) (xy 48.097193 -377.394779) (xy 48.07839 -377.402476)
			(xy 48.06823 -377.402852) (xy 47.35195 -377.402852) (xy 47.341825 -377.402332) (xy 47.323104 -377.394619)
			(xy 47.308746 -377.380343) (xy 47.300926 -377.361666) (xy 47.300388 -377.351544) (xy 47.300388 -377.193556)
			(xy 47.300002 -377.184366) (xy 47.293472 -377.167182) (xy 47.287688 -377.160028) (xy 47.265903 -377.134373)
			(xy 47.227951 -377.078788) (xy 47.196914 -377.019066) (xy 47.173239 -376.956061) (xy 47.157265 -376.890679)
			(xy 47.149219 -376.823856) (xy 43.871178 -376.823856) (xy 43.871178 -376.823915) (xy 43.863102 -376.890854)
			(xy 43.847066 -376.956343) (xy 43.823301 -377.01944) (xy 43.79215 -377.079236) (xy 43.75406 -377.134871)
			(xy 43.732196 -377.160536) (xy 43.726401 -377.167682) (xy 43.719886 -377.184872) (xy 43.719496 -377.194064)
			(xy 43.719496 -377.35129) (xy 43.718966 -377.361412) (xy 43.711248 -377.380126) (xy 43.696976 -377.394481)
			(xy 43.678307 -377.402307) (xy 43.668188 -377.402852) (xy 42.951908 -377.402852) (xy 42.941761 -377.402373)
			(xy 42.923019 -377.39459) (xy 42.908697 -377.380211) (xy 42.900988 -377.361439) (xy 42.9006 -377.35129)
			(xy 42.9006 -377.194064) (xy 42.900207 -377.184875) (xy 42.893682 -377.167691) (xy 42.8879 -377.160536)
			(xy 42.86604 -377.134868) (xy 42.827951 -377.079233) (xy 42.7968 -377.019438) (xy 42.773036 -376.956341)
			(xy 42.757 -376.890853) (xy 42.748924 -376.823915) (xy 39.470876 -376.823915) (xy 39.462838 -376.89068)
			(xy 39.446863 -376.956063) (xy 39.423187 -377.019068) (xy 39.39215 -377.078791) (xy 39.354198 -377.134377)
			(xy 39.332408 -377.160028) (xy 39.326618 -377.167178) (xy 39.320099 -377.184365) (xy 39.319708 -377.193556)
			(xy 39.319708 -377.35129) (xy 39.31916 -377.361441) (xy 39.311397 -377.380202) (xy 39.297049 -377.394566)
			(xy 39.278297 -377.402349) (xy 39.268146 -377.402852) (xy 38.551866 -377.402852) (xy 38.541705 -377.402394)
			(xy 38.522933 -377.394607) (xy 38.508569 -377.38023) (xy 38.500797 -377.361452) (xy 38.500304 -377.35129)
			(xy 38.500304 -377.193556) (xy 38.499914 -377.184367) (xy 38.493386 -377.167183) (xy 38.487604 -377.160028)
			(xy 38.465821 -377.134372) (xy 38.427875 -377.078785) (xy 38.396843 -377.019062) (xy 38.373172 -376.956058)
			(xy 38.357199 -376.890677) (xy 38.349156 -376.823855) (xy 38.349155 -376.756551) (xy 35.071091 -376.756551)
			(xy 35.07109 -376.823915) (xy 35.063014 -376.890853) (xy 35.046979 -376.956342) (xy 35.023215 -377.019439)
			(xy 34.992064 -377.079236) (xy 34.953976 -377.134871) (xy 34.932112 -377.160536) (xy 34.926319 -377.167684)
			(xy 34.919802 -377.184872) (xy 34.919412 -377.194064) (xy 34.919412 -377.35129) (xy 34.918867 -377.36141)
			(xy 34.911152 -377.380121) (xy 34.896884 -377.394476) (xy 34.878221 -377.402304) (xy 34.868104 -377.402852)
			(xy 34.151824 -377.402852) (xy 34.141678 -377.40236) (xy 34.122936 -377.394582) (xy 34.108614 -377.380208)
			(xy 34.100904 -377.361438) (xy 34.100516 -377.35129) (xy 34.100516 -377.194064) (xy 34.10012 -377.184875)
			(xy 34.093596 -377.167691) (xy 34.087816 -377.160536) (xy 34.065955 -377.134868) (xy 34.027866 -377.079234)
			(xy 33.996714 -377.019438) (xy 33.972949 -376.956342) (xy 33.956912 -376.890853) (xy 33.948836 -376.823915)
			(xy 30.670788 -376.823915) (xy 30.66275 -376.89068) (xy 30.646775 -376.956062) (xy 30.6231 -377.019067)
			(xy 30.592065 -377.078791) (xy 30.554113 -377.134376) (xy 30.532324 -377.160028) (xy 30.526536 -377.167179)
			(xy 30.520015 -377.184365) (xy 30.519624 -377.193556) (xy 30.519624 -377.35129) (xy 30.519227 -377.361466)
			(xy 30.511438 -377.380267) (xy 30.497044 -377.394654) (xy 30.478238 -377.402433) (xy 30.468062 -377.402852)
			(xy 29.751782 -377.402852) (xy 29.741622 -377.402381) (xy 29.72285 -377.394599) (xy 29.708485 -377.380226)
			(xy 29.700713 -377.36145) (xy 29.70022 -377.35129) (xy 29.70022 -377.193556) (xy 29.699827 -377.184367)
			(xy 29.693301 -377.167183) (xy 29.68752 -377.160028) (xy 29.665737 -377.134372) (xy 29.627789 -377.078786)
			(xy 29.596757 -377.019063) (xy 29.573084 -376.956059) (xy 29.557112 -376.890677) (xy 29.549068 -376.823855)
			(xy 29.549067 -376.756551) (xy 1.524 -376.756551) (xy 1.524 -378.323793) (xy 27.348888 -378.323793)
			(xy 27.34889 -378.256368) (xy 27.356968 -378.189428) (xy 27.373006 -378.123938) (xy 27.396772 -378.06084)
			(xy 27.427925 -378.001043) (xy 27.466015 -377.945408) (xy 27.48788 -377.919742) (xy 27.493681 -377.9126)
			(xy 27.500194 -377.895407) (xy 27.50058 -377.886214) (xy 27.50058 -377.728734) (xy 27.501056 -377.718605)
			(xy 27.50878 -377.699877) (xy 27.52307 -377.685518) (xy 27.541761 -377.677705) (xy 27.551888 -377.677172)
			(xy 28.268168 -377.677172) (xy 28.278317 -377.677647) (xy 28.297063 -377.685427) (xy 28.311387 -377.699807)
			(xy 28.319092 -377.718584) (xy 28.319476 -377.728734) (xy 28.319476 -377.886214) (xy 28.319885 -377.895401)
			(xy 28.3264 -377.912585) (xy 28.332176 -377.919742) (xy 28.354015 -377.945428) (xy 28.392106 -378.001059)
			(xy 28.42326 -378.060852) (xy 28.447026 -378.123946) (xy 28.463064 -378.189433) (xy 28.471143 -378.256369)
			(xy 28.471145 -378.323734) (xy 31.749183 -378.323734) (xy 31.749186 -378.256427) (xy 31.757233 -378.189602)
			(xy 31.773209 -378.124218) (xy 31.796886 -378.061212) (xy 31.827924 -378.001488) (xy 31.865878 -377.945902)
			(xy 31.887668 -377.92025) (xy 31.893477 -377.913114) (xy 31.899982 -377.895916) (xy 31.900368 -377.886722)
			(xy 31.900368 -377.728734) (xy 31.900793 -377.718561) (xy 31.908572 -377.699761) (xy 31.922958 -377.685374)
			(xy 31.941757 -377.677593) (xy 31.95193 -377.677172) (xy 32.66821 -377.677172) (xy 32.678386 -377.677557)
			(xy 32.697188 -377.685351) (xy 32.711574 -377.699749) (xy 32.719352 -377.718557) (xy 32.719772 -377.728734)
			(xy 32.719772 -377.886722) (xy 32.720178 -377.89591) (xy 32.726695 -377.913094) (xy 32.732472 -377.92025)
			(xy 32.754234 -377.945924) (xy 32.792182 -378.001507) (xy 32.823216 -378.061228) (xy 32.84689 -378.12423)
			(xy 32.862864 -378.189609) (xy 32.87091 -378.256429) (xy 32.870913 -378.323732) (xy 32.870906 -378.323793)
			(xy 36.148976 -378.323793) (xy 36.148978 -378.256368) (xy 36.157056 -378.189429) (xy 36.173093 -378.123939)
			(xy 36.196859 -378.060841) (xy 36.22801 -378.001044) (xy 36.2661 -377.945408) (xy 36.287964 -377.919742)
			(xy 36.293775 -377.912608) (xy 36.300279 -377.895409) (xy 36.300664 -377.886214) (xy 36.300664 -377.728734)
			(xy 36.301155 -377.718607) (xy 36.308876 -377.699882) (xy 36.323162 -377.685523) (xy 36.341847 -377.677707)
			(xy 36.351972 -377.677172) (xy 37.068252 -377.677172) (xy 37.0784 -377.67766) (xy 37.097145 -377.685435)
			(xy 37.11147 -377.699811) (xy 37.119176 -377.718585) (xy 37.11956 -377.728734) (xy 37.11956 -377.886214)
			(xy 37.119972 -377.895401) (xy 37.126485 -377.912585) (xy 37.13226 -377.919742) (xy 37.1541 -377.945428)
			(xy 37.192192 -378.001058) (xy 37.223346 -378.060851) (xy 37.247113 -378.123946) (xy 37.263152 -378.189433)
			(xy 37.27123 -378.256369) (xy 37.271233 -378.323792) (xy 37.271233 -378.323794) (xy 40.548742 -378.323794)
			(xy 40.548744 -378.256367) (xy 40.556824 -378.189426) (xy 40.572863 -378.123935) (xy 40.596633 -378.060837)
			(xy 40.627789 -378.00104) (xy 40.665885 -377.945406) (xy 40.687752 -377.919742) (xy 40.693562 -377.912607)
			(xy 40.700067 -377.895408) (xy 40.700452 -377.886214) (xy 40.700452 -377.728734) (xy 40.700955 -377.718608)
			(xy 40.708674 -377.699885) (xy 40.722955 -377.685528) (xy 40.741637 -377.677709) (xy 40.75176 -377.677172)
			(xy 41.46804 -377.677172) (xy 41.478193 -377.677588) (xy 41.496941 -377.685392) (xy 41.511262 -377.699789)
			(xy 41.518965 -377.718579) (xy 41.519348 -377.728734) (xy 41.519348 -377.886214) (xy 41.519763 -377.8954)
			(xy 41.526275 -377.912584) (xy 41.532048 -377.919742) (xy 41.553888 -377.945427) (xy 41.591981 -378.001058)
			(xy 41.623136 -378.060851) (xy 41.646904 -378.123945) (xy 41.662943 -378.189432) (xy 41.671021 -378.256369)
			(xy 41.671024 -378.323792) (xy 41.671024 -378.323793) (xy 71.348797 -378.323793) (xy 71.348799 -378.256368)
			(xy 71.356877 -378.189428) (xy 71.372915 -378.123937) (xy 71.396682 -378.060839) (xy 71.427835 -378.001042)
			(xy 71.465927 -377.945407) (xy 71.487792 -377.919742) (xy 71.493595 -377.912601) (xy 71.500106 -377.895407)
			(xy 71.500492 -377.886214) (xy 71.500492 -377.728734) (xy 71.501053 -377.718615) (xy 71.508761 -377.699904)
			(xy 71.523024 -377.685548) (xy 71.541685 -377.67772) (xy 71.5518 -377.677172) (xy 72.26808 -377.677172)
			(xy 72.278229 -377.677637) (xy 72.296976 -377.685421) (xy 72.311299 -377.699804) (xy 72.319005 -377.718583)
			(xy 72.319388 -377.728734) (xy 72.319388 -377.886214) (xy 72.319794 -377.895402) (xy 72.326311 -377.912586)
			(xy 72.332088 -377.919742) (xy 72.353927 -377.945428) (xy 72.392017 -378.001059) (xy 72.42317 -378.060853)
			(xy 72.446936 -378.123947) (xy 72.462973 -378.189433) (xy 72.471052 -378.25637) (xy 72.471054 -378.323734)
			(xy 75.749092 -378.323734) (xy 75.749095 -378.256427) (xy 75.757142 -378.189601) (xy 75.773119 -378.124217)
			(xy 75.796796 -378.061212) (xy 75.827835 -378.001488) (xy 75.86579 -377.945902) (xy 75.88758 -377.92025)
			(xy 75.893378 -377.913106) (xy 75.899892 -377.895915) (xy 75.90028 -377.886722) (xy 75.90028 -377.728734)
			(xy 75.900693 -377.718559) (xy 75.908474 -377.699757) (xy 75.922864 -377.68537) (xy 75.941667 -377.677591)
			(xy 75.951842 -377.677172) (xy 76.668122 -377.677172) (xy 76.678299 -377.677547) (xy 76.697101 -377.685345)
			(xy 76.711486 -377.699746) (xy 76.719264 -377.718556) (xy 76.719684 -377.728734) (xy 76.719684 -377.886722)
			(xy 76.720087 -377.89591) (xy 76.726606 -377.913094) (xy 76.732384 -377.92025) (xy 76.754146 -377.945923)
			(xy 76.792094 -378.001507) (xy 76.823127 -378.061228) (xy 76.8468 -378.12423) (xy 76.862774 -378.189609)
			(xy 76.87082 -378.256429) (xy 76.870822 -378.323732) (xy 76.870815 -378.323793) (xy 80.148885 -378.323793)
			(xy 80.148887 -378.256368) (xy 80.156965 -378.189428) (xy 80.173003 -378.123938) (xy 80.196769 -378.06084)
			(xy 80.227921 -378.001043) (xy 80.266011 -377.945408) (xy 80.287876 -377.919742) (xy 80.293677 -377.9126)
			(xy 80.30019 -377.895407) (xy 80.300576 -377.886214) (xy 80.300576 -377.728734) (xy 80.301056 -377.718605)
			(xy 80.308779 -377.699878) (xy 80.323068 -377.685519) (xy 80.341758 -377.677705) (xy 80.351884 -377.677172)
			(xy 81.068164 -377.677172) (xy 81.078312 -377.677651) (xy 81.097058 -377.685429) (xy 81.111382 -377.699808)
			(xy 81.119088 -377.718584) (xy 81.119472 -377.728734) (xy 81.119472 -377.886214) (xy 81.119882 -377.895401)
			(xy 81.126396 -377.912585) (xy 81.132172 -377.919742) (xy 81.154011 -377.945428) (xy 81.192103 -378.001059)
			(xy 81.223256 -378.060852) (xy 81.247023 -378.123946) (xy 81.263061 -378.189433) (xy 81.27114 -378.256369)
			(xy 81.271142 -378.323792) (xy 81.271142 -378.323793) (xy 84.548676 -378.323793) (xy 84.548678 -378.256368)
			(xy 84.556756 -378.189429) (xy 84.572793 -378.123939) (xy 84.596559 -378.060841) (xy 84.62771 -378.001044)
			(xy 84.6658 -377.945408) (xy 84.687664 -377.919742) (xy 84.693475 -377.912608) (xy 84.699979 -377.895409)
			(xy 84.700364 -377.886214) (xy 84.700364 -377.728734) (xy 84.700855 -377.718607) (xy 84.708576 -377.699882)
			(xy 84.722862 -377.685523) (xy 84.741547 -377.677707) (xy 84.751672 -377.677172) (xy 85.467952 -377.677172)
			(xy 85.4781 -377.67766) (xy 85.496845 -377.685435) (xy 85.51117 -377.699811) (xy 85.518876 -377.718585)
			(xy 85.51926 -377.728734) (xy 85.51926 -377.886214) (xy 85.519672 -377.895401) (xy 85.526185 -377.912585)
			(xy 85.53196 -377.919742) (xy 85.5538 -377.945428) (xy 85.591892 -378.001058) (xy 85.623046 -378.060851)
			(xy 85.646813 -378.123946) (xy 85.662852 -378.189433) (xy 85.67093 -378.256369) (xy 85.670933 -378.323734)
			(xy 115.349234 -378.323734) (xy 115.349237 -378.256427) (xy 115.357283 -378.189603) (xy 115.373258 -378.12422)
			(xy 115.396932 -378.061215) (xy 115.427966 -378.00149) (xy 115.465916 -377.945903) (xy 115.487704 -377.92025)
			(xy 115.493505 -377.913108) (xy 115.500017 -377.895915) (xy 115.500404 -377.886722) (xy 115.500404 -377.728734)
			(xy 115.500961 -377.718583) (xy 115.508717 -377.699821) (xy 115.523064 -377.685456) (xy 115.541815 -377.677674)
			(xy 115.551966 -377.677172) (xy 116.268246 -377.677172) (xy 116.278411 -377.677597) (xy 116.297188 -377.685393)
			(xy 116.311552 -377.69978) (xy 116.319319 -377.718568) (xy 116.319808 -377.728734) (xy 116.319808 -377.886722)
			(xy 116.320206 -377.895911) (xy 116.326728 -377.913095) (xy 116.332508 -377.92025) (xy 116.354272 -377.945922)
			(xy 116.392225 -378.001505) (xy 116.423262 -378.061225) (xy 116.446939 -378.124227) (xy 116.462915 -378.189607)
			(xy 116.470962 -378.256428) (xy 116.470964 -378.323732) (xy 116.470957 -378.323793) (xy 119.749003 -378.323793)
			(xy 119.749005 -378.256368) (xy 119.757084 -378.189428) (xy 119.773122 -378.123937) (xy 119.796889 -378.060839)
			(xy 119.828043 -378.001042) (xy 119.866134 -377.945407) (xy 119.888 -377.919742) (xy 119.893804 -377.912602)
			(xy 119.900314 -377.895407) (xy 119.9007 -377.886214) (xy 119.9007 -377.728734) (xy 119.901253 -377.718614)
			(xy 119.908963 -377.699902) (xy 119.923228 -377.685546) (xy 119.941892 -377.677718) (xy 119.952008 -377.677172)
			(xy 120.668288 -377.677172) (xy 120.678438 -377.677631) (xy 120.697185 -377.685417) (xy 120.711507 -377.699802)
			(xy 120.719213 -377.718582) (xy 120.719596 -377.728734) (xy 120.719596 -377.886214) (xy 120.72 -377.895402)
			(xy 120.726518 -377.912586) (xy 120.732296 -377.919742) (xy 120.754135 -377.945428) (xy 120.792224 -378.00106)
			(xy 120.823376 -378.060853) (xy 120.847142 -378.123947) (xy 120.86318 -378.189434) (xy 120.871258 -378.25637)
			(xy 120.87126 -378.323734) (xy 124.149298 -378.323734) (xy 124.149301 -378.256426) (xy 124.157348 -378.189601)
			(xy 124.173325 -378.124217) (xy 124.197003 -378.061211) (xy 124.228042 -378.001487) (xy 124.265997 -377.945902)
			(xy 124.287788 -377.92025) (xy 124.293587 -377.913106) (xy 124.300101 -377.895915) (xy 124.300488 -377.886722)
			(xy 124.300488 -377.728734) (xy 124.300893 -377.718558) (xy 124.308676 -377.699755) (xy 124.323068 -377.685367)
			(xy 124.341874 -377.67759) (xy 124.35205 -377.677172) (xy 125.06833 -377.677172) (xy 125.078508 -377.67754)
			(xy 125.09731 -377.685341) (xy 125.111695 -377.699744) (xy 125.119473 -377.718556) (xy 125.119892 -377.728734)
			(xy 125.119892 -377.886722) (xy 125.120293 -377.89591) (xy 125.126813 -377.913094) (xy 125.132592 -377.92025)
			(xy 125.154353 -377.945924) (xy 125.192301 -378.001508) (xy 125.223334 -378.061229) (xy 125.247006 -378.12423)
			(xy 125.26298 -378.189609) (xy 125.271026 -378.256429) (xy 125.271028 -378.323732) (xy 125.271028 -378.323734)
			(xy 128.549089 -378.323734) (xy 128.549092 -378.256427) (xy 128.557139 -378.189602) (xy 128.573116 -378.124218)
			(xy 128.596793 -378.061212) (xy 128.627831 -378.001488) (xy 128.665786 -377.945902) (xy 128.687576 -377.92025)
			(xy 128.693374 -377.913105) (xy 128.699888 -377.895915) (xy 128.700276 -377.886722) (xy 128.700276 -377.728734)
			(xy 128.700693 -377.71856) (xy 128.708474 -377.699759) (xy 128.722862 -377.685371) (xy 128.741664 -377.677592)
			(xy 128.751838 -377.677172) (xy 129.468118 -377.677172) (xy 129.478295 -377.67755) (xy 129.497097 -377.685347)
			(xy 129.511482 -377.699747) (xy 129.51926 -377.718557) (xy 129.51968 -377.728734) (xy 129.51968 -377.886722)
			(xy 129.520084 -377.89591) (xy 129.526602 -377.913094) (xy 129.53238 -377.92025) (xy 129.554142 -377.945923)
			(xy 129.59209 -378.001507) (xy 129.623123 -378.061228) (xy 129.646797 -378.12423) (xy 129.662771 -378.189609)
			(xy 129.670817 -378.256429) (xy 129.670819 -378.323732) (xy 129.670819 -378.323734) (xy 159.349143 -378.323734)
			(xy 159.349146 -378.256427) (xy 159.357192 -378.189603) (xy 159.373167 -378.12422) (xy 159.396842 -378.061214)
			(xy 159.427877 -378.00149) (xy 159.465827 -377.945902) (xy 159.487616 -377.92025) (xy 159.493418 -377.913109)
			(xy 159.499929 -377.895915) (xy 159.500316 -377.886722) (xy 159.500316 -377.728734) (xy 159.500791 -377.718567)
			(xy 159.508561 -377.699778) (xy 159.522931 -377.685392) (xy 159.541712 -377.677602) (xy 159.551878 -377.677172)
			(xy 160.268158 -377.677172) (xy 160.278331 -377.677599) (xy 160.297131 -377.685377) (xy 160.311519 -377.699762)
			(xy 160.319299 -377.718561) (xy 160.31972 -377.728734) (xy 160.31972 -377.886722) (xy 160.320115 -377.895911)
			(xy 160.326639 -377.913095) (xy 160.33242 -377.92025) (xy 160.354183 -377.945923) (xy 160.392136 -378.001505)
			(xy 160.423172 -378.061226) (xy 160.446848 -378.124227) (xy 160.462824 -378.189608) (xy 160.470871 -378.256429)
			(xy 160.470874 -378.323732) (xy 160.470867 -378.323793) (xy 163.748912 -378.323793) (xy 163.748914 -378.256367)
			(xy 163.756993 -378.189427) (xy 163.773031 -378.123937) (xy 163.796799 -378.060839) (xy 163.827953 -378.001042)
			(xy 163.866046 -377.945407) (xy 163.887912 -377.919742) (xy 163.893717 -377.912603) (xy 163.900226 -377.895408)
			(xy 163.900612 -377.886214) (xy 163.900612 -377.728734) (xy 163.901154 -377.718613) (xy 163.908865 -377.699898)
			(xy 163.923134 -377.685542) (xy 163.941802 -377.677716) (xy 163.95192 -377.677172) (xy 164.6682 -377.677172)
			(xy 164.678351 -377.677621) (xy 164.697098 -377.685411) (xy 164.71142 -377.699799) (xy 164.719125 -377.718582)
			(xy 164.719508 -377.728734) (xy 164.719508 -377.886214) (xy 164.71991 -377.895402) (xy 164.726429 -377.912586)
			(xy 164.732208 -377.919742) (xy 164.754046 -377.945428) (xy 164.792135 -378.00106) (xy 164.823286 -378.060853)
			(xy 164.847052 -378.123948) (xy 164.863089 -378.189434) (xy 164.871167 -378.25637) (xy 164.871169 -378.323734)
			(xy 168.149231 -378.323734) (xy 168.149234 -378.256427) (xy 168.15728 -378.189604) (xy 168.173254 -378.12422)
			(xy 168.196928 -378.061215) (xy 168.227963 -378.00149) (xy 168.265912 -377.945903) (xy 168.2877 -377.92025)
			(xy 168.2935 -377.913107) (xy 168.300013 -377.895915) (xy 168.3004 -377.886722) (xy 168.3004 -377.728734)
			(xy 168.30096 -377.718583) (xy 168.308717 -377.699822) (xy 168.323062 -377.685457) (xy 168.341812 -377.677675)
			(xy 168.351962 -377.677172) (xy 169.068242 -377.677172) (xy 169.078407 -377.6776) (xy 169.097183 -377.685394)
			(xy 169.111548 -377.699781) (xy 169.119315 -377.718569) (xy 169.119804 -377.728734) (xy 169.119804 -377.886722)
			(xy 169.120203 -377.89591) (xy 169.126724 -377.913095) (xy 169.132504 -377.92025) (xy 169.154265 -377.945924)
			(xy 169.192212 -378.001508) (xy 169.223244 -378.061229) (xy 169.246916 -378.124231) (xy 169.26289 -378.18961)
			(xy 169.270935 -378.256429) (xy 169.270937 -378.323732) (xy 169.270937 -378.323734) (xy 172.548998 -378.323734)
			(xy 172.549001 -378.256426) (xy 172.557048 -378.189601) (xy 172.573025 -378.124217) (xy 172.596703 -378.061211)
			(xy 172.627742 -378.001487) (xy 172.665697 -377.945902) (xy 172.687488 -377.92025) (xy 172.693287 -377.913106)
			(xy 172.699801 -377.895915) (xy 172.700188 -377.886722) (xy 172.700188 -377.728734) (xy 172.700593 -377.718558)
			(xy 172.708376 -377.699755) (xy 172.722768 -377.685367) (xy 172.741574 -377.67759) (xy 172.75175 -377.677172)
			(xy 173.46803 -377.677172) (xy 173.478208 -377.67754) (xy 173.49701 -377.685341) (xy 173.511395 -377.699744)
			(xy 173.519173 -377.718556) (xy 173.519592 -377.728734) (xy 173.519592 -377.886722) (xy 173.519993 -377.89591)
			(xy 173.526513 -377.913094) (xy 173.532292 -377.92025) (xy 173.554053 -377.945924) (xy 173.592001 -378.001508)
			(xy 173.623034 -378.061229) (xy 173.646706 -378.12423) (xy 173.66268 -378.189609) (xy 173.670726 -378.256429)
			(xy 173.670728 -378.323732) (xy 173.662687 -378.390552) (xy 173.646718 -378.455932) (xy 173.623049 -378.518936)
			(xy 173.592021 -378.578659) (xy 173.554077 -378.634245) (xy 173.532292 -378.659898) (xy 173.526513 -378.667056)
			(xy 173.519988 -378.684237) (xy 173.519592 -378.693426) (xy 173.519592 -378.70003) (xy 190.444636 -378.70003)
			(xy 190.448637 -378.494991) (xy 190.460635 -378.290263) (xy 190.480612 -378.08616) (xy 190.508537 -377.882992)
			(xy 190.544367 -377.681068) (xy 190.588049 -377.480695) (xy 190.639515 -377.28218) (xy 190.698687 -377.085823)
			(xy 190.765475 -376.891925) (xy 190.839777 -376.70078) (xy 190.92148 -376.51268) (xy 191.010461 -376.327911)
			(xy 191.106582 -376.146754) (xy 191.209698 -375.969485) (xy 191.319652 -375.796375) (xy 191.436277 -375.627686)
			(xy 191.559394 -375.463676) (xy 191.688817 -375.304594) (xy 191.824347 -375.150683) (xy 191.96578 -375.002177)
			(xy 192.112899 -374.859302) (xy 192.26548 -374.722277) (xy 192.423292 -374.591308) (xy 192.586093 -374.466597)
			(xy 192.753636 -374.348332) (xy 192.925665 -374.236694) (xy 193.10192 -374.131853) (xy 193.28213 -374.033969)
			(xy 193.466022 -373.94319) (xy 193.653317 -373.859656) (xy 193.843727 -373.783492) (xy 194.036965 -373.714815)
			(xy 194.232735 -373.65373) (xy 194.430739 -373.60033) (xy 194.630675 -373.554696) (xy 194.83224 -373.516897)
			(xy 195.035126 -373.486991) (xy 195.239025 -373.465024) (xy 195.443625 -373.451029) (xy 195.648616 -373.445028)
			(xy 195.853685 -373.447028) (xy 196.058519 -373.457029) (xy 196.262807 -373.475013) (xy 196.466239 -373.500955)
			(xy 196.668503 -373.534813) (xy 196.869292 -373.576538) (xy 197.0683 -373.626064) (xy 197.265224 -373.683318)
			(xy 197.459765 -373.748211) (xy 197.651626 -373.820645) (xy 197.840514 -373.900509) (xy 198.026143 -373.987683)
			(xy 198.208229 -374.082032) (xy 198.386495 -374.183414) (xy 198.56067 -374.291674) (xy 198.730489 -374.406647)
			(xy 198.895692 -374.528158) (xy 199.056029 -374.656022) (xy 199.211255 -374.790045) (xy 199.361134 -374.930022)
			(xy 199.505437 -375.07574) (xy 199.643945 -375.226977) (xy 199.776447 -375.383504) (xy 199.902741 -375.54508)
			(xy 200.022634 -375.711461) (xy 200.135945 -375.882393) (xy 200.242501 -376.057616) (xy 200.342138 -376.236863)
			(xy 200.434707 -376.419861) (xy 200.520065 -376.606332) (xy 200.598083 -376.79599) (xy 200.668641 -376.988548)
			(xy 200.731633 -377.183713) (xy 200.786963 -377.381187) (xy 200.834546 -377.580669) (xy 200.874309 -377.781855)
			(xy 200.906193 -377.98444) (xy 200.930148 -378.188114) (xy 200.946139 -378.392568) (xy 200.95414 -378.597491)
			(xy 200.95464 -378.70003) (xy 200.95414 -378.802569) (xy 200.946139 -379.007492) (xy 200.930148 -379.211946)
			(xy 200.906193 -379.41562) (xy 200.874309 -379.618205) (xy 200.834546 -379.819391) (xy 200.786963 -380.018873)
			(xy 200.731633 -380.216347) (xy 200.668641 -380.411512) (xy 200.598083 -380.60407) (xy 200.520065 -380.793728)
			(xy 200.434707 -380.980199) (xy 200.342138 -381.163197) (xy 200.242501 -381.342444) (xy 200.135945 -381.517667)
			(xy 200.022634 -381.688599) (xy 199.902741 -381.85498) (xy 199.776447 -382.016556) (xy 199.643945 -382.173083)
			(xy 199.505437 -382.32432) (xy 199.361134 -382.470038) (xy 199.211255 -382.610015) (xy 199.056029 -382.744038)
			(xy 198.895692 -382.871902) (xy 198.730489 -382.993413) (xy 198.56067 -383.108386) (xy 198.386495 -383.216646)
			(xy 198.208229 -383.318028) (xy 198.026143 -383.412377) (xy 197.840514 -383.499551) (xy 197.651626 -383.579415)
			(xy 197.459765 -383.651849) (xy 197.265224 -383.716742) (xy 197.0683 -383.773996) (xy 196.869292 -383.823522)
			(xy 196.668503 -383.865247) (xy 196.466239 -383.899105) (xy 196.262807 -383.925047) (xy 196.058519 -383.943031)
			(xy 195.853685 -383.953032) (xy 195.648616 -383.955032) (xy 195.443625 -383.949031) (xy 195.239025 -383.935036)
			(xy 195.035126 -383.913069) (xy 194.83224 -383.883163) (xy 194.630675 -383.845364) (xy 194.430739 -383.79973)
			(xy 194.232735 -383.74633) (xy 194.036965 -383.685245) (xy 193.843727 -383.616568) (xy 193.653317 -383.540404)
			(xy 193.466022 -383.45687) (xy 193.28213 -383.366091) (xy 193.10192 -383.268207) (xy 192.925665 -383.163366)
			(xy 192.753636 -383.051728) (xy 192.586093 -382.933463) (xy 192.423292 -382.808752) (xy 192.26548 -382.677783)
			(xy 192.112899 -382.540758) (xy 191.96578 -382.397883) (xy 191.824347 -382.249377) (xy 191.688817 -382.095466)
			(xy 191.559394 -381.936384) (xy 191.436277 -381.772374) (xy 191.319652 -381.603685) (xy 191.209698 -381.430575)
			(xy 191.106582 -381.253306) (xy 191.010461 -381.072149) (xy 190.92148 -380.88738) (xy 190.839777 -380.69928)
			(xy 190.765475 -380.508135) (xy 190.698687 -380.314237) (xy 190.639515 -380.11788) (xy 190.588049 -379.919365)
			(xy 190.544367 -379.718992) (xy 190.508537 -379.517068) (xy 190.480612 -379.3139) (xy 190.460635 -379.109797)
			(xy 190.448637 -378.905069) (xy 190.444636 -378.70003) (xy 173.519592 -378.70003) (xy 173.519592 -379.186694)
			(xy 173.520007 -379.195881) (xy 173.526518 -379.213065) (xy 173.532292 -379.220222) (xy 173.554124 -379.245837)
			(xy 173.592069 -379.30143) (xy 173.623099 -379.361159) (xy 173.646768 -379.424168) (xy 173.662737 -379.489554)
			(xy 173.670777 -379.556381) (xy 173.670772 -379.623689) (xy 173.662724 -379.690514) (xy 173.646747 -379.755898)
			(xy 173.623071 -379.818905) (xy 173.592034 -379.87863) (xy 173.554082 -379.934217) (xy 173.532292 -379.95987)
			(xy 173.526482 -379.967006) (xy 173.519976 -379.984204) (xy 173.519592 -379.993398) (xy 173.519592 -380.151386)
			(xy 173.519056 -380.161539) (xy 173.511292 -380.180302) (xy 173.496939 -380.194667) (xy 173.478183 -380.202447)
			(xy 173.46803 -380.202948) (xy 172.75175 -380.202948) (xy 172.74158 -380.202495) (xy 172.722784 -380.194724)
			(xy 172.708396 -380.180347) (xy 172.700612 -380.161556) (xy 172.700188 -380.151386) (xy 172.700188 -379.993398)
			(xy 172.699781 -379.98421) (xy 172.693266 -379.967026) (xy 172.687488 -379.95987) (xy 172.665744 -379.934181)
			(xy 172.627791 -379.878601) (xy 172.596753 -379.818883) (xy 172.573075 -379.755883) (xy 172.557097 -379.690505)
			(xy 172.549049 -379.623686) (xy 172.549045 -379.556383) (xy 172.557085 -379.489563) (xy 172.573055 -379.424183)
			(xy 172.596724 -379.36118) (xy 172.627755 -379.301458) (xy 172.665702 -379.245873) (xy 172.687488 -379.220222)
			(xy 172.693299 -379.213087) (xy 172.699805 -379.195889) (xy 172.700188 -379.186694) (xy 172.700188 -378.693426)
			(xy 172.699768 -378.68424) (xy 172.693262 -378.667055) (xy 172.687488 -378.659898) (xy 172.665673 -378.634268)
			(xy 172.627722 -378.578679) (xy 172.596687 -378.518953) (xy 172.573014 -378.455946) (xy 172.557041 -378.39056)
			(xy 172.548998 -378.323734) (xy 169.270937 -378.323734) (xy 169.262897 -378.390552) (xy 169.246928 -378.455932)
			(xy 169.22326 -378.518935) (xy 169.192232 -378.578658) (xy 169.154289 -378.634245) (xy 169.132504 -378.659898)
			(xy 169.126726 -378.667057) (xy 169.1202 -378.684237) (xy 169.119804 -378.693426) (xy 169.119804 -379.186694)
			(xy 169.120216 -379.195881) (xy 169.126728 -379.213065) (xy 169.132504 -379.220222) (xy 169.154336 -379.245838)
			(xy 169.19228 -379.30143) (xy 169.223309 -379.361159) (xy 169.246977 -379.424169) (xy 169.262946 -379.489555)
			(xy 169.270986 -379.556381) (xy 169.270982 -379.623689) (xy 169.262933 -379.690513) (xy 169.246957 -379.755898)
			(xy 169.223281 -379.818904) (xy 169.192245 -379.878629) (xy 169.154293 -379.934217) (xy 169.132504 -379.95987)
			(xy 169.126696 -379.967007) (xy 169.120188 -379.984204) (xy 169.119804 -379.993398) (xy 169.119804 -380.151386)
			(xy 169.119256 -380.161538) (xy 169.111494 -380.180299) (xy 169.097146 -380.194663) (xy 169.078393 -380.202445)
			(xy 169.068242 -380.202948) (xy 168.351962 -380.202948) (xy 168.3418 -380.202497) (xy 168.323027 -380.194708)
			(xy 168.308663 -380.180329) (xy 168.300892 -380.161548) (xy 168.3004 -380.151386) (xy 168.3004 -379.993398)
			(xy 168.299991 -379.984211) (xy 168.293476 -379.967026) (xy 168.2877 -379.95987) (xy 168.265959 -379.93418)
			(xy 168.228011 -379.878598) (xy 168.196978 -379.818879) (xy 168.173304 -379.75588) (xy 168.157329 -379.690503)
			(xy 168.149282 -379.623685) (xy 168.149278 -379.556384) (xy 168.157317 -379.489565) (xy 168.173284 -379.424186)
			(xy 168.19695 -379.361184) (xy 168.227975 -379.301461) (xy 168.265916 -379.245875) (xy 168.2877 -379.220222)
			(xy 168.293512 -379.213088) (xy 168.300018 -379.195889) (xy 168.3004 -379.186694) (xy 168.3004 -378.693426)
			(xy 168.299977 -378.68424) (xy 168.293472 -378.667056) (xy 168.2877 -378.659898) (xy 168.265888 -378.634266)
			(xy 168.227942 -378.578676) (xy 168.196912 -378.518949) (xy 168.173243 -378.455942) (xy 168.157273 -378.390558)
			(xy 168.149231 -378.323734) (xy 164.871169 -378.323734) (xy 164.871169 -378.323791) (xy 164.863096 -378.390728)
			(xy 164.847063 -378.456215) (xy 164.823302 -378.519311) (xy 164.792155 -378.579106) (xy 164.75407 -378.634741)
			(xy 164.732208 -378.660406) (xy 164.726427 -378.667563) (xy 164.719903 -378.684744) (xy 164.719508 -378.693934)
			(xy 164.719508 -379.186186) (xy 164.719923 -379.195373) (xy 164.726433 -379.212557) (xy 164.732208 -379.219714)
			(xy 164.754117 -379.245342) (xy 164.792204 -379.300982) (xy 164.823352 -379.360784) (xy 164.847113 -379.423885)
			(xy 164.863145 -379.489379) (xy 164.871217 -379.556321) (xy 164.871213 -379.623748) (xy 164.863133 -379.690689)
			(xy 164.847093 -379.756181) (xy 164.823324 -379.81928) (xy 164.792168 -379.879077) (xy 164.754074 -379.934713)
			(xy 164.732208 -379.960378) (xy 164.726397 -379.967513) (xy 164.719891 -379.984711) (xy 164.719508 -379.993906)
			(xy 164.719508 -380.151386) (xy 164.718963 -380.161506) (xy 164.711249 -380.180218) (xy 164.696981 -380.194573)
			(xy 164.678317 -380.202401) (xy 164.6682 -380.202948) (xy 163.95192 -380.202948) (xy 163.941773 -380.202463)
			(xy 163.92303 -380.194683) (xy 163.908708 -380.180306) (xy 163.900999 -380.161534) (xy 163.900612 -380.151386)
			(xy 163.900612 -379.993906) (xy 163.900196 -379.98472) (xy 163.893686 -379.967535) (xy 163.887912 -379.960378)
			(xy 163.866093 -379.934676) (xy 163.828002 -379.879047) (xy 163.796849 -379.819256) (xy 163.773081 -379.756164)
			(xy 163.757042 -379.690679) (xy 163.748963 -379.623745) (xy 163.748958 -379.556324) (xy 163.75703 -379.489389)
			(xy 163.773061 -379.423902) (xy 163.79682 -379.360807) (xy 163.827966 -379.301013) (xy 163.86605 -379.245379)
			(xy 163.887912 -379.219714) (xy 163.893729 -379.212583) (xy 163.900231 -379.195382) (xy 163.900612 -379.186186)
			(xy 163.900612 -378.693934) (xy 163.900183 -378.684749) (xy 163.893682 -378.667565) (xy 163.887912 -378.660406)
			(xy 163.866022 -378.634762) (xy 163.827933 -378.579125) (xy 163.796783 -378.519326) (xy 163.77302 -378.456226)
			(xy 163.756986 -378.390734) (xy 163.748912 -378.323793) (xy 160.470867 -378.323793) (xy 160.462831 -378.390554)
			(xy 160.44686 -378.455935) (xy 160.423188 -378.518939) (xy 160.392156 -378.578661) (xy 160.354207 -378.634246)
			(xy 160.33242 -378.659898) (xy 160.326644 -378.667058) (xy 160.320116 -378.684237) (xy 160.31972 -378.693426)
			(xy 160.31972 -379.186694) (xy 160.320129 -379.195881) (xy 160.326643 -379.213066) (xy 160.33242 -379.220222)
			(xy 160.354254 -379.245836) (xy 160.392205 -379.301427) (xy 160.423238 -379.361156) (xy 160.44691 -379.424165)
			(xy 160.462881 -379.489552) (xy 160.470922 -379.55638) (xy 160.470918 -379.623689) (xy 160.462869 -379.690516)
			(xy 160.44689 -379.755901) (xy 160.42321 -379.818908) (xy 160.392169 -379.878632) (xy 160.354212 -379.934219)
			(xy 160.33242 -379.95987) (xy 160.326614 -379.967008) (xy 160.320104 -379.984204) (xy 160.31972 -379.993398)
			(xy 160.31972 -380.151386) (xy 160.319324 -380.161562) (xy 160.311536 -380.180364) (xy 160.297141 -380.194751)
			(xy 160.278334 -380.202529) (xy 160.268158 -380.202948) (xy 159.551878 -380.202948) (xy 159.541717 -380.202484)
			(xy 159.522945 -380.1947) (xy 159.50858 -380.180325) (xy 159.500808 -380.161547) (xy 159.500316 -380.151386)
			(xy 159.500316 -379.993398) (xy 159.499903 -379.984211) (xy 159.493391 -379.967027) (xy 159.487616 -379.95987)
			(xy 159.465874 -379.93418) (xy 159.427926 -379.878599) (xy 159.396892 -379.81888) (xy 159.373217 -379.75588)
			(xy 159.357242 -379.690503) (xy 159.349195 -379.623685) (xy 159.34919 -379.556384) (xy 159.35723 -379.489565)
			(xy 159.373197 -379.424186) (xy 159.396864 -379.361183) (xy 159.42789 -379.301461) (xy 159.465832 -379.245875)
			(xy 159.487616 -379.220222) (xy 159.49343 -379.213089) (xy 159.499934 -379.195889) (xy 159.500316 -379.186694)
			(xy 159.500316 -378.693426) (xy 159.49989 -378.684241) (xy 159.493387 -378.667056) (xy 159.487616 -378.659898)
			(xy 159.465803 -378.634267) (xy 159.427857 -378.578677) (xy 159.396826 -378.51895) (xy 159.373156 -378.455943)
			(xy 159.357185 -378.390558) (xy 159.349143 -378.323734) (xy 129.670819 -378.323734) (xy 129.662778 -378.390552)
			(xy 129.646808 -378.455933) (xy 129.623139 -378.518936) (xy 129.59211 -378.578659) (xy 129.554166 -378.634246)
			(xy 129.53238 -378.659898) (xy 129.526599 -378.667054) (xy 129.520076 -378.684236) (xy 129.51968 -378.693426)
			(xy 129.51968 -379.186694) (xy 129.520098 -379.19588) (xy 129.526607 -379.213064) (xy 129.53238 -379.220222)
			(xy 129.554212 -379.245837) (xy 129.592159 -379.301429) (xy 129.623189 -379.361158) (xy 129.646858 -379.424168)
			(xy 129.662827 -379.489554) (xy 129.670868 -379.55638) (xy 129.670863 -379.623689) (xy 129.662815 -379.690514)
			(xy 129.646838 -379.755899) (xy 129.623161 -379.818905) (xy 129.592123 -379.87863) (xy 129.55417 -379.934218)
			(xy 129.53238 -379.95987) (xy 129.526569 -379.967005) (xy 129.520064 -379.984203) (xy 129.51968 -379.993398)
			(xy 129.51968 -380.151386) (xy 129.519156 -380.161541) (xy 129.511389 -380.180306) (xy 129.497033 -380.194671)
			(xy 129.478272 -380.202449) (xy 129.468118 -380.202948) (xy 128.751838 -380.202948) (xy 128.741667 -380.202505)
			(xy 128.722871 -380.19473) (xy 128.708484 -380.18035) (xy 128.7007 -380.161557) (xy 128.700276 -380.151386)
			(xy 128.700276 -379.993398) (xy 128.699872 -379.98421) (xy 128.693355 -379.967025) (xy 128.687576 -379.95987)
			(xy 128.665832 -379.934181) (xy 128.62788 -379.878601) (xy 128.596842 -379.818883) (xy 128.573165 -379.755883)
			(xy 128.557188 -379.690505) (xy 128.54914 -379.623686) (xy 128.549136 -379.556384) (xy 128.557176 -379.489563)
			(xy 128.573145 -379.424183) (xy 128.596814 -379.361181) (xy 128.627844 -379.301459) (xy 128.66579 -379.245874)
			(xy 128.687576 -379.220222) (xy 128.693385 -379.213086) (xy 128.699893 -379.195889) (xy 128.700276 -379.186694)
			(xy 128.700276 -378.693426) (xy 128.699859 -378.684239) (xy 128.693351 -378.667055) (xy 128.687576 -378.659898)
			(xy 128.665762 -378.634267) (xy 128.627811 -378.578679) (xy 128.596777 -378.518952) (xy 128.573104 -378.455945)
			(xy 128.557132 -378.39056) (xy 128.549089 -378.323734) (xy 125.271028 -378.323734) (xy 125.262987 -378.390552)
			(xy 125.247018 -378.455932) (xy 125.223349 -378.518936) (xy 125.192321 -378.578659) (xy 125.154377 -378.634245)
			(xy 125.132592 -378.659898) (xy 125.126813 -378.667056) (xy 125.120288 -378.684237) (xy 125.119892 -378.693426)
			(xy 125.119892 -379.186694) (xy 125.120307 -379.195881) (xy 125.126818 -379.213065) (xy 125.132592 -379.220222)
			(xy 125.154424 -379.245837) (xy 125.192369 -379.30143) (xy 125.223399 -379.361159) (xy 125.247068 -379.424168)
			(xy 125.263037 -379.489554) (xy 125.271077 -379.556381) (xy 125.271072 -379.623689) (xy 125.263024 -379.690514)
			(xy 125.247047 -379.755898) (xy 125.223371 -379.818905) (xy 125.192334 -379.87863) (xy 125.154382 -379.934217)
			(xy 125.132592 -379.95987) (xy 125.126782 -379.967006) (xy 125.120276 -379.984204) (xy 125.119892 -379.993398)
			(xy 125.119892 -380.151386) (xy 125.119356 -380.161539) (xy 125.111592 -380.180302) (xy 125.097239 -380.194667)
			(xy 125.078483 -380.202447) (xy 125.06833 -380.202948) (xy 124.35205 -380.202948) (xy 124.34188 -380.202495)
			(xy 124.323084 -380.194724) (xy 124.308696 -380.180347) (xy 124.300912 -380.161556) (xy 124.300488 -380.151386)
			(xy 124.300488 -379.993398) (xy 124.300081 -379.98421) (xy 124.293566 -379.967026) (xy 124.287788 -379.95987)
			(xy 124.266044 -379.934181) (xy 124.228091 -379.878601) (xy 124.197053 -379.818883) (xy 124.173375 -379.755883)
			(xy 124.157397 -379.690505) (xy 124.149349 -379.623686) (xy 124.149345 -379.556383) (xy 124.157385 -379.489563)
			(xy 124.173355 -379.424183) (xy 124.197024 -379.36118) (xy 124.228055 -379.301458) (xy 124.266002 -379.245873)
			(xy 124.287788 -379.220222) (xy 124.293599 -379.213087) (xy 124.300105 -379.195889) (xy 124.300488 -379.186694)
			(xy 124.300488 -378.693426) (xy 124.300068 -378.68424) (xy 124.293562 -378.667055) (xy 124.287788 -378.659898)
			(xy 124.265973 -378.634268) (xy 124.228022 -378.578679) (xy 124.196987 -378.518953) (xy 124.173314 -378.455946)
			(xy 124.157341 -378.39056) (xy 124.149298 -378.323734) (xy 120.87126 -378.323734) (xy 120.87126 -378.323791)
			(xy 120.863187 -378.390728) (xy 120.847154 -378.456216) (xy 120.823392 -378.519311) (xy 120.792244 -378.579107)
			(xy 120.754159 -378.634741) (xy 120.732296 -378.660406) (xy 120.726514 -378.667561) (xy 120.719991 -378.684744)
			(xy 120.719596 -378.693934) (xy 120.719596 -379.186186) (xy 120.720014 -379.195372) (xy 120.726522 -379.212557)
			(xy 120.732296 -379.219714) (xy 120.754205 -379.245342) (xy 120.792293 -379.300982) (xy 120.823442 -379.360783)
			(xy 120.847204 -379.423885) (xy 120.863236 -379.489378) (xy 120.871308 -379.556321) (xy 120.871304 -379.623748)
			(xy 120.863224 -379.69069) (xy 120.847183 -379.756181) (xy 120.823414 -379.81928) (xy 120.792257 -379.879078)
			(xy 120.754163 -379.934713) (xy 120.732296 -379.960378) (xy 120.726483 -379.967512) (xy 120.719978 -379.984711)
			(xy 120.719596 -379.993906) (xy 120.719596 -380.151386) (xy 120.719063 -380.161507) (xy 120.711347 -380.180221)
			(xy 120.697075 -380.194577) (xy 120.678406 -380.202403) (xy 120.668288 -380.202948) (xy 119.952008 -380.202948)
			(xy 119.94186 -380.202473) (xy 119.923117 -380.194689) (xy 119.908795 -380.180309) (xy 119.901087 -380.161535)
			(xy 119.9007 -380.151386) (xy 119.9007 -379.993906) (xy 119.900287 -379.984719) (xy 119.893775 -379.967535)
			(xy 119.888 -379.960378) (xy 119.866181 -379.934675) (xy 119.828091 -379.879046) (xy 119.796938 -379.819255)
			(xy 119.773172 -379.756163) (xy 119.757133 -379.690679) (xy 119.749053 -379.623745) (xy 119.749049 -379.556325)
			(xy 119.757121 -379.489389) (xy 119.773151 -379.423903) (xy 119.79691 -379.360808) (xy 119.828056 -379.301013)
			(xy 119.866139 -379.245379) (xy 119.888 -379.219714) (xy 119.893816 -379.212582) (xy 119.900319 -379.195381)
			(xy 119.9007 -379.186186) (xy 119.9007 -378.693934) (xy 119.900273 -378.684749) (xy 119.893771 -378.667564)
			(xy 119.888 -378.660406) (xy 119.86611 -378.634762) (xy 119.828023 -378.579124) (xy 119.796873 -378.519325)
			(xy 119.77311 -378.456226) (xy 119.757077 -378.390734) (xy 119.749003 -378.323793) (xy 116.470957 -378.323793)
			(xy 116.462922 -378.390554) (xy 116.44695 -378.455936) (xy 116.423278 -378.518939) (xy 116.392245 -378.578662)
			(xy 116.354296 -378.634247) (xy 116.332508 -378.659898) (xy 116.326731 -378.667057) (xy 116.320204 -378.684237)
			(xy 116.319808 -378.693426) (xy 116.319808 -379.186694) (xy 116.320219 -379.195881) (xy 116.326732 -379.213066)
			(xy 116.332508 -379.220222) (xy 116.354343 -379.245836) (xy 116.392293 -379.301427) (xy 116.423328 -379.361155)
			(xy 116.447 -379.424165) (xy 116.462971 -379.489552) (xy 116.471013 -379.55638) (xy 116.471009 -379.623689)
			(xy 116.462959 -379.690516) (xy 116.44698 -379.755901) (xy 116.423299 -379.818908) (xy 116.392258 -379.878633)
			(xy 116.3543 -379.934219) (xy 116.332508 -379.95987) (xy 116.3267 -379.967007) (xy 116.320192 -379.984204)
			(xy 116.319808 -379.993398) (xy 116.319808 -380.151386) (xy 116.319256 -380.161537) (xy 116.311495 -380.180297)
			(xy 116.297148 -380.194661) (xy 116.278397 -380.202445) (xy 116.268246 -380.202948) (xy 115.551966 -380.202948)
			(xy 115.541804 -380.202494) (xy 115.523032 -380.194706) (xy 115.508667 -380.180328) (xy 115.500896 -380.161548)
			(xy 115.500404 -380.151386) (xy 115.500404 -379.993398) (xy 115.499994 -379.984211) (xy 115.49348 -379.967027)
			(xy 115.487704 -379.95987) (xy 115.465963 -379.93418) (xy 115.428015 -379.878598) (xy 115.396981 -379.81888)
			(xy 115.373307 -379.75588) (xy 115.357332 -379.690503) (xy 115.349285 -379.623685) (xy 115.349281 -379.556384)
			(xy 115.35732 -379.489565) (xy 115.373287 -379.424186) (xy 115.396953 -379.361184) (xy 115.427979 -379.301461)
			(xy 115.46592 -379.245875) (xy 115.487704 -379.220222) (xy 115.493517 -379.213088) (xy 115.500022 -379.195889)
			(xy 115.500404 -379.186694) (xy 115.500404 -378.693426) (xy 115.49998 -378.68424) (xy 115.493476 -378.667056)
			(xy 115.487704 -378.659898) (xy 115.465892 -378.634266) (xy 115.427946 -378.578676) (xy 115.396916 -378.518949)
			(xy 115.373246 -378.455942) (xy 115.357276 -378.390558) (xy 115.349234 -378.323734) (xy 85.670933 -378.323734)
			(xy 85.670933 -378.323792) (xy 85.662859 -378.390729) (xy 85.646825 -378.456217) (xy 85.623062 -378.519313)
			(xy 85.591912 -378.579108) (xy 85.553824 -378.634741) (xy 85.53196 -378.660406) (xy 85.526173 -378.667558)
			(xy 85.519654 -378.684743) (xy 85.51926 -378.693934) (xy 85.51926 -379.186186) (xy 85.519686 -379.195371)
			(xy 85.526189 -379.212555) (xy 85.53196 -379.219714) (xy 85.553871 -379.245341) (xy 85.591961 -379.30098)
			(xy 85.623111 -379.360781) (xy 85.646875 -379.423883) (xy 85.662908 -379.489377) (xy 85.670981 -379.55632)
			(xy 85.670977 -379.623749) (xy 85.662896 -379.690691) (xy 85.646854 -379.756183) (xy 85.623083 -379.819282)
			(xy 85.591925 -379.879079) (xy 85.553828 -379.934713) (xy 85.53196 -379.960378) (xy 85.526143 -379.967508)
			(xy 85.519641 -379.98471) (xy 85.51926 -379.993906) (xy 85.51926 -380.151386) (xy 85.518762 -380.161512)
			(xy 85.511039 -380.180233) (xy 85.496756 -380.194589) (xy 85.478075 -380.202409) (xy 85.467952 -380.202948)
			(xy 84.751672 -380.202948) (xy 84.741522 -380.202502) (xy 84.722778 -380.194707) (xy 84.708458 -380.180318)
			(xy 84.70075 -380.161538) (xy 84.700364 -380.151386) (xy 84.700364 -379.993906) (xy 84.699937 -379.984721)
			(xy 84.693433 -379.967537) (xy 84.687664 -379.960378) (xy 84.665846 -379.934675) (xy 84.627759 -379.879045)
			(xy 84.596608 -379.819254) (xy 84.572843 -379.756162) (xy 84.556805 -379.690678) (xy 84.548726 -379.623744)
			(xy 84.548722 -379.556325) (xy 84.556793 -379.48939) (xy 84.572822 -379.423904) (xy 84.59658 -379.36081)
			(xy 84.627723 -379.301014) (xy 84.665804 -379.24538) (xy 84.687664 -379.219714) (xy 84.693487 -379.212588)
			(xy 84.699984 -379.195383) (xy 84.700364 -379.186186) (xy 84.700364 -378.693934) (xy 84.699923 -378.68475)
			(xy 84.693429 -378.667566) (xy 84.687664 -378.660406) (xy 84.665776 -378.634761) (xy 84.62769 -378.579123)
			(xy 84.596543 -378.519324) (xy 84.572781 -378.456224) (xy 84.556749 -378.390733) (xy 84.548676 -378.323793)
			(xy 81.271142 -378.323793) (xy 81.263068 -378.390729) (xy 81.247035 -378.456217) (xy 81.223272 -378.519312)
			(xy 81.192123 -378.579108) (xy 81.154035 -378.634741) (xy 81.132172 -378.660406) (xy 81.126387 -378.667559)
			(xy 81.119866 -378.684744) (xy 81.119472 -378.693934) (xy 81.119472 -379.186186) (xy 81.119895 -379.195372)
			(xy 81.126401 -379.212556) (xy 81.132172 -379.219714) (xy 81.154082 -379.245341) (xy 81.192171 -379.300981)
			(xy 81.223322 -379.360782) (xy 81.247084 -379.423884) (xy 81.263118 -379.489378) (xy 81.27119 -379.556321)
			(xy 81.271186 -379.623748) (xy 81.263105 -379.69069) (xy 81.247064 -379.756182) (xy 81.223293 -379.819281)
			(xy 81.192136 -379.879079) (xy 81.15404 -379.934713) (xy 81.132172 -379.960378) (xy 81.126356 -379.967509)
			(xy 81.119854 -379.984711) (xy 81.119472 -379.993906) (xy 81.119472 -380.151386) (xy 81.118962 -380.16151)
			(xy 81.111241 -380.180229) (xy 81.096962 -380.194585) (xy 81.078286 -380.202407) (xy 81.068164 -380.202948)
			(xy 80.351884 -380.202948) (xy 80.341735 -380.202493) (xy 80.322991 -380.194701) (xy 80.30867 -380.180315)
			(xy 80.300962 -380.161537) (xy 80.300576 -380.151386) (xy 80.300576 -379.993906) (xy 80.300168 -379.984718)
			(xy 80.293654 -379.967534) (xy 80.287876 -379.960378) (xy 80.266058 -379.934675) (xy 80.22797 -379.879045)
			(xy 80.196818 -379.819254) (xy 80.173052 -379.756162) (xy 80.157015 -379.690678) (xy 80.148935 -379.623744)
			(xy 80.148931 -379.556325) (xy 80.157002 -379.48939) (xy 80.173032 -379.423904) (xy 80.19679 -379.360809)
			(xy 80.227934 -379.301014) (xy 80.266016 -379.24538) (xy 80.287876 -379.219714) (xy 80.293689 -379.21258)
			(xy 80.300195 -379.195381) (xy 80.300576 -379.186186) (xy 80.300576 -378.693934) (xy 80.300155 -378.684748)
			(xy 80.29365 -378.667563) (xy 80.287876 -378.660406) (xy 80.265987 -378.634761) (xy 80.227901 -378.579123)
			(xy 80.196753 -378.519324) (xy 80.172991 -378.456225) (xy 80.156958 -378.390733) (xy 80.148885 -378.323793)
			(xy 76.870815 -378.323793) (xy 76.862781 -378.390552) (xy 76.846812 -378.455933) (xy 76.823143 -378.518936)
			(xy 76.792114 -378.578659) (xy 76.75417 -378.634246) (xy 76.732384 -378.659898) (xy 76.726604 -378.667055)
			(xy 76.72008 -378.684236) (xy 76.719684 -378.693426) (xy 76.719684 -379.186694) (xy 76.720101 -379.19588)
			(xy 76.72661 -379.213065) (xy 76.732384 -379.220222) (xy 76.754216 -379.245837) (xy 76.792162 -379.30143)
			(xy 76.823192 -379.361158) (xy 76.846861 -379.424168) (xy 76.86283 -379.489554) (xy 76.870871 -379.55638)
			(xy 76.870866 -379.623689) (xy 76.862818 -379.690514) (xy 76.846841 -379.755899) (xy 76.823164 -379.818905)
			(xy 76.792127 -379.87863) (xy 76.754174 -379.934218) (xy 76.732384 -379.95987) (xy 76.726573 -379.967005)
			(xy 76.720068 -379.984203) (xy 76.719684 -379.993398) (xy 76.719684 -380.151386) (xy 76.719156 -380.16154)
			(xy 76.71139 -380.180305) (xy 76.697035 -380.19467) (xy 76.678276 -380.202449) (xy 76.668122 -380.202948)
			(xy 75.951842 -380.202948) (xy 75.941671 -380.202501) (xy 75.922875 -380.194728) (xy 75.908488 -380.180349)
			(xy 75.900704 -380.161556) (xy 75.90028 -380.151386) (xy 75.90028 -379.993398) (xy 75.899875 -379.98421)
			(xy 75.893358 -379.967026) (xy 75.88758 -379.95987) (xy 75.865836 -379.934181) (xy 75.827883 -379.878601)
			(xy 75.796846 -379.818883) (xy 75.773169 -379.755883) (xy 75.757191 -379.690505) (xy 75.749143 -379.623686)
			(xy 75.749139 -379.556383) (xy 75.757179 -379.489563) (xy 75.773148 -379.424183) (xy 75.796818 -379.36118)
			(xy 75.827848 -379.301458) (xy 75.865794 -379.245874) (xy 75.88758 -379.220222) (xy 75.89339 -379.213086)
			(xy 75.899897 -379.195889) (xy 75.90028 -379.186694) (xy 75.90028 -378.693426) (xy 75.899862 -378.68424)
			(xy 75.893354 -378.667055) (xy 75.88758 -378.659898) (xy 75.865766 -378.634267) (xy 75.827815 -378.578679)
			(xy 75.79678 -378.518953) (xy 75.773107 -378.455945) (xy 75.757135 -378.39056) (xy 75.749092 -378.323734)
			(xy 72.471054 -378.323734) (xy 72.471054 -378.323791) (xy 72.46298 -378.390728) (xy 72.446947 -378.456216)
			(xy 72.423186 -378.519312) (xy 72.392037 -378.579107) (xy 72.353951 -378.634741) (xy 72.332088 -378.660406)
			(xy 72.326305 -378.667561) (xy 72.319783 -378.684744) (xy 72.319388 -378.693934) (xy 72.319388 -379.186186)
			(xy 72.319808 -379.195372) (xy 72.326315 -379.212556) (xy 72.332088 -379.219714) (xy 72.353998 -379.245342)
			(xy 72.392086 -379.300981) (xy 72.423235 -379.360783) (xy 72.446997 -379.423884) (xy 72.46303 -379.489378)
			(xy 72.471102 -379.556321) (xy 72.471098 -379.623748) (xy 72.463017 -379.69069) (xy 72.446977 -379.756182)
			(xy 72.423207 -379.819281) (xy 72.39205 -379.879078) (xy 72.353955 -379.934713) (xy 72.332088 -379.960378)
			(xy 72.326274 -379.967511) (xy 72.31977 -379.984711) (xy 72.319388 -379.993906) (xy 72.319388 -380.151386)
			(xy 72.318863 -380.161508) (xy 72.311145 -380.180224) (xy 72.296871 -380.19458) (xy 72.278199 -380.202404)
			(xy 72.26808 -380.202948) (xy 71.5518 -380.202948) (xy 71.541652 -380.202479) (xy 71.522909 -380.194693)
			(xy 71.508587 -380.180311) (xy 71.500879 -380.161536) (xy 71.500492 -380.151386) (xy 71.500492 -379.993906)
			(xy 71.500081 -379.984719) (xy 71.493568 -379.967534) (xy 71.487792 -379.960378) (xy 71.465974 -379.934675)
			(xy 71.427884 -379.879046) (xy 71.396732 -379.819255) (xy 71.372965 -379.756163) (xy 71.356927 -379.690678)
			(xy 71.348847 -379.623744) (xy 71.348843 -379.556325) (xy 71.356914 -379.48939) (xy 71.372945 -379.423903)
			(xy 71.396703 -379.360808) (xy 71.427848 -379.301013) (xy 71.465931 -379.245379) (xy 71.487792 -379.219714)
			(xy 71.493607 -379.212582) (xy 71.500111 -379.195381) (xy 71.500492 -379.186186) (xy 71.500492 -378.693934)
			(xy 71.500067 -378.684748) (xy 71.493564 -378.667564) (xy 71.487792 -378.660406) (xy 71.465903 -378.634762)
			(xy 71.427815 -378.579124) (xy 71.396666 -378.519325) (xy 71.372904 -378.456225) (xy 71.35687 -378.390734)
			(xy 71.348797 -378.323793) (xy 41.671024 -378.323793) (xy 41.66295 -378.390729) (xy 41.646915 -378.456218)
			(xy 41.623152 -378.519314) (xy 41.592001 -378.579109) (xy 41.553912 -378.634742) (xy 41.532048 -378.660406)
			(xy 41.52626 -378.667557) (xy 41.519742 -378.684743) (xy 41.519348 -378.693934) (xy 41.519348 -379.186186)
			(xy 41.519776 -379.195371) (xy 41.526279 -379.212555) (xy 41.532048 -379.219714) (xy 41.553959 -379.245341)
			(xy 41.59205 -379.30098) (xy 41.623201 -379.360781) (xy 41.646965 -379.423883) (xy 41.662999 -379.489377)
			(xy 41.671072 -379.55632) (xy 41.671068 -379.623749) (xy 41.662987 -379.690691) (xy 41.646945 -379.756183)
			(xy 41.623173 -379.819282) (xy 41.592014 -379.879079) (xy 41.553917 -379.934714) (xy 41.532048 -379.960378)
			(xy 41.526229 -379.967507) (xy 41.519729 -379.98471) (xy 41.519348 -379.993906) (xy 41.519348 -380.151386)
			(xy 41.518862 -380.161513) (xy 41.511136 -380.180236) (xy 41.49685 -380.194594) (xy 41.478165 -380.202411)
			(xy 41.46804 -380.202948) (xy 40.75176 -380.202948) (xy 40.741609 -380.202512) (xy 40.722865 -380.194712)
			(xy 40.708545 -380.180321) (xy 40.700838 -380.161539) (xy 40.700452 -380.151386) (xy 40.700452 -379.993906)
			(xy 40.700027 -379.984721) (xy 40.693523 -379.967537) (xy 40.687752 -379.960378) (xy 40.665931 -379.934676)
			(xy 40.627838 -379.879048) (xy 40.596682 -379.819258) (xy 40.572913 -379.756165) (xy 40.556873 -379.69068)
			(xy 40.548793 -379.623745) (xy 40.548788 -379.556324) (xy 40.556861 -379.489388) (xy 40.572893 -379.423901)
			(xy 40.596654 -379.360806) (xy 40.627802 -379.301011) (xy 40.665889 -379.245378) (xy 40.687752 -379.219714)
			(xy 40.693574 -379.212587) (xy 40.700072 -379.195382) (xy 40.700452 -379.186186) (xy 40.700452 -378.693934)
			(xy 40.700014 -378.68475) (xy 40.693519 -378.667566) (xy 40.687752 -378.660406) (xy 40.665861 -378.634763)
			(xy 40.627769 -378.579126) (xy 40.596617 -378.519328) (xy 40.572852 -378.456228) (xy 40.556817 -378.390735)
			(xy 40.548742 -378.323794) (xy 37.271233 -378.323794) (xy 37.263159 -378.390729) (xy 37.247125 -378.456217)
			(xy 37.223362 -378.519313) (xy 37.192212 -378.579108) (xy 37.154124 -378.634741) (xy 37.13226 -378.660406)
			(xy 37.126473 -378.667558) (xy 37.119954 -378.684743) (xy 37.11956 -378.693934) (xy 37.11956 -379.186186)
			(xy 37.119986 -379.195371) (xy 37.126489 -379.212555) (xy 37.13226 -379.219714) (xy 37.154171 -379.245341)
			(xy 37.192261 -379.30098) (xy 37.223411 -379.360781) (xy 37.247175 -379.423883) (xy 37.263208 -379.489377)
			(xy 37.271281 -379.55632) (xy 37.271277 -379.623749) (xy 37.263196 -379.690691) (xy 37.247154 -379.756183)
			(xy 37.223383 -379.819282) (xy 37.192225 -379.879079) (xy 37.154128 -379.934713) (xy 37.13226 -379.960378)
			(xy 37.126443 -379.967508) (xy 37.119941 -379.98471) (xy 37.11956 -379.993906) (xy 37.11956 -380.151386)
			(xy 37.119062 -380.161512) (xy 37.111339 -380.180233) (xy 37.097056 -380.194589) (xy 37.078375 -380.202409)
			(xy 37.068252 -380.202948) (xy 36.351972 -380.202948) (xy 36.341822 -380.202502) (xy 36.323078 -380.194707)
			(xy 36.308758 -380.180318) (xy 36.30105 -380.161538) (xy 36.300664 -380.151386) (xy 36.300664 -379.993906)
			(xy 36.300237 -379.984721) (xy 36.293733 -379.967537) (xy 36.287964 -379.960378) (xy 36.266146 -379.934675)
			(xy 36.228059 -379.879045) (xy 36.196908 -379.819254) (xy 36.173143 -379.756162) (xy 36.157105 -379.690678)
			(xy 36.149026 -379.623744) (xy 36.149022 -379.556325) (xy 36.157093 -379.48939) (xy 36.173122 -379.423904)
			(xy 36.19688 -379.36081) (xy 36.228023 -379.301014) (xy 36.266104 -379.24538) (xy 36.287964 -379.219714)
			(xy 36.293787 -379.212588) (xy 36.300284 -379.195383) (xy 36.300664 -379.186186) (xy 36.300664 -378.693934)
			(xy 36.300223 -378.68475) (xy 36.293729 -378.667566) (xy 36.287964 -378.660406) (xy 36.266076 -378.634761)
			(xy 36.22799 -378.579123) (xy 36.196843 -378.519324) (xy 36.173081 -378.456224) (xy 36.157049 -378.390733)
			(xy 36.148976 -378.323793) (xy 32.870906 -378.323793) (xy 32.862871 -378.390552) (xy 32.846902 -378.455933)
			(xy 32.823232 -378.518936) (xy 32.792203 -378.578659) (xy 32.754258 -378.634246) (xy 32.732472 -378.659898)
			(xy 32.72669 -378.667053) (xy 32.720167 -378.684236) (xy 32.719772 -378.693426) (xy 32.719772 -379.186694)
			(xy 32.720191 -379.19588) (xy 32.726699 -379.213064) (xy 32.732472 -379.220222) (xy 32.754305 -379.245837)
			(xy 32.792251 -379.301429) (xy 32.823282 -379.361158) (xy 32.846952 -379.424167) (xy 32.862921 -379.489554)
			(xy 32.870962 -379.55638) (xy 32.870957 -379.623689) (xy 32.862909 -379.690514) (xy 32.846931 -379.755899)
			(xy 32.823254 -379.818905) (xy 32.792216 -379.87863) (xy 32.754262 -379.934218) (xy 32.732472 -379.95987)
			(xy 32.72666 -379.967004) (xy 32.720155 -379.984203) (xy 32.719772 -379.993398) (xy 32.719772 -380.151386)
			(xy 32.719325 -380.161556) (xy 32.711547 -380.180348) (xy 32.697168 -380.194733) (xy 32.678379 -380.20252)
			(xy 32.66821 -380.202948) (xy 31.95193 -380.202948) (xy 31.941759 -380.202511) (xy 31.922962 -380.194733)
			(xy 31.908576 -380.180351) (xy 31.900792 -380.161557) (xy 31.900368 -380.151386) (xy 31.900368 -379.993398)
			(xy 31.899944 -379.984213) (xy 31.893438 -379.967029) (xy 31.887668 -379.95987) (xy 31.865925 -379.934181)
			(xy 31.827973 -379.878601) (xy 31.796936 -379.818882) (xy 31.773259 -379.755883) (xy 31.757282 -379.690505)
			(xy 31.749234 -379.623686) (xy 31.74923 -379.556384) (xy 31.75727 -379.489564) (xy 31.773239 -379.424184)
			(xy 31.796908 -379.361181) (xy 31.827937 -379.301459) (xy 31.865882 -379.245874) (xy 31.887668 -379.220222)
			(xy 31.893488 -379.213094) (xy 31.899987 -379.19589) (xy 31.900368 -379.186694) (xy 31.900368 -378.693426)
			(xy 31.89993 -378.684242) (xy 31.893434 -378.667058) (xy 31.887668 -378.659898) (xy 31.865854 -378.634267)
			(xy 31.827904 -378.578678) (xy 31.79687 -378.518952) (xy 31.773198 -378.455945) (xy 31.757226 -378.39056)
			(xy 31.749183 -378.323734) (xy 28.471145 -378.323734) (xy 28.471145 -378.323792) (xy 28.463071 -378.390728)
			(xy 28.447038 -378.456216) (xy 28.423275 -378.519312) (xy 28.392126 -378.579108) (xy 28.354039 -378.634741)
			(xy 28.332176 -378.660406) (xy 28.326392 -378.66756) (xy 28.31987 -378.684744) (xy 28.319476 -378.693934)
			(xy 28.319476 -379.186186) (xy 28.319898 -379.195372) (xy 28.326404 -379.212556) (xy 28.332176 -379.219714)
			(xy 28.354036 -379.245382) (xy 28.392125 -379.301016) (xy 28.423276 -379.360812) (xy 28.447 -379.423801)
			(xy 29.549058 -379.423801) (xy 29.549059 -379.356496) (xy 29.557103 -379.289673) (xy 29.573076 -379.224291)
			(xy 29.596749 -379.161286) (xy 29.627783 -379.101562) (xy 29.665732 -379.045976) (xy 29.68752 -379.020324)
			(xy 29.693334 -379.013191) (xy 29.699837 -378.995991) (xy 29.70022 -378.986796) (xy 29.70022 -378.828554)
			(xy 29.700695 -378.818396) (xy 29.708482 -378.799629) (xy 29.722852 -378.785266) (xy 29.741623 -378.77749)
			(xy 29.751782 -378.776992) (xy 30.468062 -378.776992) (xy 30.478212 -378.777564) (xy 30.496971 -378.785317)
			(xy 30.511336 -378.799658) (xy 30.51912 -378.818405) (xy 30.519624 -378.828554) (xy 30.519624 -378.986796)
			(xy 30.520031 -378.995984) (xy 30.526546 -379.013168) (xy 30.532324 -379.020324) (xy 30.55411 -379.045978)
			(xy 30.592059 -379.101564) (xy 30.623093 -379.161287) (xy 30.646766 -379.224291) (xy 30.662739 -379.289673)
			(xy 30.670784 -379.356496) (xy 30.670784 -379.423801) (xy 30.66274 -379.490624) (xy 30.646767 -379.556006)
			(xy 30.623094 -379.61901) (xy 30.592061 -379.678734) (xy 30.554112 -379.73432) (xy 30.532324 -379.759972)
			(xy 30.526517 -379.76711) (xy 30.520008 -379.784306) (xy 30.519624 -379.7935) (xy 30.519624 -380.286768)
			(xy 30.520044 -380.295954) (xy 30.52655 -380.313139) (xy 30.532324 -380.320296) (xy 30.554132 -380.345932)
			(xy 30.592083 -380.40152) (xy 30.623117 -380.461245) (xy 30.646791 -380.524252) (xy 30.662763 -380.589636)
			(xy 30.6708 -380.656404) (xy 33.948845 -380.656404) (xy 33.95692 -380.589467) (xy 33.972953 -380.523978)
			(xy 33.996716 -380.460882) (xy 34.027865 -380.401087) (xy 34.065953 -380.345453) (xy 34.087816 -380.319788)
			(xy 34.093602 -380.312635) (xy 34.100122 -380.29545) (xy 34.100516 -380.28626) (xy 34.100516 -379.794008)
			(xy 34.100098 -379.784822) (xy 34.093589 -379.767638) (xy 34.087816 -379.76048) (xy 34.065999 -379.734776)
			(xy 34.027907 -379.679148) (xy 33.996754 -379.619357) (xy 33.972986 -379.556265) (xy 33.956947 -379.49078)
			(xy 33.948867 -379.423846) (xy 33.948863 -379.356426) (xy 33.956934 -379.289491) (xy 33.972965 -379.224004)
			(xy 33.996724 -379.160909) (xy 34.02787 -379.101114) (xy 34.065954 -379.045481) (xy 34.087816 -379.019816)
			(xy 34.093633 -379.012685) (xy 34.100135 -378.995484) (xy 34.100516 -378.986288) (xy 34.100516 -378.828554)
			(xy 34.100988 -378.818427) (xy 34.108727 -378.79971) (xy 34.123017 -378.785356) (xy 34.1417 -378.777534)
			(xy 34.151824 -378.776992) (xy 34.868104 -378.776992) (xy 34.878257 -378.777418) (xy 34.897008 -378.785214)
			(xy 34.911331 -378.799609) (xy 34.919032 -378.818399) (xy 34.919412 -378.828554) (xy 34.919412 -378.986288)
			(xy 34.919825 -378.995475) (xy 34.926336 -379.012659) (xy 34.932112 -379.019816) (xy 34.954023 -379.045443)
			(xy 34.992109 -379.101083) (xy 35.023257 -379.160885) (xy 35.047018 -379.223986) (xy 35.06305 -379.28948)
			(xy 35.071122 -379.356422) (xy 35.071117 -379.42385) (xy 35.063037 -379.490791) (xy 35.046997 -379.556283)
			(xy 35.023228 -379.619381) (xy 34.992072 -379.679179) (xy 34.953978 -379.734815) (xy 34.932112 -379.76048)
			(xy 34.9263 -379.767615) (xy 34.919794 -379.784813) (xy 34.919412 -379.794008) (xy 34.919412 -380.28626)
			(xy 34.919839 -380.295446) (xy 34.92634 -380.31263) (xy 34.932112 -380.319788) (xy 34.953995 -380.345437)
			(xy 34.992083 -380.401074) (xy 35.023232 -380.460873) (xy 35.046994 -380.523972) (xy 35.063028 -380.589463)
			(xy 35.071102 -380.656403) (xy 35.071102 -380.656464) (xy 38.349165 -380.656464) (xy 38.357207 -380.589643)
			(xy 38.373176 -380.524262) (xy 38.396845 -380.461259) (xy 38.427874 -380.401536) (xy 38.465819 -380.345949)
			(xy 38.487604 -380.320296) (xy 38.493385 -380.31314) (xy 38.499909 -380.295958) (xy 38.500304 -380.286768)
			(xy 38.500304 -379.7935) (xy 38.499893 -379.784313) (xy 38.49338 -379.767129) (xy 38.487604 -379.759972)
			(xy 38.465865 -379.73428) (xy 38.427917 -379.678699) (xy 38.396884 -379.61898) (xy 38.37321 -379.555981)
			(xy 38.357234 -379.490604) (xy 38.349187 -379.423786) (xy 38.349183 -379.356486) (xy 38.357221 -379.289667)
			(xy 38.373188 -379.224288) (xy 38.396854 -379.161286) (xy 38.42788 -379.101563) (xy 38.465821 -379.045977)
			(xy 38.487604 -379.020324) (xy 38.493416 -379.01319) (xy 38.499921 -378.995991) (xy 38.500304 -378.986796)
			(xy 38.500304 -378.828554) (xy 38.500795 -378.818397) (xy 38.508578 -378.799634) (xy 38.522944 -378.785271)
			(xy 38.541709 -378.777493) (xy 38.551866 -378.776992) (xy 39.268146 -378.776992) (xy 39.278301 -378.777495)
			(xy 39.297062 -378.785276) (xy 39.311424 -378.799638) (xy 39.319205 -378.818399) (xy 39.319708 -378.828554)
			(xy 39.319708 -378.986796) (xy 39.320118 -378.995983) (xy 39.326632 -379.013168) (xy 39.332408 -379.020324)
			(xy 39.354244 -379.045937) (xy 39.392195 -379.101528) (xy 39.423229 -379.161256) (xy 39.446902 -379.224266)
			(xy 39.462873 -379.289653) (xy 39.470914 -379.356481) (xy 39.47091 -379.423791) (xy 39.46286 -379.490618)
			(xy 39.44688 -379.556003) (xy 39.4232 -379.61901) (xy 39.392158 -379.678735) (xy 39.3542 -379.734321)
			(xy 39.332408 -379.759972) (xy 39.326599 -379.767109) (xy 39.320092 -379.784306) (xy 39.319708 -379.7935)
			(xy 39.319708 -380.286768) (xy 39.320132 -380.295954) (xy 39.326636 -380.313138) (xy 39.332408 -380.320296)
			(xy 39.354217 -380.345931) (xy 39.392169 -380.401519) (xy 39.423204 -380.461244) (xy 39.446878 -380.524251)
			(xy 39.462851 -380.589636) (xy 39.470887 -380.656404) (xy 42.748933 -380.656404) (xy 42.757007 -380.589467)
			(xy 42.773041 -380.523979) (xy 42.796803 -380.460883) (xy 42.827951 -380.401087) (xy 42.866037 -380.345453)
			(xy 42.8879 -380.319788) (xy 42.893684 -380.312634) (xy 42.900206 -380.29545) (xy 42.9006 -380.28626)
			(xy 42.9006 -379.794008) (xy 42.900186 -379.784821) (xy 42.893675 -379.767637) (xy 42.8879 -379.76048)
			(xy 42.866083 -379.734776) (xy 42.827993 -379.679147) (xy 42.79684 -379.619356) (xy 42.773073 -379.556264)
			(xy 42.757035 -379.49078) (xy 42.748955 -379.423846) (xy 42.748951 -379.356426) (xy 42.757022 -379.289491)
			(xy 42.773052 -379.224005) (xy 42.796811 -379.16091) (xy 42.827956 -379.101115) (xy 42.866039 -379.045481)
			(xy 42.8879 -379.019816) (xy 42.893715 -379.012684) (xy 42.900219 -378.995483) (xy 42.9006 -378.986288)
			(xy 42.9006 -378.828554) (xy 42.901088 -378.818429) (xy 42.908823 -378.799715) (xy 42.923108 -378.785361)
			(xy 42.941786 -378.777537) (xy 42.951908 -378.776992) (xy 43.668188 -378.776992) (xy 43.67834 -378.777431)
			(xy 43.697091 -378.785221) (xy 43.711414 -378.799613) (xy 43.719116 -378.8184) (xy 43.719496 -378.828554)
			(xy 43.719496 -378.986288) (xy 43.719913 -378.995474) (xy 43.726422 -379.012659) (xy 43.732196 -379.019816)
			(xy 43.754107 -379.045442) (xy 43.792195 -379.101082) (xy 43.823344 -379.160884) (xy 43.847105 -379.223986)
			(xy 43.863138 -379.28948) (xy 43.87121 -379.356422) (xy 43.871205 -379.42385) (xy 43.863125 -379.490791)
			(xy 43.847084 -379.556283) (xy 43.823314 -379.619382) (xy 43.792158 -379.67918) (xy 43.754063 -379.734815)
			(xy 43.732196 -379.76048) (xy 43.726382 -379.767613) (xy 43.719878 -379.784813) (xy 43.719496 -379.794008)
			(xy 43.719496 -380.28626) (xy 43.719926 -380.295445) (xy 43.726426 -380.31263) (xy 43.732196 -380.319788)
			(xy 43.75408 -380.345437) (xy 43.792168 -380.401074) (xy 43.823318 -380.460872) (xy 43.847081 -380.523971)
			(xy 43.863116 -380.589462) (xy 43.87119 -380.656402) (xy 43.87119 -380.656463) (xy 73.548987 -380.656463)
			(xy 73.557029 -380.589642) (xy 73.572999 -380.524261) (xy 73.596669 -380.461258) (xy 73.6277 -380.401535)
			(xy 73.665646 -380.345948) (xy 73.687432 -380.320296) (xy 73.693217 -380.313143) (xy 73.699738 -380.295958)
			(xy 73.700132 -380.286768) (xy 73.700132 -379.7935) (xy 73.699715 -379.784314) (xy 73.693205 -379.76713)
			(xy 73.687432 -379.759972) (xy 73.665692 -379.734281) (xy 73.627742 -379.6787) (xy 73.596707 -379.618982)
			(xy 73.573032 -379.555982) (xy 73.557056 -379.490605) (xy 73.549008 -379.423787) (xy 73.549004 -379.356486)
			(xy 73.557043 -379.289666) (xy 73.573011 -379.224287) (xy 73.596678 -379.161285) (xy 73.627705 -379.101562)
			(xy 73.665648 -379.045976) (xy 73.687432 -379.020324) (xy 73.693247 -379.013192) (xy 73.69975 -378.995991)
			(xy 73.700132 -378.986796) (xy 73.700132 -378.828554) (xy 73.700596 -378.818394) (xy 73.708384 -378.799625)
			(xy 73.722759 -378.785262) (xy 73.741534 -378.777488) (xy 73.751694 -378.776992) (xy 74.467974 -378.776992)
			(xy 74.478125 -378.777553) (xy 74.496884 -378.785311) (xy 74.511249 -378.799655) (xy 74.519032 -378.818404)
			(xy 74.519536 -378.828554) (xy 74.519536 -378.986796) (xy 74.519962 -378.995981) (xy 74.526466 -379.013165)
			(xy 74.532236 -379.020324) (xy 74.554072 -379.045937) (xy 74.592021 -379.101528) (xy 74.623053 -379.161257)
			(xy 74.646725 -379.224267) (xy 74.662695 -379.289654) (xy 74.670736 -379.356481) (xy 74.670731 -379.423791)
			(xy 74.662682 -379.490617) (xy 74.646703 -379.556002) (xy 74.623024 -379.619009) (xy 74.591984 -379.678734)
			(xy 74.554028 -379.73432) (xy 74.532236 -379.759972) (xy 74.526419 -379.767102) (xy 74.519918 -379.784304)
			(xy 74.519536 -379.7935) (xy 74.519536 -380.286768) (xy 74.519976 -380.295952) (xy 74.52647 -380.313136)
			(xy 74.532236 -380.320296) (xy 74.554044 -380.345932) (xy 74.591994 -380.40152) (xy 74.623028 -380.461246)
			(xy 74.6467 -380.524252) (xy 74.662673 -380.589637) (xy 74.670709 -380.656404) (xy 77.948754 -380.656404)
			(xy 77.956829 -380.589466) (xy 77.972863 -380.523978) (xy 77.996626 -380.460882) (xy 78.027776 -380.401086)
			(xy 78.065864 -380.345453) (xy 78.087728 -380.319788) (xy 78.093516 -380.312637) (xy 78.100035 -380.295451)
			(xy 78.100428 -380.28626) (xy 78.100428 -379.794008) (xy 78.100008 -379.784822) (xy 78.093501 -379.767638)
			(xy 78.087728 -379.76048) (xy 78.06591 -379.734776) (xy 78.027818 -379.679148) (xy 77.996664 -379.619357)
			(xy 77.972896 -379.556265) (xy 77.956856 -379.490781) (xy 77.948776 -379.423846) (xy 77.948772 -379.356426)
			(xy 77.956843 -379.28949) (xy 77.972874 -379.224004) (xy 77.996634 -379.160909) (xy 78.027781 -379.101114)
			(xy 78.065866 -379.045481) (xy 78.087728 -379.019816) (xy 78.093546 -379.012686) (xy 78.100047 -378.995484)
			(xy 78.100428 -378.986288) (xy 78.100428 -378.828554) (xy 78.100889 -378.818426) (xy 78.108629 -378.799706)
			(xy 78.122923 -378.785352) (xy 78.14161 -378.777532) (xy 78.151736 -378.776992) (xy 78.868016 -378.776992)
			(xy 78.87817 -378.777408) (xy 78.896921 -378.785208) (xy 78.911244 -378.799606) (xy 78.918945 -378.818398)
			(xy 78.919324 -378.828554) (xy 78.919324 -378.986288) (xy 78.919734 -378.995475) (xy 78.926247 -379.01266)
			(xy 78.932024 -379.019816) (xy 78.953934 -379.045443) (xy 78.99202 -379.101083) (xy 79.023167 -379.160885)
			(xy 79.046928 -379.223987) (xy 79.062959 -379.28948) (xy 79.071031 -379.356423) (xy 79.071026 -379.42385)
			(xy 79.062946 -379.490791) (xy 79.046906 -379.556282) (xy 79.023138 -379.619381) (xy 78.991983 -379.679179)
			(xy 78.95389 -379.734814) (xy 78.932024 -379.76048) (xy 78.926214 -379.767616) (xy 78.919706 -379.784813)
			(xy 78.919324 -379.794008) (xy 78.919324 -380.28626) (xy 78.919748 -380.295446) (xy 78.926251 -380.312631)
			(xy 78.932024 -380.319788) (xy 78.953907 -380.345437) (xy 78.991993 -380.401075) (xy 79.023142 -380.460873)
			(xy 79.046904 -380.523972) (xy 79.062937 -380.589463) (xy 79.071011 -380.656403) (xy 79.071011 -380.656464)
			(xy 82.349074 -380.656464) (xy 82.357116 -380.589643) (xy 82.373086 -380.524262) (xy 82.396755 -380.461258)
			(xy 82.427785 -380.401535) (xy 82.46573 -380.345948) (xy 82.487516 -380.320296) (xy 82.493299 -380.313141)
			(xy 82.499821 -380.295958) (xy 82.500216 -380.286768) (xy 82.500216 -379.7935) (xy 82.499803 -379.784313)
			(xy 82.493291 -379.767129) (xy 82.487516 -379.759972) (xy 82.465776 -379.734281) (xy 82.427828 -379.678699)
			(xy 82.396794 -379.618981) (xy 82.373119 -379.555982) (xy 82.357144 -379.490604) (xy 82.349096 -379.423786)
			(xy 82.349092 -379.356486) (xy 82.357131 -379.289667) (xy 82.373098 -379.224288) (xy 82.396764 -379.161285)
			(xy 82.427791 -379.101563) (xy 82.465732 -379.045977) (xy 82.487516 -379.020324) (xy 82.493329 -379.013191)
			(xy 82.499833 -378.995991) (xy 82.500216 -378.986796) (xy 82.500216 -378.828554) (xy 82.500695 -378.818396)
			(xy 82.508481 -378.79963) (xy 82.52285 -378.785267) (xy 82.54162 -378.777491) (xy 82.551778 -378.776992)
			(xy 83.268058 -378.776992) (xy 83.278207 -378.777567) (xy 83.296967 -378.785319) (xy 83.311332 -378.799659)
			(xy 83.319116 -378.818405) (xy 83.31962 -378.828554) (xy 83.31962 -378.986796) (xy 83.320028 -378.995984)
			(xy 83.326543 -379.013168) (xy 83.33232 -379.020324) (xy 83.354156 -379.045937) (xy 83.392107 -379.101528)
			(xy 83.42314 -379.161256) (xy 83.446812 -379.224266) (xy 83.462783 -379.289654) (xy 83.470824 -379.356481)
			(xy 83.470819 -379.423791) (xy 83.46277 -379.490618) (xy 83.446791 -379.556003) (xy 83.423111 -379.61901)
			(xy 83.392069 -379.678734) (xy 83.354112 -379.734321) (xy 83.33232 -379.759972) (xy 83.326513 -379.76711)
			(xy 83.320004 -379.784306) (xy 83.31962 -379.7935) (xy 83.31962 -380.286768) (xy 83.320041 -380.295954)
			(xy 83.326547 -380.313139) (xy 83.33232 -380.320296) (xy 83.354129 -380.345931) (xy 83.392079 -380.401519)
			(xy 83.423114 -380.461245) (xy 83.446788 -380.524252) (xy 83.46276 -380.589636) (xy 83.470797 -380.656404)
			(xy 86.748842 -380.656404) (xy 86.756916 -380.589467) (xy 86.77295 -380.523979) (xy 86.796713 -380.460883)
			(xy 86.827862 -380.401087) (xy 86.865949 -380.345453) (xy 86.887812 -380.319788) (xy 86.893598 -380.312635)
			(xy 86.900118 -380.29545) (xy 86.900512 -380.28626) (xy 86.900512 -379.794008) (xy 86.900095 -379.784822)
			(xy 86.893586 -379.767637) (xy 86.887812 -379.76048) (xy 86.865995 -379.734776) (xy 86.827904 -379.679147)
			(xy 86.79675 -379.619357) (xy 86.772983 -379.556265) (xy 86.756944 -379.49078) (xy 86.748864 -379.423846)
			(xy 86.74886 -379.356426) (xy 86.756931 -379.289491) (xy 86.772962 -379.224004) (xy 86.796721 -379.160909)
			(xy 86.827867 -379.101115) (xy 86.86595 -379.045481) (xy 86.887812 -379.019816) (xy 86.893628 -379.012685)
			(xy 86.900131 -378.995483) (xy 86.900512 -378.986288) (xy 86.900512 -378.828554) (xy 86.900988 -378.818428)
			(xy 86.908726 -378.799711) (xy 86.923015 -378.785357) (xy 86.941696 -378.777535) (xy 86.95182 -378.776992)
			(xy 87.6681 -378.776992) (xy 87.678253 -378.777422) (xy 87.697004 -378.785216) (xy 87.711327 -378.79961)
			(xy 87.719028 -378.818399) (xy 87.719408 -378.828554) (xy 87.719408 -378.986288) (xy 87.719822 -378.995475)
			(xy 87.726333 -379.012659) (xy 87.732108 -379.019816) (xy 87.754019 -379.045442) (xy 87.792106 -379.101083)
			(xy 87.823254 -379.160884) (xy 87.847015 -379.223986) (xy 87.863047 -379.28948) (xy 87.871119 -379.356422)
			(xy 87.871114 -379.42385) (xy 87.863034 -379.490791) (xy 87.846994 -379.556283) (xy 87.823224 -379.619382)
			(xy 87.792068 -379.679179) (xy 87.753975 -379.734815) (xy 87.732108 -379.76048) (xy 87.726296 -379.767614)
			(xy 87.71979 -379.784813) (xy 87.719408 -379.794008) (xy 87.719408 -380.28626) (xy 87.719836 -380.295445)
			(xy 87.726337 -380.31263) (xy 87.732108 -380.319788) (xy 87.753991 -380.345437) (xy 87.792079 -380.401074)
			(xy 87.823228 -380.460873) (xy 87.846991 -380.523972) (xy 87.863025 -380.589463) (xy 87.871099 -380.656402)
			(xy 87.871097 -380.723828) (xy 87.863019 -380.790767) (xy 87.846982 -380.856257) (xy 87.838954 -380.877572)
			(xy 105.0036 -380.877572) (xy 105.0036 -380.013972) (xy 105.00409 -379.983988) (xy 105.011918 -379.924532)
			(xy 105.027439 -379.866607) (xy 105.050388 -379.811203) (xy 105.080372 -379.759269) (xy 105.116878 -379.711693)
			(xy 105.159283 -379.669288) (xy 105.206859 -379.632782) (xy 105.258793 -379.602798) (xy 105.314197 -379.579849)
			(xy 105.372122 -379.564328) (xy 105.431578 -379.5565) (xy 105.491546 -379.5565) (xy 105.551002 -379.564328)
			(xy 105.608927 -379.579849) (xy 105.664331 -379.602798) (xy 105.716265 -379.632782) (xy 105.763841 -379.669288)
			(xy 105.806246 -379.711693) (xy 105.842752 -379.759269) (xy 105.872736 -379.811203) (xy 105.895685 -379.866607)
			(xy 105.911206 -379.924532) (xy 105.919034 -379.983988) (xy 105.919524 -380.013972) (xy 105.919524 -380.656403)
			(xy 117.548873 -380.656403) (xy 117.556947 -380.589466) (xy 117.572982 -380.523977) (xy 117.596746 -380.460881)
			(xy 117.627898 -380.401085) (xy 117.665987 -380.345452) (xy 117.687852 -380.319788) (xy 117.693643 -380.312639)
			(xy 117.700159 -380.295451) (xy 117.700552 -380.28626) (xy 117.700552 -379.794008) (xy 117.700126 -379.784823)
			(xy 117.693622 -379.767639) (xy 117.687852 -379.76048) (xy 117.666033 -379.734777) (xy 117.62794 -379.679149)
			(xy 117.596784 -379.619358) (xy 117.573015 -379.556266) (xy 117.556975 -379.490781) (xy 117.548894 -379.423846)
			(xy 117.54889 -379.356426) (xy 117.556962 -379.28949) (xy 117.572994 -379.224003) (xy 117.596755 -379.160908)
			(xy 117.627903 -379.101113) (xy 117.665989 -379.04548) (xy 117.687852 -379.019816) (xy 117.693673 -379.012688)
			(xy 117.700172 -378.995484) (xy 117.700552 -378.986288) (xy 117.700552 -378.828554) (xy 117.700989 -378.818423)
			(xy 117.708734 -378.799698) (xy 117.723036 -378.785343) (xy 117.741731 -378.777528) (xy 117.75186 -378.776992)
			(xy 118.46814 -378.776992) (xy 118.478296 -378.777389) (xy 118.497047 -378.785196) (xy 118.511369 -378.7996)
			(xy 118.519069 -378.818396) (xy 118.519448 -378.828554) (xy 118.519448 -378.986288) (xy 118.519875 -378.995473)
			(xy 118.526378 -379.012657) (xy 118.532148 -379.019816) (xy 118.554061 -379.045441) (xy 118.592152 -379.10108)
			(xy 118.623303 -379.160882) (xy 118.647067 -379.223984) (xy 118.663101 -379.289478) (xy 118.671174 -379.356422)
			(xy 118.671169 -379.42385) (xy 118.663088 -379.490793) (xy 118.647046 -379.556285) (xy 118.623274 -379.619384)
			(xy 118.592115 -379.679181) (xy 118.554017 -379.734816) (xy 118.532148 -379.76048) (xy 118.526329 -379.767609)
			(xy 118.519829 -379.784812) (xy 118.519448 -379.794008) (xy 118.519448 -380.28626) (xy 118.519889 -380.295444)
			(xy 118.526382 -380.312628) (xy 118.532148 -380.319788) (xy 118.554033 -380.345436) (xy 118.592125 -380.401072)
			(xy 118.623278 -380.46087) (xy 118.647043 -380.523969) (xy 118.663079 -380.589461) (xy 118.671154 -380.656402)
			(xy 118.671154 -380.656463) (xy 121.949193 -380.656463) (xy 121.957235 -380.589642) (xy 121.973206 -380.524261)
			(xy 121.996876 -380.461257) (xy 122.027907 -380.401534) (xy 122.065854 -380.345948) (xy 122.08764 -380.320296)
			(xy 122.093426 -380.313143) (xy 122.099946 -380.295958) (xy 122.10034 -380.286768) (xy 122.10034 -379.7935)
			(xy 122.099921 -379.784314) (xy 122.093413 -379.76713) (xy 122.08764 -379.759972) (xy 122.0659 -379.734281)
			(xy 122.027949 -379.6787) (xy 121.996914 -379.618982) (xy 121.973238 -379.555982) (xy 121.957262 -379.490605)
			(xy 121.949214 -379.423787) (xy 121.94921 -379.356485) (xy 121.957249 -379.289666) (xy 121.973217 -379.224287)
			(xy 121.996884 -379.161284) (xy 122.027912 -379.101562) (xy 122.065855 -379.045976) (xy 122.08764 -379.020324)
			(xy 122.093456 -379.013193) (xy 122.099958 -378.995991) (xy 122.10034 -378.986796) (xy 122.10034 -378.828554)
			(xy 122.100796 -378.818393) (xy 122.108586 -378.799623) (xy 122.122963 -378.785259) (xy 122.141741 -378.777486)
			(xy 122.151902 -378.776992) (xy 122.868182 -378.776992) (xy 122.878333 -378.777547) (xy 122.897093 -378.785307)
			(xy 122.911457 -378.799653) (xy 122.919241 -378.818404) (xy 122.919744 -378.828554) (xy 122.919744 -378.986796)
			(xy 122.920169 -378.995981) (xy 122.926674 -379.013165) (xy 122.932444 -379.020324) (xy 122.95428 -379.045937)
			(xy 122.992228 -379.101529) (xy 123.02326 -379.161257) (xy 123.046931 -379.224267) (xy 123.062901 -379.289654)
			(xy 123.070942 -379.356482) (xy 123.070937 -379.423791) (xy 123.062888 -379.490617) (xy 123.04691 -379.556002)
			(xy 123.023231 -379.619009) (xy 122.992191 -379.678733) (xy 122.954235 -379.73432) (xy 122.932444 -379.759972)
			(xy 122.926627 -379.767103) (xy 122.920126 -379.784305) (xy 122.919744 -379.7935) (xy 122.919744 -380.286768)
			(xy 122.920182 -380.295952) (xy 122.926678 -380.313136) (xy 122.932444 -380.320296) (xy 122.954252 -380.345932)
			(xy 122.992201 -380.40152) (xy 123.023235 -380.461246) (xy 123.046907 -380.524252) (xy 123.062879 -380.589637)
			(xy 123.070915 -380.656404) (xy 126.34896 -380.656404) (xy 126.357035 -380.589466) (xy 126.373069 -380.523978)
			(xy 126.396833 -380.460881) (xy 126.427983 -380.401086) (xy 126.466072 -380.345453) (xy 126.487936 -380.319788)
			(xy 126.493725 -380.312637) (xy 126.500243 -380.295451) (xy 126.500636 -380.28626) (xy 126.500636 -379.794008)
			(xy 126.500214 -379.784822) (xy 126.493708 -379.767638) (xy 126.487936 -379.76048) (xy 126.466118 -379.734776)
			(xy 126.428025 -379.679148) (xy 126.396871 -379.619358) (xy 126.373102 -379.556266) (xy 126.357062 -379.490781)
			(xy 126.348982 -379.423846) (xy 126.348978 -379.356426) (xy 126.357049 -379.28949) (xy 126.373081 -379.224003)
			(xy 126.396841 -379.160908) (xy 126.427988 -379.101114) (xy 126.466074 -379.045481) (xy 126.487936 -379.019816)
			(xy 126.493755 -379.012687) (xy 126.500256 -378.995484) (xy 126.500636 -378.986288) (xy 126.500636 -378.828554)
			(xy 126.501089 -378.818425) (xy 126.508831 -378.799703) (xy 126.523127 -378.785349) (xy 126.541817 -378.777531)
			(xy 126.551944 -378.776992) (xy 127.268224 -378.776992) (xy 127.278379 -378.777402) (xy 127.29713 -378.785204)
			(xy 127.311452 -378.799604) (xy 127.319153 -378.818397) (xy 127.319532 -378.828554) (xy 127.319532 -378.986288)
			(xy 127.319963 -378.995473) (xy 127.326464 -379.012656) (xy 127.332232 -379.019816) (xy 127.354142 -379.045443)
			(xy 127.392227 -379.101084) (xy 127.423374 -379.160885) (xy 127.447134 -379.223987) (xy 127.463165 -379.289481)
			(xy 127.471237 -379.356423) (xy 127.471232 -379.423849) (xy 127.463152 -379.49079) (xy 127.447113 -379.556282)
			(xy 127.423345 -379.61938) (xy 127.39219 -379.679178) (xy 127.354098 -379.734814) (xy 127.332232 -379.76048)
			(xy 127.326411 -379.767607) (xy 127.319913 -379.784812) (xy 127.319532 -379.794008) (xy 127.319532 -380.28626)
			(xy 127.319977 -380.295443) (xy 127.326468 -380.312627) (xy 127.332232 -380.319788) (xy 127.354114 -380.345438)
			(xy 127.392201 -380.401075) (xy 127.423349 -380.460874) (xy 127.44711 -380.523973) (xy 127.463143 -380.589463)
			(xy 127.471217 -380.656403) (xy 127.471217 -380.656463) (xy 130.74928 -380.656463) (xy 130.757322 -380.589642)
			(xy 130.773292 -380.524262) (xy 130.796962 -380.461258) (xy 130.827992 -380.401535) (xy 130.865938 -380.345948)
			(xy 130.887724 -380.320296) (xy 130.893508 -380.313142) (xy 130.900029 -380.295958) (xy 130.900424 -380.286768)
			(xy 130.900424 -379.7935) (xy 130.900009 -379.784313) (xy 130.893498 -379.767129) (xy 130.887724 -379.759972)
			(xy 130.865984 -379.734281) (xy 130.828035 -379.678699) (xy 130.797 -379.618981) (xy 130.773326 -379.555982)
			(xy 130.75735 -379.490605) (xy 130.749302 -379.423787) (xy 130.749298 -379.356486) (xy 130.757337 -379.289667)
			(xy 130.773304 -379.224287) (xy 130.796971 -379.161285) (xy 130.827998 -379.101563) (xy 130.86594 -379.045977)
			(xy 130.887724 -379.020324) (xy 130.893538 -379.013191) (xy 130.900042 -378.995991) (xy 130.900424 -378.986796)
			(xy 130.900424 -378.828554) (xy 130.900895 -378.818395) (xy 130.908682 -378.799628) (xy 130.923054 -378.785264)
			(xy 130.941827 -378.777489) (xy 130.951986 -378.776992) (xy 131.668266 -378.776992) (xy 131.678416 -378.77756)
			(xy 131.697175 -378.785315) (xy 131.71154 -378.799657) (xy 131.719324 -378.818405) (xy 131.719828 -378.828554)
			(xy 131.719828 -378.986796) (xy 131.720234 -378.995984) (xy 131.72675 -379.013168) (xy 131.732528 -379.020324)
			(xy 131.754364 -379.045937) (xy 131.792314 -379.101528) (xy 131.823347 -379.161257) (xy 131.847018 -379.224267)
			(xy 131.862989 -379.289654) (xy 131.87103 -379.356481) (xy 131.871025 -379.423791) (xy 131.862976 -379.490617)
			(xy 131.846997 -379.556003) (xy 131.823317 -379.619009) (xy 131.792277 -379.678734) (xy 131.75432 -379.73432)
			(xy 131.732528 -379.759972) (xy 131.72671 -379.767101) (xy 131.72021 -379.784304) (xy 131.719828 -379.7935)
			(xy 131.719828 -380.286768) (xy 131.720247 -380.295954) (xy 131.726754 -380.313139) (xy 131.732528 -380.320296)
			(xy 131.754336 -380.345932) (xy 131.792287 -380.40152) (xy 131.823321 -380.461245) (xy 131.846994 -380.524252)
			(xy 131.862967 -380.589636) (xy 131.871003 -380.656404) (xy 161.548806 -380.656404) (xy 161.55688 -380.589468)
			(xy 161.572912 -380.523981) (xy 161.596672 -380.460885) (xy 161.627819 -380.401089) (xy 161.665902 -380.345454)
			(xy 161.687764 -380.319788) (xy 161.693556 -380.31264) (xy 161.700072 -380.295451) (xy 161.700464 -380.28626)
			(xy 161.700464 -379.794008) (xy 161.700036 -379.784823) (xy 161.693533 -379.767639) (xy 161.687764 -379.76048)
			(xy 161.665948 -379.734775) (xy 161.627861 -379.679146) (xy 161.59671 -379.619354) (xy 161.572945 -379.556263)
			(xy 161.556907 -379.490779) (xy 161.548828 -379.423846) (xy 161.548823 -379.356426) (xy 161.556894 -379.289492)
			(xy 161.572923 -379.224006) (xy 161.59668 -379.160911) (xy 161.627824 -379.101116) (xy 161.665904 -379.045482)
			(xy 161.687764 -379.019816) (xy 161.693587 -379.01269) (xy 161.700084 -378.995484) (xy 161.700464 -378.986288)
			(xy 161.700464 -378.828554) (xy 161.70089 -378.818421) (xy 161.708637 -378.799695) (xy 161.722942 -378.785339)
			(xy 161.741641 -378.777526) (xy 161.751772 -378.776992) (xy 162.468052 -378.776992) (xy 162.478202 -378.777461)
			(xy 162.496952 -378.785239) (xy 162.511277 -378.799622) (xy 162.518979 -378.818402) (xy 162.51936 -378.828554)
			(xy 162.51936 -378.986288) (xy 162.519785 -378.995473) (xy 162.526289 -379.012658) (xy 162.53206 -379.019816)
			(xy 162.553973 -379.045442) (xy 162.592062 -379.101081) (xy 162.623213 -379.160882) (xy 162.646977 -379.223984)
			(xy 162.66301 -379.289479) (xy 162.671083 -379.356422) (xy 162.671078 -379.42385) (xy 162.662997 -379.490792)
			(xy 162.646955 -379.556285) (xy 162.623184 -379.619384) (xy 162.592025 -379.679181) (xy 162.553928 -379.734815)
			(xy 162.53206 -379.76048) (xy 162.526242 -379.76761) (xy 162.519741 -379.784812) (xy 162.51936 -379.794008)
			(xy 162.51936 -380.28626) (xy 162.519799 -380.295444) (xy 162.526294 -380.312628) (xy 162.53206 -380.319788)
			(xy 162.553945 -380.345436) (xy 162.592036 -380.401072) (xy 162.623188 -380.460871) (xy 162.646953 -380.52397)
			(xy 162.662988 -380.589461) (xy 162.671063 -380.656402) (xy 162.671063 -380.656463) (xy 165.949102 -380.656463)
			(xy 165.957144 -380.589642) (xy 165.973115 -380.524261) (xy 165.996786 -380.461257) (xy 166.027818 -380.401534)
			(xy 166.065765 -380.345948) (xy 166.087552 -380.320296) (xy 166.093339 -380.313144) (xy 166.099858 -380.295959)
			(xy 166.100252 -380.286768) (xy 166.100252 -379.7935) (xy 166.09983 -379.784314) (xy 166.093323 -379.76713)
			(xy 166.087552 -379.759972) (xy 166.065811 -379.734281) (xy 166.02786 -379.678701) (xy 165.996824 -379.618982)
			(xy 165.973148 -379.555983) (xy 165.957171 -379.490605) (xy 165.949123 -379.423787) (xy 165.949119 -379.356485)
			(xy 165.957158 -379.289666) (xy 165.973127 -379.224286) (xy 165.996795 -379.161284) (xy 166.027823 -379.101562)
			(xy 166.065767 -379.045976) (xy 166.087552 -379.020324) (xy 166.09337 -379.013194) (xy 166.09987 -378.995992)
			(xy 166.100252 -378.986796) (xy 166.100252 -378.828554) (xy 166.100696 -378.818392) (xy 166.108488 -378.799619)
			(xy 166.122869 -378.785255) (xy 166.141651 -378.777484) (xy 166.151814 -378.776992) (xy 166.868094 -378.776992)
			(xy 166.878246 -378.777537) (xy 166.897006 -378.785301) (xy 166.91137 -378.79965) (xy 166.919153 -378.818403)
			(xy 166.919656 -378.828554) (xy 166.919656 -378.986796) (xy 166.920078 -378.995982) (xy 166.926584 -379.013166)
			(xy 166.932356 -379.020324) (xy 166.954191 -379.045937) (xy 166.992139 -379.101529) (xy 167.02317 -379.161258)
			(xy 167.046841 -379.224268) (xy 167.06281 -379.289655) (xy 167.070851 -379.356482) (xy 167.070847 -379.423791)
			(xy 167.062798 -379.490617) (xy 167.046819 -379.556001) (xy 167.023141 -379.619008) (xy 166.992102 -379.678733)
			(xy 166.954147 -379.73432) (xy 166.932356 -379.759972) (xy 166.926541 -379.767104) (xy 166.920038 -379.784305)
			(xy 166.919656 -379.7935) (xy 166.919656 -380.286768) (xy 166.920091 -380.295952) (xy 166.926588 -380.313137)
			(xy 166.932356 -380.320296) (xy 166.954164 -380.345932) (xy 166.992112 -380.40152) (xy 167.023145 -380.461246)
			(xy 167.046817 -380.524253) (xy 167.062789 -380.589637) (xy 167.070824 -380.656403) (xy 170.34887 -380.656403)
			(xy 170.356944 -380.589466) (xy 170.372979 -380.523977) (xy 170.396743 -380.460881) (xy 170.427894 -380.401086)
			(xy 170.465984 -380.345452) (xy 170.487848 -380.319788) (xy 170.493638 -380.312638) (xy 170.500155 -380.295451)
			(xy 170.500548 -380.28626) (xy 170.500548 -379.794008) (xy 170.500123 -379.784823) (xy 170.493619 -379.767639)
			(xy 170.487848 -379.76048) (xy 170.46603 -379.734777) (xy 170.427936 -379.679149) (xy 170.396781 -379.619358)
			(xy 170.373012 -379.556266) (xy 170.356971 -379.490781) (xy 170.348891 -379.423846) (xy 170.348887 -379.356426)
			(xy 170.356959 -379.28949) (xy 170.37299 -379.224003) (xy 170.396751 -379.160908) (xy 170.427899 -379.101113)
			(xy 170.465985 -379.04548) (xy 170.487848 -379.019816) (xy 170.493669 -379.012688) (xy 170.500168 -378.995484)
			(xy 170.500548 -378.986288) (xy 170.500548 -378.828554) (xy 170.500989 -378.818423) (xy 170.508734 -378.7997)
			(xy 170.523034 -378.785345) (xy 170.541727 -378.777529) (xy 170.551856 -378.776992) (xy 171.268136 -378.776992)
			(xy 171.278291 -378.777392) (xy 171.297043 -378.785198) (xy 171.311365 -378.799601) (xy 171.319065 -378.818396)
			(xy 171.319444 -378.828554) (xy 171.319444 -378.986288) (xy 171.319872 -378.995473) (xy 171.326375 -379.012657)
			(xy 171.332144 -379.019816) (xy 171.354057 -379.045441) (xy 171.392148 -379.10108) (xy 171.4233 -379.160881)
			(xy 171.447064 -379.223984) (xy 171.463098 -379.289478) (xy 171.47117 -379.356422) (xy 171.471166 -379.42385)
			(xy 171.463085 -379.490793) (xy 171.447042 -379.556285) (xy 171.42327 -379.619384) (xy 171.392111 -379.679182)
			(xy 171.354013 -379.734816) (xy 171.332144 -379.76048) (xy 171.326324 -379.767608) (xy 171.319825 -379.784812)
			(xy 171.319444 -379.794008) (xy 171.319444 -380.28626) (xy 171.319886 -380.295444) (xy 171.326379 -380.312628)
			(xy 171.332144 -380.319788) (xy 171.35403 -380.345436) (xy 171.392121 -380.401072) (xy 171.423274 -380.46087)
			(xy 171.44704 -380.523969) (xy 171.463076 -380.589461) (xy 171.471151 -380.656402) (xy 171.471151 -380.656463)
			(xy 174.74919 -380.656463) (xy 174.757232 -380.589642) (xy 174.773202 -380.524261) (xy 174.796873 -380.461258)
			(xy 174.827904 -380.401535) (xy 174.86585 -380.345948) (xy 174.887636 -380.320296) (xy 174.893421 -380.313143)
			(xy 174.899942 -380.295958) (xy 174.900336 -380.286768) (xy 174.900336 -379.7935) (xy 174.899918 -379.784314)
			(xy 174.893409 -379.76713) (xy 174.887636 -379.759972) (xy 174.865896 -379.734281) (xy 174.827946 -379.6787)
			(xy 174.796911 -379.618982) (xy 174.773235 -379.555982) (xy 174.757259 -379.490605) (xy 174.749211 -379.423787)
			(xy 174.749207 -379.356486) (xy 174.757246 -379.289666) (xy 174.773214 -379.224287) (xy 174.796881 -379.161284)
			(xy 174.827909 -379.101562) (xy 174.865851 -379.045976) (xy 174.887636 -379.020324) (xy 174.893452 -379.013193)
			(xy 174.899954 -378.995991) (xy 174.900336 -378.986796) (xy 174.900336 -378.828554) (xy 174.900796 -378.818394)
			(xy 174.908585 -378.799624) (xy 174.922961 -378.78526) (xy 174.941737 -378.777487) (xy 174.951898 -378.776992)
			(xy 175.668178 -378.776992) (xy 175.678329 -378.77755) (xy 175.697089 -378.785309) (xy 175.711453 -378.799654)
			(xy 175.719237 -378.818404) (xy 175.71974 -378.828554) (xy 175.71974 -378.986796) (xy 175.720166 -378.995981)
			(xy 175.72667 -379.013165) (xy 175.73244 -379.020324) (xy 175.754276 -379.045937) (xy 175.792225 -379.101529)
			(xy 175.823257 -379.161257) (xy 175.846928 -379.224267) (xy 175.862898 -379.289654) (xy 175.870939 -379.356481)
			(xy 175.870934 -379.423791) (xy 175.862885 -379.490617) (xy 175.846907 -379.556002) (xy 175.823227 -379.619009)
			(xy 175.792187 -379.678734) (xy 175.754231 -379.73432) (xy 175.73244 -379.759972) (xy 175.726623 -379.767102)
			(xy 175.720122 -379.784305) (xy 175.71974 -379.7935) (xy 175.71974 -380.286768) (xy 175.720179 -380.295952)
			(xy 175.726674 -380.313136) (xy 175.73244 -380.320296) (xy 175.754248 -380.345932) (xy 175.792198 -380.40152)
			(xy 175.823231 -380.461246) (xy 175.846904 -380.524252) (xy 175.862876 -380.589637) (xy 175.870919 -380.656462)
			(xy 175.870917 -380.723769) (xy 175.862871 -380.790593) (xy 175.846895 -380.855977) (xy 175.823219 -380.918982)
			(xy 175.792182 -380.978706) (xy 175.75423 -381.034292) (xy 175.73244 -381.059944) (xy 175.726635 -381.067083)
			(xy 175.720127 -381.084278) (xy 175.71974 -381.093472) (xy 175.71974 -381.251206) (xy 175.71934 -381.261381)
			(xy 175.711549 -381.28018) (xy 175.697156 -381.294565) (xy 175.678353 -381.302346) (xy 175.668178 -381.302768)
			(xy 174.951898 -381.302768) (xy 174.941741 -381.302268) (xy 174.922973 -381.294494) (xy 174.908608 -381.280131)
			(xy 174.900832 -381.261363) (xy 174.900336 -381.251206) (xy 174.900336 -381.093472) (xy 174.899931 -381.084284)
			(xy 174.893413 -381.067101) (xy 174.887636 -381.059944) (xy 174.865868 -381.034275) (xy 174.827919 -380.978691)
			(xy 174.796885 -380.91897) (xy 174.773211 -380.855968) (xy 174.757237 -380.790587) (xy 174.749191 -380.723767)
			(xy 174.74919 -380.656463) (xy 171.471151 -380.656463) (xy 171.471149 -380.723828) (xy 171.46307 -380.790769)
			(xy 171.447031 -380.85626) (xy 171.423262 -380.919358) (xy 171.392106 -380.979154) (xy 171.354011 -381.034788)
			(xy 171.332144 -381.060452) (xy 171.326336 -381.067589) (xy 171.31983 -381.084786) (xy 171.319444 -381.09398)
			(xy 171.319444 -381.251206) (xy 171.318978 -381.261335) (xy 171.311245 -381.280059) (xy 171.296952 -381.294416)
			(xy 171.278263 -381.302232) (xy 171.268136 -381.302768) (xy 170.551856 -381.302768) (xy 170.541695 -381.302414)
			(xy 170.522936 -381.294598) (xy 170.508613 -381.28018) (xy 170.50092 -381.26137) (xy 170.500548 -381.251206)
			(xy 170.500548 -381.09398) (xy 170.500137 -381.084793) (xy 170.493623 -381.067609) (xy 170.487848 -381.060452)
			(xy 170.466002 -381.034771) (xy 170.42791 -380.97914) (xy 170.396755 -380.919347) (xy 170.372988 -380.856252)
			(xy 170.35695 -380.790764) (xy 170.348871 -380.723827) (xy 170.34887 -380.656403) (xy 167.070824 -380.656403)
			(xy 167.070831 -380.656462) (xy 167.070829 -380.723768) (xy 167.062783 -380.790592) (xy 167.046808 -380.855976)
			(xy 167.023133 -380.918981) (xy 166.992097 -380.978705) (xy 166.954145 -381.034292) (xy 166.932356 -381.059944)
			(xy 166.926553 -381.067084) (xy 166.920043 -381.084279) (xy 166.919656 -381.093472) (xy 166.919656 -381.251206)
			(xy 166.919171 -381.261365) (xy 166.911394 -381.280135) (xy 166.897025 -381.2945) (xy 166.878253 -381.302274)
			(xy 166.868094 -381.302768) (xy 166.151814 -381.302768) (xy 166.141644 -381.302325) (xy 166.122851 -381.294546)
			(xy 166.108466 -381.280166) (xy 166.100679 -381.261376) (xy 166.100252 -381.251206) (xy 166.100252 -381.093472)
			(xy 166.099844 -381.084285) (xy 166.093327 -381.067101) (xy 166.087552 -381.059944) (xy 166.065784 -381.034276)
			(xy 166.027833 -380.978692) (xy 165.996799 -380.918971) (xy 165.973124 -380.855968) (xy 165.957149 -380.790588)
			(xy 165.949103 -380.723767) (xy 165.949102 -380.656463) (xy 162.671063 -380.656463) (xy 162.671061 -380.723828)
			(xy 162.662983 -380.790768) (xy 162.646944 -380.856259) (xy 162.623176 -380.919357) (xy 162.59202 -380.979153)
			(xy 162.553927 -381.034787) (xy 162.53206 -381.060452) (xy 162.526254 -381.06759) (xy 162.519746 -381.084786)
			(xy 162.51936 -381.09398) (xy 162.51936 -381.251206) (xy 162.518878 -381.261333) (xy 162.511148 -381.280054)
			(xy 162.496861 -381.29441) (xy 162.478177 -381.302229) (xy 162.468052 -381.302768) (xy 161.751772 -381.302768)
			(xy 161.741612 -381.302401) (xy 161.722853 -381.29459) (xy 161.708529 -381.280176) (xy 161.700836 -381.261368)
			(xy 161.700464 -381.251206) (xy 161.700464 -381.09398) (xy 161.700049 -381.084794) (xy 161.693537 -381.06761)
			(xy 161.687764 -381.060452) (xy 161.665921 -381.03477) (xy 161.627834 -380.979137) (xy 161.596684 -380.919343)
			(xy 161.572921 -380.856248) (xy 161.556885 -380.790762) (xy 161.548808 -380.723826) (xy 161.548806 -380.656404)
			(xy 131.871003 -380.656404) (xy 131.87101 -380.656461) (xy 131.871008 -380.723769) (xy 131.862961 -380.790593)
			(xy 131.846985 -380.855977) (xy 131.823309 -380.918982) (xy 131.792271 -380.978706) (xy 131.754318 -381.034292)
			(xy 131.732528 -381.059944) (xy 131.726722 -381.067082) (xy 131.720215 -381.084278) (xy 131.719828 -381.093472)
			(xy 131.719828 -381.251206) (xy 131.71944 -381.261382) (xy 131.711647 -381.280184) (xy 131.69725 -381.294569)
			(xy 131.678443 -381.302348) (xy 131.668266 -381.302768) (xy 130.951986 -381.302768) (xy 130.941828 -381.302278)
			(xy 130.92306 -381.2945) (xy 130.908695 -381.280133) (xy 130.90092 -381.261364) (xy 130.900424 -381.251206)
			(xy 130.900424 -381.093472) (xy 130.900022 -381.084284) (xy 130.893502 -381.0671) (xy 130.887724 -381.059944)
			(xy 130.865956 -381.034276) (xy 130.828008 -380.978691) (xy 130.796975 -380.91897) (xy 130.773301 -380.855967)
			(xy 130.757327 -380.790587) (xy 130.749282 -380.723767) (xy 130.74928 -380.656463) (xy 127.471217 -380.656463)
			(xy 127.471215 -380.723827) (xy 127.463138 -380.790766) (xy 127.447101 -380.856256) (xy 127.423336 -380.919354)
			(xy 127.392185 -380.979151) (xy 127.354096 -381.034786) (xy 127.332232 -381.060452) (xy 127.326423 -381.067588)
			(xy 127.319918 -381.084786) (xy 127.319532 -381.09398) (xy 127.319532 -381.251206) (xy 127.319077 -381.261337)
			(xy 127.311342 -381.280063) (xy 127.297046 -381.29442) (xy 127.278352 -381.302234) (xy 127.268224 -381.302768)
			(xy 126.551944 -381.302768) (xy 126.541789 -381.302342) (xy 126.523031 -381.294555) (xy 126.508705 -381.280159)
			(xy 126.50101 -381.261363) (xy 126.500636 -381.251206) (xy 126.500636 -381.09398) (xy 126.500227 -381.084793)
			(xy 126.493712 -381.067609) (xy 126.487936 -381.060452) (xy 126.46609 -381.034771) (xy 126.427999 -380.97914)
			(xy 126.396845 -380.919346) (xy 126.373078 -380.856251) (xy 126.35704 -380.790764) (xy 126.348962 -380.723826)
			(xy 126.34896 -380.656404) (xy 123.070915 -380.656404) (xy 123.070922 -380.656462) (xy 123.07092 -380.723769)
			(xy 123.062874 -380.790593) (xy 123.046898 -380.855976) (xy 123.023223 -380.918982) (xy 122.992186 -380.978706)
			(xy 122.954234 -381.034292) (xy 122.932444 -381.059944) (xy 122.926639 -381.067083) (xy 122.920131 -381.084279)
			(xy 122.919744 -381.093472) (xy 122.919744 -381.251206) (xy 122.919341 -381.26138) (xy 122.91155 -381.280178)
			(xy 122.897158 -381.294564) (xy 122.878356 -381.302345) (xy 122.868182 -381.302768) (xy 122.151902 -381.302768)
			(xy 122.141745 -381.302265) (xy 122.122977 -381.294492) (xy 122.108612 -381.28013) (xy 122.100836 -381.261363)
			(xy 122.10034 -381.251206) (xy 122.10034 -381.093472) (xy 122.099934 -381.084285) (xy 122.093417 -381.067101)
			(xy 122.08764 -381.059944) (xy 122.065872 -381.034276) (xy 122.027923 -380.978691) (xy 121.996888 -380.91897)
			(xy 121.973215 -380.855968) (xy 121.95724 -380.790588) (xy 121.949194 -380.723767) (xy 121.949193 -380.656463)
			(xy 118.671154 -380.656463) (xy 118.671152 -380.723828) (xy 118.663073 -380.790769) (xy 118.647034 -380.85626)
			(xy 118.623265 -380.919357) (xy 118.592109 -380.979154) (xy 118.554015 -381.034788) (xy 118.532148 -381.060452)
			(xy 118.52634 -381.067589) (xy 118.519834 -381.084786) (xy 118.519448 -381.09398) (xy 118.519448 -381.251206)
			(xy 118.518978 -381.261335) (xy 118.511246 -381.280058) (xy 118.496954 -381.294415) (xy 118.478266 -381.302231)
			(xy 118.46814 -381.302768) (xy 117.75186 -381.302768) (xy 117.741699 -381.30241) (xy 117.72294 -381.294596)
			(xy 117.708617 -381.280179) (xy 117.700924 -381.261369) (xy 117.700552 -381.251206) (xy 117.700552 -381.09398)
			(xy 117.70014 -381.084793) (xy 117.693626 -381.06761) (xy 117.687852 -381.060452) (xy 117.666006 -381.034771)
			(xy 117.627913 -380.97914) (xy 117.596759 -380.919347) (xy 117.572991 -380.856252) (xy 117.556953 -380.790764)
			(xy 117.548874 -380.723827) (xy 117.548873 -380.656403) (xy 105.919524 -380.656403) (xy 105.919524 -380.877572)
			(xy 105.919034 -380.907556) (xy 105.911206 -380.967012) (xy 105.895685 -381.024937) (xy 105.872736 -381.080341)
			(xy 105.842752 -381.132275) (xy 105.806246 -381.179851) (xy 105.763841 -381.222256) (xy 105.716265 -381.258762)
			(xy 105.664331 -381.288746) (xy 105.608927 -381.311695) (xy 105.551002 -381.327216) (xy 105.491546 -381.335044)
			(xy 105.431578 -381.335044) (xy 105.372122 -381.327216) (xy 105.314197 -381.311695) (xy 105.258793 -381.288746)
			(xy 105.206859 -381.258762) (xy 105.159283 -381.222256) (xy 105.116878 -381.179851) (xy 105.080372 -381.132275)
			(xy 105.050388 -381.080341) (xy 105.027439 -381.024937) (xy 105.011918 -380.967012) (xy 105.00409 -380.907556)
			(xy 105.0036 -380.877572) (xy 87.838954 -380.877572) (xy 87.823216 -380.919355) (xy 87.792063 -380.979152)
			(xy 87.753973 -381.034787) (xy 87.732108 -381.060452) (xy 87.726308 -381.067595) (xy 87.719795 -381.084787)
			(xy 87.719408 -381.09398) (xy 87.719408 -381.251206) (xy 87.71888 -381.261327) (xy 87.711159 -381.280039)
			(xy 87.696886 -381.294394) (xy 87.678218 -381.302221) (xy 87.6681 -381.302768) (xy 86.95182 -381.302768)
			(xy 86.941663 -381.302362) (xy 86.922905 -381.294567) (xy 86.90858 -381.280165) (xy 86.900885 -381.261365)
			(xy 86.900512 -381.251206) (xy 86.900512 -381.09398) (xy 86.900109 -381.084792) (xy 86.89359 -381.067608)
			(xy 86.887812 -381.060452) (xy 86.865967 -381.034771) (xy 86.827877 -380.979139) (xy 86.796725 -380.919345)
			(xy 86.772959 -380.85625) (xy 86.756922 -380.790763) (xy 86.748844 -380.723826) (xy 86.748842 -380.656404)
			(xy 83.470797 -380.656404) (xy 83.470804 -380.656461) (xy 83.470802 -380.723769) (xy 83.462755 -380.790593)
			(xy 83.446779 -380.855977) (xy 83.423102 -380.918983) (xy 83.392064 -380.978706) (xy 83.35411 -381.034292)
			(xy 83.33232 -381.059944) (xy 83.326525 -381.06709) (xy 83.320009 -381.08428) (xy 83.31962 -381.093472)
			(xy 83.31962 -381.251206) (xy 83.31924 -381.261383) (xy 83.311445 -381.280186) (xy 83.297046 -381.294572)
			(xy 83.278236 -381.302349) (xy 83.268058 -381.302768) (xy 82.551778 -381.302768) (xy 82.54162 -381.302285)
			(xy 82.522851 -381.294504) (xy 82.508487 -381.280136) (xy 82.500712 -381.261365) (xy 82.500216 -381.251206)
			(xy 82.500216 -381.093472) (xy 82.499816 -381.084284) (xy 82.493295 -381.0671) (xy 82.487516 -381.059944)
			(xy 82.465749 -381.034275) (xy 82.427801 -380.978691) (xy 82.396768 -380.918969) (xy 82.373095 -380.855967)
			(xy 82.357121 -380.790587) (xy 82.349076 -380.723767) (xy 82.349074 -380.656464) (xy 79.071011 -380.656464)
			(xy 79.071009 -380.723827) (xy 79.062932 -380.790767) (xy 79.046895 -380.856256) (xy 79.02313 -380.919354)
			(xy 78.991978 -380.979151) (xy 78.953888 -381.034786) (xy 78.932024 -381.060452) (xy 78.926226 -381.067596)
			(xy 78.919711 -381.084787) (xy 78.919324 -381.09398) (xy 78.919324 -381.251206) (xy 78.918877 -381.261337)
			(xy 78.911141 -381.280066) (xy 78.896842 -381.294423) (xy 78.878145 -381.302235) (xy 78.868016 -381.302768)
			(xy 78.151736 -381.302768) (xy 78.14158 -381.302348) (xy 78.122823 -381.294558) (xy 78.108497 -381.28016)
			(xy 78.100802 -381.261364) (xy 78.100428 -381.251206) (xy 78.100428 -381.09398) (xy 78.100021 -381.084793)
			(xy 78.093505 -381.067609) (xy 78.087728 -381.060452) (xy 78.065883 -381.034771) (xy 78.027792 -380.979139)
			(xy 77.996638 -380.919346) (xy 77.972872 -380.856251) (xy 77.956834 -380.790763) (xy 77.948756 -380.723826)
			(xy 77.948754 -380.656404) (xy 74.670709 -380.656404) (xy 74.670716 -380.656462) (xy 74.670714 -380.723769)
			(xy 74.662667 -380.790593) (xy 74.646691 -380.855977) (xy 74.623015 -380.918982) (xy 74.591978 -380.978706)
			(xy 74.554026 -381.034292) (xy 74.532236 -381.059944) (xy 74.52643 -381.067082) (xy 74.519923 -381.084278)
			(xy 74.519536 -381.093472) (xy 74.519536 -381.251206) (xy 74.51914 -381.261381) (xy 74.511349 -381.280181)
			(xy 74.496954 -381.294567) (xy 74.478149 -381.302347) (xy 74.467974 -381.302768) (xy 73.751694 -381.302768)
			(xy 73.741537 -381.302272) (xy 73.722769 -381.294496) (xy 73.708404 -381.280131) (xy 73.700628 -381.261363)
			(xy 73.700132 -381.251206) (xy 73.700132 -381.093472) (xy 73.699728 -381.084284) (xy 73.693209 -381.0671)
			(xy 73.687432 -381.059944) (xy 73.665664 -381.034275) (xy 73.627715 -380.978691) (xy 73.596682 -380.91897)
			(xy 73.573008 -380.855967) (xy 73.557034 -380.790587) (xy 73.548988 -380.723767) (xy 73.548987 -380.656463)
			(xy 43.87119 -380.656463) (xy 43.871188 -380.723828) (xy 43.86311 -380.790767) (xy 43.847073 -380.856258)
			(xy 43.823306 -380.919355) (xy 43.792153 -380.979152) (xy 43.754061 -381.034787) (xy 43.732196 -381.060452)
			(xy 43.726394 -381.067594) (xy 43.719883 -381.084787) (xy 43.719496 -381.09398) (xy 43.719496 -381.251206)
			(xy 43.718979 -381.261329) (xy 43.711256 -381.280043) (xy 43.69698 -381.294398) (xy 43.678308 -381.302223)
			(xy 43.668188 -381.302768) (xy 42.951908 -381.302768) (xy 42.94175 -381.302371) (xy 42.922992 -381.294572)
			(xy 42.908667 -381.280167) (xy 42.900973 -381.261366) (xy 42.9006 -381.251206) (xy 42.9006 -381.09398)
			(xy 42.9002 -381.084792) (xy 42.893679 -381.067607) (xy 42.8879 -381.060452) (xy 42.866056 -381.034771)
			(xy 42.827966 -380.979138) (xy 42.796815 -380.919344) (xy 42.773049 -380.85625) (xy 42.757013 -380.790763)
			(xy 42.748935 -380.723826) (xy 42.748933 -380.656404) (xy 39.470887 -380.656404) (xy 39.470894 -380.656461)
			(xy 39.470893 -380.723769) (xy 39.462846 -380.790594) (xy 39.446869 -380.855978) (xy 39.423192 -380.918983)
			(xy 39.392153 -380.978707) (xy 39.354199 -381.034293) (xy 39.332408 -381.059944) (xy 39.326611 -381.067089)
			(xy 39.320096 -381.08428) (xy 39.319708 -381.093472) (xy 39.319708 -381.251206) (xy 39.319173 -381.261358)
			(xy 39.311405 -381.280119) (xy 39.297052 -381.294482) (xy 39.278298 -381.302265) (xy 39.268146 -381.302768)
			(xy 38.551866 -381.302768) (xy 38.541707 -381.302295) (xy 38.522938 -381.29451) (xy 38.508574 -381.280138)
			(xy 38.5008 -381.261365) (xy 38.500304 -381.251206) (xy 38.500304 -381.093472) (xy 38.499907 -381.084283)
			(xy 38.493384 -381.067099) (xy 38.487604 -381.059944) (xy 38.465837 -381.034275) (xy 38.42789 -380.97869)
			(xy 38.396858 -380.918969) (xy 38.373185 -380.855966) (xy 38.357212 -380.790587) (xy 38.349167 -380.723766)
			(xy 38.349165 -380.656464) (xy 35.071102 -380.656464) (xy 35.0711 -380.723828) (xy 35.063023 -380.790767)
			(xy 35.046985 -380.856257) (xy 35.023219 -380.919355) (xy 34.992067 -380.979151) (xy 34.953977 -381.034787)
			(xy 34.932112 -381.060452) (xy 34.926312 -381.067595) (xy 34.919799 -381.084787) (xy 34.919412 -381.09398)
			(xy 34.919412 -381.251206) (xy 34.91888 -381.261327) (xy 34.91116 -381.280038) (xy 34.896888 -381.294392)
			(xy 34.878222 -381.30222) (xy 34.868104 -381.302768) (xy 34.151824 -381.302768) (xy 34.141667 -381.302358)
			(xy 34.122909 -381.294565) (xy 34.108584 -381.280164) (xy 34.100889 -381.261365) (xy 34.100516 -381.251206)
			(xy 34.100516 -381.09398) (xy 34.100112 -381.084792) (xy 34.093594 -381.067608) (xy 34.087816 -381.060452)
			(xy 34.065971 -381.034771) (xy 34.027881 -380.979139) (xy 33.996728 -380.919345) (xy 33.972962 -380.85625)
			(xy 33.956925 -380.790763) (xy 33.948847 -380.723826) (xy 33.948845 -380.656404) (xy 30.6708 -380.656404)
			(xy 30.670807 -380.656461) (xy 30.670805 -380.723769) (xy 30.662758 -380.790593) (xy 30.646782 -380.855977)
			(xy 30.623105 -380.918982) (xy 30.592068 -380.978706) (xy 30.554114 -381.034292) (xy 30.532324 -381.059944)
			(xy 30.526529 -381.067091) (xy 30.520013 -381.08428) (xy 30.519624 -381.093472) (xy 30.519624 -381.251206)
			(xy 30.51924 -381.261383) (xy 30.511446 -381.280185) (xy 30.497048 -381.294571) (xy 30.478239 -381.302349)
			(xy 30.468062 -381.302768) (xy 29.751782 -381.302768) (xy 29.741624 -381.302282) (xy 29.722855 -381.294502)
			(xy 29.708491 -381.280135) (xy 29.700716 -381.261364) (xy 29.70022 -381.251206) (xy 29.70022 -381.093472)
			(xy 29.699819 -381.084284) (xy 29.693298 -381.0671) (xy 29.68752 -381.059944) (xy 29.665752 -381.034276)
			(xy 29.627804 -380.978691) (xy 29.596771 -380.918969) (xy 29.573098 -380.855967) (xy 29.557124 -380.790587)
			(xy 29.549079 -380.723767) (xy 29.549077 -380.656463) (xy 29.557119 -380.589643) (xy 29.573089 -380.524262)
			(xy 29.596759 -380.461258) (xy 29.627789 -380.401535) (xy 29.665734 -380.345948) (xy 29.68752 -380.320296)
			(xy 29.693303 -380.313141) (xy 29.699825 -380.295958) (xy 29.70022 -380.286768) (xy 29.70022 -379.7935)
			(xy 29.699806 -379.784313) (xy 29.693295 -379.767129) (xy 29.68752 -379.759972) (xy 29.66573 -379.734322)
			(xy 29.627781 -379.678735) (xy 29.596748 -379.619011) (xy 29.573075 -379.556006) (xy 29.557102 -379.490624)
			(xy 29.549058 -379.423801) (xy 28.447 -379.423801) (xy 28.447041 -379.423909) (xy 28.463077 -379.489397)
			(xy 28.471153 -379.556335) (xy 28.471153 -379.623759) (xy 28.463078 -379.690697) (xy 28.447043 -379.756186)
			(xy 28.423279 -379.819282) (xy 28.392128 -379.879078) (xy 28.35404 -379.934713) (xy 28.332176 -379.960378)
			(xy 28.326361 -379.96751) (xy 28.319858 -379.984711) (xy 28.319476 -379.993906) (xy 28.319476 -380.151386)
			(xy 28.318962 -380.16151) (xy 28.311242 -380.180228) (xy 28.296964 -380.194584) (xy 28.278289 -380.202406)
			(xy 28.268168 -380.202948) (xy 27.551888 -380.202948) (xy 27.541739 -380.202489) (xy 27.522996 -380.194699)
			(xy 27.508674 -380.180314) (xy 27.500966 -380.161537) (xy 27.50058 -380.151386) (xy 27.50058 -379.993906)
			(xy 27.500171 -379.984719) (xy 27.493657 -379.967534) (xy 27.48788 -379.960378) (xy 27.466012 -379.934716)
			(xy 27.427923 -379.879081) (xy 27.396771 -379.819285) (xy 27.373007 -379.756187) (xy 27.356972 -379.690698)
			(xy 27.348896 -379.623759) (xy 27.348896 -379.556335) (xy 27.356973 -379.489396) (xy 27.373009 -379.423907)
			(xy 27.396774 -379.36081) (xy 27.427926 -379.301013) (xy 27.466015 -379.245379) (xy 27.48788 -379.219714)
			(xy 27.493693 -379.21258) (xy 27.500199 -379.195381) (xy 27.50058 -379.186186) (xy 27.50058 -378.693934)
			(xy 27.500158 -378.684748) (xy 27.493653 -378.667563) (xy 27.48788 -378.660406) (xy 27.465991 -378.634761)
			(xy 27.427905 -378.579124) (xy 27.396756 -378.519324) (xy 27.372994 -378.456225) (xy 27.356961 -378.390733)
			(xy 27.348888 -378.323793) (xy 1.524 -378.323793) (xy 1.524 -382.223705) (xy 27.348899 -382.223705)
			(xy 27.3489 -382.15628) (xy 27.356976 -382.089342) (xy 27.373012 -382.023853) (xy 27.396777 -381.960755)
			(xy 27.427928 -381.900959) (xy 27.466016 -381.845324) (xy 27.48788 -381.819658) (xy 27.493675 -381.812511)
			(xy 27.500191 -381.795322) (xy 27.50058 -381.78613) (xy 27.50058 -381.628904) (xy 27.501088 -381.618798)
			(xy 27.508821 -381.600124) (xy 27.52311 -381.58583) (xy 27.541782 -381.578091) (xy 27.551888 -381.577596)
			(xy 28.268168 -381.577596) (xy 28.278288 -381.578042) (xy 28.29699 -381.585779) (xy 28.311306 -381.600086)
			(xy 28.319053 -381.618784) (xy 28.319476 -381.628904) (xy 28.319476 -381.78613) (xy 28.319877 -381.795318)
			(xy 28.326398 -381.812502) (xy 28.332176 -381.819658) (xy 28.354031 -381.845331) (xy 28.392122 -381.900964)
			(xy 28.423274 -381.960759) (xy 28.44704 -382.023855) (xy 28.463077 -382.089343) (xy 28.471154 -382.156281)
			(xy 28.471155 -382.223646) (xy 31.749194 -382.223646) (xy 31.749195 -382.156339) (xy 31.757241 -382.089516)
			(xy 31.773216 -382.024132) (xy 31.796891 -381.961127) (xy 31.827927 -381.901404) (xy 31.865879 -381.845818)
			(xy 31.887668 -381.820166) (xy 31.89347 -381.813025) (xy 31.899979 -381.795831) (xy 31.900368 -381.786638)
			(xy 31.900368 -381.628904) (xy 31.900824 -381.618754) (xy 31.908613 -381.600008) (xy 31.922998 -381.585686)
			(xy 31.941778 -381.57798) (xy 31.95193 -381.577596) (xy 32.66821 -381.577596) (xy 32.678332 -381.578117)
			(xy 32.697045 -381.58584) (xy 32.711399 -381.600115) (xy 32.719226 -381.618785) (xy 32.719772 -381.628904)
			(xy 32.719772 -381.786638) (xy 32.72017 -381.795826) (xy 32.726693 -381.81301) (xy 32.732472 -381.820166)
			(xy 32.75425 -381.845826) (xy 32.792198 -381.901412) (xy 32.823231 -381.961134) (xy 32.846904 -382.024138)
			(xy 32.862877 -382.089519) (xy 32.870922 -382.15634) (xy 32.870923 -382.223645) (xy 32.870916 -382.223704)
			(xy 36.148987 -382.223704) (xy 36.148988 -382.156281) (xy 36.157064 -382.089342) (xy 36.1731 -382.023853)
			(xy 36.196863 -381.960756) (xy 36.228013 -381.900959) (xy 36.266101 -381.845324) (xy 36.287964 -381.819658)
			(xy 36.293769 -381.812519) (xy 36.300277 -381.795323) (xy 36.300664 -381.78613) (xy 36.300664 -381.628904)
			(xy 36.301188 -381.6188) (xy 36.308917 -381.600129) (xy 36.323202 -381.585835) (xy 36.341868 -381.578094)
			(xy 36.351972 -381.577596) (xy 37.068252 -381.577596) (xy 37.078371 -381.578055) (xy 37.097073 -381.585787)
			(xy 37.111388 -381.60009) (xy 37.119136 -381.618786) (xy 37.11956 -381.628904) (xy 37.11956 -381.78613)
			(xy 37.119965 -381.795318) (xy 37.126483 -381.812501) (xy 37.13226 -381.819658) (xy 37.154116 -381.845331)
			(xy 37.192207 -381.900963) (xy 37.223361 -381.960758) (xy 37.247127 -382.023854) (xy 37.263164 -382.089343)
			(xy 37.271242 -382.156281) (xy 37.271243 -382.223704) (xy 37.271243 -382.223705) (xy 40.548753 -382.223705)
			(xy 40.548754 -382.15628) (xy 40.556832 -382.08934) (xy 40.57287 -382.02385) (xy 40.596638 -381.960752)
			(xy 40.627792 -381.900956) (xy 40.665886 -381.845322) (xy 40.687752 -381.819658) (xy 40.693555 -381.812518)
			(xy 40.700065 -381.795323) (xy 40.700452 -381.78613) (xy 40.700452 -381.628904) (xy 40.700987 -381.618801)
			(xy 40.708715 -381.600133) (xy 40.722996 -381.585839) (xy 40.741658 -381.578096) (xy 40.75176 -381.577596)
			(xy 41.46804 -381.577596) (xy 41.478151 -381.578052) (xy 41.496829 -381.585802) (xy 41.511122 -381.600108)
			(xy 41.518856 -381.618793) (xy 41.519348 -381.628904) (xy 41.519348 -381.78613) (xy 41.519755 -381.795317)
			(xy 41.526272 -381.812501) (xy 41.532048 -381.819658) (xy 41.553904 -381.84533) (xy 41.591996 -381.900963)
			(xy 41.62315 -381.960757) (xy 41.646917 -382.023853) (xy 41.662955 -382.089342) (xy 41.671033 -382.156281)
			(xy 41.671034 -382.223645) (xy 44.949073 -382.223645) (xy 44.949074 -382.15634) (xy 44.957119 -382.089516)
			(xy 44.973093 -382.024133) (xy 44.996767 -381.961128) (xy 45.027801 -381.901405) (xy 45.065751 -381.845818)
			(xy 45.08754 -381.820166) (xy 45.093339 -381.813022) (xy 45.099851 -381.795831) (xy 45.10024 -381.786638)
			(xy 45.10024 -381.628904) (xy 45.100626 -381.618745) (xy 45.108427 -381.599985) (xy 45.122836 -381.58566)
			(xy 45.141641 -381.577968) (xy 45.151802 -381.577596) (xy 45.868082 -381.577596) (xy 45.878202 -381.57814)
			(xy 45.896915 -381.585854) (xy 45.91127 -381.600122) (xy 45.919098 -381.618787) (xy 45.919644 -381.628904)
			(xy 45.919644 -381.786638) (xy 45.920049 -381.795826) (xy 45.926568 -381.813009) (xy 45.932344 -381.820166)
			(xy 45.954122 -381.845826) (xy 45.992072 -381.901411) (xy 46.023107 -381.961133) (xy 46.046781 -382.024137)
			(xy 46.062755 -382.089518) (xy 46.070801 -382.15634) (xy 46.070801 -382.223645) (xy 46.070794 -382.223705)
			(xy 71.348808 -382.223705) (xy 71.348809 -382.15628) (xy 71.356886 -382.089342) (xy 71.372922 -382.023852)
			(xy 71.396687 -381.960755) (xy 71.427838 -381.900958) (xy 71.465928 -381.845323) (xy 71.487792 -381.819658)
			(xy 71.493588 -381.812512) (xy 71.500103 -381.795322) (xy 71.500492 -381.78613) (xy 71.500492 -381.628904)
			(xy 71.500919 -381.618783) (xy 71.508664 -381.600081) (xy 71.522977 -381.585767) (xy 71.541679 -381.57802)
			(xy 71.5518 -381.577596) (xy 72.26808 -381.577596) (xy 72.278201 -381.578032) (xy 72.296903 -381.585773)
			(xy 72.311218 -381.600083) (xy 72.318965 -381.618783) (xy 72.319388 -381.628904) (xy 72.319388 -381.78613)
			(xy 72.319786 -381.795318) (xy 72.326308 -381.812503) (xy 72.332088 -381.819658) (xy 72.353943 -381.845331)
			(xy 72.392032 -381.900964) (xy 72.423184 -381.960759) (xy 72.446949 -382.023855) (xy 72.462986 -382.089343)
			(xy 72.471063 -382.156281) (xy 72.471064 -382.223646) (xy 75.749104 -382.223646) (xy 75.749104 -382.156339)
			(xy 75.75715 -382.089515) (xy 75.773125 -382.024132) (xy 75.796801 -381.961127) (xy 75.827838 -381.901403)
			(xy 75.86579 -381.845818) (xy 75.88758 -381.820166) (xy 75.893371 -381.813017) (xy 75.89989 -381.795829)
			(xy 75.90028 -381.786638) (xy 75.90028 -381.628904) (xy 75.900725 -381.618753) (xy 75.908515 -381.600004)
			(xy 75.922904 -381.585681) (xy 75.941689 -381.577978) (xy 75.951842 -381.577596) (xy 76.668122 -381.577596)
			(xy 76.678245 -381.578107) (xy 76.696958 -381.585834) (xy 76.711312 -381.600112) (xy 76.719138 -381.618784)
			(xy 76.719684 -381.628904) (xy 76.719684 -381.786638) (xy 76.720079 -381.795827) (xy 76.726604 -381.813011)
			(xy 76.732384 -381.820166) (xy 76.754161 -381.845826) (xy 76.792109 -381.901412) (xy 76.823141 -381.961135)
			(xy 76.846814 -382.024138) (xy 76.862787 -382.089519) (xy 76.870831 -382.156341) (xy 76.870832 -382.223644)
			(xy 76.870825 -382.223704) (xy 80.148896 -382.223704) (xy 80.148897 -382.15628) (xy 80.156973 -382.089342)
			(xy 80.173009 -382.023853) (xy 80.196773 -381.960755) (xy 80.227924 -381.900959) (xy 80.266012 -381.845324)
			(xy 80.287876 -381.819658) (xy 80.29367 -381.812511) (xy 80.300187 -381.795322) (xy 80.300576 -381.78613)
			(xy 80.300576 -381.628904) (xy 80.301088 -381.618798) (xy 80.30882 -381.600125) (xy 80.323108 -381.585831)
			(xy 80.341779 -381.578092) (xy 80.351884 -381.577596) (xy 81.068164 -381.577596) (xy 81.078284 -381.578046)
			(xy 81.096986 -381.585781) (xy 81.111301 -381.600087) (xy 81.119048 -381.618785) (xy 81.119472 -381.628904)
			(xy 81.119472 -381.78613) (xy 81.119874 -381.795318) (xy 81.126394 -381.812502) (xy 81.132172 -381.819658)
			(xy 81.154027 -381.845331) (xy 81.192118 -381.900964) (xy 81.223271 -381.960759) (xy 81.247037 -382.023854)
			(xy 81.263074 -382.089343) (xy 81.271151 -382.156281) (xy 81.271152 -382.223704) (xy 84.548687 -382.223704)
			(xy 84.548688 -382.156281) (xy 84.556764 -382.089342) (xy 84.5728 -382.023853) (xy 84.596563 -381.960756)
			(xy 84.627713 -381.900959) (xy 84.665801 -381.845324) (xy 84.687664 -381.819658) (xy 84.693469 -381.812519)
			(xy 84.699977 -381.795323) (xy 84.700364 -381.78613) (xy 84.700364 -381.628904) (xy 84.700888 -381.6188)
			(xy 84.708617 -381.600129) (xy 84.722902 -381.585835) (xy 84.741568 -381.578094) (xy 84.751672 -381.577596)
			(xy 85.467952 -381.577596) (xy 85.478071 -381.578055) (xy 85.496773 -381.585787) (xy 85.511088 -381.60009)
			(xy 85.518836 -381.618786) (xy 85.51926 -381.628904) (xy 85.51926 -381.78613) (xy 85.519665 -381.795318)
			(xy 85.526183 -381.812501) (xy 85.53196 -381.819658) (xy 85.553816 -381.845331) (xy 85.591907 -381.900963)
			(xy 85.623061 -381.960758) (xy 85.646827 -382.023854) (xy 85.662864 -382.089343) (xy 85.670942 -382.156281)
			(xy 85.670943 -382.223646) (xy 88.948982 -382.223646) (xy 88.948983 -382.156339) (xy 88.957028 -382.089516)
			(xy 88.973003 -382.024133) (xy 88.996677 -381.961128) (xy 89.027712 -381.901404) (xy 89.065663 -381.845818)
			(xy 89.087452 -381.820166) (xy 89.093252 -381.813023) (xy 89.099763 -381.795831) (xy 89.100152 -381.786638)
			(xy 89.100152 -381.628904) (xy 89.100624 -381.618756) (xy 89.108409 -381.600013) (xy 89.12279 -381.585691)
			(xy 89.141564 -381.577983) (xy 89.151714 -381.577596) (xy 89.867994 -381.577596) (xy 89.878115 -381.57813)
			(xy 89.896828 -381.585848) (xy 89.911183 -381.600119) (xy 89.91901 -381.618786) (xy 89.919556 -381.628904)
			(xy 89.919556 -381.786638) (xy 89.919958 -381.795826) (xy 89.926478 -381.81301) (xy 89.932256 -381.820166)
			(xy 89.954034 -381.845826) (xy 89.991983 -381.901411) (xy 90.023017 -381.961134) (xy 90.046691 -382.024137)
			(xy 90.062665 -382.089519) (xy 90.07071 -382.15634) (xy 90.070711 -382.223645) (xy 115.349246 -382.223645)
			(xy 115.349247 -382.15634) (xy 115.357291 -382.089517) (xy 115.373264 -382.024135) (xy 115.396937 -381.96113)
			(xy 115.427969 -381.901406) (xy 115.465917 -381.845819) (xy 115.487704 -381.820166) (xy 115.493498 -381.813019)
			(xy 115.500014 -381.79583) (xy 115.500404 -381.786638) (xy 115.500404 -381.628904) (xy 115.500825 -381.61875)
			(xy 115.50862 -381.599997) (xy 115.523017 -381.585673) (xy 115.54181 -381.577974) (xy 115.551966 -381.577596)
			(xy 116.268246 -381.577596) (xy 116.27837 -381.578088) (xy 116.297084 -381.585822) (xy 116.311437 -381.600106)
			(xy 116.319262 -381.618782) (xy 116.319808 -381.628904) (xy 116.319808 -381.786638) (xy 116.320198 -381.795827)
			(xy 116.326725 -381.813012) (xy 116.332508 -381.820166) (xy 116.354288 -381.845826) (xy 116.39224 -381.90141)
			(xy 116.423277 -381.961132) (xy 116.446952 -382.024135) (xy 116.462928 -382.089517) (xy 116.470973 -382.15634)
			(xy 116.470974 -382.223645) (xy 116.470967 -382.223705) (xy 119.749014 -382.223705) (xy 119.749015 -382.15628)
			(xy 119.757092 -382.089341) (xy 119.773128 -382.023852) (xy 119.796894 -381.960754) (xy 119.828046 -381.900958)
			(xy 119.866135 -381.845323) (xy 119.888 -381.819658) (xy 119.893797 -381.812513) (xy 119.900311 -381.795322)
			(xy 119.9007 -381.78613) (xy 119.9007 -381.628904) (xy 119.901119 -381.618782) (xy 119.908866 -381.600078)
			(xy 119.923182 -381.585764) (xy 119.941886 -381.578019) (xy 119.952008 -381.577596) (xy 120.668288 -381.577596)
			(xy 120.678409 -381.578026) (xy 120.697112 -381.585769) (xy 120.711426 -381.600081) (xy 120.719173 -381.618783)
			(xy 120.719596 -381.628904) (xy 120.719596 -381.78613) (xy 120.719992 -381.795319) (xy 120.726516 -381.812503)
			(xy 120.732296 -381.819658) (xy 120.75415 -381.845331) (xy 120.79224 -381.900965) (xy 120.823391 -381.96076)
			(xy 120.847156 -382.023855) (xy 120.863192 -382.089344) (xy 120.871269 -382.156281) (xy 120.87127 -382.223646)
			(xy 124.14931 -382.223646) (xy 124.14931 -382.156339) (xy 124.157356 -382.089515) (xy 124.173332 -382.024132)
			(xy 124.197008 -381.961127) (xy 124.228045 -381.901403) (xy 124.265998 -381.845818) (xy 124.287788 -381.820166)
			(xy 124.29358 -381.813018) (xy 124.300098 -381.79583) (xy 124.300488 -381.786638) (xy 124.300488 -381.628904)
			(xy 124.300925 -381.618752) (xy 124.308717 -381.600002) (xy 124.323109 -381.585679) (xy 124.341896 -381.577977)
			(xy 124.35205 -381.577596) (xy 125.06833 -381.577596) (xy 125.078453 -381.578101) (xy 125.097167 -381.58583)
			(xy 125.11152 -381.60011) (xy 125.119346 -381.618783) (xy 125.119892 -381.628904) (xy 125.119892 -381.786638)
			(xy 125.120286 -381.795827) (xy 125.126811 -381.813011) (xy 125.132592 -381.820166) (xy 125.154369 -381.845827)
			(xy 125.192316 -381.901413) (xy 125.223348 -381.961135) (xy 125.24702 -382.024139) (xy 125.262993 -382.089519)
			(xy 125.271037 -382.156341) (xy 125.271038 -382.223644) (xy 125.271038 -382.223646) (xy 128.5491 -382.223646)
			(xy 128.549101 -382.156339) (xy 128.557147 -382.089515) (xy 128.573122 -382.024132) (xy 128.596798 -381.961127)
			(xy 128.627834 -381.901404) (xy 128.665787 -381.845818) (xy 128.687576 -381.820166) (xy 128.693367 -381.813016)
			(xy 128.699886 -381.795829) (xy 128.700276 -381.786638) (xy 128.700276 -381.628904) (xy 128.700724 -381.618753)
			(xy 128.708514 -381.600005) (xy 128.722902 -381.585683) (xy 128.741685 -381.577979) (xy 128.751838 -381.577596)
			(xy 129.468118 -381.577596) (xy 129.47824 -381.57811) (xy 129.496954 -381.585836) (xy 129.511308 -381.600113)
			(xy 129.519134 -381.618784) (xy 129.51968 -381.628904) (xy 129.51968 -381.786638) (xy 129.520076 -381.795827)
			(xy 129.5266 -381.813011) (xy 129.53238 -381.820166) (xy 129.554157 -381.845826) (xy 129.592105 -381.901412)
			(xy 129.623138 -381.961135) (xy 129.64681 -382.024138) (xy 129.662784 -382.089519) (xy 129.670828 -382.156341)
			(xy 129.670829 -382.223644) (xy 129.670829 -382.223645) (xy 159.349155 -382.223645) (xy 159.349156 -382.15634)
			(xy 159.3572 -382.089517) (xy 159.373174 -382.024134) (xy 159.396847 -381.96113) (xy 159.42788 -381.901406)
			(xy 159.465828 -381.845818) (xy 159.487616 -381.820166) (xy 159.493411 -381.81302) (xy 159.499926 -381.79583)
			(xy 159.500316 -381.786638) (xy 159.500316 -381.628904) (xy 159.500725 -381.618748) (xy 159.508522 -381.599993)
			(xy 159.522923 -381.585669) (xy 159.54172 -381.577972) (xy 159.551878 -381.577596) (xy 160.268158 -381.577596)
			(xy 160.278277 -381.57816) (xy 160.296988 -381.585866) (xy 160.311345 -381.600128) (xy 160.319173 -381.618789)
			(xy 160.31972 -381.628904) (xy 160.31972 -381.786638) (xy 160.320108 -381.795828) (xy 160.326637 -381.813012)
			(xy 160.33242 -381.820166) (xy 160.354199 -381.845826) (xy 160.392151 -381.90141) (xy 160.423187 -381.961132)
			(xy 160.446862 -382.024136) (xy 160.462837 -382.089518) (xy 160.470882 -382.15634) (xy 160.470883 -382.223645)
			(xy 160.470876 -382.223705) (xy 163.748923 -382.223705) (xy 163.748924 -382.15628) (xy 163.757001 -382.089341)
			(xy 163.773038 -382.023851) (xy 163.796804 -381.960754) (xy 163.827956 -381.900957) (xy 163.866047 -381.845323)
			(xy 163.887912 -381.819658) (xy 163.89371 -381.812514) (xy 163.900224 -381.795323) (xy 163.900612 -381.78613)
			(xy 163.900612 -381.628904) (xy 163.90102 -381.61878) (xy 163.908769 -381.600074) (xy 163.923088 -381.58576)
			(xy 163.941796 -381.578016) (xy 163.95192 -381.577596) (xy 164.6682 -381.577596) (xy 164.678322 -381.578016)
			(xy 164.697025 -381.585763) (xy 164.711339 -381.600079) (xy 164.719085 -381.618782) (xy 164.719508 -381.628904)
			(xy 164.719508 -381.78613) (xy 164.719902 -381.795319) (xy 164.726426 -381.812503) (xy 164.732208 -381.819658)
			(xy 164.754062 -381.845331) (xy 164.79215 -381.900965) (xy 164.823301 -381.96076) (xy 164.847065 -382.023856)
			(xy 164.863101 -382.089344) (xy 164.871178 -382.156281) (xy 164.871179 -382.223645) (xy 168.149243 -382.223645)
			(xy 168.149244 -382.15634) (xy 168.157288 -382.089517) (xy 168.173261 -382.024135) (xy 168.196933 -381.96113)
			(xy 168.227965 -381.901406) (xy 168.265913 -381.845819) (xy 168.2877 -381.820166) (xy 168.293494 -381.813019)
			(xy 168.30001 -381.79583) (xy 168.3004 -381.786638) (xy 168.3004 -381.628904) (xy 168.300825 -381.61875)
			(xy 168.308619 -381.599998) (xy 168.323015 -381.585674) (xy 168.341806 -381.577975) (xy 168.351962 -381.577596)
			(xy 169.068242 -381.577596) (xy 169.078366 -381.578091) (xy 169.09708 -381.585824) (xy 169.111433 -381.600107)
			(xy 169.119258 -381.618783) (xy 169.119804 -381.628904) (xy 169.119804 -381.786638) (xy 169.120195 -381.795827)
			(xy 169.126722 -381.813012) (xy 169.132504 -381.820166) (xy 169.154281 -381.845827) (xy 169.192227 -381.901413)
			(xy 169.223258 -381.961136) (xy 169.24693 -382.024139) (xy 169.262902 -382.08952) (xy 169.270946 -382.156341)
			(xy 169.270947 -382.223644) (xy 169.270947 -382.223646) (xy 172.54901 -382.223646) (xy 172.54901 -382.156339)
			(xy 172.557056 -382.089515) (xy 172.573032 -382.024132) (xy 172.596708 -381.961127) (xy 172.627745 -381.901403)
			(xy 172.665698 -381.845818) (xy 172.687488 -381.820166) (xy 172.69328 -381.813018) (xy 172.699798 -381.79583)
			(xy 172.700188 -381.786638) (xy 172.700188 -381.628904) (xy 172.700625 -381.618752) (xy 172.708417 -381.600002)
			(xy 172.722809 -381.585679) (xy 172.741596 -381.577977) (xy 172.75175 -381.577596) (xy 173.46803 -381.577596)
			(xy 173.478153 -381.578101) (xy 173.496867 -381.58583) (xy 173.51122 -381.60011) (xy 173.519046 -381.618783)
			(xy 173.519592 -381.628904) (xy 173.519592 -381.786638) (xy 173.519986 -381.795827) (xy 173.526511 -381.813011)
			(xy 173.532292 -381.820166) (xy 173.554069 -381.845827) (xy 173.592016 -381.901413) (xy 173.623048 -381.961135)
			(xy 173.64672 -382.024139) (xy 173.662693 -382.089519) (xy 173.670737 -382.156341) (xy 173.670738 -382.223644)
			(xy 173.662695 -382.290466) (xy 173.646725 -382.355847) (xy 173.623054 -382.418851) (xy 173.592024 -382.478574)
			(xy 173.554078 -382.534161) (xy 173.532292 -382.559814) (xy 173.526506 -382.566967) (xy 173.519985 -382.584151)
			(xy 173.519592 -382.593342) (xy 173.519592 -383.086864) (xy 173.520021 -383.096049) (xy 173.526522 -383.113234)
			(xy 173.532292 -383.120392) (xy 173.554094 -383.146032) (xy 173.592041 -383.201621) (xy 173.623072 -383.261346)
			(xy 173.646507 -383.323727) (xy 174.749152 -383.323727) (xy 174.749155 -383.256419) (xy 174.757202 -383.189594)
			(xy 174.773179 -383.12421) (xy 174.796856 -383.061204) (xy 174.827893 -383.001479) (xy 174.865846 -382.945892)
			(xy 174.887636 -382.92024) (xy 174.893445 -382.913104) (xy 174.899951 -382.895906) (xy 174.900336 -382.886712)
			(xy 174.900336 -382.728724) (xy 174.900742 -382.718567) (xy 174.908536 -382.699808) (xy 174.922939 -382.685482)
			(xy 174.941739 -382.677788) (xy 174.951898 -382.677416) (xy 175.668178 -382.677416) (xy 175.6783 -382.677944)
			(xy 175.697017 -382.68566) (xy 175.711373 -382.699933) (xy 175.719197 -382.718605) (xy 175.71974 -382.728724)
			(xy 175.71974 -382.886712) (xy 175.720158 -382.895898) (xy 175.726668 -382.913082) (xy 175.73244 -382.92024)
			(xy 175.754193 -382.945921) (xy 175.792144 -383.001503) (xy 175.82318 -383.061222) (xy 175.846856 -383.124223)
			(xy 175.862832 -383.189602) (xy 175.870879 -383.256422) (xy 175.870883 -383.323724) (xy 175.862842 -383.390545)
			(xy 175.846872 -383.455925) (xy 175.823202 -383.518928) (xy 175.792172 -383.578651) (xy 175.754226 -383.634236)
			(xy 175.73244 -383.659888) (xy 175.726616 -383.667014) (xy 175.720119 -383.684219) (xy 175.71974 -383.693416)
			(xy 175.71974 -384.186684) (xy 175.720171 -384.195869) (xy 175.726672 -384.213053) (xy 175.73244 -384.220212)
			(xy 175.754264 -384.245835) (xy 175.792213 -384.301425) (xy 175.823246 -384.361152) (xy 175.846918 -384.424161)
			(xy 175.862889 -384.489547) (xy 175.87093 -384.556373) (xy 175.870927 -384.623681) (xy 175.862879 -384.690507)
			(xy 175.846902 -384.755891) (xy 175.823224 -384.818897) (xy 175.792185 -384.878622) (xy 175.754231 -384.934208)
			(xy 175.73244 -384.95986) (xy 175.726628 -384.966994) (xy 175.720124 -384.984193) (xy 175.71974 -384.993388)
			(xy 175.71974 -385.151376) (xy 175.71926 -385.161524) (xy 175.71148 -385.180268) (xy 175.697101 -385.194591)
			(xy 175.678327 -385.202298) (xy 175.668178 -385.202684) (xy 174.951898 -385.202684) (xy 174.941774 -385.202176)
			(xy 174.923058 -385.194452) (xy 174.908702 -385.180172) (xy 174.900879 -385.161497) (xy 174.900336 -385.151376)
			(xy 174.900336 -384.993388) (xy 174.899924 -384.984201) (xy 174.893411 -384.967017) (xy 174.887636 -384.95986)
			(xy 174.865884 -384.934179) (xy 174.827934 -384.878596) (xy 174.7969 -384.818877) (xy 174.773225 -384.755876)
			(xy 174.75725 -384.690497) (xy 174.749203 -384.623678) (xy 174.749199 -384.556376) (xy 174.75724 -384.489556)
			(xy 174.773209 -384.424176) (xy 174.796878 -384.361173) (xy 174.827906 -384.30145) (xy 174.865851 -384.245864)
			(xy 174.887636 -384.220212) (xy 174.893457 -384.213084) (xy 174.899956 -384.19588) (xy 174.900336 -384.186684)
			(xy 174.900336 -383.693416) (xy 174.89991 -383.684231) (xy 174.893407 -383.667046) (xy 174.887636 -383.659888)
			(xy 174.865813 -383.634265) (xy 174.827865 -383.578674) (xy 174.796834 -383.518947) (xy 174.773163 -383.455938)
			(xy 174.757193 -383.390553) (xy 174.749152 -383.323727) (xy 173.646507 -383.323727) (xy 173.646742 -383.324352)
			(xy 173.662713 -383.389736) (xy 173.670756 -383.456559) (xy 173.670754 -383.523865) (xy 173.662709 -383.590688)
			(xy 173.646735 -383.656071) (xy 173.623062 -383.719076) (xy 173.592028 -383.7788) (xy 173.55408 -383.834387)
			(xy 173.532292 -383.86004) (xy 173.526495 -383.867185) (xy 173.519981 -383.884376) (xy 173.519592 -383.893568)
			(xy 173.519592 -384.051556) (xy 173.519142 -384.061708) (xy 173.51136 -384.080461) (xy 173.496971 -384.094786)
			(xy 173.478184 -384.102486) (xy 173.46803 -384.102864) (xy 172.75175 -384.102864) (xy 172.741627 -384.102333)
			(xy 172.722908 -384.094622) (xy 172.70855 -384.080349) (xy 172.700728 -384.061676) (xy 172.700188 -384.051556)
			(xy 172.700188 -383.893568) (xy 172.699796 -383.884379) (xy 172.69327 -383.867194) (xy 172.687488 -383.86004)
			(xy 172.665715 -383.834376) (xy 172.627762 -383.778792) (xy 172.596725 -383.719071) (xy 172.57305 -383.656068)
			(xy 172.557074 -383.590686) (xy 172.549028 -383.523864) (xy 172.549026 -383.45656) (xy 172.55707 -383.389737)
			(xy 172.573042 -383.324355) (xy 172.596716 -383.261351) (xy 172.62775 -383.201629) (xy 172.6657 -383.146043)
			(xy 172.687488 -383.120392) (xy 172.693269 -383.113236) (xy 172.699793 -383.096054) (xy 172.700188 -383.086864)
			(xy 172.700188 -382.593342) (xy 172.69976 -382.584157) (xy 172.693259 -382.566972) (xy 172.687488 -382.559814)
			(xy 172.665689 -382.534171) (xy 172.627737 -382.478584) (xy 172.596702 -382.41886) (xy 172.573027 -382.355854)
			(xy 172.557054 -382.29047) (xy 172.54901 -382.223646) (xy 169.270947 -382.223646) (xy 169.262905 -382.290465)
			(xy 169.246934 -382.355847) (xy 169.223264 -382.41885) (xy 169.192235 -382.478574) (xy 169.15429 -382.534161)
			(xy 169.132504 -382.559814) (xy 169.126719 -382.566968) (xy 169.120197 -382.584152) (xy 169.119804 -382.593342)
			(xy 169.119804 -383.086864) (xy 169.120231 -383.096049) (xy 169.126733 -383.113234) (xy 169.132504 -383.120392)
			(xy 169.154306 -383.146032) (xy 169.192252 -383.201621) (xy 169.223282 -383.261347) (xy 169.246739 -383.323787)
			(xy 170.348832 -383.323787) (xy 170.348835 -383.256359) (xy 170.356915 -383.189418) (xy 170.372956 -383.123926)
			(xy 170.396726 -383.060827) (xy 170.427884 -383.001031) (xy 170.46598 -382.945396) (xy 170.487848 -382.919732)
			(xy 170.493662 -382.912599) (xy 170.500165 -382.895399) (xy 170.500548 -382.886204) (xy 170.500548 -382.728724)
			(xy 170.501103 -382.718623) (xy 170.508823 -382.699955) (xy 170.523098 -382.685662) (xy 170.541756 -382.677917)
			(xy 170.551856 -382.677416) (xy 171.268136 -382.677416) (xy 171.278249 -382.677856) (xy 171.296931 -382.685608)
			(xy 171.311225 -382.699919) (xy 171.318956 -382.71861) (xy 171.319444 -382.728724) (xy 171.319444 -382.886204)
			(xy 171.319865 -382.89539) (xy 171.326372 -382.912574) (xy 171.332144 -382.919732) (xy 171.353975 -382.945425)
			(xy 171.392068 -383.001055) (xy 171.423223 -383.060846) (xy 171.446992 -383.12394) (xy 171.463032 -383.189426)
			(xy 171.471111 -383.256362) (xy 171.471115 -383.323784) (xy 171.463041 -383.390721) (xy 171.447008 -383.456209)
			(xy 171.423246 -383.519304) (xy 171.392096 -383.579099) (xy 171.354008 -383.634732) (xy 171.332144 -383.660396)
			(xy 171.32636 -383.66755) (xy 171.319839 -383.684734) (xy 171.319444 -383.693924) (xy 171.319444 -384.186176)
			(xy 171.319878 -384.19536) (xy 171.326376 -384.212544) (xy 171.332144 -384.219704) (xy 171.354045 -384.245339)
			(xy 171.392137 -384.300977) (xy 171.423289 -384.360776) (xy 171.447054 -384.423877) (xy 171.463088 -384.489371)
			(xy 171.471162 -384.556313) (xy 171.471159 -384.623741) (xy 171.463078 -384.690683) (xy 171.447037 -384.756174)
			(xy 171.423267 -384.819273) (xy 171.392109 -384.87907) (xy 171.354012 -384.934704) (xy 171.332144 -384.960368)
			(xy 171.326329 -384.9675) (xy 171.319827 -384.984701) (xy 171.319444 -384.993896) (xy 171.319444 -385.151376)
			(xy 171.318896 -385.161478) (xy 171.311175 -385.180147) (xy 171.296897 -385.194441) (xy 171.278237 -385.202185)
			(xy 171.268136 -385.202684) (xy 170.551856 -385.202684) (xy 170.541742 -385.20225) (xy 170.52306 -385.194495)
			(xy 170.508766 -385.180183) (xy 170.501036 -385.16149) (xy 170.500548 -385.151376) (xy 170.500548 -384.993896)
			(xy 170.500129 -384.98471) (xy 170.49362 -384.967526) (xy 170.487848 -384.960368) (xy 170.466018 -384.934674)
			(xy 170.427925 -384.879045) (xy 170.39677 -384.819253) (xy 170.373001 -384.75616) (xy 170.356962 -384.690674)
			(xy 170.348883 -384.623738) (xy 170.348879 -384.556316) (xy 170.356952 -384.489379) (xy 170.372985 -384.423892)
			(xy 170.396748 -384.360796) (xy 170.427897 -384.301001) (xy 170.465984 -384.245368) (xy 170.487848 -384.219704)
			(xy 170.493631 -384.21255) (xy 170.500153 -384.195366) (xy 170.500548 -384.186176) (xy 170.500548 -383.693924)
			(xy 170.500116 -383.684739) (xy 170.493616 -383.667555) (xy 170.487848 -383.660396) (xy 170.465947 -383.634761)
			(xy 170.427856 -383.579123) (xy 170.396704 -383.519323) (xy 170.37294 -383.456222) (xy 170.356906 -383.390729)
			(xy 170.348832 -383.323787) (xy 169.246739 -383.323787) (xy 169.246952 -383.324353) (xy 169.262922 -383.389736)
			(xy 169.270965 -383.456559) (xy 169.270963 -383.523865) (xy 169.262918 -383.590688) (xy 169.246945 -383.65607)
			(xy 169.223272 -383.719075) (xy 169.192239 -383.7788) (xy 169.154291 -383.834387) (xy 169.132504 -383.86004)
			(xy 169.126708 -383.867186) (xy 169.120193 -383.884376) (xy 169.119804 -383.893568) (xy 169.119804 -384.051556)
			(xy 169.119342 -384.061707) (xy 169.111562 -384.080457) (xy 169.097177 -384.094782) (xy 169.078394 -384.102484)
			(xy 169.068242 -384.102864) (xy 168.351962 -384.102864) (xy 168.341833 -384.102405) (xy 168.323112 -384.094665)
			(xy 168.308757 -384.080371) (xy 168.300939 -384.061682) (xy 168.3004 -384.051556) (xy 168.3004 -383.893568)
			(xy 168.300005 -383.884379) (xy 168.293481 -383.867195) (xy 168.2877 -383.86004) (xy 168.265929 -383.834374)
			(xy 168.227982 -383.778789) (xy 168.196951 -383.719067) (xy 168.173279 -383.656064) (xy 168.157306 -383.590684)
			(xy 168.149261 -383.523864) (xy 168.149259 -383.456561) (xy 168.157301 -383.38974) (xy 168.173272 -383.324359)
			(xy 168.196941 -383.261355) (xy 168.22797 -383.201632) (xy 168.265914 -383.146045) (xy 168.2877 -383.120392)
			(xy 168.293482 -383.113237) (xy 168.300006 -383.096054) (xy 168.3004 -383.086864) (xy 168.3004 -382.593342)
			(xy 168.29997 -382.584157) (xy 168.29347 -382.566972) (xy 168.2877 -382.559814) (xy 168.265904 -382.534169)
			(xy 168.227958 -382.478581) (xy 168.196927 -382.418856) (xy 168.173256 -382.355851) (xy 168.157285 -382.290468)
			(xy 168.149243 -382.223645) (xy 164.871179 -382.223645) (xy 164.871179 -382.223704) (xy 164.863104 -382.290641)
			(xy 164.84707 -382.35613) (xy 164.823307 -382.419226) (xy 164.792158 -382.479022) (xy 164.754071 -382.534657)
			(xy 164.732208 -382.560322) (xy 164.726421 -382.567474) (xy 164.7199 -382.584659) (xy 164.719508 -382.59385)
			(xy 164.719508 -383.086356) (xy 164.719937 -383.095541) (xy 164.726437 -383.112726) (xy 164.732208 -383.119884)
			(xy 164.754087 -383.145536) (xy 164.792175 -383.201173) (xy 164.823325 -383.260971) (xy 164.846959 -383.323727)
			(xy 165.949064 -383.323727) (xy 165.949067 -383.256419) (xy 165.957115 -383.189594) (xy 165.973092 -383.124209)
			(xy 165.996769 -383.061203) (xy 166.027808 -383.001479) (xy 166.065762 -382.945892) (xy 166.087552 -382.92024)
			(xy 166.093363 -382.913105) (xy 166.099868 -382.895907) (xy 166.100252 -382.886712) (xy 166.100252 -382.728724)
			(xy 166.10074 -382.718577) (xy 166.108519 -382.699835) (xy 166.122895 -382.685512) (xy 166.141666 -382.677803)
			(xy 166.151814 -382.677416) (xy 166.868094 -382.677416) (xy 166.878217 -382.677931) (xy 166.896934 -382.685652)
			(xy 166.911289 -382.699929) (xy 166.919113 -382.718603) (xy 166.919656 -382.728724) (xy 166.919656 -382.886712)
			(xy 166.92007 -382.895899) (xy 166.926582 -382.913082) (xy 166.932356 -382.92024) (xy 166.954108 -382.945921)
			(xy 166.992059 -383.001503) (xy 167.023094 -383.061223) (xy 167.046769 -383.124224) (xy 167.062744 -383.189602)
			(xy 167.070791 -383.256422) (xy 167.070795 -383.323724) (xy 167.062754 -383.390544) (xy 167.046785 -383.455925)
			(xy 167.023116 -383.518928) (xy 166.992086 -383.57865) (xy 166.954142 -383.634236) (xy 166.932356 -383.659888)
			(xy 166.926534 -383.667015) (xy 166.920036 -383.68422) (xy 166.919656 -383.693416) (xy 166.919656 -384.186684)
			(xy 166.920084 -384.195869) (xy 166.926586 -384.213053) (xy 166.932356 -384.220212) (xy 166.954179 -384.245835)
			(xy 166.992127 -384.301425) (xy 167.023159 -384.361153) (xy 167.04683 -384.424161) (xy 167.062801 -384.489547)
			(xy 167.070842 -384.556373) (xy 167.070839 -384.623681) (xy 167.062791 -384.690506) (xy 167.046814 -384.75589)
			(xy 167.023137 -384.818897) (xy 166.9921 -384.878621) (xy 166.954146 -384.934208) (xy 166.932356 -384.95986)
			(xy 166.926546 -384.966995) (xy 166.92004 -384.984194) (xy 166.919656 -384.993388) (xy 166.919656 -385.151376)
			(xy 166.91916 -385.161522) (xy 166.911383 -385.180263) (xy 166.89701 -385.194585) (xy 166.878241 -385.202296)
			(xy 166.868094 -385.202684) (xy 166.151814 -385.202684) (xy 166.141691 -385.202163) (xy 166.122975 -385.194444)
			(xy 166.108619 -385.180169) (xy 166.100795 -385.161496) (xy 166.100252 -385.151376) (xy 166.100252 -384.993388)
			(xy 166.099836 -384.984202) (xy 166.093325 -384.967018) (xy 166.087552 -384.95986) (xy 166.065799 -384.934179)
			(xy 166.027849 -384.878597) (xy 165.996813 -384.818877) (xy 165.973138 -384.755877) (xy 165.957162 -384.690498)
			(xy 165.949115 -384.623678) (xy 165.949111 -384.556376) (xy 165.957152 -384.489555) (xy 165.973122 -384.424175)
			(xy 165.996791 -384.361172) (xy 166.027821 -384.30145) (xy 166.065766 -384.245864) (xy 166.087552 -384.220212)
			(xy 166.093375 -384.213086) (xy 166.099872 -384.19588) (xy 166.100252 -384.186684) (xy 166.100252 -383.693416)
			(xy 166.099823 -383.684231) (xy 166.093321 -383.667047) (xy 166.087552 -383.659888) (xy 166.065728 -383.634265)
			(xy 166.02778 -383.578675) (xy 165.996747 -383.518947) (xy 165.973076 -383.455939) (xy 165.957105 -383.390553)
			(xy 165.949064 -383.323727) (xy 164.846959 -383.323727) (xy 164.847088 -383.32407) (xy 164.863122 -383.38956)
			(xy 164.871196 -383.4565) (xy 164.871195 -383.523924) (xy 164.863117 -383.590864) (xy 164.84708 -383.656353)
			(xy 164.823315 -383.719451) (xy 164.792163 -383.779248) (xy 164.754073 -383.834883) (xy 164.732208 -383.860548)
			(xy 164.726409 -383.867692) (xy 164.719896 -383.884883) (xy 164.719508 -383.894076) (xy 164.719508 -384.051556)
			(xy 164.719048 -384.061675) (xy 164.711316 -384.080376) (xy 164.697013 -384.094691) (xy 164.678318 -384.102439)
			(xy 164.6682 -384.102864) (xy 163.95192 -384.102864) (xy 163.941794 -384.102467) (xy 163.923084 -384.094719)
			(xy 163.908768 -384.080396) (xy 163.901028 -384.061682) (xy 163.900612 -384.051556) (xy 163.900612 -383.894076)
			(xy 163.900211 -383.884888) (xy 163.893691 -383.867704) (xy 163.887912 -383.860548) (xy 163.866063 -383.83487)
			(xy 163.827973 -383.779238) (xy 163.796821 -383.719443) (xy 163.773056 -383.656348) (xy 163.757019 -383.59086)
			(xy 163.748941 -383.523923) (xy 163.74894 -383.456501) (xy 163.757014 -383.389563) (xy 163.773049 -383.324075)
			(xy 163.796811 -383.260979) (xy 163.827961 -383.201183) (xy 163.866049 -383.145549) (xy 163.887912 -383.119884)
			(xy 163.893699 -383.112732) (xy 163.900219 -383.095547) (xy 163.900612 -383.086356) (xy 163.900612 -382.59385)
			(xy 163.900175 -382.584666) (xy 163.89368 -382.567481) (xy 163.887912 -382.560322) (xy 163.866038 -382.534665)
			(xy 163.827949 -382.47903) (xy 163.796798 -382.419232) (xy 163.773034 -382.356134) (xy 163.756998 -382.290644)
			(xy 163.748923 -382.223705) (xy 160.470876 -382.223705) (xy 160.46284 -382.290468) (xy 160.446866 -382.35585)
			(xy 160.423193 -382.418854) (xy 160.392159 -382.478577) (xy 160.354208 -382.534162) (xy 160.33242 -382.559814)
			(xy 160.326637 -382.566969) (xy 160.320114 -382.584152) (xy 160.31972 -382.593342) (xy 160.31972 -383.086864)
			(xy 160.320143 -383.09605) (xy 160.326647 -383.113235) (xy 160.33242 -383.120392) (xy 160.354225 -383.146031)
			(xy 160.392176 -383.201618) (xy 160.42321 -383.261343) (xy 160.446672 -383.323786) (xy 161.548769 -383.323786)
			(xy 161.548772 -383.25636) (xy 161.556851 -383.18942) (xy 161.572889 -383.123929) (xy 161.596656 -383.060831)
			(xy 161.627809 -383.001034) (xy 161.665899 -382.945398) (xy 161.687764 -382.919732) (xy 161.69358 -382.912601)
			(xy 161.700081 -382.895399) (xy 161.700464 -382.886204) (xy 161.700464 -382.728724) (xy 161.701004 -382.718621)
			(xy 161.708727 -382.69995) (xy 161.723007 -382.685656) (xy 161.74167 -382.677914) (xy 161.751772 -382.677416)
			(xy 162.468052 -382.677416) (xy 162.478173 -382.677856) (xy 162.496879 -382.685591) (xy 162.511195 -382.699901)
			(xy 162.51894 -382.718603) (xy 162.51936 -382.728724) (xy 162.51936 -382.886204) (xy 162.519777 -382.89539)
			(xy 162.526287 -382.912574) (xy 162.53206 -382.919732) (xy 162.55389 -382.945426) (xy 162.591982 -383.001055)
			(xy 162.623137 -383.060847) (xy 162.646905 -383.12394) (xy 162.662944 -383.189426) (xy 162.671023 -383.256362)
			(xy 162.671027 -383.323784) (xy 162.662954 -383.39072) (xy 162.646921 -383.456208) (xy 162.623159 -383.519303)
			(xy 162.59201 -383.579098) (xy 162.553923 -383.634731) (xy 162.53206 -383.660396) (xy 162.526278 -383.667551)
			(xy 162.519755 -383.684734) (xy 162.51936 -383.693924) (xy 162.51936 -384.186176) (xy 162.51979 -384.195361)
			(xy 162.526291 -384.212545) (xy 162.53206 -384.219704) (xy 162.553961 -384.245339) (xy 162.592051 -384.300977)
			(xy 162.623202 -384.360777) (xy 162.646966 -384.423878) (xy 162.663 -384.489371) (xy 162.671074 -384.556313)
			(xy 162.671071 -384.623741) (xy 162.662991 -384.690682) (xy 162.64695 -384.756174) (xy 162.62318 -384.819272)
			(xy 162.592023 -384.879069) (xy 162.553928 -384.934703) (xy 162.53206 -384.960368) (xy 162.526247 -384.967501)
			(xy 162.519743 -384.984701) (xy 162.51936 -384.993896) (xy 162.51936 -385.151376) (xy 162.518964 -385.161502)
			(xy 162.511216 -385.180213) (xy 162.496893 -385.194529) (xy 162.478178 -385.202268) (xy 162.468052 -385.202684)
			(xy 161.751772 -385.202684) (xy 161.741659 -385.202238) (xy 161.722978 -385.194488) (xy 161.708683 -385.180179)
			(xy 161.700952 -385.161489) (xy 161.700464 -385.151376) (xy 161.700464 -384.993896) (xy 161.700041 -384.98471)
			(xy 161.693535 -384.967527) (xy 161.687764 -384.960368) (xy 161.665937 -384.934673) (xy 161.627849 -384.879042)
			(xy 161.596699 -384.819249) (xy 161.572934 -384.756157) (xy 161.556897 -384.690671) (xy 161.548819 -384.623737)
			(xy 161.548816 -384.556317) (xy 161.556888 -384.489382) (xy 161.572918 -384.423895) (xy 161.596677 -384.3608)
			(xy 161.627821 -384.301005) (xy 161.665903 -384.24537) (xy 161.687764 -384.219704) (xy 161.693549 -384.212551)
			(xy 161.700069 -384.195366) (xy 161.700464 -384.186176) (xy 161.700464 -383.693924) (xy 161.700028 -383.68474)
			(xy 161.693531 -383.667556) (xy 161.687764 -383.660396) (xy 161.665866 -383.634759) (xy 161.627781 -383.57912)
			(xy 161.596634 -383.519319) (xy 161.572873 -383.456219) (xy 161.556841 -383.390727) (xy 161.548769 -383.323786)
			(xy 160.446672 -383.323786) (xy 160.446884 -383.32435) (xy 160.462857 -383.389734) (xy 160.470901 -383.456558)
			(xy 160.470899 -383.523866) (xy 160.462853 -383.59069) (xy 160.446877 -383.656074) (xy 160.423201 -383.719079)
			(xy 160.392163 -383.778803) (xy 160.35421 -383.834388) (xy 160.33242 -383.86004) (xy 160.326626 -383.867187)
			(xy 160.320109 -383.884376) (xy 160.31972 -383.893568) (xy 160.31972 -384.051556) (xy 160.319243 -384.061705)
			(xy 160.311465 -384.080452) (xy 160.297086 -384.094777) (xy 160.278308 -384.102481) (xy 160.268158 -384.102864)
			(xy 159.551878 -384.102864) (xy 159.54175 -384.102392) (xy 159.523029 -384.094657) (xy 159.508674 -384.080367)
			(xy 159.500855 -384.061681) (xy 159.500316 -384.051556) (xy 159.500316 -383.893568) (xy 159.499918 -383.88438)
			(xy 159.493395 -383.867196) (xy 159.487616 -383.86004) (xy 159.465845 -383.834375) (xy 159.427897 -383.77879)
			(xy 159.396864 -383.719068) (xy 159.373191 -383.656065) (xy 159.357218 -383.590684) (xy 159.349173 -383.523864)
			(xy 159.349172 -383.45656) (xy 159.357214 -383.389739) (xy 159.373184 -383.324358) (xy 159.396854 -383.261354)
			(xy 159.427884 -383.201631) (xy 159.46583 -383.146044) (xy 159.487616 -383.120392) (xy 159.4934 -383.113238)
			(xy 159.499922 -383.096054) (xy 159.500316 -383.086864) (xy 159.500316 -382.593342) (xy 159.499882 -382.584157)
			(xy 159.493384 -382.566973) (xy 159.487616 -382.559814) (xy 159.465819 -382.53417) (xy 159.427872 -382.478582)
			(xy 159.396841 -382.418857) (xy 159.373169 -382.355851) (xy 159.357198 -382.290468) (xy 159.349155 -382.223645)
			(xy 129.670829 -382.223645) (xy 129.662786 -382.290466) (xy 129.646815 -382.355847) (xy 129.623144 -382.418851)
			(xy 129.592113 -382.478575) (xy 129.554167 -382.534162) (xy 129.53238 -382.559814) (xy 129.526593 -382.566966)
			(xy 129.520073 -382.584151) (xy 129.51968 -382.593342) (xy 129.51968 -383.086864) (xy 129.520112 -383.096049)
			(xy 129.526611 -383.113233) (xy 129.53238 -383.120392) (xy 129.554183 -383.146031) (xy 129.59213 -383.20162)
			(xy 129.623162 -383.261346) (xy 129.646598 -383.323727) (xy 130.749242 -383.323727) (xy 130.749246 -383.256419)
			(xy 130.757293 -383.189594) (xy 130.77327 -383.12421) (xy 130.796946 -383.061204) (xy 130.827982 -383.00148)
			(xy 130.865935 -382.945892) (xy 130.887724 -382.92024) (xy 130.893531 -382.913103) (xy 130.900039 -382.895906)
			(xy 130.900424 -382.886712) (xy 130.900424 -382.728724) (xy 130.900842 -382.718568) (xy 130.908634 -382.699812)
			(xy 130.923032 -382.685487) (xy 130.941828 -382.67779) (xy 130.951986 -382.677416) (xy 131.668266 -382.677416)
			(xy 131.678388 -382.677954) (xy 131.697103 -382.685666) (xy 131.71146 -382.699937) (xy 131.719284 -382.718606)
			(xy 131.719828 -382.728724) (xy 131.719828 -382.886712) (xy 131.720226 -382.895901) (xy 131.726747 -382.913085)
			(xy 131.732528 -382.92024) (xy 131.754281 -382.945921) (xy 131.792233 -383.001502) (xy 131.82327 -383.061222)
			(xy 131.846946 -383.124223) (xy 131.862923 -383.189602) (xy 131.87097 -383.256422) (xy 131.870973 -383.323724)
			(xy 131.862932 -383.390545) (xy 131.846962 -383.455926) (xy 131.823292 -383.518929) (xy 131.792261 -383.578651)
			(xy 131.754314 -383.634236) (xy 131.732528 -383.659888) (xy 131.726703 -383.667013) (xy 131.720207 -383.684219)
			(xy 131.719828 -383.693416) (xy 131.719828 -384.186684) (xy 131.720239 -384.195871) (xy 131.726751 -384.213056)
			(xy 131.732528 -384.220212) (xy 131.754352 -384.245834) (xy 131.792302 -384.301424) (xy 131.823336 -384.361152)
			(xy 131.847008 -384.42416) (xy 131.86298 -384.489546) (xy 131.871021 -384.556373) (xy 131.871018 -384.623681)
			(xy 131.86297 -384.690507) (xy 131.846992 -384.755892) (xy 131.823314 -384.818898) (xy 131.792274 -384.878622)
			(xy 131.754319 -384.934208) (xy 131.732528 -384.95986) (xy 131.726715 -384.966993) (xy 131.720212 -384.984193)
			(xy 131.719828 -384.993388) (xy 131.719828 -385.151376) (xy 131.719359 -385.161525) (xy 131.711577 -385.180272)
			(xy 131.697195 -385.194595) (xy 131.678417 -385.202301) (xy 131.668266 -385.202684) (xy 130.951986 -385.202684)
			(xy 130.941861 -385.202185) (xy 130.923145 -385.194457) (xy 130.90879 -385.180175) (xy 130.900967 -385.161498)
			(xy 130.900424 -385.151376) (xy 130.900424 -384.993388) (xy 130.900014 -384.984201) (xy 130.8935 -384.967017)
			(xy 130.887724 -384.95986) (xy 130.865972 -384.934178) (xy 130.828023 -384.878596) (xy 130.796989 -384.818876)
			(xy 130.773315 -384.755876) (xy 130.75734 -384.690497) (xy 130.749294 -384.623678) (xy 130.74929 -384.556376)
			(xy 130.757331 -384.489556) (xy 130.773299 -384.424176) (xy 130.796967 -384.361173) (xy 130.827996 -384.301451)
			(xy 130.865939 -384.245865) (xy 130.887724 -384.220212) (xy 130.893543 -384.213083) (xy 130.900044 -384.19588)
			(xy 130.900424 -384.186684) (xy 130.900424 -383.693416) (xy 130.900001 -383.68423) (xy 130.893495 -383.667046)
			(xy 130.887724 -383.659888) (xy 130.865901 -383.634265) (xy 130.827955 -383.578674) (xy 130.796924 -383.518946)
			(xy 130.773254 -383.455938) (xy 130.757284 -383.390552) (xy 130.749242 -383.323727) (xy 129.646598 -383.323727)
			(xy 129.646833 -383.324352) (xy 129.662804 -383.389735) (xy 129.670846 -383.456559) (xy 129.670845 -383.523865)
			(xy 129.6628 -383.590688) (xy 129.646826 -383.656071) (xy 129.623152 -383.719076) (xy 129.592118 -383.778801)
			(xy 129.554168 -383.834388) (xy 129.53238 -383.86004) (xy 129.526582 -383.867184) (xy 129.520069 -383.884375)
			(xy 129.51968 -383.893568) (xy 129.51968 -384.051556) (xy 129.519242 -384.06171) (xy 129.511457 -384.080465)
			(xy 129.497065 -384.094791) (xy 129.478274 -384.102488) (xy 129.468118 -384.102864) (xy 128.751838 -384.102864)
			(xy 128.741714 -384.102342) (xy 128.722995 -384.094628) (xy 128.708637 -384.080352) (xy 128.700816 -384.061677)
			(xy 128.700276 -384.051556) (xy 128.700276 -383.893568) (xy 128.699886 -383.884379) (xy 128.693359 -383.867194)
			(xy 128.687576 -383.86004) (xy 128.665803 -383.834375) (xy 128.627851 -383.778792) (xy 128.596815 -383.71907)
			(xy 128.57314 -383.656067) (xy 128.557165 -383.590686) (xy 128.549119 -383.523864) (xy 128.549117 -383.45656)
			(xy 128.55716 -383.389738) (xy 128.573133 -383.324356) (xy 128.596805 -383.261352) (xy 128.627839 -383.201629)
			(xy 128.665788 -383.146044) (xy 128.687576 -383.120392) (xy 128.693356 -383.113235) (xy 128.699881 -383.096054)
			(xy 128.700276 -383.086864) (xy 128.700276 -382.593342) (xy 128.699851 -382.584156) (xy 128.693348 -382.566971)
			(xy 128.687576 -382.559814) (xy 128.665777 -382.53417) (xy 128.627826 -382.478584) (xy 128.596792 -382.418859)
			(xy 128.573118 -382.355853) (xy 128.557144 -382.29047) (xy 128.5491 -382.223646) (xy 125.271038 -382.223646)
			(xy 125.262995 -382.290466) (xy 125.247025 -382.355847) (xy 125.223354 -382.418851) (xy 125.192324 -382.478574)
			(xy 125.154378 -382.534161) (xy 125.132592 -382.559814) (xy 125.126806 -382.566967) (xy 125.120285 -382.584151)
			(xy 125.119892 -382.593342) (xy 125.119892 -383.086864) (xy 125.120321 -383.096049) (xy 125.126822 -383.113234)
			(xy 125.132592 -383.120392) (xy 125.154394 -383.146032) (xy 125.192341 -383.201621) (xy 125.223372 -383.261346)
			(xy 125.24683 -383.323787) (xy 126.348923 -383.323787) (xy 126.348926 -383.256359) (xy 126.357006 -383.189418)
			(xy 126.373047 -383.123926) (xy 126.396816 -383.060828) (xy 126.427973 -383.001031) (xy 126.466069 -382.945397)
			(xy 126.487936 -382.919732) (xy 126.493749 -382.912598) (xy 126.500253 -382.895399) (xy 126.500636 -382.886204)
			(xy 126.500636 -382.728724) (xy 126.501036 -382.718599) (xy 126.508783 -382.699889) (xy 126.523105 -382.685572)
			(xy 126.541818 -382.677832) (xy 126.551944 -382.677416) (xy 127.268224 -382.677416) (xy 127.278336 -382.677866)
			(xy 127.297018 -382.685614) (xy 127.311313 -382.699922) (xy 127.319044 -382.718611) (xy 127.319532 -382.728724)
			(xy 127.319532 -382.886204) (xy 127.319956 -382.895389) (xy 127.326462 -382.912573) (xy 127.332232 -382.919732)
			(xy 127.354059 -382.945427) (xy 127.392147 -383.001058) (xy 127.423298 -383.06085) (xy 127.447062 -383.123943)
			(xy 127.463099 -383.189428) (xy 127.471178 -383.256363) (xy 127.471181 -383.323783) (xy 127.463109 -383.390718)
			(xy 127.447078 -383.456205) (xy 127.42332 -383.5193) (xy 127.392175 -383.579096) (xy 127.354093 -383.63473)
			(xy 127.332232 -383.660396) (xy 127.326446 -383.667549) (xy 127.319927 -383.684734) (xy 127.319532 -383.693924)
			(xy 127.319532 -384.186176) (xy 127.319969 -384.19536) (xy 127.326466 -384.212544) (xy 127.332232 -384.219704)
			(xy 127.35413 -384.245341) (xy 127.392216 -384.30098) (xy 127.423363 -384.36078) (xy 127.447124 -384.423881)
			(xy 127.463156 -384.489373) (xy 127.471228 -384.556314) (xy 127.471225 -384.62374) (xy 127.463146 -384.69068)
			(xy 127.447108 -384.756171) (xy 127.423341 -384.819269) (xy 127.392188 -384.879066) (xy 127.354097 -384.934702)
			(xy 127.332232 -384.960368) (xy 127.326416 -384.967499) (xy 127.319915 -384.984701) (xy 127.319532 -384.993896)
			(xy 127.319532 -385.151376) (xy 127.318996 -385.161479) (xy 127.311272 -385.180151) (xy 127.296991 -385.194445)
			(xy 127.278327 -385.202187) (xy 127.268224 -385.202684) (xy 126.551944 -385.202684) (xy 126.541822 -385.202247)
			(xy 126.523117 -385.194511) (xy 126.5088 -385.1802) (xy 126.501056 -385.161497) (xy 126.500636 -385.151376)
			(xy 126.500636 -384.993896) (xy 126.50022 -384.98471) (xy 126.49371 -384.967526) (xy 126.487936 -384.960368)
			(xy 126.466106 -384.934674) (xy 126.428014 -384.879045) (xy 126.39686 -384.819253) (xy 126.373092 -384.756159)
			(xy 126.357053 -384.690673) (xy 126.348974 -384.623738) (xy 126.34897 -384.556316) (xy 126.357043 -384.48938)
			(xy 126.373076 -384.423892) (xy 126.396838 -384.360797) (xy 126.427986 -384.301002) (xy 126.466073 -384.245369)
			(xy 126.487936 -384.219704) (xy 126.493718 -384.212549) (xy 126.50024 -384.195366) (xy 126.500636 -384.186176)
			(xy 126.500636 -383.693924) (xy 126.500206 -383.684739) (xy 126.493705 -383.667555) (xy 126.487936 -383.660396)
			(xy 126.466035 -383.634761) (xy 126.427945 -383.579123) (xy 126.396794 -383.519323) (xy 126.373031 -383.456222)
			(xy 126.356996 -383.390729) (xy 126.348923 -383.323787) (xy 125.24683 -383.323787) (xy 125.247042 -383.324352)
			(xy 125.263013 -383.389736) (xy 125.271056 -383.456559) (xy 125.271054 -383.523865) (xy 125.263009 -383.590688)
			(xy 125.247035 -383.656071) (xy 125.223362 -383.719076) (xy 125.192328 -383.7788) (xy 125.15438 -383.834387)
			(xy 125.132592 -383.86004) (xy 125.126795 -383.867185) (xy 125.120281 -383.884376) (xy 125.119892 -383.893568)
			(xy 125.119892 -384.051556) (xy 125.119442 -384.061708) (xy 125.11166 -384.080461) (xy 125.097271 -384.094786)
			(xy 125.078484 -384.102486) (xy 125.06833 -384.102864) (xy 124.35205 -384.102864) (xy 124.341927 -384.102333)
			(xy 124.323208 -384.094622) (xy 124.30885 -384.080349) (xy 124.301028 -384.061676) (xy 124.300488 -384.051556)
			(xy 124.300488 -383.893568) (xy 124.300096 -383.884379) (xy 124.29357 -383.867194) (xy 124.287788 -383.86004)
			(xy 124.266015 -383.834376) (xy 124.228062 -383.778792) (xy 124.197025 -383.719071) (xy 124.17335 -383.656068)
			(xy 124.157374 -383.590686) (xy 124.149328 -383.523864) (xy 124.149326 -383.45656) (xy 124.15737 -383.389737)
			(xy 124.173342 -383.324355) (xy 124.197016 -383.261351) (xy 124.22805 -383.201629) (xy 124.266 -383.146043)
			(xy 124.287788 -383.120392) (xy 124.293569 -383.113236) (xy 124.300093 -383.096054) (xy 124.300488 -383.086864)
			(xy 124.300488 -382.593342) (xy 124.30006 -382.584157) (xy 124.293559 -382.566972) (xy 124.287788 -382.559814)
			(xy 124.265989 -382.534171) (xy 124.228037 -382.478584) (xy 124.197002 -382.41886) (xy 124.173327 -382.355854)
			(xy 124.157354 -382.29047) (xy 124.14931 -382.223646) (xy 120.87127 -382.223646) (xy 120.87127 -382.223704)
			(xy 120.863195 -382.290642) (xy 120.84716 -382.35613) (xy 120.823397 -382.419227) (xy 120.792247 -382.479023)
			(xy 120.75416 -382.534657) (xy 120.732296 -382.560322) (xy 120.726507 -382.567473) (xy 120.719988 -382.584659)
			(xy 120.719596 -382.59385) (xy 120.719596 -383.086356) (xy 120.720028 -383.095541) (xy 120.726527 -383.112725)
			(xy 120.732296 -383.119884) (xy 120.754176 -383.145536) (xy 120.792264 -383.201173) (xy 120.823415 -383.26097)
			(xy 120.847049 -383.323727) (xy 121.949155 -383.323727) (xy 121.949158 -383.256419) (xy 121.957206 -383.189594)
			(xy 121.973182 -383.12421) (xy 121.996859 -383.061204) (xy 122.027897 -383.001479) (xy 122.06585 -382.945892)
			(xy 122.08764 -382.92024) (xy 122.09345 -382.913104) (xy 122.099955 -382.895906) (xy 122.10034 -382.886712)
			(xy 122.10034 -382.728724) (xy 122.100742 -382.718566) (xy 122.108537 -382.699807) (xy 122.122941 -382.685481)
			(xy 122.141742 -382.677788) (xy 122.151902 -382.677416) (xy 122.868182 -382.677416) (xy 122.878305 -382.677941)
			(xy 122.897021 -382.685658) (xy 122.911377 -382.699932) (xy 122.919201 -382.718604) (xy 122.919744 -382.728724)
			(xy 122.919744 -382.886712) (xy 122.920161 -382.895898) (xy 122.926671 -382.913082) (xy 122.932444 -382.92024)
			(xy 122.954197 -382.945921) (xy 122.992148 -383.001503) (xy 123.023183 -383.061222) (xy 123.046859 -383.124223)
			(xy 123.062835 -383.189602) (xy 123.070882 -383.256422) (xy 123.070886 -383.323724) (xy 123.062845 -383.390545)
			(xy 123.046875 -383.455925) (xy 123.023206 -383.518928) (xy 122.992176 -383.57865) (xy 122.95423 -383.634236)
			(xy 122.932444 -383.659888) (xy 122.926621 -383.667014) (xy 122.920124 -383.684219) (xy 122.919744 -383.693416)
			(xy 122.919744 -384.186684) (xy 122.920174 -384.195869) (xy 122.926675 -384.213053) (xy 122.932444 -384.220212)
			(xy 122.954268 -384.245835) (xy 122.992217 -384.301425) (xy 123.023249 -384.361152) (xy 123.046921 -384.424161)
			(xy 123.062892 -384.489547) (xy 123.070933 -384.556373) (xy 123.07093 -384.623681) (xy 123.062882 -384.690507)
			(xy 123.046905 -384.755891) (xy 123.023227 -384.818897) (xy 122.992189 -384.878622) (xy 122.954235 -384.934208)
			(xy 122.932444 -384.95986) (xy 122.926633 -384.966994) (xy 122.920128 -384.984193) (xy 122.919744 -384.993388)
			(xy 122.919744 -385.151376) (xy 122.91926 -385.161523) (xy 122.91148 -385.180267) (xy 122.897103 -385.194589)
			(xy 122.878331 -385.202298) (xy 122.868182 -385.202684) (xy 122.151902 -385.202684) (xy 122.141778 -385.202172)
			(xy 122.123062 -385.19445) (xy 122.108706 -385.180171) (xy 122.100883 -385.161497) (xy 122.10034 -385.151376)
			(xy 122.10034 -384.993388) (xy 122.099927 -384.984201) (xy 122.093414 -384.967017) (xy 122.08764 -384.95986)
			(xy 122.065888 -384.934179) (xy 122.027938 -384.878596) (xy 121.996903 -384.818877) (xy 121.973228 -384.755876)
			(xy 121.957253 -384.690498) (xy 121.949206 -384.623678) (xy 121.949202 -384.556376) (xy 121.957243 -384.489556)
			(xy 121.973212 -384.424176) (xy 121.996881 -384.361173) (xy 122.02791 -384.30145) (xy 122.065855 -384.245864)
			(xy 122.08764 -384.220212) (xy 122.093461 -384.213085) (xy 122.09996 -384.19588) (xy 122.10034 -384.186684)
			(xy 122.10034 -383.693416) (xy 122.099913 -383.684231) (xy 122.09341 -383.667047) (xy 122.08764 -383.659888)
			(xy 122.065817 -383.634265) (xy 122.027869 -383.578674) (xy 121.996837 -383.518947) (xy 121.973166 -383.455939)
			(xy 121.957196 -383.390553) (xy 121.949155 -383.323727) (xy 120.847049 -383.323727) (xy 120.847178 -383.324069)
			(xy 120.863212 -383.38956) (xy 120.871287 -383.4565) (xy 120.871286 -383.523925) (xy 120.863208 -383.590864)
			(xy 120.847171 -383.656354) (xy 120.823405 -383.719452) (xy 120.792252 -383.779248) (xy 120.754161 -383.834883)
			(xy 120.732296 -383.860548) (xy 120.726496 -383.867691) (xy 120.719984 -383.884883) (xy 120.719596 -383.894076)
			(xy 120.719596 -384.051556) (xy 120.719148 -384.061676) (xy 120.711413 -384.080379) (xy 120.697106 -384.094695)
			(xy 120.678408 -384.102441) (xy 120.668288 -384.102864) (xy 119.952008 -384.102864) (xy 119.941882 -384.102477)
			(xy 119.923171 -384.094724) (xy 119.908855 -384.080399) (xy 119.901116 -384.061683) (xy 119.9007 -384.051556)
			(xy 119.9007 -383.894076) (xy 119.900302 -383.884888) (xy 119.89378 -383.867703) (xy 119.888 -383.860548)
			(xy 119.866152 -383.83487) (xy 119.828063 -383.779237) (xy 119.796911 -383.719443) (xy 119.773146 -383.656348)
			(xy 119.75711 -383.59086) (xy 119.749032 -383.523923) (xy 119.749031 -383.456501) (xy 119.757105 -383.389564)
			(xy 119.773139 -383.324075) (xy 119.796901 -383.260979) (xy 119.82805 -383.201184) (xy 119.866137 -383.145549)
			(xy 119.888 -383.119884) (xy 119.893786 -383.112731) (xy 119.900307 -383.095547) (xy 119.9007 -383.086356)
			(xy 119.9007 -382.59385) (xy 119.900266 -382.584665) (xy 119.893769 -382.567481) (xy 119.888 -382.560322)
			(xy 119.866126 -382.534665) (xy 119.828038 -382.479029) (xy 119.796888 -382.419232) (xy 119.773124 -382.356134)
			(xy 119.757089 -382.290644) (xy 119.749014 -382.223705) (xy 116.470967 -382.223705) (xy 116.46293 -382.290468)
			(xy 116.446957 -382.35585) (xy 116.423283 -382.418855) (xy 116.392248 -382.478577) (xy 116.354297 -382.534163)
			(xy 116.332508 -382.559814) (xy 116.326724 -382.566968) (xy 116.320202 -382.584152) (xy 116.319808 -382.593342)
			(xy 116.319808 -383.086864) (xy 116.320234 -383.09605) (xy 116.326736 -383.113234) (xy 116.332508 -383.120392)
			(xy 116.354313 -383.146031) (xy 116.392265 -383.201618) (xy 116.4233 -383.261343) (xy 116.446764 -383.323787)
			(xy 117.548835 -383.323787) (xy 117.548838 -383.256359) (xy 117.556918 -383.189418) (xy 117.572959 -383.123926)
			(xy 117.59673 -383.060827) (xy 117.627888 -383.00103) (xy 117.665984 -382.945396) (xy 117.687852 -382.919732)
			(xy 117.693666 -382.9126) (xy 117.700169 -382.895399) (xy 117.700552 -382.886204) (xy 117.700552 -382.728724)
			(xy 117.701103 -382.718623) (xy 117.708824 -382.699954) (xy 117.7231 -382.68566) (xy 117.741759 -382.677916)
			(xy 117.75186 -382.677416) (xy 118.46814 -382.677416) (xy 118.478253 -382.677853) (xy 118.496935 -382.685607)
			(xy 118.511229 -382.699918) (xy 118.51896 -382.71861) (xy 118.519448 -382.728724) (xy 118.519448 -382.886204)
			(xy 118.519868 -382.89539) (xy 118.526376 -382.912574) (xy 118.532148 -382.919732) (xy 118.553978 -382.945426)
			(xy 118.592072 -383.001055) (xy 118.623227 -383.060847) (xy 118.646995 -383.12394) (xy 118.663035 -383.189426)
			(xy 118.671114 -383.256362) (xy 118.671118 -383.323784) (xy 118.663045 -383.390721) (xy 118.647011 -383.456208)
			(xy 118.623249 -383.519304) (xy 118.592099 -383.579099) (xy 118.554012 -383.634732) (xy 118.532148 -383.660396)
			(xy 118.526364 -383.66755) (xy 118.519843 -383.684734) (xy 118.519448 -383.693924) (xy 118.519448 -384.186176)
			(xy 118.519881 -384.195361) (xy 118.52638 -384.212545) (xy 118.532148 -384.219704) (xy 118.554049 -384.245339)
			(xy 118.59214 -384.300977) (xy 118.623292 -384.360777) (xy 118.647057 -384.423878) (xy 118.663091 -384.489371)
			(xy 118.671165 -384.556313) (xy 118.671162 -384.623741) (xy 118.663082 -384.690682) (xy 118.647041 -384.756174)
			(xy 118.62327 -384.819273) (xy 118.592112 -384.87907) (xy 118.554016 -384.934704) (xy 118.532148 -384.960368)
			(xy 118.526334 -384.9675) (xy 118.519831 -384.984701) (xy 118.519448 -384.993896) (xy 118.519448 -385.151376)
			(xy 118.518897 -385.161477) (xy 118.511176 -385.180146) (xy 118.4969 -385.19444) (xy 118.478241 -385.202184)
			(xy 118.46814 -385.202684) (xy 117.75186 -385.202684) (xy 117.741747 -385.202247) (xy 117.723065 -385.194493)
			(xy 117.708771 -385.180182) (xy 117.70104 -385.16149) (xy 117.700552 -385.151376) (xy 117.700552 -384.993896)
			(xy 117.700132 -384.98471) (xy 117.693624 -384.967526) (xy 117.687852 -384.960368) (xy 117.666022 -384.934674)
			(xy 117.627928 -384.879045) (xy 117.596773 -384.819253) (xy 117.573005 -384.75616) (xy 117.556965 -384.690674)
			(xy 117.548886 -384.623738) (xy 117.548882 -384.556316) (xy 117.556955 -384.489379) (xy 117.572989 -384.423892)
			(xy 117.596751 -384.360796) (xy 117.627901 -384.301001) (xy 117.665988 -384.245368) (xy 117.687852 -384.219704)
			(xy 117.693636 -384.21255) (xy 117.700157 -384.195366) (xy 117.700552 -384.186176) (xy 117.700552 -383.693924)
			(xy 117.700119 -383.684739) (xy 117.69362 -383.667555) (xy 117.687852 -383.660396) (xy 117.665951 -383.634761)
			(xy 117.62786 -383.579123) (xy 117.596708 -383.519323) (xy 117.572943 -383.456222) (xy 117.556909 -383.390729)
			(xy 117.548835 -383.323787) (xy 116.446764 -383.323787) (xy 116.446975 -383.324349) (xy 116.462948 -383.389733)
			(xy 116.470992 -383.456558) (xy 116.47099 -383.523866) (xy 116.462944 -383.59069) (xy 116.446967 -383.656074)
			(xy 116.423291 -383.719079) (xy 116.392252 -383.778803) (xy 116.354298 -383.834389) (xy 116.332508 -383.86004)
			(xy 116.326713 -383.867186) (xy 116.320197 -383.884376) (xy 116.319808 -383.893568) (xy 116.319808 -384.051556)
			(xy 116.319342 -384.061706) (xy 116.311563 -384.080456) (xy 116.297179 -384.094781) (xy 116.278398 -384.102483)
			(xy 116.268246 -384.102864) (xy 115.551966 -384.102864) (xy 115.541838 -384.102401) (xy 115.523116 -384.094663)
			(xy 115.508761 -384.08037) (xy 115.500943 -384.061682) (xy 115.500404 -384.051556) (xy 115.500404 -383.893568)
			(xy 115.500009 -383.884379) (xy 115.493485 -383.867195) (xy 115.487704 -383.86004) (xy 115.465933 -383.834374)
			(xy 115.427986 -383.778789) (xy 115.396954 -383.719067) (xy 115.373282 -383.656064) (xy 115.357309 -383.590684)
			(xy 115.349264 -383.523864) (xy 115.349262 -383.45656) (xy 115.357305 -383.38974) (xy 115.373275 -383.324359)
			(xy 115.396944 -383.261355) (xy 115.427974 -383.201632) (xy 115.465918 -383.146045) (xy 115.487704 -383.120392)
			(xy 115.493487 -383.113237) (xy 115.50001 -383.096054) (xy 115.500404 -383.086864) (xy 115.500404 -382.593342)
			(xy 115.499973 -382.584157) (xy 115.493474 -382.566973) (xy 115.487704 -382.559814) (xy 115.465908 -382.534169)
			(xy 115.427961 -382.478581) (xy 115.39693 -382.418856) (xy 115.37326 -382.355851) (xy 115.357288 -382.290468)
			(xy 115.349246 -382.223645) (xy 90.070711 -382.223645) (xy 90.062667 -382.290467) (xy 90.046695 -382.355848)
			(xy 90.023023 -382.418852) (xy 89.991991 -382.478576) (xy 89.954043 -382.534162) (xy 89.932256 -382.559814)
			(xy 89.926465 -382.566963) (xy 89.919948 -382.584151) (xy 89.919556 -382.593342) (xy 89.919556 -383.086864)
			(xy 89.919994 -383.096048) (xy 89.926489 -383.113232) (xy 89.932256 -383.120392) (xy 89.95406 -383.146031)
			(xy 89.992008 -383.201619) (xy 90.023041 -383.261345) (xy 90.046478 -383.323726) (xy 91.149124 -383.323726)
			(xy 91.149128 -383.256419) (xy 91.157175 -383.189595) (xy 91.17315 -383.124211) (xy 91.196825 -383.061205)
			(xy 91.227861 -383.001481) (xy 91.265811 -382.945893) (xy 91.2876 -382.92024) (xy 91.293405 -382.9131)
			(xy 91.299914 -382.895906) (xy 91.3003 -382.886712) (xy 91.3003 -382.728724) (xy 91.300741 -382.718571)
			(xy 91.308529 -382.699819) (xy 91.32292 -382.685495) (xy 91.341708 -382.677795) (xy 91.351862 -382.677416)
			(xy 92.068142 -382.677416) (xy 92.078268 -382.677891) (xy 92.096986 -382.685629) (xy 92.11134 -382.699918)
			(xy 92.119162 -382.7186) (xy 92.119704 -382.728724) (xy 92.119704 -382.886712) (xy 92.120108 -382.8959)
			(xy 92.126626 -382.913084) (xy 92.132404 -382.92024) (xy 92.154155 -382.945922) (xy 92.192102 -383.001505)
			(xy 92.223135 -383.061225) (xy 92.246808 -383.124225) (xy 92.262782 -383.189604) (xy 92.270828 -383.256422)
			(xy 92.270831 -383.323724) (xy 92.262791 -383.390543) (xy 92.246824 -383.455923) (xy 92.223157 -383.518926)
			(xy 92.19213 -383.578648) (xy 92.154188 -383.634235) (xy 92.132404 -383.659888) (xy 92.126588 -383.66702)
			(xy 92.120085 -383.68422) (xy 92.119704 -383.693416) (xy 92.119704 -384.186684) (xy 92.120121 -384.19587)
			(xy 92.12663 -384.213055) (xy 92.132404 -384.220212) (xy 92.154226 -384.245836) (xy 92.192171 -384.301427)
			(xy 92.2232 -384.361155) (xy 92.246869 -384.424163) (xy 92.262838 -384.489548) (xy 92.270879 -384.556374)
			(xy 92.270875 -384.623681) (xy 92.262828 -384.690505) (xy 92.246853 -384.755889) (xy 92.223178 -384.818894)
			(xy 92.192143 -384.878619) (xy 92.154193 -384.934207) (xy 92.132404 -384.95986) (xy 92.1266 -384.967)
			(xy 92.12009 -384.984194) (xy 92.119704 -384.993388) (xy 92.119704 -385.151376) (xy 92.119259 -385.161528)
			(xy 92.111472 -385.180279) (xy 92.097082 -385.194603) (xy 92.078296 -385.202305) (xy 92.068142 -385.202684)
			(xy 91.351862 -385.202684) (xy 91.341736 -385.202205) (xy 91.323018 -385.194469) (xy 91.308664 -385.180181)
			(xy 91.300842 -385.1615) (xy 91.3003 -385.151376) (xy 91.3003 -384.993388) (xy 91.299895 -384.9842)
			(xy 91.293378 -384.967016) (xy 91.2876 -384.95986) (xy 91.265849 -384.934178) (xy 91.227901 -384.878595)
			(xy 91.196869 -384.818875) (xy 91.173196 -384.755875) (xy 91.157221 -384.690497) (xy 91.149175 -384.623678)
			(xy 91.149172 -384.556376) (xy 91.157212 -384.489557) (xy 91.17318 -384.424177) (xy 91.196847 -384.361174)
			(xy 91.227874 -384.301451) (xy 91.265816 -384.245865) (xy 91.2876 -384.220212) (xy 91.293416 -384.213081)
			(xy 91.299919 -384.19588) (xy 91.3003 -384.186684) (xy 91.3003 -383.693416) (xy 91.299882 -383.68423)
			(xy 91.293374 -383.667045) (xy 91.2876 -383.659888) (xy 91.265778 -383.634264) (xy 91.227833 -383.578673)
			(xy 91.196803 -383.518945) (xy 91.173134 -383.455937) (xy 91.157165 -383.390552) (xy 91.149124 -383.323726)
			(xy 90.046478 -383.323726) (xy 90.046713 -383.324351) (xy 90.062685 -383.389735) (xy 90.070728 -383.456559)
			(xy 90.070727 -383.523865) (xy 90.062681 -383.590689) (xy 90.046706 -383.656072) (xy 90.023031 -383.719077)
			(xy 89.991996 -383.778801) (xy 89.954045 -383.834388) (xy 89.932256 -383.86004) (xy 89.926454 -383.867181)
			(xy 89.919944 -383.884375) (xy 89.919556 -383.893568) (xy 89.919556 -384.051556) (xy 89.919043 -384.0617)
			(xy 89.911273 -384.080441) (xy 89.896905 -384.094764) (xy 89.87814 -384.102475) (xy 89.867994 -384.102864)
			(xy 89.151714 -384.102864) (xy 89.141589 -384.102362) (xy 89.122869 -384.09464) (xy 89.108512 -384.080358)
			(xy 89.100692 -384.061679) (xy 89.100152 -384.051556) (xy 89.100152 -383.893568) (xy 89.099745 -383.884381)
			(xy 89.093228 -383.867197) (xy 89.087452 -383.86004) (xy 89.06568 -383.834375) (xy 89.02773 -383.778791)
			(xy 88.996695 -383.719069) (xy 88.973021 -383.656066) (xy 88.957046 -383.590685) (xy 88.949001 -383.523864)
			(xy 88.948999 -383.45656) (xy 88.957042 -383.389738) (xy 88.973014 -383.324357) (xy 88.996685 -383.261353)
			(xy 89.027717 -383.20163) (xy 89.065665 -383.146044) (xy 89.087452 -383.120392) (xy 89.093241 -383.113242)
			(xy 89.099759 -383.096055) (xy 89.100152 -383.086864) (xy 89.100152 -382.593342) (xy 89.09971 -382.584158)
			(xy 89.093217 -382.566975) (xy 89.087452 -382.559814) (xy 89.065654 -382.53417) (xy 89.027704 -382.478583)
			(xy 88.996671 -382.418858) (xy 88.972998 -382.355853) (xy 88.957025 -382.290469) (xy 88.948982 -382.223646)
			(xy 85.670943 -382.223646) (xy 85.670943 -382.223704) (xy 85.662867 -382.290643) (xy 85.646832 -382.356132)
			(xy 85.623067 -382.419228) (xy 85.591915 -382.479024) (xy 85.553825 -382.534657) (xy 85.53196 -382.560322)
			(xy 85.526167 -382.567469) (xy 85.519651 -382.584658) (xy 85.51926 -382.59385) (xy 85.51926 -383.086356)
			(xy 85.5197 -383.09554) (xy 85.526194 -383.112724) (xy 85.53196 -383.119884) (xy 85.553841 -383.145536)
			(xy 85.591932 -383.201171) (xy 85.623084 -383.260969) (xy 85.646743 -383.323786) (xy 86.748805 -383.323786)
			(xy 86.748808 -383.25636) (xy 86.756888 -383.189419) (xy 86.772927 -383.123927) (xy 86.796696 -383.060829)
			(xy 86.827852 -383.001032) (xy 86.865945 -382.945397) (xy 86.887812 -382.919732) (xy 86.893621 -382.912596)
			(xy 86.900128 -382.895398) (xy 86.900512 -382.886204) (xy 86.900512 -382.728724) (xy 86.900936 -382.718602)
			(xy 86.908678 -382.699896) (xy 86.922993 -382.685581) (xy 86.941698 -382.677837) (xy 86.95182 -382.677416)
			(xy 87.6681 -382.677416) (xy 87.678224 -382.677816) (xy 87.696931 -382.685568) (xy 87.711246 -382.699889)
			(xy 87.718988 -382.718599) (xy 87.719408 -382.728724) (xy 87.719408 -382.886204) (xy 87.719815 -382.895392)
			(xy 87.726331 -382.912576) (xy 87.732108 -382.919732) (xy 87.753936 -382.945427) (xy 87.792026 -383.001057)
			(xy 87.823177 -383.060849) (xy 87.846943 -383.123942) (xy 87.862981 -383.189428) (xy 87.87106 -383.256363)
			(xy 87.871063 -383.323783) (xy 87.862991 -383.390719) (xy 87.846959 -383.456206) (xy 87.8232 -383.519301)
			(xy 87.792053 -383.579096) (xy 87.75397 -383.634731) (xy 87.732108 -383.660396) (xy 87.726332 -383.667556)
			(xy 87.719805 -383.684735) (xy 87.719408 -383.693924) (xy 87.719408 -384.186176) (xy 87.719828 -384.195362)
			(xy 87.726335 -384.212547) (xy 87.732108 -384.219704) (xy 87.754007 -384.24534) (xy 87.792094 -384.300979)
			(xy 87.823243 -384.360779) (xy 87.847005 -384.42388) (xy 87.863037 -384.489373) (xy 87.87111 -384.556314)
			(xy 87.871107 -384.62374) (xy 87.863028 -384.690681) (xy 87.846989 -384.756172) (xy 87.823221 -384.81927)
			(xy 87.792066 -384.879067) (xy 87.753974 -384.934703) (xy 87.732108 -384.960368) (xy 87.726301 -384.967506)
			(xy 87.719792 -384.984702) (xy 87.719408 -384.993896) (xy 87.719408 -385.151376) (xy 87.718965 -385.161496)
			(xy 87.711226 -385.180198) (xy 87.696918 -385.194512) (xy 87.67822 -385.20226) (xy 87.6681 -385.202684)
			(xy 86.95182 -385.202684) (xy 86.941697 -385.202267) (xy 86.922991 -385.194523) (xy 86.908675 -385.180206)
			(xy 86.900932 -385.161499) (xy 86.900512 -385.151376) (xy 86.900512 -384.993896) (xy 86.900101 -384.984709)
			(xy 86.893587 -384.967525) (xy 86.887812 -384.960368) (xy 86.865983 -384.934674) (xy 86.827892 -384.879044)
			(xy 86.796739 -384.819252) (xy 86.772973 -384.756158) (xy 86.756934 -384.690673) (xy 86.748855 -384.623738)
			(xy 86.748852 -384.556316) (xy 86.756925 -384.48938) (xy 86.772957 -384.423893) (xy 86.796717 -384.360798)
			(xy 86.827865 -384.301003) (xy 86.86595 -384.245369) (xy 86.887812 -384.219704) (xy 86.893591 -384.212546)
			(xy 86.900116 -384.195365) (xy 86.900512 -384.186176) (xy 86.900512 -383.693924) (xy 86.900088 -383.684738)
			(xy 86.893583 -383.667554) (xy 86.887812 -383.660396) (xy 86.865912 -383.63476) (xy 86.827824 -383.579122)
			(xy 86.796674 -383.519322) (xy 86.772911 -383.456221) (xy 86.756878 -383.390728) (xy 86.748805 -383.323786)
			(xy 85.646743 -383.323786) (xy 85.646849 -383.324068) (xy 85.662885 -383.389559) (xy 85.67096 -383.456499)
			(xy 85.670959 -383.523925) (xy 85.662881 -383.590865) (xy 85.646842 -383.656355) (xy 85.623074 -383.719453)
			(xy 85.59192 -383.77925) (xy 85.553826 -383.834883) (xy 85.53196 -383.860548) (xy 85.526156 -383.867687)
			(xy 85.519647 -383.884883) (xy 85.51926 -383.894076) (xy 85.51926 -384.051556) (xy 85.518847 -384.061681)
			(xy 85.511106 -384.080391) (xy 85.496787 -384.094708) (xy 85.478077 -384.102448) (xy 85.467952 -384.102864)
			(xy 84.751672 -384.102864) (xy 84.741543 -384.102506) (xy 84.722832 -384.094742) (xy 84.708517 -384.080407)
			(xy 84.70078 -384.061685) (xy 84.700364 -384.051556) (xy 84.700364 -383.894076) (xy 84.699951 -383.884889)
			(xy 84.693438 -383.867706) (xy 84.687664 -383.860548) (xy 84.665817 -383.834869) (xy 84.62773 -383.779236)
			(xy 84.596581 -383.719441) (xy 84.572817 -383.656346) (xy 84.556782 -383.590859) (xy 84.548705 -383.523923)
			(xy 84.548704 -383.456501) (xy 84.556778 -383.389565) (xy 84.57281 -383.324077) (xy 84.596571 -383.260981)
			(xy 84.627718 -383.201185) (xy 84.665802 -383.14555) (xy 84.687664 -383.119884) (xy 84.693458 -383.112737)
			(xy 84.699972 -383.095548) (xy 84.700364 -383.086356) (xy 84.700364 -382.59385) (xy 84.699916 -382.584667)
			(xy 84.693427 -382.567483) (xy 84.687664 -382.560322) (xy 84.665791 -382.534664) (xy 84.627705 -382.479028)
			(xy 84.596557 -382.41923) (xy 84.572795 -382.356132) (xy 84.556761 -382.290643) (xy 84.548687 -382.223704)
			(xy 81.271152 -382.223704) (xy 81.263076 -382.290642) (xy 81.247041 -382.356131) (xy 81.223277 -382.419228)
			(xy 81.192126 -382.479023) (xy 81.154036 -382.534657) (xy 81.132172 -382.560322) (xy 81.12638 -382.56747)
			(xy 81.119863 -382.584659) (xy 81.119472 -382.59385) (xy 81.119472 -383.086356) (xy 81.11991 -383.09554)
			(xy 81.126405 -383.112724) (xy 81.132172 -383.119884) (xy 81.154053 -383.145536) (xy 81.192143 -383.201172)
			(xy 81.223294 -383.260969) (xy 81.246931 -383.323727) (xy 82.349036 -383.323727) (xy 82.34904 -383.256419)
			(xy 82.357087 -383.189595) (xy 82.373063 -383.124211) (xy 82.396739 -383.061205) (xy 82.427775 -383.00148)
			(xy 82.465727 -382.945892) (xy 82.487516 -382.92024) (xy 82.493322 -382.913102) (xy 82.499831 -382.895906)
			(xy 82.500216 -382.886712) (xy 82.500216 -382.728724) (xy 82.500641 -382.718569) (xy 82.508432 -382.699814)
			(xy 82.522828 -382.68549) (xy 82.541621 -382.677792) (xy 82.551778 -382.677416) (xy 83.268058 -382.677416)
			(xy 83.278179 -382.67796) (xy 83.296895 -382.68567) (xy 83.311252 -382.699938) (xy 83.319076 -382.718606)
			(xy 83.31962 -382.728724) (xy 83.31962 -382.886712) (xy 83.32002 -382.8959) (xy 83.32654 -382.913085)
			(xy 83.33232 -382.92024) (xy 83.354074 -382.945921) (xy 83.392026 -383.001502) (xy 83.423063 -383.061221)
			(xy 83.44674 -383.124222) (xy 83.462717 -383.189601) (xy 83.470764 -383.256421) (xy 83.470767 -383.323724)
			(xy 83.462726 -383.390545) (xy 83.446756 -383.455926) (xy 83.423085 -383.518929) (xy 83.392054 -383.578651)
			(xy 83.354107 -383.634236) (xy 83.33232 -383.659888) (xy 83.326506 -383.667021) (xy 83.320001 -383.684221)
			(xy 83.31962 -383.693416) (xy 83.31962 -384.186684) (xy 83.320033 -384.195871) (xy 83.326544 -384.213056)
			(xy 83.33232 -384.220212) (xy 83.354144 -384.245835) (xy 83.392095 -384.301424) (xy 83.423129 -384.361152)
			(xy 83.446801 -384.42416) (xy 83.462773 -384.489546) (xy 83.470815 -384.556373) (xy 83.470812 -384.623681)
			(xy 83.462763 -384.690507) (xy 83.446785 -384.755892) (xy 83.423107 -384.818898) (xy 83.392067 -384.878622)
			(xy 83.354111 -384.934208) (xy 83.33232 -384.95986) (xy 83.326518 -384.967001) (xy 83.320006 -384.984195)
			(xy 83.31962 -384.993388) (xy 83.31962 -385.151376) (xy 83.319159 -385.161526) (xy 83.311375 -385.180274)
			(xy 83.296991 -385.194598) (xy 83.27821 -385.202302) (xy 83.268058 -385.202684) (xy 82.551778 -385.202684)
			(xy 82.541653 -385.202192) (xy 82.522936 -385.194462) (xy 82.508581 -385.180178) (xy 82.500758 -385.161499)
			(xy 82.500216 -385.151376) (xy 82.500216 -384.993388) (xy 82.499808 -384.984201) (xy 82.493293 -384.967016)
			(xy 82.487516 -384.95986) (xy 82.465765 -384.934178) (xy 82.427816 -384.878595) (xy 82.396783 -384.818876)
			(xy 82.373109 -384.755875) (xy 82.357134 -384.690497) (xy 82.349088 -384.623678) (xy 82.349084 -384.556376)
			(xy 82.357125 -384.489556) (xy 82.373093 -384.424177) (xy 82.396761 -384.361174) (xy 82.427788 -384.301451)
			(xy 82.465731 -384.245865) (xy 82.487516 -384.220212) (xy 82.493334 -384.213082) (xy 82.499835 -384.19588)
			(xy 82.500216 -384.186684) (xy 82.500216 -383.693416) (xy 82.499794 -383.68423) (xy 82.493288 -383.667046)
			(xy 82.487516 -383.659888) (xy 82.465694 -383.634265) (xy 82.427747 -383.578674) (xy 82.396717 -383.518946)
			(xy 82.373047 -383.455938) (xy 82.357077 -383.390552) (xy 82.349036 -383.323727) (xy 81.246931 -383.323727)
			(xy 81.247059 -383.324068) (xy 81.263094 -383.389559) (xy 81.271169 -383.456499) (xy 81.271168 -383.523925)
			(xy 81.26309 -383.590865) (xy 81.247052 -383.656355) (xy 81.223285 -383.719453) (xy 81.19213 -383.779249)
			(xy 81.154038 -383.834883) (xy 81.132172 -383.860548) (xy 81.126369 -383.867688) (xy 81.119859 -383.884883)
			(xy 81.119472 -383.894076) (xy 81.119472 -384.051556) (xy 81.119047 -384.061679) (xy 81.111308 -384.080387)
			(xy 81.096994 -384.094704) (xy 81.078287 -384.102446) (xy 81.068164 -384.102864) (xy 80.351884 -384.102864)
			(xy 80.341756 -384.102496) (xy 80.323045 -384.094736) (xy 80.30873 -384.080405) (xy 80.300992 -384.061685)
			(xy 80.300576 -384.051556) (xy 80.300576 -383.894076) (xy 80.300183 -383.884887) (xy 80.293658 -383.867703)
			(xy 80.287876 -383.860548) (xy 80.266029 -383.834869) (xy 80.227941 -383.779236) (xy 80.196791 -383.719442)
			(xy 80.173027 -383.656347) (xy 80.156991 -383.590859) (xy 80.148914 -383.523923) (xy 80.148913 -383.456501)
			(xy 80.156987 -383.389564) (xy 80.17302 -383.324076) (xy 80.196781 -383.26098) (xy 80.227929 -383.201184)
			(xy 80.266014 -383.14555) (xy 80.287876 -383.119884) (xy 80.293659 -383.112729) (xy 80.300183 -383.095546)
			(xy 80.300576 -383.086356) (xy 80.300576 -382.59385) (xy 80.300147 -382.584665) (xy 80.293647 -382.56748)
			(xy 80.287876 -382.560322) (xy 80.266003 -382.534664) (xy 80.227916 -382.479028) (xy 80.196767 -382.419231)
			(xy 80.173005 -382.356133) (xy 80.156971 -382.290643) (xy 80.148896 -382.223704) (xy 76.870825 -382.223704)
			(xy 76.862789 -382.290466) (xy 76.846818 -382.355847) (xy 76.823147 -382.418851) (xy 76.792117 -382.478575)
			(xy 76.75417 -382.534162) (xy 76.732384 -382.559814) (xy 76.726597 -382.566966) (xy 76.720077 -382.584151)
			(xy 76.719684 -382.593342) (xy 76.719684 -383.086864) (xy 76.720115 -383.096049) (xy 76.726615 -383.113233)
			(xy 76.732384 -383.120392) (xy 76.754187 -383.146031) (xy 76.792134 -383.20162) (xy 76.823165 -383.261346)
			(xy 76.846624 -383.323787) (xy 77.948717 -383.323787) (xy 77.94872 -383.256359) (xy 77.9568 -383.189418)
			(xy 77.97284 -383.123927) (xy 77.99661 -383.060828) (xy 78.027766 -383.001031) (xy 78.065861 -382.945397)
			(xy 78.087728 -382.919732) (xy 78.09354 -382.912598) (xy 78.100045 -382.895399) (xy 78.100428 -382.886204)
			(xy 78.100428 -382.728724) (xy 78.100836 -382.7186) (xy 78.108582 -382.699891) (xy 78.122901 -382.685575)
			(xy 78.141611 -382.677834) (xy 78.151736 -382.677416) (xy 78.868016 -382.677416) (xy 78.878142 -382.677803)
			(xy 78.896849 -382.685559) (xy 78.911163 -382.699885) (xy 78.918905 -382.718598) (xy 78.919324 -382.728724)
			(xy 78.919324 -382.886204) (xy 78.919727 -382.895392) (xy 78.926245 -382.912577) (xy 78.932024 -382.919732)
			(xy 78.953852 -382.945427) (xy 78.99194 -383.001058) (xy 79.023091 -383.06085) (xy 79.046856 -383.123943)
			(xy 79.062893 -383.189428) (xy 79.070972 -383.256363) (xy 79.070975 -383.323783) (xy 79.062903 -383.390719)
			(xy 79.046872 -383.456205) (xy 79.023113 -383.519301) (xy 78.991968 -383.579096) (xy 78.953885 -383.63473)
			(xy 78.932024 -383.660396) (xy 78.926249 -383.667557) (xy 78.919721 -383.684735) (xy 78.919324 -383.693924)
			(xy 78.919324 -384.186176) (xy 78.91974 -384.195363) (xy 78.926249 -384.212547) (xy 78.932024 -384.219704)
			(xy 78.953922 -384.24534) (xy 78.992009 -384.30098) (xy 79.023156 -384.36078) (xy 79.046917 -384.423881)
			(xy 79.06295 -384.489373) (xy 79.071022 -384.556314) (xy 79.071019 -384.62374) (xy 79.06294 -384.69068)
			(xy 79.046901 -384.756171) (xy 79.023134 -384.819269) (xy 78.991981 -384.879067) (xy 78.953889 -384.934702)
			(xy 78.932024 -384.960368) (xy 78.926219 -384.967507) (xy 78.919709 -384.984702) (xy 78.919324 -384.993896)
			(xy 78.919324 -385.151376) (xy 78.918865 -385.161494) (xy 78.911129 -385.180193) (xy 78.896826 -385.194507)
			(xy 78.878134 -385.202257) (xy 78.868016 -385.202684) (xy 78.151736 -385.202684) (xy 78.141614 -385.202254)
			(xy 78.122908 -385.194515) (xy 78.108592 -385.180202) (xy 78.100848 -385.161498) (xy 78.100428 -385.151376)
			(xy 78.100428 -384.993896) (xy 78.100014 -384.984709) (xy 78.093502 -384.967525) (xy 78.087728 -384.960368)
			(xy 78.065898 -384.934674) (xy 78.027807 -384.879044) (xy 77.996653 -384.819252) (xy 77.972886 -384.756159)
			(xy 77.956847 -384.690673) (xy 77.948768 -384.623738) (xy 77.948764 -384.556316) (xy 77.956837 -384.48938)
			(xy 77.972869 -384.423893) (xy 77.996631 -384.360797) (xy 78.027779 -384.301002) (xy 78.065865 -384.245369)
			(xy 78.087728 -384.219704) (xy 78.093509 -384.212548) (xy 78.100032 -384.195366) (xy 78.100428 -384.186176)
			(xy 78.100428 -383.693924) (xy 78.1 -383.684739) (xy 78.093498 -383.667555) (xy 78.087728 -383.660396)
			(xy 78.065828 -383.63476) (xy 78.027738 -383.579122) (xy 77.996587 -383.519322) (xy 77.972824 -383.456221)
			(xy 77.95679 -383.390728) (xy 77.948717 -383.323787) (xy 76.846624 -383.323787) (xy 76.846836 -383.324352)
			(xy 76.862807 -383.389735) (xy 76.870849 -383.456559) (xy 76.870848 -383.523865) (xy 76.862803 -383.590688)
			(xy 76.846829 -383.656071) (xy 76.823155 -383.719076) (xy 76.792121 -383.7788) (xy 76.754172 -383.834388)
			(xy 76.732384 -383.86004) (xy 76.726586 -383.867184) (xy 76.720073 -383.884376) (xy 76.719684 -383.893568)
			(xy 76.719684 -384.051556) (xy 76.719242 -384.061709) (xy 76.711458 -384.080464) (xy 76.697067 -384.094789)
			(xy 76.678277 -384.102488) (xy 76.668122 -384.102864) (xy 75.951842 -384.102864) (xy 75.941718 -384.102339)
			(xy 75.922999 -384.094626) (xy 75.908642 -384.080351) (xy 75.90082 -384.061677) (xy 75.90028 -384.051556)
			(xy 75.90028 -383.893568) (xy 75.89989 -383.884379) (xy 75.893363 -383.867194) (xy 75.88758 -383.86004)
			(xy 75.865807 -383.834375) (xy 75.827855 -383.778792) (xy 75.796819 -383.71907) (xy 75.773143 -383.656067)
			(xy 75.757168 -383.590686) (xy 75.749122 -383.523864) (xy 75.74912 -383.45656) (xy 75.757164 -383.389738)
			(xy 75.773136 -383.324356) (xy 75.796809 -383.261352) (xy 75.827842 -383.201629) (xy 75.865792 -383.146044)
			(xy 75.88758 -383.120392) (xy 75.89336 -383.113235) (xy 75.899885 -383.096054) (xy 75.90028 -383.086864)
			(xy 75.90028 -382.593342) (xy 75.899854 -382.584156) (xy 75.893352 -382.566972) (xy 75.88758 -382.559814)
			(xy 75.865781 -382.53417) (xy 75.82783 -382.478584) (xy 75.796795 -382.418859) (xy 75.773121 -382.355854)
			(xy 75.757147 -382.29047) (xy 75.749104 -382.223646) (xy 72.471064 -382.223646) (xy 72.471064 -382.223704)
			(xy 72.462989 -382.290642) (xy 72.446954 -382.356131) (xy 72.42319 -382.419227) (xy 72.39204 -382.479023)
			(xy 72.353952 -382.534657) (xy 72.332088 -382.560322) (xy 72.326298 -382.567472) (xy 72.31978 -382.584659)
			(xy 72.319388 -382.59385) (xy 72.319388 -383.086356) (xy 72.319822 -383.095541) (xy 72.326319 -383.112725)
			(xy 72.332088 -383.119884) (xy 72.353968 -383.145536) (xy 72.392057 -383.201172) (xy 72.423208 -383.26097)
			(xy 72.446843 -383.323727) (xy 73.548949 -383.323727) (xy 73.548952 -383.256419) (xy 73.556999 -383.189594)
			(xy 73.572976 -383.12421) (xy 73.596652 -383.061204) (xy 73.62769 -383.001479) (xy 73.665642 -382.945892)
			(xy 73.687432 -382.92024) (xy 73.693241 -382.913103) (xy 73.699747 -382.895906) (xy 73.700132 -382.886712)
			(xy 73.700132 -382.728724) (xy 73.700542 -382.718567) (xy 73.708335 -382.699809) (xy 73.722736 -382.685484)
			(xy 73.741535 -382.677789) (xy 73.751694 -382.677416) (xy 74.467974 -382.677416) (xy 74.478096 -382.677947)
			(xy 74.496812 -382.685662) (xy 74.511169 -382.699934) (xy 74.518993 -382.718605) (xy 74.519536 -382.728724)
			(xy 74.519536 -382.886712) (xy 74.519955 -382.895898) (xy 74.526464 -382.913082) (xy 74.532236 -382.92024)
			(xy 74.553989 -382.945921) (xy 74.591941 -383.001503) (xy 74.622977 -383.061222) (xy 74.646653 -383.124223)
			(xy 74.662629 -383.189602) (xy 74.670676 -383.256422) (xy 74.670679 -383.323724) (xy 74.662639 -383.390545)
			(xy 74.646669 -383.455925) (xy 74.622999 -383.518928) (xy 74.591968 -383.578651) (xy 74.554022 -383.634236)
			(xy 74.532236 -383.659888) (xy 74.526412 -383.667013) (xy 74.519915 -383.684219) (xy 74.519536 -383.693416)
			(xy 74.519536 -384.186684) (xy 74.519968 -384.195869) (xy 74.526468 -384.213052) (xy 74.532236 -384.220212)
			(xy 74.55406 -384.245835) (xy 74.592009 -384.301425) (xy 74.623043 -384.361152) (xy 74.646714 -384.424161)
			(xy 74.662686 -384.489547) (xy 74.670727 -384.556373) (xy 74.670724 -384.623681) (xy 74.662676 -384.690507)
			(xy 74.646698 -384.755891) (xy 74.623021 -384.818897) (xy 74.591982 -384.878622) (xy 74.554027 -384.934208)
			(xy 74.532236 -384.95986) (xy 74.526424 -384.966994) (xy 74.51992 -384.984193) (xy 74.519536 -384.993388)
			(xy 74.519536 -385.151376) (xy 74.51906 -385.161524) (xy 74.511279 -385.180269) (xy 74.496899 -385.194592)
			(xy 74.478124 -385.202299) (xy 74.467974 -385.202684) (xy 73.751694 -385.202684) (xy 73.74157 -385.202179)
			(xy 73.722853 -385.194454) (xy 73.708498 -385.180173) (xy 73.700675 -385.161497) (xy 73.700132 -385.151376)
			(xy 73.700132 -384.993388) (xy 73.699721 -384.984201) (xy 73.693207 -384.967017) (xy 73.687432 -384.95986)
			(xy 73.66568 -384.934178) (xy 73.627731 -384.878596) (xy 73.596696 -384.818877) (xy 73.573022 -384.755876)
			(xy 73.557047 -384.690497) (xy 73.549 -384.623678) (xy 73.548996 -384.556376) (xy 73.557037 -384.489556)
			(xy 73.573006 -384.424176) (xy 73.596674 -384.361173) (xy 73.627703 -384.30145) (xy 73.665647 -384.245864)
			(xy 73.687432 -384.220212) (xy 73.693253 -384.213084) (xy 73.699752 -384.19588) (xy 73.700132 -384.186684)
			(xy 73.700132 -383.693416) (xy 73.699707 -383.684231) (xy 73.693203 -383.667046) (xy 73.687432 -383.659888)
			(xy 73.665609 -383.634265) (xy 73.627662 -383.578674) (xy 73.59663 -383.518946) (xy 73.57296 -383.455938)
			(xy 73.55699 -383.390553) (xy 73.548949 -383.323727) (xy 72.446843 -383.323727) (xy 72.446972 -383.324069)
			(xy 72.463006 -383.38956) (xy 72.471081 -383.456499) (xy 72.47108 -383.523925) (xy 72.463002 -383.590864)
			(xy 72.446964 -383.656354) (xy 72.423198 -383.719452) (xy 72.392045 -383.779248) (xy 72.353953 -383.834883)
			(xy 72.332088 -383.860548) (xy 72.326287 -383.86769) (xy 72.319775 -383.884883) (xy 72.319388 -383.894076)
			(xy 72.319388 -384.051556) (xy 72.318948 -384.061677) (xy 72.311212 -384.080382) (xy 72.296902 -384.094698)
			(xy 72.278201 -384.102443) (xy 72.26808 -384.102864) (xy 71.5518 -384.102864) (xy 71.541673 -384.102483)
			(xy 71.522963 -384.094728) (xy 71.508647 -384.0804) (xy 71.500908 -384.061683) (xy 71.500492 -384.051556)
			(xy 71.500492 -383.894076) (xy 71.500095 -383.884887) (xy 71.493572 -383.867703) (xy 71.487792 -383.860548)
			(xy 71.465944 -383.83487) (xy 71.427855 -383.779237) (xy 71.396704 -383.719442) (xy 71.37294 -383.656347)
			(xy 71.356903 -383.59086) (xy 71.348826 -383.523923) (xy 71.348825 -383.456501) (xy 71.356899 -383.389564)
			(xy 71.372933 -383.324076) (xy 71.396695 -383.26098) (xy 71.427843 -383.201184) (xy 71.465929 -383.145549)
			(xy 71.487792 -383.119884) (xy 71.493577 -383.11273) (xy 71.500099 -383.095546) (xy 71.500492 -383.086356)
			(xy 71.500492 -382.59385) (xy 71.50006 -382.584665) (xy 71.493562 -382.56748) (xy 71.487792 -382.560322)
			(xy 71.465918 -382.534665) (xy 71.427831 -382.479029) (xy 71.396681 -382.419231) (xy 71.372918 -382.356134)
			(xy 71.356883 -382.290644) (xy 71.348808 -382.223705) (xy 46.070794 -382.223705) (xy 46.062758 -382.290467)
			(xy 46.046786 -382.355849) (xy 46.023113 -382.418853) (xy 45.99208 -382.478576) (xy 45.954131 -382.534162)
			(xy 45.932344 -382.559814) (xy 45.926552 -382.566962) (xy 45.920036 -382.584151) (xy 45.919644 -382.593342)
			(xy 45.919644 -383.086864) (xy 45.920084 -383.096048) (xy 45.926578 -383.113232) (xy 45.932344 -383.120392)
			(xy 45.954148 -383.146031) (xy 45.992098 -383.201619) (xy 46.023131 -383.261344) (xy 46.04657 -383.323727)
			(xy 47.149191 -383.323727) (xy 47.149195 -383.256419) (xy 47.157243 -383.189593) (xy 47.173221 -383.124208)
			(xy 47.1969 -383.061202) (xy 47.22794 -383.001477) (xy 47.265897 -382.945892) (xy 47.287688 -382.92024)
			(xy 47.293491 -382.913099) (xy 47.300002 -382.895905) (xy 47.300388 -382.886712) (xy 47.300388 -382.728724)
			(xy 47.300841 -382.718573) (xy 47.308626 -382.699823) (xy 47.323013 -382.685499) (xy 47.341797 -382.677797)
			(xy 47.35195 -382.677416) (xy 48.06823 -382.677416) (xy 48.078356 -382.677901) (xy 48.097073 -382.685634)
			(xy 48.111427 -382.699921) (xy 48.11925 -382.718601) (xy 48.119792 -382.728724) (xy 48.119792 -382.886712)
			(xy 48.120198 -382.8959) (xy 48.126715 -382.913084) (xy 48.132492 -382.92024) (xy 48.154243 -382.945922)
			(xy 48.192191 -383.001505) (xy 48.223224 -383.061224) (xy 48.246898 -383.124225) (xy 48.262872 -383.189603)
			(xy 48.270919 -383.256422) (xy 48.270922 -383.323724) (xy 48.262882 -383.390543) (xy 48.246914 -383.455923)
			(xy 48.223247 -383.518926) (xy 48.192219 -383.578649) (xy 48.154277 -383.634236) (xy 48.132492 -383.659888)
			(xy 48.126675 -383.667018) (xy 48.120173 -383.68422) (xy 48.119792 -383.693416) (xy 48.119792 -384.186684)
			(xy 48.120212 -384.19587) (xy 48.126719 -384.213054) (xy 48.132492 -384.220212) (xy 48.154314 -384.245835)
			(xy 48.19226 -384.301427) (xy 48.22329 -384.361155) (xy 48.246959 -384.424163) (xy 48.262929 -384.489548)
			(xy 48.27097 -384.556373) (xy 48.270966 -384.623681) (xy 48.262919 -384.690505) (xy 48.246943 -384.755889)
			(xy 48.223268 -384.818895) (xy 48.192232 -384.87862) (xy 48.154281 -384.934207) (xy 48.132492 -384.95986)
			(xy 48.126687 -384.966999) (xy 48.120177 -384.984194) (xy 48.119792 -384.993388) (xy 48.119792 -385.151376)
			(xy 48.119359 -385.16153) (xy 48.11157 -385.180283) (xy 48.097176 -385.194608) (xy 48.078386 -385.202307)
			(xy 48.06823 -385.202684) (xy 47.35195 -385.202684) (xy 47.341829 -385.202133) (xy 47.323114 -385.194426)
			(xy 47.308757 -385.18016) (xy 47.300932 -385.161493) (xy 47.300388 -385.151376) (xy 47.300388 -384.993388)
			(xy 47.299986 -384.9842) (xy 47.293467 -384.967016) (xy 47.287688 -384.95986) (xy 47.265934 -384.934179)
			(xy 47.227981 -384.878598) (xy 47.196944 -384.818879) (xy 47.173267 -384.755878) (xy 47.15729 -384.690499)
			(xy 47.149242 -384.623679) (xy 47.149239 -384.556376) (xy 47.15728 -384.489554) (xy 47.173251 -384.424174)
			(xy 47.196921 -384.361171) (xy 47.227953 -384.301448) (xy 47.265901 -384.245863) (xy 47.287688 -384.220212)
			(xy 47.293503 -384.21308) (xy 47.300007 -384.195879) (xy 47.300388 -384.186684) (xy 47.300388 -383.693416)
			(xy 47.299973 -383.684229) (xy 47.293463 -383.667045) (xy 47.287688 -383.659888) (xy 47.265863 -383.634266)
			(xy 47.227913 -383.578676) (xy 47.196878 -383.518949) (xy 47.173205 -383.45594) (xy 47.157233 -383.390554)
			(xy 47.149191 -383.323727) (xy 46.04657 -383.323727) (xy 46.046804 -383.32435) (xy 46.062776 -383.389734)
			(xy 46.070819 -383.456559) (xy 46.070818 -383.523865) (xy 46.062772 -383.590689) (xy 46.046797 -383.656073)
			(xy 46.023121 -383.719078) (xy 45.992085 -383.778802) (xy 45.954133 -383.834388) (xy 45.932344 -383.86004)
			(xy 45.926541 -383.86718) (xy 45.920032 -383.884375) (xy 45.919644 -383.893568) (xy 45.919644 -384.051556)
			(xy 45.919143 -384.061702) (xy 45.91137 -384.080445) (xy 45.896998 -384.094768) (xy 45.878229 -384.102477)
			(xy 45.868082 -384.102864) (xy 45.151802 -384.102864) (xy 45.141676 -384.102372) (xy 45.122956 -384.094645)
			(xy 45.108599 -384.080361) (xy 45.100779 -384.06168) (xy 45.10024 -384.051556) (xy 45.10024 -383.893568)
			(xy 45.099836 -383.88438) (xy 45.093317 -383.867197) (xy 45.08754 -383.86004) (xy 45.065768 -383.834375)
			(xy 45.027819 -383.77879) (xy 44.996785 -383.719068) (xy 44.973111 -383.656066) (xy 44.957137 -383.590685)
			(xy 44.949092 -383.523864) (xy 44.94909 -383.45656) (xy 44.957133 -383.389739) (xy 44.973104 -383.324357)
			(xy 44.996775 -383.261354) (xy 45.027806 -383.20163) (xy 45.065753 -383.146044) (xy 45.08754 -383.120392)
			(xy 45.093328 -383.113241) (xy 45.099847 -383.096055) (xy 45.10024 -383.086864) (xy 45.10024 -382.593342)
			(xy 45.0998 -382.584158) (xy 45.093306 -382.566974) (xy 45.08754 -382.559814) (xy 45.065742 -382.53417)
			(xy 45.027794 -382.478582) (xy 44.996761 -382.418858) (xy 44.973088 -382.355852) (xy 44.957116 -382.290469)
			(xy 44.949073 -382.223645) (xy 41.671034 -382.223645) (xy 41.671034 -382.223704) (xy 41.662958 -382.290643)
			(xy 41.646922 -382.356132) (xy 41.623157 -382.419229) (xy 41.592004 -382.479024) (xy 41.553913 -382.534658)
			(xy 41.532048 -382.560322) (xy 41.526253 -382.567468) (xy 41.519739 -382.584658) (xy 41.519348 -382.59385)
			(xy 41.519348 -383.086356) (xy 41.519791 -383.095539) (xy 41.526283 -383.112723) (xy 41.532048 -383.119884)
			(xy 41.55393 -383.145535) (xy 41.592021 -383.201171) (xy 41.623174 -383.260968) (xy 41.646834 -383.323786)
			(xy 42.748896 -383.323786) (xy 42.748899 -383.25636) (xy 42.756978 -383.189419) (xy 42.773018 -383.123928)
			(xy 42.796786 -383.06083) (xy 42.827941 -383.001032) (xy 42.866034 -382.945397) (xy 42.8879 -382.919732)
			(xy 42.893708 -382.912595) (xy 42.900216 -382.895398) (xy 42.9006 -382.886204) (xy 42.9006 -382.728724)
			(xy 42.901035 -382.718603) (xy 42.908776 -382.6999) (xy 42.923086 -382.685585) (xy 42.941787 -382.677839)
			(xy 42.951908 -382.677416) (xy 43.668188 -382.677416) (xy 43.678312 -382.677826) (xy 43.697018 -382.685573)
			(xy 43.711333 -382.699892) (xy 43.719076 -382.7186) (xy 43.719496 -382.728724) (xy 43.719496 -382.886204)
			(xy 43.719905 -382.895391) (xy 43.72642 -382.912575) (xy 43.732196 -382.919732) (xy 43.754025 -382.945426)
			(xy 43.792115 -383.001057) (xy 43.823267 -383.060849) (xy 43.847034 -383.123942) (xy 43.863072 -383.189427)
			(xy 43.871151 -383.256363) (xy 43.871154 -383.323783) (xy 43.863081 -383.390719) (xy 43.84705 -383.456206)
			(xy 43.823289 -383.519302) (xy 43.792143 -383.579097) (xy 43.754058 -383.634731) (xy 43.732196 -383.660396)
			(xy 43.726418 -383.667554) (xy 43.719892 -383.684735) (xy 43.719496 -383.693924) (xy 43.719496 -384.186176)
			(xy 43.719919 -384.195362) (xy 43.726424 -384.212546) (xy 43.732196 -384.219704) (xy 43.754095 -384.24534)
			(xy 43.792183 -384.300979) (xy 43.823333 -384.360779) (xy 43.847095 -384.42388) (xy 43.863128 -384.489372)
			(xy 43.871201 -384.556314) (xy 43.871198 -384.62374) (xy 43.863118 -384.690681) (xy 43.847079 -384.756172)
			(xy 43.823311 -384.819271) (xy 43.792156 -384.879068) (xy 43.754062 -384.934703) (xy 43.732196 -384.960368)
			(xy 43.726388 -384.967505) (xy 43.71988 -384.984702) (xy 43.719496 -384.993896) (xy 43.719496 -385.151376)
			(xy 43.719064 -385.161497) (xy 43.711323 -385.180201) (xy 43.697011 -385.194517) (xy 43.678309 -385.202262)
			(xy 43.668188 -385.202684) (xy 42.951908 -385.202684) (xy 42.941784 -385.202277) (xy 42.923078 -385.194529)
			(xy 42.908762 -385.180209) (xy 42.90102 -385.1615) (xy 42.9006 -385.151376) (xy 42.9006 -384.993896)
			(xy 42.900192 -384.984709) (xy 42.893677 -384.967524) (xy 42.8879 -384.960368) (xy 42.866071 -384.934674)
			(xy 42.827982 -384.879043) (xy 42.796829 -384.819251) (xy 42.773063 -384.756158) (xy 42.757025 -384.690672)
			(xy 42.748946 -384.623737) (xy 42.748943 -384.556317) (xy 42.757015 -384.489381) (xy 42.773047 -384.423894)
			(xy 42.796807 -384.360798) (xy 42.827954 -384.301003) (xy 42.866038 -384.245369) (xy 42.8879 -384.219704)
			(xy 42.893677 -384.212545) (xy 42.900204 -384.195365) (xy 42.9006 -384.186176) (xy 42.9006 -383.693924)
			(xy 42.900178 -383.684738) (xy 42.893673 -383.667554) (xy 42.8879 -383.660396) (xy 42.866001 -383.63476)
			(xy 42.827913 -383.579121) (xy 42.796764 -383.519321) (xy 42.773002 -383.45622) (xy 42.756969 -383.390728)
			(xy 42.748896 -383.323786) (xy 41.646834 -383.323786) (xy 41.64694 -383.324067) (xy 41.662976 -383.389558)
			(xy 41.671051 -383.456499) (xy 41.67105 -383.523925) (xy 41.662971 -383.590865) (xy 41.646933 -383.656356)
			(xy 41.623164 -383.719454) (xy 41.592009 -383.77925) (xy 41.553915 -383.834884) (xy 41.532048 -383.860548)
			(xy 41.526242 -383.867686) (xy 41.519734 -383.884882) (xy 41.519348 -383.894076) (xy 41.519348 -384.051556)
			(xy 41.518849 -384.06167) (xy 41.511124 -384.080363) (xy 41.496834 -384.094677) (xy 41.478153 -384.102432)
			(xy 41.46804 -384.102864) (xy 40.75176 -384.102864) (xy 40.74163 -384.102516) (xy 40.722919 -384.094748)
			(xy 40.708605 -384.08041) (xy 40.700868 -384.061686) (xy 40.700452 -384.051556) (xy 40.700452 -383.894076)
			(xy 40.700042 -383.884889) (xy 40.693527 -383.867705) (xy 40.687752 -383.860548) (xy 40.665902 -383.834871)
			(xy 40.627809 -383.779239) (xy 40.596655 -383.719445) (xy 40.572888 -383.65635) (xy 40.556849 -383.590862)
			(xy 40.548772 -383.523924) (xy 40.54877 -383.4565) (xy 40.556845 -383.389562) (xy 40.572881 -383.324073)
			(xy 40.596645 -383.260977) (xy 40.627797 -383.201182) (xy 40.665887 -383.145548) (xy 40.687752 -383.119884)
			(xy 40.693544 -383.112736) (xy 40.70006 -383.095547) (xy 40.700452 -383.086356) (xy 40.700452 -382.59385)
			(xy 40.700006 -382.584667) (xy 40.693516 -382.567483) (xy 40.687752 -382.560322) (xy 40.665876 -382.534666)
			(xy 40.627785 -382.479031) (xy 40.596631 -382.419234) (xy 40.572865 -382.356136) (xy 40.556829 -382.290645)
			(xy 40.548753 -382.223705) (xy 37.271243 -382.223705) (xy 37.263167 -382.290643) (xy 37.247132 -382.356132)
			(xy 37.223367 -382.419228) (xy 37.192215 -382.479024) (xy 37.154125 -382.534657) (xy 37.13226 -382.560322)
			(xy 37.126467 -382.567469) (xy 37.119951 -382.584658) (xy 37.11956 -382.59385) (xy 37.11956 -383.086356)
			(xy 37.12 -383.09554) (xy 37.126494 -383.112724) (xy 37.13226 -383.119884) (xy 37.154141 -383.145536)
			(xy 37.192232 -383.201171) (xy 37.223384 -383.260969) (xy 37.247021 -383.323727) (xy 38.349127 -383.323727)
			(xy 38.349131 -383.256419) (xy 38.357178 -383.189595) (xy 38.373154 -383.124211) (xy 38.396829 -383.061205)
			(xy 38.427864 -383.00148) (xy 38.465815 -382.945893) (xy 38.487604 -382.92024) (xy 38.493409 -382.913101)
			(xy 38.499919 -382.895906) (xy 38.500304 -382.886712) (xy 38.500304 -382.728724) (xy 38.500741 -382.718571)
			(xy 38.50853 -382.699818) (xy 38.522922 -382.685494) (xy 38.541711 -382.677794) (xy 38.551866 -382.677416)
			(xy 39.268146 -382.677416) (xy 39.278273 -382.677888) (xy 39.29699 -382.685627) (xy 39.311344 -382.699917)
			(xy 39.319166 -382.7186) (xy 39.319708 -382.728724) (xy 39.319708 -382.886712) (xy 39.320111 -382.8959)
			(xy 39.326629 -382.913084) (xy 39.332408 -382.92024) (xy 39.354162 -382.945921) (xy 39.392115 -383.001502)
			(xy 39.423153 -383.061221) (xy 39.44683 -383.124222) (xy 39.462807 -383.189601) (xy 39.470855 -383.256421)
			(xy 39.470858 -383.323725) (xy 39.462817 -383.390546) (xy 39.446846 -383.455926) (xy 39.423175 -383.51893)
			(xy 39.392143 -383.578652) (xy 39.354195 -383.634237) (xy 39.332408 -383.659888) (xy 39.326592 -383.66702)
			(xy 39.320089 -383.684221) (xy 39.319708 -383.693416) (xy 39.319708 -384.186684) (xy 39.320124 -384.195871)
			(xy 39.326633 -384.213055) (xy 39.332408 -384.220212) (xy 39.354233 -384.245834) (xy 39.392184 -384.301424)
			(xy 39.423219 -384.361151) (xy 39.446892 -384.42416) (xy 39.462864 -384.489546) (xy 39.470906 -384.556373)
			(xy 39.470902 -384.623682) (xy 39.462854 -384.690507) (xy 39.446876 -384.755892) (xy 39.423196 -384.818898)
			(xy 39.392156 -384.878623) (xy 39.354199 -384.934209) (xy 39.332408 -384.95986) (xy 39.326604 -384.967)
			(xy 39.320094 -384.984195) (xy 39.319708 -384.993388) (xy 39.319708 -385.151376) (xy 39.319259 -385.161528)
			(xy 39.311473 -385.180278) (xy 39.297085 -385.194602) (xy 39.278299 -385.202304) (xy 39.268146 -385.202684)
			(xy 38.551866 -385.202684) (xy 38.54174 -385.202202) (xy 38.523023 -385.194468) (xy 38.508668 -385.18018)
			(xy 38.500846 -385.1615) (xy 38.500304 -385.151376) (xy 38.500304 -384.993388) (xy 38.499899 -384.9842)
			(xy 38.493381 -384.967016) (xy 38.487604 -384.95986) (xy 38.465853 -384.934178) (xy 38.427905 -384.878595)
			(xy 38.396872 -384.818875) (xy 38.373199 -384.755875) (xy 38.357224 -384.690497) (xy 38.349178 -384.623678)
			(xy 38.349175 -384.556376) (xy 38.357215 -384.489557) (xy 38.373183 -384.424177) (xy 38.39685 -384.361174)
			(xy 38.427877 -384.301451) (xy 38.465819 -384.245865) (xy 38.487604 -384.220212) (xy 38.493421 -384.213081)
			(xy 38.499923 -384.19588) (xy 38.500304 -384.186684) (xy 38.500304 -383.693416) (xy 38.499885 -383.68423)
			(xy 38.493377 -383.667045) (xy 38.487604 -383.659888) (xy 38.465782 -383.634264) (xy 38.427837 -383.578673)
			(xy 38.396807 -383.518945) (xy 38.373138 -383.455937) (xy 38.357168 -383.390552) (xy 38.349127 -383.323727)
			(xy 37.247021 -383.323727) (xy 37.247149 -383.324068) (xy 37.263185 -383.389559) (xy 37.27126 -383.456499)
			(xy 37.271259 -383.523925) (xy 37.263181 -383.590865) (xy 37.247142 -383.656355) (xy 37.223374 -383.719453)
			(xy 37.19222 -383.77925) (xy 37.154126 -383.834883) (xy 37.13226 -383.860548) (xy 37.126456 -383.867687)
			(xy 37.119947 -383.884883) (xy 37.11956 -383.894076) (xy 37.11956 -384.051556) (xy 37.119147 -384.061681)
			(xy 37.111406 -384.080391) (xy 37.097087 -384.094708) (xy 37.078377 -384.102448) (xy 37.068252 -384.102864)
			(xy 36.351972 -384.102864) (xy 36.341843 -384.102506) (xy 36.323132 -384.094742) (xy 36.308817 -384.080407)
			(xy 36.30108 -384.061685) (xy 36.300664 -384.051556) (xy 36.300664 -383.894076) (xy 36.300251 -383.884889)
			(xy 36.293738 -383.867706) (xy 36.287964 -383.860548) (xy 36.266117 -383.834869) (xy 36.22803 -383.779236)
			(xy 36.196881 -383.719441) (xy 36.173117 -383.656346) (xy 36.157082 -383.590859) (xy 36.149005 -383.523923)
			(xy 36.149004 -383.456501) (xy 36.157078 -383.389565) (xy 36.17311 -383.324077) (xy 36.196871 -383.260981)
			(xy 36.228018 -383.201185) (xy 36.266102 -383.14555) (xy 36.287964 -383.119884) (xy 36.293758 -383.112737)
			(xy 36.300272 -383.095548) (xy 36.300664 -383.086356) (xy 36.300664 -382.59385) (xy 36.300216 -382.584667)
			(xy 36.293727 -382.567483) (xy 36.287964 -382.560322) (xy 36.266091 -382.534664) (xy 36.228005 -382.479028)
			(xy 36.196857 -382.41923) (xy 36.173095 -382.356132) (xy 36.157061 -382.290643) (xy 36.148987 -382.223704)
			(xy 32.870916 -382.223704) (xy 32.86288 -382.290466) (xy 32.846909 -382.355848) (xy 32.823237 -382.418852)
			(xy 32.792206 -382.478575) (xy 32.754259 -382.534162) (xy 32.732472 -382.559814) (xy 32.726683 -382.566965)
			(xy 32.720165 -382.584151) (xy 32.719772 -382.593342) (xy 32.719772 -383.086864) (xy 32.720206 -383.096049)
			(xy 32.726704 -383.113233) (xy 32.732472 -383.120392) (xy 32.754275 -383.146031) (xy 32.792223 -383.20162)
			(xy 32.823255 -383.261345) (xy 32.846714 -383.323786) (xy 33.948808 -383.323786) (xy 33.948811 -383.25636)
			(xy 33.956891 -383.189419) (xy 33.972931 -383.123927) (xy 33.996699 -383.060829) (xy 34.027855 -383.001032)
			(xy 34.065949 -382.945397) (xy 34.087816 -382.919732) (xy 34.093626 -382.912596) (xy 34.100132 -382.895398)
			(xy 34.100516 -382.886204) (xy 34.100516 -382.728724) (xy 34.100936 -382.718601) (xy 34.108679 -382.699895)
			(xy 34.122995 -382.685579) (xy 34.141701 -382.677836) (xy 34.151824 -382.677416) (xy 34.868104 -382.677416)
			(xy 34.878229 -382.677813) (xy 34.896935 -382.685566) (xy 34.91125 -382.699888) (xy 34.918992 -382.718599)
			(xy 34.919412 -382.728724) (xy 34.919412 -382.886204) (xy 34.919818 -382.895392) (xy 34.926334 -382.912576)
			(xy 34.932112 -382.919732) (xy 34.95394 -382.945427) (xy 34.992029 -383.001057) (xy 35.023181 -383.060849)
			(xy 35.046946 -383.123942) (xy 35.062984 -383.189428) (xy 35.071063 -383.256363) (xy 35.071066 -383.323783)
			(xy 35.062994 -383.390719) (xy 35.046962 -383.456206) (xy 35.023203 -383.519301) (xy 34.992057 -383.579096)
			(xy 34.953973 -383.634731) (xy 34.932112 -383.660396) (xy 34.926336 -383.667556) (xy 34.919809 -383.684735)
			(xy 34.919412 -383.693924) (xy 34.919412 -384.186176) (xy 34.919831 -384.195362) (xy 34.926338 -384.212547)
			(xy 34.932112 -384.219704) (xy 34.954011 -384.24534) (xy 34.992098 -384.300979) (xy 35.023246 -384.36078)
			(xy 35.047008 -384.42388) (xy 35.06304 -384.489373) (xy 35.071113 -384.556314) (xy 35.07111 -384.62374)
			(xy 35.063031 -384.690681) (xy 35.046992 -384.756172) (xy 35.023224 -384.81927) (xy 34.99207 -384.879067)
			(xy 34.953978 -384.934703) (xy 34.932112 -384.960368) (xy 34.926305 -384.967506) (xy 34.919796 -384.984702)
			(xy 34.919412 -384.993896) (xy 34.919412 -385.151376) (xy 34.918965 -385.161495) (xy 34.911227 -385.180196)
			(xy 34.89692 -385.194511) (xy 34.878223 -385.202259) (xy 34.868104 -385.202684) (xy 34.151824 -385.202684)
			(xy 34.141701 -385.202264) (xy 34.122995 -385.194521) (xy 34.108679 -385.180205) (xy 34.100936 -385.161499)
			(xy 34.100516 -385.151376) (xy 34.100516 -384.993896) (xy 34.100104 -384.984709) (xy 34.093591 -384.967525)
			(xy 34.087816 -384.960368) (xy 34.065987 -384.934674) (xy 34.027896 -384.879044) (xy 33.996743 -384.819252)
			(xy 33.972976 -384.756159) (xy 33.956937 -384.690673) (xy 33.948858 -384.623738) (xy 33.948855 -384.556316)
			(xy 33.956928 -384.48938) (xy 33.97296 -384.423893) (xy 33.996721 -384.360798) (xy 34.027868 -384.301003)
			(xy 34.065954 -384.245369) (xy 34.087816 -384.219704) (xy 34.093595 -384.212547) (xy 34.10012 -384.195365)
			(xy 34.100516 -384.186176) (xy 34.100516 -383.693924) (xy 34.100091 -383.684739) (xy 34.093587 -383.667554)
			(xy 34.087816 -383.660396) (xy 34.065916 -383.63476) (xy 34.027827 -383.579122) (xy 33.996677 -383.519322)
			(xy 33.972915 -383.456221) (xy 33.956881 -383.390728) (xy 33.948808 -383.323786) (xy 32.846714 -383.323786)
			(xy 32.846926 -383.324351) (xy 32.862898 -383.389735) (xy 32.87094 -383.456559) (xy 32.870939 -383.523865)
			(xy 32.862893 -383.590689) (xy 32.846919 -383.656072) (xy 32.823245 -383.719077) (xy 32.79221 -383.778801)
			(xy 32.75426 -383.834388) (xy 32.732472 -383.86004) (xy 32.726672 -383.867183) (xy 32.72016 -383.884375)
			(xy 32.719772 -383.893568) (xy 32.719772 -384.051556) (xy 32.719342 -384.061711) (xy 32.711555 -384.080468)
			(xy 32.697161 -384.094793) (xy 32.678367 -384.10249) (xy 32.66821 -384.102864) (xy 31.95193 -384.102864)
			(xy 31.941806 -384.102349) (xy 31.923086 -384.094632) (xy 31.908729 -384.080354) (xy 31.900908 -384.061678)
			(xy 31.900368 -384.051556) (xy 31.900368 -383.893568) (xy 31.899958 -383.884381) (xy 31.893443 -383.867197)
			(xy 31.887668 -383.86004) (xy 31.865895 -383.834375) (xy 31.827944 -383.778791) (xy 31.796908 -383.71907)
			(xy 31.773234 -383.656067) (xy 31.757259 -383.590686) (xy 31.749213 -383.523864) (xy 31.749211 -383.45656)
			(xy 31.757254 -383.389738) (xy 31.773226 -383.324356) (xy 31.796899 -383.261352) (xy 31.827932 -383.201629)
			(xy 31.86588 -383.146044) (xy 31.887668 -383.120392) (xy 31.893459 -383.113243) (xy 31.899975 -383.096055)
			(xy 31.900368 -383.086864) (xy 31.900368 -382.593342) (xy 31.899923 -382.584159) (xy 31.893432 -382.566975)
			(xy 31.887668 -382.559814) (xy 31.86587 -382.53417) (xy 31.827919 -382.478583) (xy 31.796885 -382.418859)
			(xy 31.773211 -382.355853) (xy 31.757238 -382.29047) (xy 31.749194 -382.223646) (xy 28.471155 -382.223646)
			(xy 28.471155 -382.223704) (xy 28.463079 -382.290642) (xy 28.447044 -382.356131) (xy 28.42328 -382.419228)
			(xy 28.392129 -382.479023) (xy 28.35404 -382.534657) (xy 28.332176 -382.560322) (xy 28.326385 -382.567471)
			(xy 28.319868 -382.584659) (xy 28.319476 -382.59385) (xy 28.319476 -383.086356) (xy 28.319913 -383.09554)
			(xy 28.326409 -383.112725) (xy 28.332176 -383.119884) (xy 28.354057 -383.145536) (xy 28.392146 -383.201172)
			(xy 28.423298 -383.26097) (xy 28.446934 -383.323727) (xy 29.549039 -383.323727) (xy 29.549043 -383.256419)
			(xy 29.55709 -383.189594) (xy 29.573066 -383.12421) (xy 29.596742 -383.061205) (xy 29.627779 -383.00148)
			(xy 29.665731 -382.945892) (xy 29.68752 -382.92024) (xy 29.693327 -382.913102) (xy 29.699835 -382.895906)
			(xy 29.70022 -382.886712) (xy 29.70022 -382.728724) (xy 29.700641 -382.718569) (xy 29.708433 -382.699813)
			(xy 29.72283 -382.685488) (xy 29.741625 -382.677791) (xy 29.751782 -382.677416) (xy 30.468062 -382.677416)
			(xy 30.478183 -382.677957) (xy 30.496899 -382.685668) (xy 30.511256 -382.699938) (xy 30.51908 -382.718606)
			(xy 30.519624 -382.728724) (xy 30.519624 -382.886712) (xy 30.520023 -382.8959) (xy 30.526544 -382.913085)
			(xy 30.532324 -382.92024) (xy 30.554077 -382.945921) (xy 30.59203 -383.001502) (xy 30.623067 -383.061222)
			(xy 30.646743 -383.124222) (xy 30.66272 -383.189601) (xy 30.670767 -383.256421) (xy 30.67077 -383.323724)
			(xy 30.662729 -383.390545) (xy 30.646759 -383.455926) (xy 30.623089 -383.518929) (xy 30.592058 -383.578651)
			(xy 30.554111 -383.634236) (xy 30.532324 -383.659888) (xy 30.52651 -383.667021) (xy 30.520005 -383.684221)
			(xy 30.519624 -383.693416) (xy 30.519624 -384.186684) (xy 30.520036 -384.195871) (xy 30.526548 -384.213056)
			(xy 30.532324 -384.220212) (xy 30.554149 -384.245834) (xy 30.592099 -384.301424) (xy 30.623132 -384.361152)
			(xy 30.646805 -384.42416) (xy 30.662776 -384.489546) (xy 30.670818 -384.556373) (xy 30.670815 -384.623681)
			(xy 30.662767 -384.690507) (xy 30.646789 -384.755892) (xy 30.62311 -384.818898) (xy 30.592071 -384.878622)
			(xy 30.554115 -384.934209) (xy 30.532324 -384.95986) (xy 30.526522 -384.967002) (xy 30.52001 -384.984195)
			(xy 30.519624 -384.993388) (xy 30.519624 -385.151376) (xy 30.519159 -385.161526) (xy 30.511376 -385.180273)
			(xy 30.496993 -385.194596) (xy 30.478213 -385.202301) (xy 30.468062 -385.202684) (xy 29.751782 -385.202684)
			(xy 29.741657 -385.202189) (xy 29.72294 -385.19446) (xy 29.708585 -385.180177) (xy 29.700762 -385.161498)
			(xy 29.70022 -385.151376) (xy 29.70022 -384.993388) (xy 29.699811 -384.984201) (xy 29.693296 -384.967017)
			(xy 29.68752 -384.95986) (xy 29.665769 -384.934178) (xy 29.62782 -384.878596) (xy 29.596786 -384.818876)
			(xy 29.573112 -384.755875) (xy 29.557137 -384.690497) (xy 29.549091 -384.623678) (xy 29.549087 -384.556376)
			(xy 29.557128 -384.489556) (xy 29.573096 -384.424176) (xy 29.596764 -384.361174) (xy 29.627792 -384.301451)
			(xy 29.665735 -384.245865) (xy 29.68752 -384.220212) (xy 29.693339 -384.213083) (xy 29.69984 -384.19588)
			(xy 29.70022 -384.186684) (xy 29.70022 -383.693416) (xy 29.699797 -383.68423) (xy 29.693292 -383.667046)
			(xy 29.68752 -383.659888) (xy 29.665697 -383.634265) (xy 29.627751 -383.578674) (xy 29.59672 -383.518946)
			(xy 29.57305 -383.455938) (xy 29.55708 -383.390552) (xy 29.549039 -383.323727) (xy 28.446934 -383.323727)
			(xy 28.447062 -383.324068) (xy 28.463097 -383.389559) (xy 28.471172 -383.456499) (xy 28.471171 -383.523925)
			(xy 28.463093 -383.590865) (xy 28.447055 -383.656355) (xy 28.423288 -383.719452) (xy 28.392134 -383.779249)
			(xy 28.354042 -383.834883) (xy 28.332176 -383.860548) (xy 28.326374 -383.867689) (xy 28.319863 -383.884883)
			(xy 28.319476 -383.894076) (xy 28.319476 -384.051556) (xy 28.319047 -384.061679) (xy 28.311309 -384.080386)
			(xy 28.296996 -384.094702) (xy 28.27829 -384.102445) (xy 28.268168 -384.102864) (xy 27.551888 -384.102864)
			(xy 27.54176 -384.102493) (xy 27.523049 -384.094734) (xy 27.508734 -384.080404) (xy 27.500996 -384.061684)
			(xy 27.50058 -384.051556) (xy 27.50058 -383.894076) (xy 27.500186 -383.884887) (xy 27.493661 -383.867703)
			(xy 27.48788 -383.860548) (xy 27.466032 -383.834869) (xy 27.427945 -383.779236) (xy 27.396794 -383.719442)
			(xy 27.37303 -383.656347) (xy 27.356994 -383.59086) (xy 27.348917 -383.523923) (xy 27.348916 -383.456501)
			(xy 27.35699 -383.389564) (xy 27.373023 -383.324076) (xy 27.396784 -383.26098) (xy 27.427932 -383.201184)
			(xy 27.466018 -383.14555) (xy 27.48788 -383.119884) (xy 27.493664 -383.112729) (xy 27.500187 -383.095546)
			(xy 27.50058 -383.086356) (xy 27.50058 -382.59385) (xy 27.50015 -382.584665) (xy 27.49365 -382.56748)
			(xy 27.48788 -382.560322) (xy 27.466007 -382.534665) (xy 27.42792 -382.479028) (xy 27.396771 -382.419231)
			(xy 27.373008 -382.356133) (xy 27.356974 -382.290643) (xy 27.348899 -382.223705) (xy 1.524 -382.223705)
			(xy 1.524 -385.583938) (xy 100.447856 -385.583938) (xy 100.447856 -384.720338) (xy 100.448346 -384.690354)
			(xy 100.456174 -384.630898) (xy 100.471695 -384.572973) (xy 100.494644 -384.517569) (xy 100.524628 -384.465635)
			(xy 100.561134 -384.418059) (xy 100.603539 -384.375654) (xy 100.651115 -384.339148) (xy 100.703049 -384.309164)
			(xy 100.758453 -384.286215) (xy 100.816378 -384.270694) (xy 100.875834 -384.262866) (xy 100.935802 -384.262866)
			(xy 100.995258 -384.270694) (xy 101.053183 -384.286215) (xy 101.108587 -384.309164) (xy 101.160521 -384.339148)
			(xy 101.208097 -384.375654) (xy 101.250502 -384.418059) (xy 101.287008 -384.465635) (xy 101.316992 -384.517569)
			(xy 101.339941 -384.572973) (xy 101.355462 -384.630898) (xy 101.36329 -384.690354) (xy 101.36378 -384.720338)
			(xy 101.36378 -385.319283) (xy 104.635826 -385.319283) (xy 104.635826 -385.259317) (xy 104.643653 -385.199864)
			(xy 104.659172 -385.141942) (xy 104.682119 -385.08654) (xy 104.7121 -385.034608) (xy 104.748603 -384.987032)
			(xy 104.791004 -384.944628) (xy 104.838576 -384.908121) (xy 104.890506 -384.878136) (xy 104.945906 -384.855184)
			(xy 105.003827 -384.83966) (xy 105.063279 -384.831828) (xy 105.093262 -384.831336) (xy 105.956862 -384.831336)
			(xy 105.986849 -384.831807) (xy 106.046311 -384.83963) (xy 106.104243 -384.855149) (xy 106.159653 -384.878097)
			(xy 106.211594 -384.908081) (xy 106.259176 -384.944589) (xy 106.301586 -384.986995) (xy 106.338098 -385.034574)
			(xy 106.368087 -385.086513) (xy 106.391039 -385.141921) (xy 106.406562 -385.199852) (xy 106.414391 -385.259313)
			(xy 106.414391 -385.319287) (xy 106.406562 -385.378748) (xy 106.391039 -385.436679) (xy 106.368087 -385.492087)
			(xy 106.338098 -385.544026) (xy 106.301586 -385.591605) (xy 106.259176 -385.634011) (xy 106.211594 -385.670519)
			(xy 106.159653 -385.700503) (xy 106.104243 -385.723451) (xy 106.046311 -385.73897) (xy 105.986849 -385.746793)
			(xy 105.956862 -385.74726) (xy 105.093262 -385.74726) (xy 105.063279 -385.746772) (xy 105.003827 -385.73894)
			(xy 104.945906 -385.723416) (xy 104.890506 -385.700464) (xy 104.838576 -385.670479) (xy 104.791004 -385.633972)
			(xy 104.748603 -385.591568) (xy 104.7121 -385.543992) (xy 104.682119 -385.49206) (xy 104.659172 -385.436658)
			(xy 104.643653 -385.378736) (xy 104.635826 -385.319283) (xy 101.36378 -385.319283) (xy 101.36378 -385.583938)
			(xy 101.36329 -385.613922) (xy 101.355462 -385.673378) (xy 101.339941 -385.731303) (xy 101.316992 -385.786707)
			(xy 101.287008 -385.838641) (xy 101.250502 -385.886217) (xy 101.208097 -385.928622) (xy 101.160521 -385.965128)
			(xy 101.108587 -385.995112) (xy 101.053183 -386.018061) (xy 100.995258 -386.033582) (xy 100.935802 -386.04141)
			(xy 100.875834 -386.04141) (xy 100.816378 -386.033582) (xy 100.758453 -386.018061) (xy 100.703049 -385.995112)
			(xy 100.651115 -385.965128) (xy 100.603539 -385.928622) (xy 100.561134 -385.886217) (xy 100.524628 -385.838641)
			(xy 100.494644 -385.786707) (xy 100.471695 -385.731303) (xy 100.456174 -385.673378) (xy 100.448346 -385.613922)
			(xy 100.447856 -385.583938) (xy 1.524 -385.583938) (xy 1.524 -387.121908) (xy 1.52439 -387.132027)
			(xy 1.53214 -387.150718) (xy 1.546542 -387.164931) (xy 1.55575 -387.169152) (xy 1.642872 -387.204458)
			(xy 1.647438 -387.206216) (xy 1.657031 -387.20814) (xy 1.661922 -387.208268) (xy 1.698498 -387.192774)
			(xy 1.72014 -387.171139) (xy 1.768171 -387.133222) (xy 1.820826 -387.102041) (xy 1.877165 -387.078154)
			(xy 1.936184 -387.061985) (xy 1.996831 -387.053823) (xy 2.027428 -387.053328) (xy 2.057385 -387.053817)
			(xy 2.116788 -387.061635) (xy 2.174662 -387.077136) (xy 2.230019 -387.100056) (xy 2.281912 -387.130004)
			(xy 2.329454 -387.166466) (xy 2.371832 -387.20882) (xy 2.408322 -387.256341) (xy 2.438299 -387.308217)
			(xy 2.46125 -387.363561) (xy 2.476785 -387.421427) (xy 2.484636 -387.480825) (xy 2.485136 -387.510782)
			(xy 2.485136 -388.37489) (xy 2.484647 -388.404864) (xy 2.476825 -388.464299) (xy 2.461315 -388.522205)
			(xy 2.438381 -388.577593) (xy 2.408417 -388.629515) (xy 2.371935 -388.677083) (xy 2.329557 -388.719484)
			(xy 2.28201 -388.755994) (xy 2.230105 -388.785987) (xy 2.17473 -388.808951) (xy 2.116832 -388.824494)
			(xy 2.057402 -388.83235) (xy 2.027428 -388.832852) (xy 1.996831 -388.832343) (xy 1.936181 -388.824192)
			(xy 1.877159 -388.80803) (xy 1.820818 -388.784147) (xy 1.768161 -388.752969) (xy 1.720129 -388.715051)
			(xy 1.698498 -388.693406) (xy 1.661922 -388.677912) (xy 1.657032 -388.678051) (xy 1.647441 -388.679974)
			(xy 1.642872 -388.681722) (xy 1.55575 -388.717028) (xy 1.546556 -388.721247) (xy 1.53222 -388.735496)
			(xy 1.524469 -388.754165) (xy 1.524 -388.764272) (xy 1.524 -393.100052) (xy 194.140844 -393.100052)
			(xy 194.144848 -392.894864) (xy 194.156855 -392.689988) (xy 194.176846 -392.485737) (xy 194.204791 -392.282422)
			(xy 194.240647 -392.080351) (xy 194.284361 -391.879833) (xy 194.335864 -391.681174) (xy 194.395079 -391.484675)
			(xy 194.461915 -391.290636) (xy 194.536271 -391.099353) (xy 194.618034 -390.911116) (xy 194.707079 -390.726213)
			(xy 194.80327 -390.544925) (xy 194.906461 -390.367528) (xy 195.016495 -390.194291) (xy 195.133204 -390.02548)
			(xy 195.25641 -389.861351) (xy 195.385927 -389.702154) (xy 195.521556 -389.548132) (xy 195.663091 -389.399518)
			(xy 195.810316 -389.25654) (xy 195.963008 -389.119415) (xy 196.120934 -388.988351) (xy 196.283853 -388.863549)
			(xy 196.451518 -388.745199) (xy 196.623672 -388.63348) (xy 196.800054 -388.528563) (xy 196.980395 -388.430608)
			(xy 197.164421 -388.339764) (xy 197.351851 -388.256168) (xy 197.5424 -388.179949) (xy 197.735777 -388.111223)
			(xy 197.931689 -388.050094) (xy 198.129836 -387.996655) (xy 198.329918 -387.950988) (xy 198.531629 -387.913161)
			(xy 198.734662 -387.883234) (xy 198.938709 -387.861251) (xy 199.143458 -387.847246) (xy 199.348597 -387.84124)
			(xy 199.553814 -387.843242) (xy 199.758797 -387.85325) (xy 199.963234 -387.871247) (xy 200.166812 -387.897207)
			(xy 200.369223 -387.93109) (xy 200.570157 -387.972845) (xy 200.76931 -388.022408) (xy 200.966377 -388.079703)
			(xy 201.161059 -388.144643) (xy 201.353059 -388.217129) (xy 201.542084 -388.297052) (xy 201.727847 -388.384288)
			(xy 201.910065 -388.478706) (xy 202.088461 -388.580161) (xy 202.262762 -388.6885) (xy 202.432704 -388.803556)
			(xy 202.598027 -388.925156) (xy 202.75848 -389.053113) (xy 202.913819 -389.187232) (xy 203.063806 -389.327311)
			(xy 203.208214 -389.473135) (xy 203.346822 -389.624481) (xy 203.47942 -389.781121) (xy 203.605806 -389.942815)
			(xy 203.725786 -390.109317) (xy 203.839179 -390.280373) (xy 203.945812 -390.455723) (xy 204.045522 -390.6351)
			(xy 204.138158 -390.81823) (xy 204.223578 -391.004836) (xy 204.301652 -391.194632) (xy 204.372262 -391.38733)
			(xy 204.435299 -391.582636) (xy 204.490669 -391.780252) (xy 204.538286 -391.979879) (xy 204.578078 -392.181211)
			(xy 204.609985 -392.383943) (xy 204.633958 -392.587765) (xy 204.64996 -392.792368) (xy 204.657967 -392.997438)
			(xy 204.658468 -393.100052) (xy 204.657967 -393.202666) (xy 204.64996 -393.407736) (xy 204.633958 -393.612339)
			(xy 204.609985 -393.816161) (xy 204.578078 -394.018893) (xy 204.538286 -394.220225) (xy 204.490669 -394.419852)
			(xy 204.435299 -394.617468) (xy 204.372262 -394.812774) (xy 204.301652 -395.005472) (xy 204.223578 -395.195268)
			(xy 204.138158 -395.381874) (xy 204.045522 -395.565004) (xy 203.945812 -395.744381) (xy 203.839179 -395.919731)
			(xy 203.725786 -396.090787) (xy 203.605806 -396.257289) (xy 203.47942 -396.418983) (xy 203.346822 -396.575623)
			(xy 203.208214 -396.726969) (xy 203.063806 -396.872793) (xy 202.913819 -397.012872) (xy 202.75848 -397.146991)
			(xy 202.598027 -397.274948) (xy 202.432704 -397.396548) (xy 202.262762 -397.511604) (xy 202.088461 -397.619943)
			(xy 201.910065 -397.721398) (xy 201.727847 -397.815816) (xy 201.542084 -397.903052) (xy 201.353059 -397.982975)
			(xy 201.161059 -398.055461) (xy 200.966377 -398.120401) (xy 200.76931 -398.177696) (xy 200.570157 -398.227259)
			(xy 200.369223 -398.269014) (xy 200.166812 -398.302897) (xy 199.963234 -398.328857) (xy 199.758797 -398.346854)
			(xy 199.553814 -398.356862) (xy 199.348597 -398.358864) (xy 199.143458 -398.352858) (xy 198.938709 -398.338853)
			(xy 198.734662 -398.31687) (xy 198.531629 -398.286943) (xy 198.329918 -398.249116) (xy 198.129836 -398.203449)
			(xy 197.931689 -398.15001) (xy 197.735777 -398.088881) (xy 197.5424 -398.020155) (xy 197.351851 -397.943936)
			(xy 197.164421 -397.86034) (xy 196.980395 -397.769496) (xy 196.800054 -397.671541) (xy 196.623672 -397.566624)
			(xy 196.451518 -397.454905) (xy 196.283853 -397.336555) (xy 196.120934 -397.211753) (xy 195.963008 -397.080689)
			(xy 195.810316 -396.943564) (xy 195.663091 -396.800586) (xy 195.521556 -396.651972) (xy 195.385927 -396.49795)
			(xy 195.25641 -396.338753) (xy 195.133204 -396.174624) (xy 195.016495 -396.005813) (xy 194.906461 -395.832576)
			(xy 194.80327 -395.655179) (xy 194.707079 -395.473891) (xy 194.618034 -395.288988) (xy 194.536271 -395.100751)
			(xy 194.461915 -394.909468) (xy 194.395079 -394.715429) (xy 194.335864 -394.51893) (xy 194.284361 -394.320271)
			(xy 194.240647 -394.119753) (xy 194.204791 -393.917682) (xy 194.176846 -393.714367) (xy 194.156855 -393.510116)
			(xy 194.144848 -393.30524) (xy 194.140844 -393.100052) (xy 1.524 -393.100052) (xy 1.524 -398.100042)
			(xy 2.59945 -398.100042) (xy 2.603399 -397.95679) (xy 2.615233 -397.813972) (xy 2.634917 -397.672024)
			(xy 2.66239 -397.531375) (xy 2.69757 -397.392454) (xy 2.740349 -397.255681) (xy 2.790598 -397.121473)
			(xy 2.848163 -396.990236) (xy 2.912871 -396.86237) (xy 2.984524 -396.738263) (xy 3.062906 -396.618291)
			(xy 3.147777 -396.50282) (xy 3.238881 -396.392199) (xy 3.33594 -396.286765) (xy 3.438659 -396.186838)
			(xy 3.546728 -396.092721) (xy 3.659817 -396.0047) (xy 3.777583 -395.923042) (xy 3.899669 -395.847997)
			(xy 4.025703 -395.77979) (xy 4.155304 -395.71863) (xy 4.288077 -395.664703) (xy 4.423619 -395.618171)
			(xy 4.561518 -395.579177) (xy 4.701356 -395.547838) (xy 4.842709 -395.524251) (xy 4.985146 -395.508486)
			(xy 5.128235 -395.500591) (xy 5.199888 -395.500098) (xy 6.800088 -395.500098) (xy 6.871742 -395.500579)
			(xy 7.014831 -395.508473) (xy 7.157269 -395.524238) (xy 7.298622 -395.547826) (xy 7.438461 -395.579164)
			(xy 7.576361 -395.618158) (xy 7.711903 -395.66469) (xy 7.844677 -395.718618) (xy 7.974278 -395.779778)
			(xy 8.100313 -395.847985) (xy 8.222399 -395.923031) (xy 8.340166 -396.004689) (xy 8.453256 -396.09271)
			(xy 8.561325 -396.186827) (xy 8.664045 -396.286755) (xy 8.761105 -396.392189) (xy 8.852209 -396.502811)
			(xy 8.93708 -396.618283) (xy 9.015462 -396.738255) (xy 9.087116 -396.862363) (xy 9.151824 -396.990229)
			(xy 9.20939 -397.121466) (xy 9.259639 -397.255675) (xy 9.302418 -397.392449) (xy 9.337598 -397.531371)
			(xy 9.365072 -397.67202) (xy 9.384756 -397.813969) (xy 9.385578 -397.823885) (xy 27.348879 -397.823885)
			(xy 27.348883 -397.756458) (xy 27.356962 -397.689518) (xy 27.373001 -397.624027) (xy 27.396769 -397.560929)
			(xy 27.427923 -397.501131) (xy 27.466014 -397.445496) (xy 27.48788 -397.41983) (xy 27.493686 -397.412692)
			(xy 27.500196 -397.395496) (xy 27.50058 -397.386302) (xy 27.50058 -396.89405) (xy 27.50015 -396.884865)
			(xy 27.49365 -396.86768) (xy 27.48788 -396.860522) (xy 27.466007 -396.834865) (xy 27.42792 -396.779228)
			(xy 27.396771 -396.719431) (xy 27.373008 -396.656333) (xy 27.356974 -396.590843) (xy 27.348899 -396.523905)
			(xy 27.3489 -396.45648) (xy 27.356976 -396.389542) (xy 27.373012 -396.324053) (xy 27.396777 -396.260955)
			(xy 27.427928 -396.201159) (xy 27.466016 -396.145524) (xy 27.48788 -396.119858) (xy 27.493675 -396.112711)
			(xy 27.500191 -396.095522) (xy 27.50058 -396.08633) (xy 27.50058 -395.92885) (xy 27.501069 -395.918722)
			(xy 27.508787 -395.899994) (xy 27.523074 -395.885635) (xy 27.541762 -395.877821) (xy 27.551888 -395.877288)
			(xy 28.268168 -395.877288) (xy 28.278319 -395.877747) (xy 28.297068 -395.88553) (xy 28.311392 -395.899915)
			(xy 28.319095 -395.918698) (xy 28.319476 -395.92885) (xy 28.319476 -396.08633) (xy 28.319877 -396.095518)
			(xy 28.326398 -396.112702) (xy 28.332176 -396.119858) (xy 28.354031 -396.145531) (xy 28.392122 -396.201164)
			(xy 28.423274 -396.260959) (xy 28.44704 -396.324055) (xy 28.463077 -396.389543) (xy 28.471154 -396.456481)
			(xy 28.471155 -396.523904) (xy 28.463079 -396.590842) (xy 28.447044 -396.656331) (xy 28.42328 -396.719428)
			(xy 28.392129 -396.779223) (xy 28.35404 -396.834857) (xy 28.332176 -396.860522) (xy 28.326385 -396.867671)
			(xy 28.319868 -396.884859) (xy 28.319476 -396.89405) (xy 28.319476 -397.386302) (xy 28.31989 -397.395489)
			(xy 28.326402 -397.412673) (xy 28.332176 -397.41983) (xy 28.354003 -397.445526) (xy 28.392095 -397.501155)
			(xy 28.420857 -397.556356) (xy 29.549071 -397.556356) (xy 29.557114 -397.489534) (xy 29.573085 -397.424153)
			(xy 29.596756 -397.361149) (xy 29.627787 -397.301425) (xy 29.665733 -397.245838) (xy 29.68752 -397.220186)
			(xy 29.693307 -397.213034) (xy 29.699827 -397.195849) (xy 29.70022 -397.186658) (xy 29.70022 -397.028924)
			(xy 29.700641 -397.018769) (xy 29.708433 -397.000013) (xy 29.72283 -396.985688) (xy 29.741625 -396.977991)
			(xy 29.751782 -396.977616) (xy 30.468062 -396.977616) (xy 30.478183 -396.978157) (xy 30.496899 -396.985868)
			(xy 30.511256 -397.000138) (xy 30.51908 -397.018806) (xy 30.519624 -397.028924) (xy 30.519624 -397.186658)
			(xy 30.520049 -397.195844) (xy 30.526552 -397.213029) (xy 30.532324 -397.220186) (xy 30.554123 -397.24583)
			(xy 30.592074 -397.301416) (xy 30.623108 -397.361141) (xy 30.646782 -397.424147) (xy 30.662756 -397.48953)
			(xy 30.6708 -397.556354) (xy 30.670799 -397.623661) (xy 30.662753 -397.690485) (xy 30.646778 -397.755868)
			(xy 30.623102 -397.818873) (xy 30.620528 -397.823826) (xy 31.749174 -397.823826) (xy 31.749178 -397.756517)
			(xy 31.757226 -397.689691) (xy 31.773204 -397.624307) (xy 31.796882 -397.5613) (xy 31.827922 -397.501576)
			(xy 31.865877 -397.44599) (xy 31.887668 -397.420338) (xy 31.893482 -397.413205) (xy 31.899984 -397.396005)
			(xy 31.900368 -397.38681) (xy 31.900368 -396.893542) (xy 31.899923 -396.884359) (xy 31.893432 -396.867175)
			(xy 31.887668 -396.860014) (xy 31.86587 -396.83437) (xy 31.827919 -396.778783) (xy 31.796885 -396.719059)
			(xy 31.773211 -396.656053) (xy 31.757238 -396.59067) (xy 31.749194 -396.523846) (xy 31.749195 -396.456539)
			(xy 31.757241 -396.389716) (xy 31.773216 -396.324332) (xy 31.796891 -396.261327) (xy 31.827927 -396.201604)
			(xy 31.865879 -396.146018) (xy 31.887668 -396.120366) (xy 31.89347 -396.113225) (xy 31.899979 -396.096031)
			(xy 31.900368 -396.086838) (xy 31.900368 -395.92885) (xy 31.900805 -395.918678) (xy 31.90858 -395.899879)
			(xy 31.922962 -395.885491) (xy 31.941758 -395.877709) (xy 31.95193 -395.877288) (xy 32.66821 -395.877288)
			(xy 32.678388 -395.877657) (xy 32.697193 -395.885455) (xy 32.711579 -395.899858) (xy 32.719355 -395.918671)
			(xy 32.719772 -395.92885) (xy 32.719772 -396.086838) (xy 32.72017 -396.096026) (xy 32.726693 -396.11321)
			(xy 32.732472 -396.120366) (xy 32.75425 -396.146026) (xy 32.792198 -396.201612) (xy 32.823231 -396.261334)
			(xy 32.846904 -396.324338) (xy 32.862877 -396.389719) (xy 32.870922 -396.45654) (xy 32.870923 -396.523845)
			(xy 32.86288 -396.590666) (xy 32.846909 -396.656048) (xy 32.823237 -396.719052) (xy 32.792206 -396.778775)
			(xy 32.754259 -396.834362) (xy 32.732472 -396.860014) (xy 32.726683 -396.867165) (xy 32.720165 -396.884351)
			(xy 32.719772 -396.893542) (xy 32.719772 -397.38681) (xy 32.720183 -397.395997) (xy 32.726697 -397.413181)
			(xy 32.732472 -397.420338) (xy 32.754222 -397.446021) (xy 32.792171 -397.501603) (xy 32.820593 -397.556296)
			(xy 33.948839 -397.556296) (xy 33.956914 -397.489358) (xy 33.972949 -397.423869) (xy 33.996713 -397.360773)
			(xy 34.027863 -397.300977) (xy 34.065952 -397.245343) (xy 34.087816 -397.219678) (xy 34.093606 -397.212528)
			(xy 34.100124 -397.195341) (xy 34.100516 -397.18615) (xy 34.100516 -397.028924) (xy 34.100936 -397.018801)
			(xy 34.108679 -397.000095) (xy 34.122995 -396.985779) (xy 34.141701 -396.978036) (xy 34.151824 -396.977616)
			(xy 34.868104 -396.977616) (xy 34.878229 -396.978013) (xy 34.896935 -396.985766) (xy 34.91125 -397.000088)
			(xy 34.918992 -397.018799) (xy 34.919412 -397.028924) (xy 34.919412 -397.18615) (xy 34.919843 -397.195335)
			(xy 34.926342 -397.21252) (xy 34.932112 -397.219678) (xy 34.953985 -397.245335) (xy 34.992073 -397.300971)
			(xy 35.023223 -397.360769) (xy 35.046986 -397.423867) (xy 35.06302 -397.489356) (xy 35.071095 -397.556295)
			(xy 35.071094 -397.62372) (xy 35.063017 -397.690658) (xy 35.046981 -397.756148) (xy 35.023216 -397.819245)
			(xy 35.020799 -397.823884) (xy 36.148967 -397.823884) (xy 36.148971 -397.756458) (xy 36.15705 -397.689518)
			(xy 36.173088 -397.624028) (xy 36.196855 -397.560929) (xy 36.228008 -397.501132) (xy 36.266099 -397.445496)
			(xy 36.287964 -397.41983) (xy 36.293781 -397.412699) (xy 36.300282 -397.395497) (xy 36.300664 -397.386302)
			(xy 36.300664 -396.89405) (xy 36.300216 -396.884867) (xy 36.293727 -396.867683) (xy 36.287964 -396.860522)
			(xy 36.266091 -396.834864) (xy 36.228005 -396.779228) (xy 36.196857 -396.71943) (xy 36.173095 -396.656332)
			(xy 36.157061 -396.590843) (xy 36.148987 -396.523904) (xy 36.148988 -396.456481) (xy 36.157064 -396.389542)
			(xy 36.1731 -396.324053) (xy 36.196863 -396.260956) (xy 36.228013 -396.201159) (xy 36.266101 -396.145524)
			(xy 36.287964 -396.119858) (xy 36.293769 -396.112719) (xy 36.300277 -396.095523) (xy 36.300664 -396.08633)
			(xy 36.300664 -395.92885) (xy 36.301168 -395.918724) (xy 36.308884 -395.899999) (xy 36.323166 -395.88564)
			(xy 36.341848 -395.877823) (xy 36.351972 -395.877288) (xy 37.068252 -395.877288) (xy 37.078402 -395.877761)
			(xy 37.097151 -395.885538) (xy 37.111475 -395.899919) (xy 37.119179 -395.918699) (xy 37.11956 -395.92885)
			(xy 37.11956 -396.08633) (xy 37.119965 -396.095518) (xy 37.126483 -396.112701) (xy 37.13226 -396.119858)
			(xy 37.154116 -396.145531) (xy 37.192207 -396.201163) (xy 37.223361 -396.260958) (xy 37.247127 -396.324054)
			(xy 37.263164 -396.389543) (xy 37.271242 -396.456481) (xy 37.271243 -396.523904) (xy 37.263167 -396.590843)
			(xy 37.247132 -396.656332) (xy 37.223367 -396.719428) (xy 37.192215 -396.779224) (xy 37.154125 -396.834857)
			(xy 37.13226 -396.860522) (xy 37.126467 -396.867669) (xy 37.119951 -396.884858) (xy 37.11956 -396.89405)
			(xy 37.11956 -397.386302) (xy 37.119978 -397.395488) (xy 37.126487 -397.412672) (xy 37.13226 -397.41983)
			(xy 37.154088 -397.445525) (xy 37.192181 -397.501155) (xy 37.220943 -397.556356) (xy 38.349159 -397.556356)
			(xy 38.357201 -397.489534) (xy 38.373172 -397.424153) (xy 38.396842 -397.361149) (xy 38.427873 -397.301426)
			(xy 38.465818 -397.245839) (xy 38.487604 -397.220186) (xy 38.493389 -397.213033) (xy 38.499911 -397.195848)
			(xy 38.500304 -397.186658) (xy 38.500304 -397.028924) (xy 38.500741 -397.018771) (xy 38.50853 -397.000018)
			(xy 38.522922 -396.985694) (xy 38.541711 -396.977994) (xy 38.551866 -396.977616) (xy 39.268146 -396.977616)
			(xy 39.278273 -396.978088) (xy 39.29699 -396.985827) (xy 39.311344 -397.000117) (xy 39.319166 -397.0188)
			(xy 39.319708 -397.028924) (xy 39.319708 -397.186658) (xy 39.320136 -397.195843) (xy 39.326637 -397.213028)
			(xy 39.332408 -397.220186) (xy 39.354207 -397.245829) (xy 39.392159 -397.301416) (xy 39.423195 -397.36114)
			(xy 39.446869 -397.424146) (xy 39.462843 -397.48953) (xy 39.470887 -397.556354) (xy 39.470887 -397.623661)
			(xy 39.462841 -397.690485) (xy 39.446865 -397.755869) (xy 39.423189 -397.818874) (xy 39.420585 -397.823885)
			(xy 40.548734 -397.823885) (xy 40.548737 -397.756458) (xy 40.556817 -397.689516) (xy 40.572859 -397.624024)
			(xy 40.596629 -397.560925) (xy 40.627787 -397.501128) (xy 40.665884 -397.445494) (xy 40.687752 -397.41983)
			(xy 40.693567 -397.412698) (xy 40.700069 -397.395497) (xy 40.700452 -397.386302) (xy 40.700452 -396.89405)
			(xy 40.700006 -396.884867) (xy 40.693516 -396.867683) (xy 40.687752 -396.860522) (xy 40.665876 -396.834866)
			(xy 40.627785 -396.779231) (xy 40.596631 -396.719434) (xy 40.572865 -396.656336) (xy 40.556829 -396.590845)
			(xy 40.548753 -396.523905) (xy 40.548754 -396.45648) (xy 40.556832 -396.38954) (xy 40.57287 -396.32405)
			(xy 40.596638 -396.260952) (xy 40.627792 -396.201156) (xy 40.665886 -396.145522) (xy 40.687752 -396.119858)
			(xy 40.693555 -396.112718) (xy 40.700065 -396.095523) (xy 40.700452 -396.08633) (xy 40.700452 -395.92885)
			(xy 40.700968 -395.918725) (xy 40.708682 -395.900003) (xy 40.722959 -395.885644) (xy 40.741638 -395.877825)
			(xy 40.75176 -395.877288) (xy 41.46804 -395.877288) (xy 41.478195 -395.877689) (xy 41.496946 -395.885495)
			(xy 41.511268 -395.899898) (xy 41.518968 -395.918693) (xy 41.519348 -395.92885) (xy 41.519348 -396.08633)
			(xy 41.519755 -396.095517) (xy 41.526272 -396.112701) (xy 41.532048 -396.119858) (xy 41.553904 -396.14553)
			(xy 41.591996 -396.201163) (xy 41.62315 -396.260957) (xy 41.646917 -396.324053) (xy 41.662955 -396.389542)
			(xy 41.671033 -396.456481) (xy 41.671034 -396.523904) (xy 41.662958 -396.590843) (xy 41.646922 -396.656332)
			(xy 41.623157 -396.719429) (xy 41.592004 -396.779224) (xy 41.553913 -396.834858) (xy 41.532048 -396.860522)
			(xy 41.526253 -396.867668) (xy 41.519739 -396.884858) (xy 41.519348 -396.89405) (xy 41.519348 -397.386302)
			(xy 41.519769 -397.395488) (xy 41.526276 -397.412672) (xy 41.532048 -397.41983) (xy 41.553876 -397.445525)
			(xy 41.59197 -397.501154) (xy 41.620702 -397.556296) (xy 42.748927 -397.556296) (xy 42.757002 -397.489358)
			(xy 42.773037 -397.42387) (xy 42.7968 -397.360774) (xy 42.827949 -397.300978) (xy 42.866037 -397.245343)
			(xy 42.8879 -397.219678) (xy 42.893688 -397.212527) (xy 42.900208 -397.195341) (xy 42.9006 -397.18615)
			(xy 42.9006 -397.028924) (xy 42.901035 -397.018803) (xy 42.908776 -397.0001) (xy 42.923086 -396.985785)
			(xy 42.941787 -396.978039) (xy 42.951908 -396.977616) (xy 43.668188 -396.977616) (xy 43.678312 -396.978026)
			(xy 43.697018 -396.985773) (xy 43.711333 -397.000092) (xy 43.719076 -397.0188) (xy 43.719496 -397.028924)
			(xy 43.719496 -397.18615) (xy 43.719931 -397.195335) (xy 43.726427 -397.212519) (xy 43.732196 -397.219678)
			(xy 43.75407 -397.245335) (xy 43.792159 -397.300971) (xy 43.823309 -397.360768) (xy 43.847073 -397.423866)
			(xy 43.863108 -397.489356) (xy 43.871183 -397.556295) (xy 43.871182 -397.62372) (xy 43.863105 -397.690659)
			(xy 43.847068 -397.756148) (xy 43.823303 -397.819246) (xy 43.820917 -397.823825) (xy 44.949053 -397.823825)
			(xy 44.949057 -397.756517) (xy 44.957105 -397.689692) (xy 44.973082 -397.624308) (xy 44.996759 -397.561302)
			(xy 45.027796 -397.501577) (xy 45.06575 -397.44599) (xy 45.08754 -397.420338) (xy 45.09335 -397.413203)
			(xy 45.099856 -397.396004) (xy 45.10024 -397.38681) (xy 45.10024 -396.893542) (xy 45.0998 -396.884358)
			(xy 45.093306 -396.867174) (xy 45.08754 -396.860014) (xy 45.065742 -396.83437) (xy 45.027794 -396.778782)
			(xy 44.996761 -396.719058) (xy 44.973088 -396.656052) (xy 44.957116 -396.590669) (xy 44.949073 -396.523845)
			(xy 44.949074 -396.45654) (xy 44.957119 -396.389716) (xy 44.973093 -396.324333) (xy 44.996767 -396.261328)
			(xy 45.027801 -396.201605) (xy 45.065751 -396.146018) (xy 45.08754 -396.120366) (xy 45.093339 -396.113222)
			(xy 45.099851 -396.096031) (xy 45.10024 -396.086838) (xy 45.10024 -395.92885) (xy 45.100705 -395.918681)
			(xy 45.108474 -395.899887) (xy 45.122847 -395.885501) (xy 45.141634 -395.877714) (xy 45.151802 -395.877288)
			(xy 45.868082 -395.877288) (xy 45.878259 -395.87768) (xy 45.897063 -395.885468) (xy 45.91145 -395.899864)
			(xy 45.919227 -395.918673) (xy 45.919644 -395.92885) (xy 45.919644 -396.086838) (xy 45.920049 -396.096026)
			(xy 45.926568 -396.113209) (xy 45.932344 -396.120366) (xy 45.954122 -396.146026) (xy 45.992072 -396.201611)
			(xy 46.023107 -396.261333) (xy 46.046781 -396.324337) (xy 46.062755 -396.389718) (xy 46.070801 -396.45654)
			(xy 46.070801 -396.523845) (xy 46.062758 -396.590667) (xy 46.046786 -396.656049) (xy 46.023113 -396.719053)
			(xy 45.99208 -396.778776) (xy 45.954131 -396.834362) (xy 45.932344 -396.860014) (xy 45.926552 -396.867162)
			(xy 45.920036 -396.884351) (xy 45.919644 -396.893542) (xy 45.919644 -397.38681) (xy 45.920062 -397.395996)
			(xy 45.926572 -397.41318) (xy 45.932344 -397.420338) (xy 45.954095 -397.446021) (xy 45.992046 -397.501602)
			(xy 46.020501 -397.556355) (xy 47.149223 -397.556355) (xy 47.157267 -397.489532) (xy 47.17324 -397.42415)
			(xy 47.196914 -397.361146) (xy 47.227949 -397.301423) (xy 47.265899 -397.245837) (xy 47.287688 -397.220186)
			(xy 47.293472 -397.213032) (xy 47.299994 -397.195848) (xy 47.300388 -397.186658) (xy 47.300388 -397.028924)
			(xy 47.300841 -397.018773) (xy 47.308626 -397.000023) (xy 47.323013 -396.985699) (xy 47.341797 -396.977997)
			(xy 47.35195 -396.977616) (xy 48.06823 -396.977616) (xy 48.078356 -396.978101) (xy 48.097073 -396.985834)
			(xy 48.111427 -397.000121) (xy 48.11925 -397.018801) (xy 48.119792 -397.028924) (xy 48.119792 -397.186658)
			(xy 48.120224 -397.195843) (xy 48.126723 -397.213027) (xy 48.132492 -397.220186) (xy 48.154289 -397.24583)
			(xy 48.192235 -397.301419) (xy 48.223266 -397.361144) (xy 48.246937 -397.424149) (xy 48.262908 -397.489532)
			(xy 48.270951 -397.556355) (xy 48.27095 -397.62366) (xy 48.262906 -397.690483) (xy 48.246933 -397.755865)
			(xy 48.22326 -397.81887) (xy 48.192227 -397.878594) (xy 48.154279 -397.934181) (xy 48.132492 -397.959834)
			(xy 48.126698 -397.966981) (xy 48.120182 -397.98417) (xy 48.119792 -397.993362) (xy 48.119792 -398.486884)
			(xy 48.120212 -398.49607) (xy 48.126719 -398.513254) (xy 48.132492 -398.520412) (xy 48.154314 -398.546035)
			(xy 48.19226 -398.601627) (xy 48.22329 -398.661355) (xy 48.246959 -398.724363) (xy 48.262929 -398.789748)
			(xy 48.27097 -398.856573) (xy 48.270966 -398.923881) (xy 48.262919 -398.990705) (xy 48.246943 -399.056089)
			(xy 48.223268 -399.119095) (xy 48.192232 -399.17882) (xy 48.154281 -399.234407) (xy 48.132492 -399.26006)
			(xy 48.126687 -399.267199) (xy 48.120177 -399.284394) (xy 48.119792 -399.293588) (xy 48.119792 -399.451576)
			(xy 48.119359 -399.46173) (xy 48.11157 -399.480483) (xy 48.097176 -399.494808) (xy 48.078386 -399.502507)
			(xy 48.06823 -399.502884) (xy 47.35195 -399.502884) (xy 47.341829 -399.502333) (xy 47.323114 -399.494626)
			(xy 47.308757 -399.48036) (xy 47.300932 -399.461693) (xy 47.300388 -399.451576) (xy 47.300388 -399.293588)
			(xy 47.299986 -399.2844) (xy 47.293467 -399.267216) (xy 47.287688 -399.26006) (xy 47.265934 -399.234379)
			(xy 47.227981 -399.178798) (xy 47.196944 -399.119079) (xy 47.173267 -399.056078) (xy 47.15729 -398.990699)
			(xy 47.149242 -398.923879) (xy 47.149239 -398.856576) (xy 47.15728 -398.789754) (xy 47.173251 -398.724374)
			(xy 47.196921 -398.661371) (xy 47.227953 -398.601648) (xy 47.265901 -398.546063) (xy 47.287688 -398.520412)
			(xy 47.293503 -398.51328) (xy 47.300007 -398.496079) (xy 47.300388 -398.486884) (xy 47.300388 -397.993362)
			(xy 47.299999 -397.984172) (xy 47.293471 -397.966988) (xy 47.287688 -397.959834) (xy 47.265909 -397.934174)
			(xy 47.227956 -397.87859) (xy 47.19692 -397.818868) (xy 47.173244 -397.755864) (xy 47.157269 -397.690483)
			(xy 47.149224 -397.62366) (xy 47.149223 -397.556355) (xy 46.020501 -397.556355) (xy 46.023082 -397.561322)
			(xy 46.046757 -397.624322) (xy 46.062733 -397.689701) (xy 46.070781 -397.75652) (xy 46.070784 -397.823823)
			(xy 46.062744 -397.890643) (xy 46.046774 -397.956023) (xy 46.023105 -398.019026) (xy 45.992075 -398.078748)
			(xy 45.95413 -398.134334) (xy 45.932344 -398.159986) (xy 45.926522 -398.167113) (xy 45.920024 -398.184318)
			(xy 45.919644 -398.193514) (xy 45.919644 -398.351502) (xy 45.919237 -398.361676) (xy 45.911448 -398.380474)
			(xy 45.897057 -398.39486) (xy 45.878256 -398.402641) (xy 45.868082 -398.403064) (xy 45.151802 -398.403064)
			(xy 45.141645 -398.402565) (xy 45.122876 -398.394792) (xy 45.108511 -398.380427) (xy 45.100736 -398.361659)
			(xy 45.10024 -398.351502) (xy 45.10024 -398.193514) (xy 45.099814 -398.184329) (xy 45.093311 -398.167145)
			(xy 45.08754 -398.159986) (xy 45.065715 -398.134365) (xy 45.027767 -398.078774) (xy 44.996735 -398.019046)
			(xy 44.973065 -397.956037) (xy 44.957094 -397.890651) (xy 44.949053 -397.823825) (xy 43.820917 -397.823825)
			(xy 43.792151 -397.879042) (xy 43.754061 -397.934677) (xy 43.732196 -397.960342) (xy 43.726399 -397.967487)
			(xy 43.719885 -397.984678) (xy 43.719496 -397.99387) (xy 43.719496 -398.486376) (xy 43.719919 -398.495562)
			(xy 43.726424 -398.512746) (xy 43.732196 -398.519904) (xy 43.754095 -398.54554) (xy 43.792183 -398.601179)
			(xy 43.823333 -398.660979) (xy 43.847095 -398.72408) (xy 43.863128 -398.789572) (xy 43.871201 -398.856514)
			(xy 43.871198 -398.92394) (xy 43.863118 -398.990881) (xy 43.847079 -399.056372) (xy 43.823311 -399.119471)
			(xy 43.792156 -399.179268) (xy 43.754062 -399.234903) (xy 43.732196 -399.260568) (xy 43.726388 -399.267705)
			(xy 43.71988 -399.284902) (xy 43.719496 -399.294096) (xy 43.719496 -399.451576) (xy 43.719064 -399.461697)
			(xy 43.711323 -399.480401) (xy 43.697011 -399.494717) (xy 43.678309 -399.502462) (xy 43.668188 -399.502884)
			(xy 42.951908 -399.502884) (xy 42.941784 -399.502477) (xy 42.923078 -399.494729) (xy 42.908762 -399.480409)
			(xy 42.90102 -399.4617) (xy 42.9006 -399.451576) (xy 42.9006 -399.294096) (xy 42.900192 -399.284909)
			(xy 42.893677 -399.267724) (xy 42.8879 -399.260568) (xy 42.866071 -399.234874) (xy 42.827982 -399.179243)
			(xy 42.796829 -399.119451) (xy 42.773063 -399.056358) (xy 42.757025 -398.990872) (xy 42.748946 -398.923937)
			(xy 42.748943 -398.856517) (xy 42.757015 -398.789581) (xy 42.773047 -398.724094) (xy 42.796807 -398.660998)
			(xy 42.827954 -398.601203) (xy 42.866038 -398.545569) (xy 42.8879 -398.519904) (xy 42.893677 -398.512745)
			(xy 42.900204 -398.495565) (xy 42.9006 -398.486376) (xy 42.9006 -397.99387) (xy 42.900204 -397.984681)
			(xy 42.893681 -397.967497) (xy 42.8879 -397.960342) (xy 42.866046 -397.934669) (xy 42.827957 -397.879035)
			(xy 42.796806 -397.81924) (xy 42.773041 -397.756144) (xy 42.757005 -397.690656) (xy 42.748928 -397.623719)
			(xy 42.748927 -397.556296) (xy 41.620702 -397.556296) (xy 41.623125 -397.560946) (xy 41.646894 -397.624039)
			(xy 41.662933 -397.689525) (xy 41.671013 -397.756461) (xy 41.671016 -397.823882) (xy 41.662944 -397.890819)
			(xy 41.646911 -397.956307) (xy 41.623148 -398.019402) (xy 41.591999 -398.079197) (xy 41.553912 -398.13483)
			(xy 41.532048 -398.160494) (xy 41.526265 -398.167649) (xy 41.519744 -398.184832) (xy 41.519348 -398.194022)
			(xy 41.519348 -398.351502) (xy 41.518875 -398.36163) (xy 41.511144 -398.380354) (xy 41.496853 -398.39471)
			(xy 41.478166 -398.402527) (xy 41.46804 -398.403064) (xy 40.75176 -398.403064) (xy 40.741599 -398.40271)
			(xy 40.722839 -398.394895) (xy 40.708515 -398.380477) (xy 40.700824 -398.361666) (xy 40.700452 -398.351502)
			(xy 40.700452 -398.194022) (xy 40.70002 -398.184837) (xy 40.69352 -398.167653) (xy 40.687752 -398.160494)
			(xy 40.665849 -398.13486) (xy 40.627758 -398.079223) (xy 40.596606 -398.019423) (xy 40.572842 -397.956321)
			(xy 40.556807 -397.890828) (xy 40.548734 -397.823885) (xy 39.420585 -397.823885) (xy 39.392151 -397.878597)
			(xy 39.354198 -397.934183) (xy 39.332408 -397.959834) (xy 39.326615 -397.966982) (xy 39.320098 -397.98417)
			(xy 39.319708 -397.993362) (xy 39.319708 -398.486884) (xy 39.320124 -398.496071) (xy 39.326633 -398.513255)
			(xy 39.332408 -398.520412) (xy 39.354233 -398.546034) (xy 39.392184 -398.601624) (xy 39.423219 -398.661351)
			(xy 39.446892 -398.72436) (xy 39.462864 -398.789746) (xy 39.470906 -398.856573) (xy 39.470902 -398.923882)
			(xy 39.462854 -398.990707) (xy 39.446876 -399.056092) (xy 39.423196 -399.119098) (xy 39.392156 -399.178823)
			(xy 39.354199 -399.234409) (xy 39.332408 -399.26006) (xy 39.326604 -399.2672) (xy 39.320094 -399.284395)
			(xy 39.319708 -399.293588) (xy 39.319708 -399.451576) (xy 39.319259 -399.461728) (xy 39.311473 -399.480478)
			(xy 39.297085 -399.494802) (xy 39.278299 -399.502504) (xy 39.268146 -399.502884) (xy 38.551866 -399.502884)
			(xy 38.54174 -399.502402) (xy 38.523023 -399.494668) (xy 38.508668 -399.48038) (xy 38.500846 -399.4617)
			(xy 38.500304 -399.451576) (xy 38.500304 -399.293588) (xy 38.499899 -399.2844) (xy 38.493381 -399.267216)
			(xy 38.487604 -399.26006) (xy 38.465853 -399.234378) (xy 38.427905 -399.178795) (xy 38.396872 -399.119075)
			(xy 38.373199 -399.056075) (xy 38.357224 -398.990697) (xy 38.349178 -398.923878) (xy 38.349175 -398.856576)
			(xy 38.357215 -398.789757) (xy 38.373183 -398.724377) (xy 38.39685 -398.661374) (xy 38.427877 -398.601651)
			(xy 38.465819 -398.546065) (xy 38.487604 -398.520412) (xy 38.493421 -398.513281) (xy 38.499923 -398.49608)
			(xy 38.500304 -398.486884) (xy 38.500304 -397.993362) (xy 38.499911 -397.984173) (xy 38.493385 -397.966989)
			(xy 38.487604 -397.959834) (xy 38.465827 -397.934173) (xy 38.42788 -397.878587) (xy 38.396849 -397.818865)
			(xy 38.373177 -397.755861) (xy 38.357204 -397.69048) (xy 38.34916 -397.623659) (xy 38.349159 -397.556356)
			(xy 37.220943 -397.556356) (xy 37.223335 -397.560946) (xy 37.247103 -397.624039) (xy 37.263142 -397.689525)
			(xy 37.271222 -397.756461) (xy 37.271225 -397.823882) (xy 37.263153 -397.890819) (xy 37.24712 -397.956306)
			(xy 37.223358 -398.019402) (xy 37.19221 -398.079196) (xy 37.154123 -398.134829) (xy 37.13226 -398.160494)
			(xy 37.126478 -398.16765) (xy 37.119956 -398.184832) (xy 37.11956 -398.194022) (xy 37.11956 -398.351502)
			(xy 37.119075 -398.361629) (xy 37.111347 -398.38035) (xy 37.09706 -398.394706) (xy 37.078376 -398.402525)
			(xy 37.068252 -398.403064) (xy 36.351972 -398.403064) (xy 36.341812 -398.402701) (xy 36.323052 -398.394889)
			(xy 36.308728 -398.380474) (xy 36.301036 -398.361665) (xy 36.300664 -398.351502) (xy 36.300664 -398.194022)
			(xy 36.300229 -398.184838) (xy 36.293731 -398.167654) (xy 36.287964 -398.160494) (xy 36.266064 -398.134859)
			(xy 36.227979 -398.079219) (xy 36.196832 -398.019419) (xy 36.173071 -397.956318) (xy 36.15704 -397.890825)
			(xy 36.148967 -397.823884) (xy 35.020799 -397.823884) (xy 34.992065 -397.879042) (xy 34.953976 -397.934677)
			(xy 34.932112 -397.960342) (xy 34.926316 -397.967488) (xy 34.919801 -397.984678) (xy 34.919412 -397.99387)
			(xy 34.919412 -398.486376) (xy 34.919831 -398.495562) (xy 34.926338 -398.512747) (xy 34.932112 -398.519904)
			(xy 34.954011 -398.54554) (xy 34.992098 -398.601179) (xy 35.023246 -398.66098) (xy 35.047008 -398.72408)
			(xy 35.06304 -398.789573) (xy 35.071113 -398.856514) (xy 35.07111 -398.92394) (xy 35.063031 -398.990881)
			(xy 35.046992 -399.056372) (xy 35.023224 -399.11947) (xy 34.99207 -399.179267) (xy 34.953978 -399.234903)
			(xy 34.932112 -399.260568) (xy 34.926305 -399.267706) (xy 34.919796 -399.284902) (xy 34.919412 -399.294096)
			(xy 34.919412 -399.451576) (xy 34.918965 -399.461695) (xy 34.911227 -399.480396) (xy 34.89692 -399.494711)
			(xy 34.878223 -399.502459) (xy 34.868104 -399.502884) (xy 34.151824 -399.502884) (xy 34.141701 -399.502464)
			(xy 34.122995 -399.494721) (xy 34.108679 -399.480405) (xy 34.100936 -399.461699) (xy 34.100516 -399.451576)
			(xy 34.100516 -399.294096) (xy 34.100104 -399.284909) (xy 34.093591 -399.267725) (xy 34.087816 -399.260568)
			(xy 34.065987 -399.234874) (xy 34.027896 -399.179244) (xy 33.996743 -399.119452) (xy 33.972976 -399.056359)
			(xy 33.956937 -398.990873) (xy 33.948858 -398.923938) (xy 33.948855 -398.856516) (xy 33.956928 -398.78958)
			(xy 33.97296 -398.724093) (xy 33.996721 -398.660998) (xy 34.027868 -398.601203) (xy 34.065954 -398.545569)
			(xy 34.087816 -398.519904) (xy 34.093595 -398.512747) (xy 34.10012 -398.495565) (xy 34.100516 -398.486376)
			(xy 34.100516 -397.99387) (xy 34.100117 -397.984682) (xy 34.093595 -397.967498) (xy 34.087816 -397.960342)
			(xy 34.065961 -397.934669) (xy 34.027871 -397.879036) (xy 33.996719 -397.819241) (xy 33.972954 -397.756145)
			(xy 33.956917 -397.690657) (xy 33.94884 -397.623719) (xy 33.948839 -397.556296) (xy 32.820593 -397.556296)
			(xy 32.823205 -397.561323) (xy 32.84688 -397.624323) (xy 32.862855 -397.689702) (xy 32.870902 -397.756521)
			(xy 32.870905 -397.823822) (xy 32.862865 -397.890642) (xy 32.846897 -397.956022) (xy 32.823229 -398.019025)
			(xy 32.7922 -398.078747) (xy 32.754257 -398.134334) (xy 32.732472 -398.159986) (xy 32.726653 -398.167115)
			(xy 32.720152 -398.184318) (xy 32.719772 -398.193514) (xy 32.719772 -398.351502) (xy 32.719268 -398.361659)
			(xy 32.711495 -398.380426) (xy 32.697133 -398.394791) (xy 32.678367 -398.402567) (xy 32.66821 -398.403064)
			(xy 31.95193 -398.403064) (xy 31.941761 -398.402611) (xy 31.922967 -398.394837) (xy 31.908581 -398.38046)
			(xy 31.900795 -398.361671) (xy 31.900368 -398.351502) (xy 31.900368 -398.193514) (xy 31.899936 -398.184329)
			(xy 31.893436 -398.167146) (xy 31.887668 -398.159986) (xy 31.865842 -398.134365) (xy 31.827892 -398.078775)
			(xy 31.796859 -398.019047) (xy 31.773187 -397.956039) (xy 31.757216 -397.890652) (xy 31.749174 -397.823826)
			(xy 30.620528 -397.823826) (xy 30.592066 -397.878596) (xy 30.554113 -397.934182) (xy 30.532324 -397.959834)
			(xy 30.526533 -397.966984) (xy 30.520014 -397.984171) (xy 30.519624 -397.993362) (xy 30.519624 -398.486884)
			(xy 30.520036 -398.496071) (xy 30.526548 -398.513256) (xy 30.532324 -398.520412) (xy 30.554149 -398.546034)
			(xy 30.592099 -398.601624) (xy 30.623132 -398.661352) (xy 30.646805 -398.72436) (xy 30.662776 -398.789746)
			(xy 30.670818 -398.856573) (xy 30.670815 -398.923881) (xy 30.662767 -398.990707) (xy 30.646789 -399.056092)
			(xy 30.62311 -399.119098) (xy 30.592071 -399.178822) (xy 30.554115 -399.234409) (xy 30.532324 -399.26006)
			(xy 30.526522 -399.267202) (xy 30.52001 -399.284395) (xy 30.519624 -399.293588) (xy 30.519624 -399.451576)
			(xy 30.519159 -399.461726) (xy 30.511376 -399.480473) (xy 30.496993 -399.494796) (xy 30.478213 -399.502501)
			(xy 30.468062 -399.502884) (xy 29.751782 -399.502884) (xy 29.741657 -399.502389) (xy 29.72294 -399.49466)
			(xy 29.708585 -399.480377) (xy 29.700762 -399.461698) (xy 29.70022 -399.451576) (xy 29.70022 -399.293588)
			(xy 29.699811 -399.284401) (xy 29.693296 -399.267217) (xy 29.68752 -399.26006) (xy 29.665769 -399.234378)
			(xy 29.62782 -399.178796) (xy 29.596786 -399.119076) (xy 29.573112 -399.056075) (xy 29.557137 -398.990697)
			(xy 29.549091 -398.923878) (xy 29.549087 -398.856576) (xy 29.557128 -398.789756) (xy 29.573096 -398.724376)
			(xy 29.596764 -398.661374) (xy 29.627792 -398.601651) (xy 29.665735 -398.546065) (xy 29.68752 -398.520412)
			(xy 29.693339 -398.513283) (xy 29.69984 -398.49608) (xy 29.70022 -398.486884) (xy 29.70022 -397.993362)
			(xy 29.699824 -397.984173) (xy 29.6933 -397.966989) (xy 29.68752 -397.959834) (xy 29.665743 -397.934174)
			(xy 29.627795 -397.878588) (xy 29.596762 -397.818865) (xy 29.57309 -397.755862) (xy 29.557116 -397.690481)
			(xy 29.549072 -397.623659) (xy 29.549071 -397.556356) (xy 28.420857 -397.556356) (xy 28.423249 -397.560947)
			(xy 28.447016 -397.62404) (xy 28.463055 -397.689526) (xy 28.471134 -397.756461) (xy 28.471138 -397.823882)
			(xy 28.463065 -397.890818) (xy 28.447033 -397.956305) (xy 28.423272 -398.019401) (xy 28.392124 -398.079196)
			(xy 28.354039 -398.134829) (xy 28.332176 -398.160494) (xy 28.326397 -398.167651) (xy 28.319873 -398.184833)
			(xy 28.319476 -398.194022) (xy 28.319476 -398.351502) (xy 28.318975 -398.361627) (xy 28.31125 -398.380345)
			(xy 28.296968 -398.394701) (xy 28.27829 -398.402523) (xy 28.268168 -398.403064) (xy 27.551888 -398.403064)
			(xy 27.541729 -398.402688) (xy 27.522969 -398.394881) (xy 27.508645 -398.38047) (xy 27.500952 -398.361664)
			(xy 27.50058 -398.351502) (xy 27.50058 -398.194022) (xy 27.500164 -398.184835) (xy 27.493655 -398.167651)
			(xy 27.48788 -398.160494) (xy 27.465979 -398.134859) (xy 27.427893 -398.07922) (xy 27.396745 -398.019419)
			(xy 27.372984 -397.956318) (xy 27.356952 -397.890826) (xy 27.348879 -397.823885) (xy 9.385578 -397.823885)
			(xy 9.39659 -397.956787) (xy 9.400539 -398.10004) (xy 9.39659 -398.243293) (xy 9.384756 -398.386111)
			(xy 9.365072 -398.52806) (xy 9.337598 -398.668709) (xy 9.302418 -398.807631) (xy 9.259639 -398.944405)
			(xy 9.20939 -399.078614) (xy 9.151824 -399.209851) (xy 9.087116 -399.337717) (xy 9.015462 -399.461825)
			(xy 8.93708 -399.581797) (xy 8.852209 -399.697269) (xy 8.761105 -399.807891) (xy 8.664045 -399.913325)
			(xy 8.561325 -400.013253) (xy 8.453256 -400.10737) (xy 8.340166 -400.195391) (xy 8.222399 -400.277049)
			(xy 8.100313 -400.352095) (xy 7.974278 -400.420302) (xy 7.844677 -400.481462) (xy 7.711903 -400.53539)
			(xy 7.576361 -400.581922) (xy 7.438461 -400.620916) (xy 7.298622 -400.652254) (xy 7.157269 -400.675842)
			(xy 7.014831 -400.691607) (xy 6.871742 -400.699501) (xy 6.800088 -400.699986) (xy 5.199888 -400.699986)
			(xy 5.128235 -400.699493) (xy 4.985146 -400.691598) (xy 4.842709 -400.675833) (xy 4.701356 -400.652246)
			(xy 4.561518 -400.620907) (xy 4.423619 -400.581913) (xy 4.288077 -400.535381) (xy 4.155304 -400.481454)
			(xy 4.025703 -400.420294) (xy 3.899669 -400.352087) (xy 3.777583 -400.277042) (xy 3.659817 -400.195384)
			(xy 3.546728 -400.107363) (xy 3.438659 -400.013246) (xy 3.33594 -399.913319) (xy 3.238881 -399.807885)
			(xy 3.147777 -399.697264) (xy 3.062906 -399.581793) (xy 2.984524 -399.461821) (xy 2.912871 -399.337714)
			(xy 2.848163 -399.209848) (xy 2.790598 -399.078611) (xy 2.740349 -398.944403) (xy 2.69757 -398.80763)
			(xy 2.66239 -398.668709) (xy 2.634917 -398.52806) (xy 2.615233 -398.386112) (xy 2.603399 -398.243294)
			(xy 2.59945 -398.100042) (xy 1.524 -398.100042) (xy 1.524 -401.723796) (xy 27.348891 -401.723796)
			(xy 27.348893 -401.656371) (xy 27.35697 -401.589432) (xy 27.373007 -401.523942) (xy 27.396773 -401.460844)
			(xy 27.427925 -401.401047) (xy 27.466015 -401.345412) (xy 27.48788 -401.319746) (xy 27.49368 -401.312603)
			(xy 27.500193 -401.295411) (xy 27.50058 -401.286218) (xy 27.50058 -400.793966) (xy 27.500191 -400.784777)
			(xy 27.493663 -400.767592) (xy 27.48788 -400.760438) (xy 27.466023 -400.734768) (xy 27.427935 -400.679133)
			(xy 27.396785 -400.619338) (xy 27.373022 -400.556241) (xy 27.356986 -400.490753) (xy 27.34891 -400.423816)
			(xy 27.34891 -400.356393) (xy 27.356985 -400.289456) (xy 27.373019 -400.223967) (xy 27.396782 -400.160871)
			(xy 27.42793 -400.101074) (xy 27.466017 -400.04544) (xy 27.48788 -400.019774) (xy 27.493668 -400.012622)
			(xy 27.500188 -399.995437) (xy 27.50058 -399.986246) (xy 27.50058 -399.828766) (xy 27.501 -399.818632)
			(xy 27.508746 -399.799903) (xy 27.523053 -399.785546) (xy 27.541756 -399.777735) (xy 27.551888 -399.777204)
			(xy 28.268168 -399.777204) (xy 28.278321 -399.777648) (xy 28.297073 -399.785433) (xy 28.311398 -399.799824)
			(xy 28.319098 -399.818612) (xy 28.319476 -399.828766) (xy 28.319476 -399.986246) (xy 28.319918 -399.99543)
			(xy 28.32641 -400.012614) (xy 28.332176 -400.019774) (xy 28.354047 -400.045434) (xy 28.392137 -400.101069)
			(xy 28.423289 -400.160865) (xy 28.447053 -400.223963) (xy 28.463089 -400.289453) (xy 28.471165 -400.356392)
			(xy 28.471165 -400.423817) (xy 28.463088 -400.490756) (xy 28.447051 -400.556246) (xy 28.423285 -400.619343)
			(xy 28.392132 -400.679139) (xy 28.354041 -400.734773) (xy 28.332176 -400.760438) (xy 28.326378 -400.767582)
			(xy 28.319865 -400.784774) (xy 28.319476 -400.793966) (xy 28.319476 -401.286218) (xy 28.319883 -401.295405)
			(xy 28.326399 -401.31259) (xy 28.332176 -401.319746) (xy 28.354019 -401.345429) (xy 28.39211 -401.40106)
			(xy 28.423263 -401.460854) (xy 28.446989 -401.523838) (xy 29.549051 -401.523838) (xy 29.549053 -401.456532)
			(xy 29.557098 -401.389708) (xy 29.573073 -401.324325) (xy 29.596747 -401.26132) (xy 29.627782 -401.201596)
			(xy 29.665732 -401.146008) (xy 29.68752 -401.120356) (xy 29.69332 -401.113213) (xy 29.699832 -401.096021)
			(xy 29.70022 -401.086828) (xy 29.70022 -400.92884) (xy 29.700655 -400.918686) (xy 29.708441 -400.899931)
			(xy 29.722834 -400.885605) (xy 29.741626 -400.877908) (xy 29.751782 -400.877532) (xy 30.468062 -400.877532)
			(xy 30.478185 -400.878058) (xy 30.496904 -400.885771) (xy 30.511261 -400.900046) (xy 30.519083 -400.91872)
			(xy 30.519624 -400.92884) (xy 30.519624 -401.086828) (xy 30.520015 -401.096017) (xy 30.526542 -401.113202)
			(xy 30.532324 -401.120356) (xy 30.554093 -401.146024) (xy 30.592045 -401.201607) (xy 30.623081 -401.261328)
			(xy 30.646757 -401.324331) (xy 30.662732 -401.389711) (xy 30.670778 -401.456533) (xy 30.67078 -401.523837)
			(xy 30.662738 -401.590659) (xy 30.646766 -401.65604) (xy 30.623093 -401.719044) (xy 30.620654 -401.723737)
			(xy 31.749186 -401.723737) (xy 31.749188 -401.65643) (xy 31.757235 -401.589605) (xy 31.773211 -401.524221)
			(xy 31.796887 -401.461216) (xy 31.827925 -401.401492) (xy 31.865878 -401.345906) (xy 31.887668 -401.320254)
			(xy 31.893475 -401.313116) (xy 31.899981 -401.29592) (xy 31.900368 -401.286726) (xy 31.900368 -400.793458)
			(xy 31.899963 -400.784271) (xy 31.893444 -400.767087) (xy 31.887668 -400.75993) (xy 31.865885 -400.734273)
			(xy 31.827935 -400.678688) (xy 31.796899 -400.618966) (xy 31.773225 -400.555962) (xy 31.757251 -400.49058)
			(xy 31.749206 -400.423757) (xy 31.749205 -400.356452) (xy 31.757249 -400.289629) (xy 31.773222 -400.224247)
			(xy 31.796896 -400.161243) (xy 31.82793 -400.10152) (xy 31.86588 -400.045934) (xy 31.887668 -400.020282)
			(xy 31.893463 -400.013136) (xy 31.899977 -399.995946) (xy 31.900368 -399.986754) (xy 31.900368 -399.828766)
			(xy 31.900806 -399.818602) (xy 31.908597 -399.799827) (xy 31.92298 -399.785462) (xy 31.941766 -399.777694)
			(xy 31.95193 -399.777204) (xy 32.66821 -399.777204) (xy 32.678364 -399.777725) (xy 32.697127 -399.785496)
			(xy 32.711491 -399.799853) (xy 32.719271 -399.818612) (xy 32.719772 -399.828766) (xy 32.719772 -399.986754)
			(xy 32.720211 -399.995938) (xy 32.726705 -400.013122) (xy 32.732472 -400.020282) (xy 32.754265 -400.045929)
			(xy 32.792213 -400.101517) (xy 32.823246 -400.161241) (xy 32.846918 -400.224246) (xy 32.86289 -400.289629)
			(xy 32.870933 -400.356452) (xy 32.870933 -400.423757) (xy 32.862888 -400.49058) (xy 32.846915 -400.555962)
			(xy 32.823242 -400.618967) (xy 32.792209 -400.678691) (xy 32.75426 -400.734278) (xy 32.732472 -400.75993)
			(xy 32.726677 -400.767076) (xy 32.720162 -400.784266) (xy 32.719772 -400.793458) (xy 32.719772 -401.286726)
			(xy 32.720176 -401.295914) (xy 32.726695 -401.313098) (xy 32.732472 -401.320254) (xy 32.754237 -401.345924)
			(xy 32.792186 -401.401508) (xy 32.82322 -401.46123) (xy 32.846893 -401.524232) (xy 32.862868 -401.589612)
			(xy 32.870913 -401.656432) (xy 32.870915 -401.723735) (xy 32.862873 -401.790556) (xy 32.846903 -401.855937)
			(xy 32.823233 -401.91894) (xy 32.792203 -401.978663) (xy 32.754258 -402.03425) (xy 32.732472 -402.059902)
			(xy 32.726688 -402.067056) (xy 32.720167 -402.08424) (xy 32.719772 -402.09343) (xy 32.719772 -402.251418)
			(xy 32.719282 -402.261576) (xy 32.711503 -402.280343) (xy 32.697137 -402.294708) (xy 32.678368 -402.302483)
			(xy 32.66821 -402.30298) (xy 31.95193 -402.30298) (xy 31.941763 -402.302512) (xy 31.922972 -402.29474)
			(xy 31.908587 -402.280368) (xy 31.900798 -402.261585) (xy 31.900368 -402.251418) (xy 31.900368 -402.09343)
			(xy 31.899928 -402.084246) (xy 31.893434 -402.067062) (xy 31.887668 -402.059902) (xy 31.865858 -402.034268)
			(xy 31.827908 -401.97868) (xy 31.796874 -401.918954) (xy 31.773201 -401.855947) (xy 31.757229 -401.790562)
			(xy 31.749186 -401.723737) (xy 30.620654 -401.723737) (xy 30.59206 -401.778767) (xy 30.554112 -401.834352)
			(xy 30.532324 -401.860004) (xy 30.526546 -401.867163) (xy 30.520019 -401.884343) (xy 30.519624 -401.893532)
			(xy 30.519624 -402.3868) (xy 30.520029 -402.395988) (xy 30.526546 -402.413172) (xy 30.532324 -402.420328)
			(xy 30.554114 -402.445978) (xy 30.592063 -402.501565) (xy 30.623097 -402.561289) (xy 30.64677 -402.624293)
			(xy 30.662743 -402.689676) (xy 30.670787 -402.756499) (xy 30.670787 -402.823804) (xy 30.670778 -402.823878)
			(xy 33.948799 -402.823878) (xy 33.948804 -402.75645) (xy 33.956885 -402.689508) (xy 33.972926 -402.624016)
			(xy 33.996696 -402.560917) (xy 34.027853 -402.50112) (xy 34.065949 -402.445485) (xy 34.087816 -402.41982)
			(xy 34.093631 -402.412688) (xy 34.100134 -402.395487) (xy 34.100516 -402.386292) (xy 34.100516 -401.89404)
			(xy 34.100083 -401.884855) (xy 34.093585 -401.867671) (xy 34.087816 -401.860512) (xy 34.065932 -401.834863)
			(xy 34.027843 -401.779227) (xy 33.996692 -401.719428) (xy 33.972928 -401.656329) (xy 33.956894 -401.590838)
			(xy 33.948819 -401.523898) (xy 33.948821 -401.456472) (xy 33.956899 -401.389532) (xy 33.972937 -401.324042)
			(xy 33.996704 -401.260944) (xy 34.027858 -401.201147) (xy 34.06595 -401.145513) (xy 34.087816 -401.119848)
			(xy 34.093619 -401.112707) (xy 34.100129 -401.095513) (xy 34.100516 -401.08632) (xy 34.100516 -400.92884)
			(xy 34.100949 -400.918718) (xy 34.108687 -400.900012) (xy 34.122999 -400.885696) (xy 34.141702 -400.877952)
			(xy 34.151824 -400.877532) (xy 34.868104 -400.877532) (xy 34.878231 -400.877914) (xy 34.89694 -400.885669)
			(xy 34.911256 -400.899997) (xy 34.918995 -400.918713) (xy 34.919412 -400.92884) (xy 34.919412 -401.08632)
			(xy 34.91981 -401.095509) (xy 34.926332 -401.112693) (xy 34.932112 -401.119848) (xy 34.953956 -401.14553)
			(xy 34.992044 -401.201162) (xy 35.023195 -401.260956) (xy 35.04696 -401.324051) (xy 35.062997 -401.389538)
			(xy 35.071074 -401.456474) (xy 35.071076 -401.523896) (xy 35.063002 -401.590833) (xy 35.046969 -401.65632)
			(xy 35.023208 -401.719416) (xy 35.020926 -401.723796) (xy 36.148978 -401.723796) (xy 36.14898 -401.656371)
			(xy 36.157058 -401.589432) (xy 36.173095 -401.523942) (xy 36.19686 -401.460845) (xy 36.228011 -401.401047)
			(xy 36.2661 -401.345412) (xy 36.287964 -401.319746) (xy 36.293774 -401.312611) (xy 36.300279 -401.295412)
			(xy 36.300664 -401.286218) (xy 36.300664 -400.793966) (xy 36.300256 -400.784779) (xy 36.293739 -400.767595)
			(xy 36.287964 -400.760438) (xy 36.266107 -400.734767) (xy 36.228021 -400.679133) (xy 36.196872 -400.619337)
			(xy 36.173109 -400.556241) (xy 36.157074 -400.490753) (xy 36.148998 -400.423816) (xy 36.148998 -400.356393)
			(xy 36.157072 -400.289456) (xy 36.173106 -400.223968) (xy 36.196868 -400.160871) (xy 36.228016 -400.101075)
			(xy 36.266102 -400.04544) (xy 36.287964 -400.019774) (xy 36.293762 -400.01263) (xy 36.300274 -399.995438)
			(xy 36.300664 -399.986246) (xy 36.300664 -399.828766) (xy 36.301099 -399.818634) (xy 36.308843 -399.799908)
			(xy 36.323145 -399.785552) (xy 36.341842 -399.777738) (xy 36.351972 -399.777204) (xy 37.068252 -399.777204)
			(xy 37.078404 -399.777661) (xy 37.097156 -399.785442) (xy 37.111481 -399.799828) (xy 37.119181 -399.818613)
			(xy 37.11956 -399.828766) (xy 37.11956 -399.986246) (xy 37.120005 -399.995429) (xy 37.126496 -400.012613)
			(xy 37.13226 -400.019774) (xy 37.154131 -400.045434) (xy 37.192222 -400.101068) (xy 37.223375 -400.160865)
			(xy 37.247141 -400.223962) (xy 37.263177 -400.289453) (xy 37.271253 -400.356392) (xy 37.271252 -400.423817)
			(xy 37.263175 -400.490756) (xy 37.247138 -400.556246) (xy 37.223371 -400.619344) (xy 37.192218 -400.67914)
			(xy 37.154126 -400.734773) (xy 37.13226 -400.760438) (xy 37.12646 -400.76758) (xy 37.119948 -400.784773)
			(xy 37.11956 -400.793966) (xy 37.11956 -401.286218) (xy 37.11997 -401.295405) (xy 37.126485 -401.312589)
			(xy 37.13226 -401.319746) (xy 37.154104 -401.345428) (xy 37.192196 -401.40106) (xy 37.22335 -401.460853)
			(xy 37.247117 -401.523948) (xy 37.263155 -401.589435) (xy 37.271233 -401.656372) (xy 37.271235 -401.723795)
			(xy 37.263161 -401.790732) (xy 37.247127 -401.856221) (xy 37.223363 -401.919317) (xy 37.192213 -401.979112)
			(xy 37.154124 -402.034745) (xy 37.13226 -402.06041) (xy 37.126472 -402.067561) (xy 37.119953 -402.084747)
			(xy 37.11956 -402.093938) (xy 37.11956 -402.251418) (xy 37.119088 -402.261546) (xy 37.111355 -402.280268)
			(xy 37.097064 -402.294623) (xy 37.078378 -402.302442) (xy 37.068252 -402.30298) (xy 36.351972 -402.30298)
			(xy 36.341814 -402.302601) (xy 36.323057 -402.294792) (xy 36.308734 -402.280383) (xy 36.301038 -402.261579)
			(xy 36.300664 -402.251418) (xy 36.300664 -402.093938) (xy 36.300221 -402.084755) (xy 36.293729 -402.067571)
			(xy 36.287964 -402.06041) (xy 36.26608 -402.034762) (xy 36.227994 -401.979124) (xy 36.196846 -401.919325)
			(xy 36.173085 -401.856226) (xy 36.157052 -401.790735) (xy 36.148978 -401.723796) (xy 35.020926 -401.723796)
			(xy 34.99206 -401.779212) (xy 34.953974 -401.834847) (xy 34.932112 -401.860512) (xy 34.926329 -401.867667)
			(xy 34.919806 -401.88485) (xy 34.919412 -401.89404) (xy 34.919412 -402.386292) (xy 34.919823 -402.395479)
			(xy 34.926336 -402.412664) (xy 34.932112 -402.41982) (xy 34.953928 -402.445524) (xy 34.992018 -402.501154)
			(xy 35.02317 -402.560944) (xy 35.046936 -402.624036) (xy 35.062975 -402.68952) (xy 35.071054 -402.756454)
			(xy 35.071059 -402.823818) (xy 38.349119 -402.823818) (xy 38.349123 -402.75651) (xy 38.357172 -402.689685)
			(xy 38.373149 -402.6243) (xy 38.396825 -402.561294) (xy 38.427862 -402.501569) (xy 38.465814 -402.445981)
			(xy 38.487604 -402.420328) (xy 38.493414 -402.413192) (xy 38.499921 -402.395995) (xy 38.500304 -402.3868)
			(xy 38.500304 -401.893532) (xy 38.499878 -401.884347) (xy 38.493375 -401.867162) (xy 38.487604 -401.860004)
			(xy 38.465798 -401.834368) (xy 38.427852 -401.778778) (xy 38.396821 -401.719052) (xy 38.373151 -401.656045)
			(xy 38.357181 -401.590662) (xy 38.349139 -401.523838) (xy 38.34914 -401.456532) (xy 38.357186 -401.389709)
			(xy 38.37316 -401.324326) (xy 38.396834 -401.261321) (xy 38.427867 -401.201596) (xy 38.465816 -401.146009)
			(xy 38.487604 -401.120356) (xy 38.493402 -401.113212) (xy 38.499916 -401.096021) (xy 38.500304 -401.086828)
			(xy 38.500304 -400.92884) (xy 38.500755 -400.918688) (xy 38.508538 -400.899936) (xy 38.522926 -400.885611)
			(xy 38.541712 -400.87791) (xy 38.551866 -400.877532) (xy 39.268146 -400.877532) (xy 39.278275 -400.877989)
			(xy 39.296995 -400.88573) (xy 39.31135 -400.900025) (xy 39.319169 -400.918714) (xy 39.319708 -400.92884)
			(xy 39.319708 -401.086828) (xy 39.320103 -401.096017) (xy 39.326627 -401.113201) (xy 39.332408 -401.120356)
			(xy 39.354178 -401.146024) (xy 39.392131 -401.201607) (xy 39.423168 -401.261328) (xy 39.446844 -401.32433)
			(xy 39.46282 -401.389711) (xy 39.470866 -401.456533) (xy 39.470868 -401.523837) (xy 39.462825 -401.590659)
			(xy 39.446853 -401.656041) (xy 39.42318 -401.719045) (xy 39.420711 -401.723797) (xy 40.548745 -401.723797)
			(xy 40.548747 -401.65637) (xy 40.556826 -401.58943) (xy 40.572865 -401.523939) (xy 40.596634 -401.460841)
			(xy 40.62779 -401.401044) (xy 40.665885 -401.34541) (xy 40.687752 -401.319746) (xy 40.69356 -401.312609)
			(xy 40.700067 -401.295412) (xy 40.700452 -401.286218) (xy 40.700452 -400.793966) (xy 40.700046 -400.784779)
			(xy 40.693528 -400.767595) (xy 40.687752 -400.760438) (xy 40.665892 -400.734769) (xy 40.6278 -400.679136)
			(xy 40.596646 -400.619341) (xy 40.572879 -400.556244) (xy 40.556842 -400.490755) (xy 40.548764 -400.423817)
			(xy 40.548764 -400.356392) (xy 40.55684 -400.289454) (xy 40.572876 -400.223964) (xy 40.596642 -400.160867)
			(xy 40.627795 -400.101072) (xy 40.665887 -400.045438) (xy 40.687752 -400.019774) (xy 40.693549 -400.012629)
			(xy 40.700062 -399.995438) (xy 40.700452 -399.986246) (xy 40.700452 -399.828766) (xy 40.700899 -399.818636)
			(xy 40.70864 -399.799911) (xy 40.722939 -399.785556) (xy 40.741632 -399.77774) (xy 40.75176 -399.777204)
			(xy 41.46804 -399.777204) (xy 41.478197 -399.777589) (xy 41.496951 -399.785399) (xy 41.511273 -399.799806)
			(xy 41.518971 -399.818606) (xy 41.519348 -399.828766) (xy 41.519348 -399.986246) (xy 41.519796 -399.995429)
			(xy 41.526285 -400.012613) (xy 41.532048 -400.019774) (xy 41.55392 -400.045433) (xy 41.592012 -400.101068)
			(xy 41.623165 -400.160864) (xy 41.646931 -400.223962) (xy 41.662968 -400.289452) (xy 41.671044 -400.356392)
			(xy 41.671043 -400.423817) (xy 41.662966 -400.490757) (xy 41.646928 -400.556247) (xy 41.623161 -400.619344)
			(xy 41.592007 -400.67914) (xy 41.553914 -400.734774) (xy 41.532048 -400.760438) (xy 41.526246 -400.767579)
			(xy 41.519736 -400.784773) (xy 41.519348 -400.793966) (xy 41.519348 -401.286218) (xy 41.519761 -401.295405)
			(xy 41.526274 -401.312588) (xy 41.532048 -401.319746) (xy 41.553892 -401.345428) (xy 41.591985 -401.401059)
			(xy 41.62314 -401.460852) (xy 41.646907 -401.523947) (xy 41.662946 -401.589435) (xy 41.671024 -401.656372)
			(xy 41.671026 -401.723795) (xy 41.662952 -401.790733) (xy 41.646917 -401.856221) (xy 41.623153 -401.919317)
			(xy 41.592002 -401.979113) (xy 41.553912 -402.034746) (xy 41.532048 -402.06041) (xy 41.526258 -402.06756)
			(xy 41.519741 -402.084747) (xy 41.519348 -402.093938) (xy 41.519348 -402.251418) (xy 41.518888 -402.261547)
			(xy 41.511152 -402.280271) (xy 41.496858 -402.294627) (xy 41.478167 -402.302444) (xy 41.46804 -402.30298)
			(xy 40.75176 -402.30298) (xy 40.741601 -402.302611) (xy 40.722844 -402.294798) (xy 40.708521 -402.280385)
			(xy 40.700826 -402.26158) (xy 40.700452 -402.251418) (xy 40.700452 -402.093938) (xy 40.700012 -402.084754)
			(xy 40.693518 -402.06757) (xy 40.687752 -402.06041) (xy 40.665865 -402.034763) (xy 40.627773 -401.979127)
			(xy 40.59662 -401.919329) (xy 40.572855 -401.85623) (xy 40.55682 -401.790738) (xy 40.548745 -401.723797)
			(xy 39.420711 -401.723797) (xy 39.392146 -401.778768) (xy 39.354196 -401.834353) (xy 39.332408 -401.860004)
			(xy 39.326628 -401.867161) (xy 39.320103 -401.884342) (xy 39.319708 -401.893532) (xy 39.319708 -402.3868)
			(xy 39.320116 -402.395987) (xy 39.326631 -402.413172) (xy 39.332408 -402.420328) (xy 39.35415 -402.446018)
			(xy 39.392104 -402.501598) (xy 39.423142 -402.561316) (xy 39.44682 -402.624315) (xy 39.462798 -402.689694)
			(xy 39.470847 -402.756513) (xy 39.470851 -402.823815) (xy 39.470843 -402.823878) (xy 42.748887 -402.823878)
			(xy 42.748892 -402.75645) (xy 42.756972 -402.689509) (xy 42.773013 -402.624017) (xy 42.796782 -402.560918)
			(xy 42.827939 -402.501121) (xy 42.866033 -402.445485) (xy 42.8879 -402.41982) (xy 42.893713 -402.412686)
			(xy 42.900218 -402.395487) (xy 42.9006 -402.386292) (xy 42.9006 -401.89404) (xy 42.900171 -401.884855)
			(xy 42.89367 -401.86767) (xy 42.8879 -401.860512) (xy 42.866016 -401.834863) (xy 42.827928 -401.779226)
			(xy 42.796778 -401.719428) (xy 42.773015 -401.656329) (xy 42.756981 -401.590838) (xy 42.748907 -401.523898)
			(xy 42.748909 -401.456472) (xy 42.756987 -401.389533) (xy 42.773024 -401.324043) (xy 42.796791 -401.260945)
			(xy 42.827944 -401.201148) (xy 42.866035 -401.145513) (xy 42.8879 -401.119848) (xy 42.893701 -401.112706)
			(xy 42.900213 -401.095513) (xy 42.9006 -401.08632) (xy 42.9006 -400.92884) (xy 42.901049 -400.91872)
			(xy 42.908784 -400.900017) (xy 42.923091 -400.885702) (xy 42.941788 -400.877955) (xy 42.951908 -400.877532)
			(xy 43.668188 -400.877532) (xy 43.678314 -400.877927) (xy 43.697023 -400.885677) (xy 43.711339 -400.9)
			(xy 43.719079 -400.918714) (xy 43.719496 -400.92884) (xy 43.719496 -401.08632) (xy 43.719897 -401.095508)
			(xy 43.726417 -401.112692) (xy 43.732196 -401.119848) (xy 43.75404 -401.145529) (xy 43.79213 -401.201162)
			(xy 43.823282 -401.260955) (xy 43.847047 -401.32405) (xy 43.863084 -401.389537) (xy 43.871162 -401.456474)
			(xy 43.871164 -401.523896) (xy 43.86309 -401.590833) (xy 43.847056 -401.656321) (xy 43.823294 -401.719417)
			(xy 43.821044 -401.723737) (xy 44.949064 -401.723737) (xy 44.949066 -401.65643) (xy 44.957113 -401.589606)
			(xy 44.973088 -401.524222) (xy 44.996763 -401.461217) (xy 45.027799 -401.401493) (xy 45.065751 -401.345906)
			(xy 45.08754 -401.320254) (xy 45.093344 -401.313114) (xy 45.099853 -401.295919) (xy 45.10024 -401.286726)
			(xy 45.10024 -400.793458) (xy 45.099841 -400.78427) (xy 45.093319 -400.767086) (xy 45.08754 -400.75993)
			(xy 45.065758 -400.734273) (xy 45.027809 -400.678687) (xy 44.996776 -400.618964) (xy 44.973103 -400.55596)
			(xy 44.957129 -400.490579) (xy 44.949085 -400.423757) (xy 44.949084 -400.356452) (xy 44.957128 -400.28963)
			(xy 44.9731 -400.224248) (xy 44.996772 -400.161244) (xy 45.027805 -400.101521) (xy 45.065753 -400.045934)
			(xy 45.08754 -400.020282) (xy 45.093332 -400.013134) (xy 45.099848 -399.995945) (xy 45.10024 -399.986754)
			(xy 45.10024 -399.828766) (xy 45.100706 -399.818606) (xy 45.108492 -399.799835) (xy 45.122866 -399.785471)
			(xy 45.141641 -399.777698) (xy 45.151802 -399.777204) (xy 45.868082 -399.777204) (xy 45.878234 -399.777747)
			(xy 45.896997 -399.785509) (xy 45.911361 -399.79986) (xy 45.919143 -399.818614) (xy 45.919644 -399.828766)
			(xy 45.919644 -399.986754) (xy 45.920089 -399.995937) (xy 45.92658 -400.013121) (xy 45.932344 -400.020282)
			(xy 45.954138 -400.045929) (xy 45.992088 -400.101516) (xy 46.023122 -400.16124) (xy 46.046795 -400.224245)
			(xy 46.062768 -400.289628) (xy 46.070812 -400.356452) (xy 46.070811 -400.423757) (xy 46.062766 -400.490581)
			(xy 46.046792 -400.555963) (xy 46.023118 -400.618968) (xy 45.992083 -400.678692) (xy 45.954132 -400.734278)
			(xy 45.932344 -400.75993) (xy 45.926545 -400.767073) (xy 45.920033 -400.784266) (xy 45.919644 -400.793458)
			(xy 45.919644 -401.286726) (xy 45.920054 -401.295913) (xy 45.926569 -401.313097) (xy 45.932344 -401.320254)
			(xy 45.95411 -401.345924) (xy 45.992061 -401.401507) (xy 46.023096 -401.461228) (xy 46.046771 -401.524231)
			(xy 46.062746 -401.589611) (xy 46.070792 -401.656432) (xy 46.070794 -401.723735) (xy 46.062752 -401.790557)
			(xy 46.046781 -401.855938) (xy 46.02311 -401.918941) (xy 45.992078 -401.978664) (xy 45.954131 -402.03425)
			(xy 45.932344 -402.059902) (xy 45.926557 -402.067054) (xy 45.920038 -402.084239) (xy 45.919644 -402.09343)
			(xy 45.919644 -402.251418) (xy 45.919181 -402.261579) (xy 45.911397 -402.280352) (xy 45.897022 -402.294718)
			(xy 45.878244 -402.302488) (xy 45.868082 -402.30298) (xy 45.151802 -402.30298) (xy 45.141647 -402.302465)
			(xy 45.122881 -402.294695) (xy 45.108516 -402.280336) (xy 45.100739 -402.261573) (xy 45.10024 -402.251418)
			(xy 45.10024 -402.09343) (xy 45.099806 -402.084246) (xy 45.093308 -402.067061) (xy 45.08754 -402.059902)
			(xy 45.06573 -402.034268) (xy 45.027782 -401.978679) (xy 44.99675 -401.918953) (xy 44.973078 -401.855946)
			(xy 44.957107 -401.790561) (xy 44.949064 -401.723737) (xy 43.821044 -401.723737) (xy 43.792146 -401.779213)
			(xy 43.754059 -401.834847) (xy 43.732196 -401.860512) (xy 43.726411 -401.867666) (xy 43.71989 -401.88485)
			(xy 43.719496 -401.89404) (xy 43.719496 -402.386292) (xy 43.719911 -402.395479) (xy 43.726421 -402.412663)
			(xy 43.732196 -402.41982) (xy 43.754013 -402.445524) (xy 43.792103 -402.501153) (xy 43.823256 -402.560944)
			(xy 43.847023 -402.624036) (xy 43.863062 -402.68952) (xy 43.871142 -402.756454) (xy 43.871146 -402.823874)
			(xy 43.863075 -402.890809) (xy 43.847045 -402.956295) (xy 43.823286 -403.01939) (xy 43.792141 -403.079185)
			(xy 43.754057 -403.134819) (xy 43.732196 -403.160484) (xy 43.726381 -403.167616) (xy 43.719877 -403.184817)
			(xy 43.719496 -403.194012) (xy 43.719496 -403.351492) (xy 43.719077 -403.361614) (xy 43.711331 -403.380319)
			(xy 43.697015 -403.394633) (xy 43.67831 -403.402378) (xy 43.668188 -403.4028) (xy 42.951908 -403.4028)
			(xy 42.941786 -403.402377) (xy 42.923083 -403.394632) (xy 42.908768 -403.380317) (xy 42.901023 -403.361614)
			(xy 42.9006 -403.351492) (xy 42.9006 -403.194012) (xy 42.900184 -403.184825) (xy 42.893674 -403.167641)
			(xy 42.8879 -403.160484) (xy 42.865989 -403.134858) (xy 42.827902 -403.079218) (xy 42.796753 -403.019416)
			(xy 42.772992 -402.956314) (xy 42.756959 -402.89082) (xy 42.748887 -402.823878) (xy 39.470843 -402.823878)
			(xy 39.462811 -402.890635) (xy 39.446841 -402.956016) (xy 39.423172 -403.019018) (xy 39.392141 -403.07874)
			(xy 39.354194 -403.134325) (xy 39.332408 -403.159976) (xy 39.326598 -403.167111) (xy 39.320091 -403.184309)
			(xy 39.319708 -403.193504) (xy 39.319708 -403.351492) (xy 39.319272 -403.361645) (xy 39.311481 -403.380395)
			(xy 39.297088 -403.394719) (xy 39.278301 -403.40242) (xy 39.268146 -403.4028) (xy 38.551866 -403.4028)
			(xy 38.541742 -403.402303) (xy 38.523028 -403.394571) (xy 38.508674 -403.380289) (xy 38.500849 -403.361613)
			(xy 38.500304 -403.351492) (xy 38.500304 -403.193504) (xy 38.499891 -403.184317) (xy 38.493379 -403.167133)
			(xy 38.487604 -403.159976) (xy 38.46577 -403.134362) (xy 38.427825 -403.078769) (xy 38.396796 -403.01904)
			(xy 38.373127 -402.956031) (xy 38.357159 -402.890644) (xy 38.349119 -402.823818) (xy 35.071059 -402.823818)
			(xy 35.071059 -402.823874) (xy 35.062988 -402.890809) (xy 35.046958 -402.956295) (xy 35.023199 -403.01939)
			(xy 34.992055 -403.079185) (xy 34.953973 -403.134819) (xy 34.932112 -403.160484) (xy 34.926299 -403.167617)
			(xy 34.919794 -403.184817) (xy 34.919412 -403.194012) (xy 34.919412 -403.351492) (xy 34.918978 -403.361612)
			(xy 34.911234 -403.380314) (xy 34.896924 -403.394628) (xy 34.878224 -403.402375) (xy 34.868104 -403.4028)
			(xy 34.151824 -403.4028) (xy 34.141703 -403.402365) (xy 34.123 -403.394624) (xy 34.108685 -403.380314)
			(xy 34.100939 -403.361613) (xy 34.100516 -403.351492) (xy 34.100516 -403.194012) (xy 34.100096 -403.184826)
			(xy 34.093589 -403.167642) (xy 34.087816 -403.160484) (xy 34.065904 -403.134858) (xy 34.027816 -403.079218)
			(xy 33.996666 -403.019417) (xy 33.972904 -402.956315) (xy 33.956872 -402.890821) (xy 33.948799 -402.823878)
			(xy 30.670778 -402.823878) (xy 30.662742 -402.890627) (xy 30.646769 -402.956009) (xy 30.623096 -403.019014)
			(xy 30.592062 -403.078738) (xy 30.554112 -403.134324) (xy 30.532324 -403.159976) (xy 30.526515 -403.167113)
			(xy 30.520007 -403.18431) (xy 30.519624 -403.193504) (xy 30.519624 -403.351492) (xy 30.519172 -403.361643)
			(xy 30.511384 -403.38039) (xy 30.496997 -403.394713) (xy 30.478214 -403.402417) (xy 30.468062 -403.4028)
			(xy 29.751782 -403.4028) (xy 29.741659 -403.40229) (xy 29.722945 -403.394563) (xy 29.708591 -403.380285)
			(xy 29.700765 -403.361612) (xy 29.70022 -403.351492) (xy 29.70022 -403.193504) (xy 29.699804 -403.184318)
			(xy 29.693294 -403.167133) (xy 29.68752 -403.159976) (xy 29.665734 -403.134322) (xy 29.627785 -403.078736)
			(xy 29.596752 -403.019013) (xy 29.573079 -402.956008) (xy 29.557106 -402.890626) (xy 29.549061 -402.823804)
			(xy 29.549061 -402.756499) (xy 29.557105 -402.689677) (xy 29.573078 -402.624294) (xy 29.59675 -402.56129)
			(xy 29.627784 -402.501566) (xy 29.665732 -402.44598) (xy 29.68752 -402.420328) (xy 29.693332 -402.413194)
			(xy 29.699837 -402.395995) (xy 29.70022 -402.3868) (xy 29.70022 -401.893532) (xy 29.69979 -401.884347)
			(xy 29.69329 -401.867163) (xy 29.68752 -401.860004) (xy 29.665713 -401.834368) (xy 29.627766 -401.778779)
			(xy 29.596735 -401.719053) (xy 29.573064 -401.656046) (xy 29.557093 -401.590662) (xy 29.549051 -401.523838)
			(xy 28.446989 -401.523838) (xy 28.44703 -401.523948) (xy 28.463067 -401.589436) (xy 28.471145 -401.656372)
			(xy 28.471147 -401.723795) (xy 28.463073 -401.790732) (xy 28.447039 -401.85622) (xy 28.423277 -401.919316)
			(xy 28.392127 -401.979111) (xy 28.354039 -402.034745) (xy 28.332176 -402.06041) (xy 28.32639 -402.067562)
			(xy 28.31987 -402.084748) (xy 28.319476 -402.093938) (xy 28.319476 -402.251418) (xy 28.318989 -402.261544)
			(xy 28.311258 -402.280263) (xy 28.296972 -402.294618) (xy 28.278291 -402.302439) (xy 28.268168 -402.30298)
			(xy 27.551888 -402.30298) (xy 27.541731 -402.302588) (xy 27.522974 -402.294785) (xy 27.50865 -402.280379)
			(xy 27.500954 -402.261578) (xy 27.50058 -402.251418) (xy 27.50058 -402.093938) (xy 27.500156 -402.084752)
			(xy 27.493653 -402.067567) (xy 27.48788 -402.06041) (xy 27.465995 -402.034762) (xy 27.427908 -401.979125)
			(xy 27.39676 -401.919326) (xy 27.372998 -401.856227) (xy 27.356964 -401.790736) (xy 27.348891 -401.723796)
			(xy 1.524 -401.723796) (xy 1.524 -404.502366) (xy 1.524459 -404.513094) (xy 1.533205 -404.532683)
			(xy 1.549214 -404.546963) (xy 1.559306 -404.550626) (xy 1.66751 -404.58517) (xy 1.698752 -404.574756)
			(xy 1.708404 -404.56104) (xy 1.769258 -404.475991) (xy 1.896821 -404.310242) (xy 2.030874 -404.149697)
			(xy 2.171205 -403.994609) (xy 2.317592 -403.845223) (xy 2.469804 -403.701777) (xy 2.627599 -403.564498)
			(xy 2.790728 -403.433601) (xy 2.958933 -403.309295) (xy 3.131949 -403.191776) (xy 3.3095 -403.081229)
			(xy 3.491307 -402.977831) (xy 3.677082 -402.881743) (xy 3.866531 -402.793119) (xy 4.059354 -402.712099)
			(xy 4.255247 -402.63881) (xy 4.453898 -402.573369) (xy 4.654995 -402.515878) (xy 4.858219 -402.46643)
			(xy 5.063249 -402.425102) (xy 5.269759 -402.39196) (xy 5.477425 -402.367056) (xy 5.685916 -402.350429)
			(xy 5.894903 -402.342106) (xy 5.99948 -402.341588) (xy 5.999988 -402.341588) (xy 6.101963 -402.342082)
			(xy 6.30576 -402.349991) (xy 6.509097 -402.365795) (xy 6.711669 -402.389472) (xy 6.913169 -402.420987)
			(xy 7.113297 -402.46029) (xy 7.31175 -402.507324) (xy 7.50823 -402.562018) (xy 7.702441 -402.62429)
			(xy 7.894092 -402.694045) (xy 8.082893 -402.771179) (xy 8.268562 -402.855576) (xy 8.450819 -402.947108)
			(xy 8.629389 -403.045639) (xy 8.804005 -403.15102) (xy 8.974403 -403.263093) (xy 9.140327 -403.381689)
			(xy 9.301528 -403.506629) (xy 9.457763 -403.637725) (xy 9.608797 -403.774782) (xy 9.754403 -403.917591)
			(xy 9.894363 -404.065939) (xy 10.028464 -404.219603) (xy 10.156507 -404.378351) (xy 10.278298 -404.541944)
			(xy 10.393653 -404.710137) (xy 10.502401 -404.882676) (xy 10.604376 -405.059302) (xy 10.699426 -405.23975)
			(xy 10.787407 -405.423747) (xy 10.868188 -405.611018) (xy 10.873087 -405.623707) (xy 27.348902 -405.623707)
			(xy 27.348902 -405.556284) (xy 27.356979 -405.489345) (xy 27.373014 -405.423856) (xy 27.396778 -405.360759)
			(xy 27.427928 -405.300963) (xy 27.466016 -405.245328) (xy 27.48788 -405.219662) (xy 27.493673 -405.212514)
			(xy 27.50019 -405.195326) (xy 27.50058 -405.186134) (xy 27.50058 -404.693882) (xy 27.500183 -404.684693)
			(xy 27.493661 -404.667509) (xy 27.48788 -404.660354) (xy 27.466038 -404.634671) (xy 27.42795 -404.579038)
			(xy 27.3968 -404.519244) (xy 27.373035 -404.45615) (xy 27.356999 -404.390663) (xy 27.348922 -404.323727)
			(xy 27.34892 -404.256306) (xy 27.356993 -404.189369) (xy 27.373025 -404.123882) (xy 27.396786 -404.060786)
			(xy 27.427933 -404.00099) (xy 27.466018 -403.945356) (xy 27.48788 -403.91969) (xy 27.493661 -403.912534)
			(xy 27.500186 -403.895352) (xy 27.50058 -403.886162) (xy 27.50058 -403.728682) (xy 27.501013 -403.718549)
			(xy 27.508754 -403.69982) (xy 27.523057 -403.685463) (xy 27.541757 -403.677651) (xy 27.551888 -403.67712)
			(xy 28.268168 -403.67712) (xy 28.278323 -403.677548) (xy 28.297078 -403.685337) (xy 28.311404 -403.699732)
			(xy 28.319101 -403.718525) (xy 28.319476 -403.728682) (xy 28.319476 -403.886162) (xy 28.31991 -403.895347)
			(xy 28.326408 -403.912531) (xy 28.332176 -403.91969) (xy 28.354062 -403.945337) (xy 28.392152 -404.000974)
			(xy 28.423303 -404.060772) (xy 28.447067 -404.123871) (xy 28.463102 -404.189363) (xy 28.471176 -404.256304)
			(xy 28.471174 -404.323729) (xy 28.463096 -404.39067) (xy 28.447057 -404.45616) (xy 28.42329 -404.519258)
			(xy 28.392135 -404.579055) (xy 28.354042 -404.634689) (xy 28.332176 -404.660354) (xy 28.326371 -404.667493)
			(xy 28.319862 -404.684688) (xy 28.319476 -404.693882) (xy 28.319476 -405.186134) (xy 28.319875 -405.195322)
			(xy 28.326397 -405.212506) (xy 28.332176 -405.219662) (xy 28.354035 -405.245332) (xy 28.392125 -405.300965)
			(xy 28.423278 -405.36076) (xy 28.447043 -405.423857) (xy 28.46308 -405.489345) (xy 28.471157 -405.556284)
			(xy 28.471157 -405.623707) (xy 28.463081 -405.690646) (xy 28.447046 -405.756135) (xy 28.423281 -405.819231)
			(xy 28.39213 -405.879027) (xy 28.35404 -405.934661) (xy 28.332176 -405.960326) (xy 28.326383 -405.967474)
			(xy 28.319867 -405.984662) (xy 28.319476 -405.993854) (xy 28.319476 -406.151334) (xy 28.319002 -406.161461)
			(xy 28.311266 -406.18018) (xy 28.296976 -406.194534) (xy 28.278293 -406.202355) (xy 28.268168 -406.202896)
			(xy 27.551888 -406.202896) (xy 27.541733 -406.202488) (xy 27.522979 -406.194688) (xy 27.508656 -406.180287)
			(xy 27.500957 -406.161492) (xy 27.50058 -406.151334) (xy 27.50058 -405.993854) (xy 27.500148 -405.984669)
			(xy 27.49365 -405.967484) (xy 27.48788 -405.960326) (xy 27.466011 -405.934665) (xy 27.427924 -405.87903)
			(xy 27.396774 -405.819233) (xy 27.373011 -405.756135) (xy 27.356977 -405.690646) (xy 27.348902 -405.623707)
			(xy 10.873087 -405.623707) (xy 10.941646 -405.80128) (xy 11.007672 -405.994247) (xy 11.066165 -406.189629)
			(xy 11.117039 -406.387133) (xy 11.160216 -406.58646) (xy 11.18442 -406.72373) (xy 29.549042 -406.72373)
			(xy 29.549045 -406.656422) (xy 29.557092 -406.589598) (xy 29.573068 -406.524214) (xy 29.596744 -406.461208)
			(xy 29.627779 -406.401484) (xy 29.665731 -406.345896) (xy 29.68752 -406.320244) (xy 29.693325 -406.313105)
			(xy 29.699834 -406.29591) (xy 29.70022 -406.286716) (xy 29.70022 -405.793448) (xy 29.699782 -405.784264)
			(xy 29.693287 -405.767079) (xy 29.68752 -405.75992) (xy 29.665729 -405.734271) (xy 29.627781 -405.678684)
			(xy 29.596749 -405.618959) (xy 29.573078 -405.555955) (xy 29.557105 -405.490572) (xy 29.549062 -405.423749)
			(xy 29.549062 -405.356444) (xy 29.557107 -405.289622) (xy 29.573079 -405.22424) (xy 29.596752 -405.161235)
			(xy 29.627784 -405.101511) (xy 29.665733 -405.045924) (xy 29.68752 -405.020272) (xy 29.693313 -405.013125)
			(xy 29.699829 -404.995936) (xy 29.70022 -404.986744) (xy 29.70022 -404.828756) (xy 29.700586 -404.818597)
			(xy 29.7084 -404.799839) (xy 29.722814 -404.785517) (xy 29.74162 -404.777822) (xy 29.751782 -404.777448)
			(xy 30.468062 -404.777448) (xy 30.478187 -404.777958) (xy 30.496909 -404.785675) (xy 30.511267 -404.799954)
			(xy 30.519086 -404.818634) (xy 30.519624 -404.828756) (xy 30.519624 -404.986744) (xy 30.520008 -404.995934)
			(xy 30.526539 -405.013118) (xy 30.532324 -405.020272) (xy 30.554109 -405.045927) (xy 30.59206 -405.101512)
			(xy 30.623096 -405.161235) (xy 30.64677 -405.224239) (xy 30.662745 -405.289621) (xy 30.67079 -405.356444)
			(xy 30.67079 -405.42375) (xy 30.662746 -405.490573) (xy 30.646772 -405.555955) (xy 30.623098 -405.61896)
			(xy 30.620661 -405.623649) (xy 31.749197 -405.623649) (xy 31.749198 -405.556342) (xy 31.757243 -405.489519)
			(xy 31.773217 -405.424136) (xy 31.796892 -405.361131) (xy 31.827928 -405.301408) (xy 31.865879 -405.245822)
			(xy 31.887668 -405.22017) (xy 31.893468 -405.213028) (xy 31.899979 -405.195835) (xy 31.900368 -405.186642)
			(xy 31.900368 -404.693374) (xy 31.899955 -404.684187) (xy 31.893441 -404.667004) (xy 31.887668 -404.659846)
			(xy 31.865901 -404.634176) (xy 31.82795 -404.578593) (xy 31.796914 -404.518872) (xy 31.773239 -404.45587)
			(xy 31.757263 -404.39049) (xy 31.749217 -404.323668) (xy 31.749215 -404.256365) (xy 31.757257 -404.189543)
			(xy 31.773229 -404.124162) (xy 31.7969 -404.061158) (xy 31.827933 -404.001435) (xy 31.865881 -403.94585)
			(xy 31.887668 -403.920198) (xy 31.893456 -403.913047) (xy 31.899974 -403.895861) (xy 31.900368 -403.88667)
			(xy 31.900368 -403.728682) (xy 31.90075 -403.718506) (xy 31.908547 -403.699705) (xy 31.922945 -403.68532)
			(xy 31.941753 -403.677541) (xy 31.95193 -403.67712) (xy 32.66821 -403.67712) (xy 32.678366 -403.677625)
			(xy 32.697132 -403.685399) (xy 32.711496 -403.699761) (xy 32.719273 -403.718526) (xy 32.719772 -403.728682)
			(xy 32.719772 -403.88667) (xy 32.720203 -403.895855) (xy 32.726703 -403.913039) (xy 32.732472 -403.920198)
			(xy 32.754281 -403.945832) (xy 32.792229 -404.001422) (xy 32.82326 -404.061148) (xy 32.846931 -404.124155)
			(xy 32.862902 -404.189539) (xy 32.870945 -404.256363) (xy 32.870943 -404.32367) (xy 32.862897 -404.390494)
			(xy 32.846922 -404.455877) (xy 32.823247 -404.518882) (xy 32.792212 -404.578607) (xy 32.754261 -404.634194)
			(xy 32.732472 -404.659846) (xy 32.72667 -404.666987) (xy 32.720159 -404.684181) (xy 32.719772 -404.693374)
			(xy 32.719772 -405.186642) (xy 32.720168 -405.195831) (xy 32.726692 -405.213014) (xy 32.732472 -405.22017)
			(xy 32.754254 -405.245827) (xy 32.792202 -405.301413) (xy 32.823235 -405.361136) (xy 32.846907 -405.42414)
			(xy 32.862881 -405.489521) (xy 32.870925 -405.556343) (xy 32.870926 -405.623648) (xy 32.862882 -405.69047)
			(xy 32.84691 -405.755851) (xy 32.823239 -405.818856) (xy 32.792207 -405.878579) (xy 32.754259 -405.934166)
			(xy 32.732472 -405.959818) (xy 32.726682 -405.966967) (xy 32.720164 -405.984155) (xy 32.719772 -405.993346)
			(xy 32.719772 -406.151334) (xy 32.719295 -406.161493) (xy 32.711511 -406.180261) (xy 32.697141 -406.194624)
			(xy 32.678369 -406.202399) (xy 32.66821 -406.202896) (xy 31.95193 -406.202896) (xy 31.941778 -406.202343)
			(xy 31.923016 -406.194585) (xy 31.908651 -406.180237) (xy 31.900869 -406.161485) (xy 31.900368 -406.151334)
			(xy 31.900368 -405.993346) (xy 31.899921 -405.984163) (xy 31.893431 -405.966979) (xy 31.887668 -405.959818)
			(xy 31.865874 -405.934171) (xy 31.827923 -405.878584) (xy 31.796888 -405.81886) (xy 31.773215 -405.755855)
			(xy 31.757241 -405.690472) (xy 31.749197 -405.623649) (xy 30.620661 -405.623649) (xy 30.592063 -405.678683)
			(xy 30.554113 -405.734268) (xy 30.532324 -405.75992) (xy 30.526539 -405.767074) (xy 30.520017 -405.784258)
			(xy 30.519624 -405.793448) (xy 30.519624 -406.286716) (xy 30.520021 -406.295905) (xy 30.526543 -406.313089)
			(xy 30.532324 -406.320244) (xy 30.554081 -406.345922) (xy 30.592034 -406.401503) (xy 30.62307 -406.461223)
			(xy 30.646746 -406.524224) (xy 30.662723 -406.589604) (xy 30.67077 -406.656424) (xy 30.670773 -406.723728)
			(xy 30.670766 -406.723789) (xy 33.948811 -406.723789) (xy 33.948814 -406.656363) (xy 33.956893 -406.589422)
			(xy 33.972932 -406.523931) (xy 33.996701 -406.460833) (xy 34.027856 -406.401036) (xy 34.06595 -406.345401)
			(xy 34.087816 -406.319736) (xy 34.093624 -406.312599) (xy 34.100131 -406.295402) (xy 34.100516 -406.286208)
			(xy 34.100516 -405.793956) (xy 34.100123 -405.784767) (xy 34.093597 -405.767583) (xy 34.087816 -405.760428)
			(xy 34.065948 -405.734766) (xy 34.027858 -405.679132) (xy 33.996706 -405.619335) (xy 33.972942 -405.556238)
			(xy 33.956906 -405.490748) (xy 33.94883 -405.423809) (xy 33.948831 -405.356385) (xy 33.956907 -405.289446)
			(xy 33.972944 -405.223957) (xy 33.996709 -405.160859) (xy 34.027861 -405.101063) (xy 34.065951 -405.045429)
			(xy 34.087816 -405.019764) (xy 34.093612 -405.012619) (xy 34.100127 -404.995428) (xy 34.100516 -404.986236)
			(xy 34.100516 -404.828756) (xy 34.10095 -404.818642) (xy 34.108705 -404.79996) (xy 34.123017 -404.785666)
			(xy 34.14171 -404.777936) (xy 34.151824 -404.777448) (xy 34.868104 -404.777448) (xy 34.878207 -404.777981)
			(xy 34.896875 -404.78571) (xy 34.911168 -404.799992) (xy 34.918911 -404.818654) (xy 34.919412 -404.828756)
			(xy 34.919412 -404.986236) (xy 34.919802 -404.995425) (xy 34.926329 -405.01261) (xy 34.932112 -405.019764)
			(xy 34.953972 -405.045433) (xy 34.99206 -405.101067) (xy 35.02321 -405.160863) (xy 35.046974 -405.223959)
			(xy 35.063009 -405.289448) (xy 35.071085 -405.356385) (xy 35.071085 -405.423809) (xy 35.06301 -405.490746)
			(xy 35.046976 -405.556235) (xy 35.023212 -405.619332) (xy 35.020933 -405.623707) (xy 36.14899 -405.623707)
			(xy 36.14899 -405.556284) (xy 36.157066 -405.489346) (xy 36.173101 -405.423857) (xy 36.196864 -405.36076)
			(xy 36.228014 -405.300963) (xy 36.266101 -405.245328) (xy 36.287964 -405.219662) (xy 36.293767 -405.212522)
			(xy 36.300276 -405.195327) (xy 36.300664 -405.186134) (xy 36.300664 -404.693882) (xy 36.300248 -404.684696)
			(xy 36.293737 -404.667512) (xy 36.287964 -404.660354) (xy 36.266123 -404.63467) (xy 36.228036 -404.579038)
			(xy 36.196886 -404.519244) (xy 36.173122 -404.456149) (xy 36.157087 -404.390663) (xy 36.149009 -404.323727)
			(xy 36.149007 -404.256306) (xy 36.157081 -404.18937) (xy 36.173113 -404.123882) (xy 36.196873 -404.060787)
			(xy 36.228019 -404.000991) (xy 36.266103 -403.945356) (xy 36.287964 -403.91969) (xy 36.293755 -403.912541)
			(xy 36.300271 -403.895353) (xy 36.300664 -403.886162) (xy 36.300664 -403.728682) (xy 36.301112 -403.718551)
			(xy 36.30885 -403.699825) (xy 36.323149 -403.685468) (xy 36.341843 -403.677654) (xy 36.351972 -403.67712)
			(xy 37.068252 -403.67712) (xy 37.078405 -403.677561) (xy 37.097161 -403.685345) (xy 37.111486 -403.699736)
			(xy 37.119184 -403.718527) (xy 37.11956 -403.728682) (xy 37.11956 -403.886162) (xy 37.119998 -403.895346)
			(xy 37.126493 -403.91253) (xy 37.13226 -403.91969) (xy 37.154147 -403.945337) (xy 37.192238 -404.000973)
			(xy 37.22339 -404.060771) (xy 37.247154 -404.123871) (xy 37.26319 -404.189362) (xy 37.271264 -404.256303)
			(xy 37.271262 -404.32373) (xy 37.263184 -404.39067) (xy 37.247145 -404.456161) (xy 37.223376 -404.519259)
			(xy 37.192221 -404.579055) (xy 37.154127 -404.634689) (xy 37.13226 -404.660354) (xy 37.126453 -404.667492)
			(xy 37.119946 -404.684688) (xy 37.11956 -404.693882) (xy 37.11956 -405.186134) (xy 37.119963 -405.195322)
			(xy 37.126483 -405.212506) (xy 37.13226 -405.219662) (xy 37.154119 -405.245331) (xy 37.192211 -405.300964)
			(xy 37.223364 -405.36076) (xy 37.24713 -405.423856) (xy 37.263168 -405.489345) (xy 37.271245 -405.556284)
			(xy 37.271245 -405.623707) (xy 37.263169 -405.690646) (xy 37.247133 -405.756135) (xy 37.223368 -405.819232)
			(xy 37.192216 -405.879028) (xy 37.154125 -405.934661) (xy 37.13226 -405.960326) (xy 37.126465 -405.967472)
			(xy 37.11995 -405.984662) (xy 37.11956 -405.993854) (xy 37.11956 -406.151334) (xy 37.119101 -406.161463)
			(xy 37.111362 -406.180185) (xy 37.097068 -406.19454) (xy 37.078379 -406.202358) (xy 37.068252 -406.202896)
			(xy 36.351972 -406.202896) (xy 36.341816 -406.202501) (xy 36.323062 -406.194696) (xy 36.308739 -406.180291)
			(xy 36.301041 -406.161493) (xy 36.300664 -406.151334) (xy 36.300664 -405.993854) (xy 36.300214 -405.984671)
			(xy 36.293726 -405.967487) (xy 36.287964 -405.960326) (xy 36.266095 -405.934665) (xy 36.228009 -405.879029)
			(xy 36.196861 -405.819232) (xy 36.173099 -405.756135) (xy 36.157065 -405.690645) (xy 36.14899 -405.623707)
			(xy 35.020933 -405.623707) (xy 34.992063 -405.679128) (xy 34.953975 -405.734763) (xy 34.932112 -405.760428)
			(xy 34.926322 -405.767578) (xy 34.919803 -405.784765) (xy 34.919412 -405.793956) (xy 34.919412 -406.286208)
			(xy 34.919816 -406.295396) (xy 34.926334 -406.31258) (xy 34.932112 -406.319736) (xy 34.953944 -406.345427)
			(xy 34.992033 -406.401058) (xy 35.023184 -406.460851) (xy 35.04695 -406.523945) (xy 35.062987 -406.58943)
			(xy 35.071065 -406.656366) (xy 35.071068 -406.723729) (xy 38.34913 -406.723729) (xy 38.349133 -406.656422)
			(xy 38.35718 -406.589598) (xy 38.373155 -406.524215) (xy 38.39683 -406.461209) (xy 38.427865 -406.401484)
			(xy 38.465815 -406.345897) (xy 38.487604 -406.320244) (xy 38.493407 -406.313104) (xy 38.499918 -406.295909)
			(xy 38.500304 -406.286716) (xy 38.500304 -405.793448) (xy 38.49987 -405.784263) (xy 38.493373 -405.767079)
			(xy 38.487604 -405.75992) (xy 38.465813 -405.734271) (xy 38.427867 -405.678683) (xy 38.396836 -405.618959)
			(xy 38.373165 -405.555954) (xy 38.357193 -405.490572) (xy 38.34915 -405.423749) (xy 38.34915 -405.356445)
			(xy 38.357194 -405.289622) (xy 38.373167 -405.22424) (xy 38.396838 -405.161236) (xy 38.42787 -405.101512)
			(xy 38.465817 -405.045925) (xy 38.487604 -405.020272) (xy 38.493395 -405.013123) (xy 38.499913 -404.995935)
			(xy 38.500304 -404.986744) (xy 38.500304 -404.828756) (xy 38.500686 -404.818599) (xy 38.508497 -404.799844)
			(xy 38.522905 -404.785523) (xy 38.541706 -404.777825) (xy 38.551866 -404.777448) (xy 39.268146 -404.777448)
			(xy 39.278277 -404.777889) (xy 39.297 -404.785634) (xy 39.311355 -404.799934) (xy 39.319171 -404.818627)
			(xy 39.319708 -404.828756) (xy 39.319708 -404.986744) (xy 39.320095 -404.995934) (xy 39.326624 -405.013118)
			(xy 39.332408 -405.020272) (xy 39.354193 -405.045927) (xy 39.392146 -405.101512) (xy 39.423182 -405.161234)
			(xy 39.446858 -405.224239) (xy 39.462832 -405.289621) (xy 39.470878 -405.356444) (xy 39.470878 -405.42375)
			(xy 39.462833 -405.490573) (xy 39.446859 -405.555956) (xy 39.423185 -405.61896) (xy 39.420718 -405.623708)
			(xy 40.548756 -405.623708) (xy 40.548757 -405.556283) (xy 40.556834 -405.489343) (xy 40.572872 -405.423853)
			(xy 40.596639 -405.360756) (xy 40.627793 -405.30096) (xy 40.665886 -405.245326) (xy 40.687752 -405.219662)
			(xy 40.693554 -405.212521) (xy 40.700064 -405.195327) (xy 40.700452 -405.186134) (xy 40.700452 -404.693882)
			(xy 40.700039 -404.684695) (xy 40.693526 -404.667512) (xy 40.687752 -404.660354) (xy 40.665908 -404.634672)
			(xy 40.627815 -404.579041) (xy 40.59666 -404.519248) (xy 40.572893 -404.456153) (xy 40.556854 -404.390665)
			(xy 40.548776 -404.323728) (xy 40.548774 -404.256305) (xy 40.556848 -404.189367) (xy 40.572883 -404.123879)
			(xy 40.596647 -404.060783) (xy 40.627798 -404.000987) (xy 40.665888 -403.945354) (xy 40.687752 -403.91969)
			(xy 40.693542 -403.91254) (xy 40.700059 -403.895353) (xy 40.700452 -403.886162) (xy 40.700452 -403.728682)
			(xy 40.700912 -403.718553) (xy 40.708648 -403.699829) (xy 40.722942 -403.685473) (xy 40.741633 -403.677656)
			(xy 40.75176 -403.67712) (xy 41.46804 -403.67712) (xy 41.478199 -403.677489) (xy 41.496956 -403.685302)
			(xy 41.511279 -403.699715) (xy 41.518974 -403.71852) (xy 41.519348 -403.728682) (xy 41.519348 -403.886162)
			(xy 41.519788 -403.895346) (xy 41.526282 -403.91253) (xy 41.532048 -403.91969) (xy 41.553935 -403.945337)
			(xy 41.592027 -404.000973) (xy 41.62318 -404.060771) (xy 41.646945 -404.12387) (xy 41.66298 -404.189362)
			(xy 41.671055 -404.256303) (xy 41.671053 -404.32373) (xy 41.662974 -404.39067) (xy 41.646935 -404.456161)
			(xy 41.623166 -404.519259) (xy 41.59201 -404.579056) (xy 41.553915 -404.63469) (xy 41.532048 -404.660354)
			(xy 41.52624 -404.667491) (xy 41.519733 -404.684688) (xy 41.519348 -404.693882) (xy 41.519348 -405.186134)
			(xy 41.519754 -405.195321) (xy 41.526272 -405.212505) (xy 41.532048 -405.219662) (xy 41.553908 -405.245331)
			(xy 41.592 -405.300964) (xy 41.623154 -405.360759) (xy 41.646921 -405.423856) (xy 41.662958 -405.489345)
			(xy 41.671036 -405.556283) (xy 41.671036 -405.623708) (xy 41.66296 -405.690646) (xy 41.646924 -405.756136)
			(xy 41.623158 -405.819233) (xy 41.592005 -405.879028) (xy 41.553913 -405.934662) (xy 41.532048 -405.960326)
			(xy 41.526251 -405.967471) (xy 41.519738 -405.984662) (xy 41.519348 -405.993854) (xy 41.519348 -406.151334)
			(xy 41.518901 -406.161464) (xy 41.51116 -406.180189) (xy 41.496861 -406.194544) (xy 41.478168 -406.20236)
			(xy 41.46804 -406.202896) (xy 40.75176 -406.202896) (xy 40.741603 -406.202511) (xy 40.722849 -406.194701)
			(xy 40.708527 -406.180294) (xy 40.700829 -406.161494) (xy 40.700452 -406.151334) (xy 40.700452 -405.993854)
			(xy 40.700004 -405.984671) (xy 40.693515 -405.967487) (xy 40.687752 -405.960326) (xy 40.66588 -405.934667)
			(xy 40.627788 -405.879032) (xy 40.596635 -405.819236) (xy 40.572869 -405.756138) (xy 40.556832 -405.690648)
			(xy 40.548756 -405.623708) (xy 39.420718 -405.623708) (xy 39.392149 -405.678683) (xy 39.354197 -405.734269)
			(xy 39.332408 -405.75992) (xy 39.326621 -405.767072) (xy 39.3201 -405.784257) (xy 39.319708 -405.793448)
			(xy 39.319708 -406.286716) (xy 39.320109 -406.295904) (xy 39.326629 -406.313088) (xy 39.332408 -406.320244)
			(xy 39.354166 -406.345921) (xy 39.392119 -406.401503) (xy 39.423157 -406.461222) (xy 39.446834 -406.524224)
			(xy 39.46281 -406.589604) (xy 39.470858 -406.656424) (xy 39.470861 -406.723728) (xy 39.470854 -406.723789)
			(xy 42.748899 -406.723789) (xy 42.748901 -406.656363) (xy 42.756981 -406.589422) (xy 42.773019 -406.523932)
			(xy 42.796787 -406.460833) (xy 42.827942 -406.401036) (xy 42.866034 -406.345401) (xy 42.8879 -406.319736)
			(xy 42.893706 -406.312598) (xy 42.900215 -406.295402) (xy 42.9006 -406.286208) (xy 42.9006 -405.793956)
			(xy 42.900211 -405.784767) (xy 42.893683 -405.767582) (xy 42.8879 -405.760428) (xy 42.866032 -405.734766)
			(xy 42.827944 -405.679131) (xy 42.796793 -405.619334) (xy 42.773029 -405.556237) (xy 42.756994 -405.490748)
			(xy 42.748918 -405.423809) (xy 42.748919 -405.356385) (xy 42.756995 -405.289446) (xy 42.773031 -405.223957)
			(xy 42.796795 -405.16086) (xy 42.827947 -405.101064) (xy 42.866036 -405.045429) (xy 42.8879 -405.019764)
			(xy 42.893694 -405.012617) (xy 42.90021 -404.995428) (xy 42.9006 -404.986236) (xy 42.9006 -404.828756)
			(xy 42.901049 -404.818644) (xy 42.908801 -404.799965) (xy 42.923109 -404.785672) (xy 42.941796 -404.777939)
			(xy 42.951908 -404.777448) (xy 43.668188 -404.777448) (xy 43.67829 -404.777994) (xy 43.696958 -404.785718)
			(xy 43.711251 -404.799995) (xy 43.718995 -404.818655) (xy 43.719496 -404.828756) (xy 43.719496 -404.986236)
			(xy 43.71989 -404.995425) (xy 43.726415 -405.012609) (xy 43.732196 -405.019764) (xy 43.754056 -405.045432)
			(xy 43.792145 -405.101066) (xy 43.823296 -405.160862) (xy 43.847061 -405.223959) (xy 43.863097 -405.289447)
			(xy 43.871173 -405.356385) (xy 43.871173 -405.423809) (xy 43.863098 -405.490747) (xy 43.847063 -405.556236)
			(xy 43.823299 -405.619332) (xy 43.792148 -405.679128) (xy 43.75406 -405.734763) (xy 43.732196 -405.760428)
			(xy 43.726405 -405.767577) (xy 43.719887 -405.784765) (xy 43.719496 -405.793956) (xy 43.719496 -406.286208)
			(xy 43.719903 -406.295395) (xy 43.726419 -406.31258) (xy 43.732196 -406.319736) (xy 43.754029 -406.345427)
			(xy 43.792119 -406.401058) (xy 43.823271 -406.46085) (xy 43.847037 -406.523944) (xy 43.863075 -406.58943)
			(xy 43.871153 -406.656365) (xy 43.871156 -406.72373) (xy 47.149194 -406.72373) (xy 47.149197 -406.656422)
			(xy 47.157245 -406.589596) (xy 47.173223 -406.524212) (xy 47.196901 -406.461206) (xy 47.227941 -406.401481)
			(xy 47.265897 -406.345896) (xy 47.287688 -406.320244) (xy 47.293489 -406.313102) (xy 47.300002 -406.295909)
			(xy 47.300388 -406.286716) (xy 47.300388 -405.793448) (xy 47.299958 -405.784263) (xy 47.293458 -405.767078)
			(xy 47.287688 -405.75992) (xy 47.265895 -405.734272) (xy 47.227943 -405.678686) (xy 47.196907 -405.618962)
			(xy 47.173232 -405.555957) (xy 47.157258 -405.490574) (xy 47.149214 -405.42375) (xy 47.149214 -405.356444)
			(xy 47.157259 -405.28962) (xy 47.173234 -405.224237) (xy 47.19691 -405.161232) (xy 47.227946 -405.101509)
			(xy 47.265899 -405.045924) (xy 47.287688 -405.020272) (xy 47.293478 -405.013122) (xy 47.299997 -404.995935)
			(xy 47.300388 -404.986744) (xy 47.300388 -404.828756) (xy 47.300785 -404.818601) (xy 47.308593 -404.79985)
			(xy 47.322997 -404.785528) (xy 47.341792 -404.777828) (xy 47.35195 -404.777448) (xy 48.06823 -404.777448)
			(xy 48.07836 -404.777902) (xy 48.097083 -404.785641) (xy 48.111439 -404.799937) (xy 48.119255 -404.818629)
			(xy 48.119792 -404.828756) (xy 48.119792 -404.986744) (xy 48.120183 -404.995933) (xy 48.12671 -405.013117)
			(xy 48.132492 -405.020272) (xy 48.154275 -405.045928) (xy 48.192222 -405.101514) (xy 48.223254 -405.161238)
			(xy 48.246925 -405.224242) (xy 48.262897 -405.289623) (xy 48.270941 -405.356445) (xy 48.270942 -405.423749)
			(xy 48.262899 -405.490571) (xy 48.246927 -405.555952) (xy 48.223256 -405.618957) (xy 48.192225 -405.67868)
			(xy 48.154279 -405.734267) (xy 48.132492 -405.75992) (xy 48.126704 -405.767071) (xy 48.120184 -405.784257)
			(xy 48.119792 -405.793448) (xy 48.119792 -406.286716) (xy 48.120196 -406.295904) (xy 48.126714 -406.313088)
			(xy 48.132492 -406.320244) (xy 48.154247 -406.345922) (xy 48.192195 -406.401506) (xy 48.223228 -406.461226)
			(xy 48.246901 -406.524227) (xy 48.262876 -406.589606) (xy 48.270922 -406.656425) (xy 48.270925 -406.723727)
			(xy 48.262884 -406.790547) (xy 48.246916 -406.855927) (xy 48.223248 -406.91893) (xy 48.19222 -406.978653)
			(xy 48.154277 -407.034239) (xy 48.132492 -407.059892) (xy 48.126715 -407.067051) (xy 48.120189 -407.084231)
			(xy 48.119792 -407.09342) (xy 48.119792 -407.251408) (xy 48.119385 -407.261564) (xy 48.111585 -407.280318)
			(xy 48.097184 -407.294641) (xy 48.078388 -407.302339) (xy 48.06823 -407.302716) (xy 47.35195 -407.302716)
			(xy 47.341821 -407.302231) (xy 47.323093 -407.294512) (xy 47.308733 -407.280224) (xy 47.30092 -407.261534)
			(xy 47.300388 -407.251408) (xy 47.300388 -407.09342) (xy 47.299971 -407.084233) (xy 47.293462 -407.067049)
			(xy 47.287688 -407.059892) (xy 47.265867 -407.034266) (xy 47.227916 -406.978677) (xy 47.196882 -406.91895)
			(xy 47.173209 -406.855942) (xy 47.157236 -406.790556) (xy 47.149194 -406.72373) (xy 43.871156 -406.72373)
			(xy 43.871156 -406.723787) (xy 43.863084 -406.790723) (xy 43.847051 -406.85621) (xy 43.823291 -406.919306)
			(xy 43.792143 -406.979101) (xy 43.754058 -407.034735) (xy 43.732196 -407.0604) (xy 43.726416 -407.067557)
			(xy 43.719892 -407.084739) (xy 43.719496 -407.093928) (xy 43.719496 -407.251408) (xy 43.71909 -407.261531)
			(xy 43.711339 -407.280236) (xy 43.697019 -407.29455) (xy 43.678312 -407.302294) (xy 43.668188 -407.302716)
			(xy 42.951908 -407.302716) (xy 42.941802 -407.302209) (xy 42.923127 -407.294477) (xy 42.908832 -407.280187)
			(xy 42.901094 -407.261514) (xy 42.9006 -407.251408) (xy 42.9006 -407.093928) (xy 42.900176 -407.084742)
			(xy 42.893672 -407.067558) (xy 42.8879 -407.0604) (xy 42.866005 -407.034761) (xy 42.827917 -406.979122)
			(xy 42.796768 -406.919323) (xy 42.773005 -406.856222) (xy 42.756972 -406.79073) (xy 42.748899 -406.723789)
			(xy 39.470854 -406.723789) (xy 39.462819 -406.790549) (xy 39.446848 -406.85593) (xy 39.423176 -406.918933)
			(xy 39.392144 -406.978656) (xy 39.354195 -407.034241) (xy 39.332408 -407.059892) (xy 39.326633 -407.067053)
			(xy 39.320105 -407.084231) (xy 39.319708 -407.09342) (xy 39.319708 -407.251408) (xy 39.319285 -407.261562)
			(xy 39.311488 -407.280313) (xy 39.297092 -407.294635) (xy 39.278302 -407.302336) (xy 39.268146 -407.302716)
			(xy 38.551866 -407.302716) (xy 38.541732 -407.3023) (xy 38.523001 -407.294553) (xy 38.508645 -407.280245)
			(xy 38.500835 -407.261541) (xy 38.500304 -407.251408) (xy 38.500304 -407.09342) (xy 38.499883 -407.084234)
			(xy 38.493377 -407.06705) (xy 38.487604 -407.059892) (xy 38.465786 -407.034265) (xy 38.42784 -406.978674)
			(xy 38.39681 -406.918947) (xy 38.373141 -406.855939) (xy 38.357171 -406.790554) (xy 38.34913 -406.723729)
			(xy 35.071068 -406.723729) (xy 35.071068 -406.723786) (xy 35.062996 -406.790722) (xy 35.046964 -406.856209)
			(xy 35.023204 -406.919305) (xy 34.992058 -406.9791) (xy 34.953974 -407.034735) (xy 34.932112 -407.0604)
			(xy 34.926334 -407.067559) (xy 34.919808 -407.084739) (xy 34.919412 -407.093928) (xy 34.919412 -407.251408)
			(xy 34.918922 -407.261516) (xy 34.911184 -407.280192) (xy 34.896888 -407.294486) (xy 34.878212 -407.302222)
			(xy 34.868104 -407.302716) (xy 34.151824 -407.302716) (xy 34.141705 -407.302265) (xy 34.123005 -407.294528)
			(xy 34.10869 -407.280222) (xy 34.100941 -407.261527) (xy 34.100516 -407.251408) (xy 34.100516 -407.093928)
			(xy 34.100089 -407.084743) (xy 34.093586 -407.067558) (xy 34.087816 -407.0604) (xy 34.06592 -407.034761)
			(xy 34.027831 -406.979123) (xy 33.996681 -406.919323) (xy 33.972918 -406.856223) (xy 33.956884 -406.790731)
			(xy 33.948811 -406.723789) (xy 30.670766 -406.723789) (xy 30.662731 -406.790549) (xy 30.646761 -406.855929)
			(xy 30.62309 -406.918933) (xy 30.592058 -406.978655) (xy 30.554111 -407.03424) (xy 30.532324 -407.059892)
			(xy 30.526551 -407.067054) (xy 30.520022 -407.084232) (xy 30.519624 -407.09342) (xy 30.519624 -407.251408)
			(xy 30.519185 -407.26156) (xy 30.511392 -407.280307) (xy 30.497001 -407.29463) (xy 30.478216 -407.302333)
			(xy 30.468062 -407.302716) (xy 29.751782 -407.302716) (xy 29.741649 -407.302287) (xy 29.722919 -407.294545)
			(xy 29.708561 -407.280241) (xy 29.700751 -407.261539) (xy 29.70022 -407.251408) (xy 29.70022 -407.09342)
			(xy 29.699796 -407.084234) (xy 29.693291 -407.06705) (xy 29.68752 -407.059892) (xy 29.665701 -407.034265)
			(xy 29.627755 -406.978675) (xy 29.596724 -406.918948) (xy 29.573054 -406.85594) (xy 29.557084 -406.790555)
			(xy 29.549042 -406.72373) (xy 11.18442 -406.72373) (xy 11.195631 -406.787312) (xy 11.223232 -406.989386)
			(xy 11.242977 -407.192379) (xy 11.254836 -407.395984) (xy 11.258791 -407.599896) (xy 11.254836 -407.803808)
			(xy 11.242977 -408.007413) (xy 11.223232 -408.210406) (xy 11.195631 -408.41248) (xy 11.160216 -408.613332)
			(xy 11.117039 -408.812659) (xy 11.066165 -409.010163) (xy 11.007672 -409.205545) (xy 10.941646 -409.398512)
			(xy 10.893241 -409.523886) (xy 27.348881 -409.523886) (xy 27.348884 -409.45646) (xy 27.356963 -409.38952)
			(xy 27.373002 -409.324029) (xy 27.396769 -409.26093) (xy 27.427923 -409.201133) (xy 27.466015 -409.145498)
			(xy 27.48788 -409.119832) (xy 27.493686 -409.112693) (xy 27.500196 -409.095498) (xy 27.50058 -409.086304)
			(xy 27.50058 -408.594052) (xy 27.500149 -408.584867) (xy 27.49365 -408.567682) (xy 27.48788 -408.560524)
			(xy 27.466009 -408.534865) (xy 27.427922 -408.479229) (xy 27.396772 -408.419432) (xy 27.37301 -408.356334)
			(xy 27.356975 -408.290845) (xy 27.3489 -408.223906) (xy 27.348901 -408.156482) (xy 27.356977 -408.089544)
			(xy 27.373013 -408.024054) (xy 27.396777 -407.960957) (xy 27.427928 -407.901161) (xy 27.466016 -407.845526)
			(xy 27.48788 -407.81986) (xy 27.493674 -407.812713) (xy 27.500191 -407.795524) (xy 27.50058 -407.786332)
			(xy 27.50058 -407.628852) (xy 27.501045 -407.618743) (xy 27.508795 -407.600067) (xy 27.523098 -407.585775)
			(xy 27.541778 -407.578038) (xy 27.551888 -407.577544) (xy 28.268168 -407.577544) (xy 28.278268 -407.57811)
			(xy 28.296935 -407.585826) (xy 28.311229 -407.600098) (xy 28.318975 -407.618753) (xy 28.319476 -407.628852)
			(xy 28.319476 -407.786332) (xy 28.319876 -407.79552) (xy 28.326397 -407.812704) (xy 28.332176 -407.81986)
			(xy 28.354033 -407.845531) (xy 28.392123 -407.901164) (xy 28.423276 -407.96096) (xy 28.447042 -408.024056)
			(xy 28.463078 -408.089544) (xy 28.471155 -408.156482) (xy 28.471156 -408.223906) (xy 28.46308 -408.290844)
			(xy 28.447045 -408.356333) (xy 28.423281 -408.419429) (xy 28.39213 -408.479225) (xy 28.35404 -408.534859)
			(xy 28.332176 -408.560524) (xy 28.326384 -408.567672) (xy 28.319867 -408.584861) (xy 28.319476 -408.594052)
			(xy 28.319476 -409.086304) (xy 28.319889 -409.095491) (xy 28.326401 -409.112675) (xy 28.332176 -409.119832)
			(xy 28.354005 -409.145526) (xy 28.392097 -409.201156) (xy 28.42325 -409.260948) (xy 28.447018 -409.324041)
			(xy 28.463056 -409.389527) (xy 28.471135 -409.456462) (xy 28.471139 -409.523884) (xy 28.463066 -409.59082)
			(xy 28.447034 -409.656307) (xy 28.423273 -409.719403) (xy 28.392125 -409.779198) (xy 28.354039 -409.834831)
			(xy 28.332176 -409.860496) (xy 28.326396 -409.867653) (xy 28.319872 -409.884835) (xy 28.319476 -409.894024)
			(xy 28.319476 -410.051504) (xy 28.319087 -410.06163) (xy 28.311333 -410.080338) (xy 28.297008 -410.094653)
			(xy 28.278294 -410.102394) (xy 28.268168 -410.102812) (xy 27.551888 -410.102812) (xy 27.54178 -410.102325)
			(xy 27.523104 -410.094585) (xy 27.50881 -410.080289) (xy 27.501074 -410.061612) (xy 27.50058 -410.051504)
			(xy 27.50058 -409.894024) (xy 27.500163 -409.884837) (xy 27.493655 -409.867653) (xy 27.48788 -409.860496)
			(xy 27.465981 -409.83486) (xy 27.427895 -409.77922) (xy 27.396747 -409.71942) (xy 27.372986 -409.656319)
			(xy 27.356953 -409.590827) (xy 27.348881 -409.523886) (xy 10.893241 -409.523886) (xy 10.868188 -409.588774)
			(xy 10.787407 -409.776045) (xy 10.699426 -409.960042) (xy 10.604376 -410.14049) (xy 10.502401 -410.317116)
			(xy 10.393653 -410.489655) (xy 10.301759 -410.623641) (xy 29.549054 -410.623641) (xy 29.549055 -410.556335)
			(xy 29.5571 -410.489512) (xy 29.573074 -410.424129) (xy 29.596748 -410.361124) (xy 29.627782 -410.301399)
			(xy 29.665732 -410.245812) (xy 29.68752 -410.22016) (xy 29.693318 -410.213016) (xy 29.699831 -410.195825)
			(xy 29.70022 -410.186632) (xy 29.70022 -409.693364) (xy 29.699823 -409.684176) (xy 29.6933 -409.666992)
			(xy 29.68752 -409.659836) (xy 29.665745 -409.634174) (xy 29.627797 -409.578588) (xy 29.596764 -409.518866)
			(xy 29.573091 -409.455863) (xy 29.557118 -409.390482) (xy 29.549073 -409.323661) (xy 29.549072 -409.256357)
			(xy 29.557115 -409.189536) (xy 29.573086 -409.124154) (xy 29.596757 -409.06115) (xy 29.627787 -409.001427)
			(xy 29.665734 -408.94584) (xy 29.68752 -408.920188) (xy 29.693306 -408.913036) (xy 29.699827 -408.895851)
			(xy 29.70022 -408.88666) (xy 29.70022 -408.728672) (xy 29.700599 -408.718514) (xy 29.708408 -408.699757)
			(xy 29.722817 -408.685434) (xy 29.741621 -408.677738) (xy 29.751782 -408.677364) (xy 30.468062 -408.677364)
			(xy 30.478189 -408.677859) (xy 30.496914 -408.685578) (xy 30.511272 -408.699863) (xy 30.519089 -408.718547)
			(xy 30.519624 -408.728672) (xy 30.519624 -408.88666) (xy 30.520048 -408.895846) (xy 30.526551 -408.913031)
			(xy 30.532324 -408.920188) (xy 30.554125 -408.94583) (xy 30.592075 -409.001417) (xy 30.62311 -409.061142)
			(xy 30.646784 -409.124148) (xy 30.662757 -409.189531) (xy 30.670801 -409.256356) (xy 30.6708 -409.323662)
			(xy 30.662754 -409.390486) (xy 30.646779 -409.45587) (xy 30.623103 -409.518875) (xy 30.62053 -409.523827)
			(xy 31.749176 -409.523827) (xy 31.749179 -409.456519) (xy 31.757227 -409.389693) (xy 31.773205 -409.324309)
			(xy 31.796883 -409.261302) (xy 31.827922 -409.201578) (xy 31.865877 -409.145992) (xy 31.887668 -409.12034)
			(xy 31.893481 -409.113207) (xy 31.899984 -409.096007) (xy 31.900368 -409.086812) (xy 31.900368 -408.593544)
			(xy 31.899922 -408.584361) (xy 31.893432 -408.567177) (xy 31.887668 -408.560016) (xy 31.865872 -408.534371)
			(xy 31.827921 -408.478784) (xy 31.796887 -408.41906) (xy 31.773213 -408.356054) (xy 31.75724 -408.290671)
			(xy 31.749196 -408.223847) (xy 31.749197 -408.156541) (xy 31.757242 -408.089717) (xy 31.773217 -408.024334)
			(xy 31.796892 -407.961329) (xy 31.827927 -407.901606) (xy 31.865879 -407.84602) (xy 31.887668 -407.820368)
			(xy 31.893469 -407.813226) (xy 31.899979 -407.796033) (xy 31.900368 -407.78684) (xy 31.900368 -407.628852)
			(xy 31.900782 -407.618699) (xy 31.908587 -407.599952) (xy 31.922985 -407.585631) (xy 31.941775 -407.577927)
			(xy 31.95193 -407.577544) (xy 32.66821 -407.577544) (xy 32.678338 -407.578019) (xy 32.69706 -407.58575)
			(xy 32.711416 -407.60004) (xy 32.719234 -407.618727) (xy 32.719772 -407.628852) (xy 32.719772 -407.78684)
			(xy 32.720169 -407.796028) (xy 32.726693 -407.813212) (xy 32.732472 -407.820368) (xy 32.754252 -407.846027)
			(xy 32.7922 -407.901612) (xy 32.823233 -407.961335) (xy 32.846906 -408.024339) (xy 32.862879 -408.08972)
			(xy 32.870924 -408.156542) (xy 32.870924 -408.223846) (xy 32.862881 -408.290668) (xy 32.846909 -408.35605)
			(xy 32.823238 -408.419054) (xy 32.792206 -408.478777) (xy 32.754259 -408.534364) (xy 32.732472 -408.560016)
			(xy 32.726682 -408.567166) (xy 32.720164 -408.584353) (xy 32.719772 -408.593544) (xy 32.719772 -409.086812)
			(xy 32.720183 -409.095999) (xy 32.726697 -409.113183) (xy 32.732472 -409.12034) (xy 32.754224 -409.146022)
			(xy 32.792173 -409.201604) (xy 32.823207 -409.261324) (xy 32.846881 -409.324324) (xy 32.862857 -409.389703)
			(xy 32.870903 -409.456522) (xy 32.870907 -409.523824) (xy 32.862866 -409.590644) (xy 32.846897 -409.656024)
			(xy 32.823229 -409.719027) (xy 32.792201 -409.778749) (xy 32.754257 -409.834336) (xy 32.732472 -409.859988)
			(xy 32.726652 -409.867116) (xy 32.720152 -409.88432) (xy 32.719772 -409.893516) (xy 32.719772 -410.051504)
			(xy 32.719381 -410.061662) (xy 32.711579 -410.08042) (xy 32.697172 -410.094744) (xy 32.67837 -410.102438)
			(xy 32.66821 -410.102812) (xy 31.95193 -410.102812) (xy 31.941812 -410.102251) (xy 31.923101 -410.094542)
			(xy 31.908745 -410.080279) (xy 31.900916 -410.061619) (xy 31.900368 -410.051504) (xy 31.900368 -409.893516)
			(xy 31.899935 -409.884332) (xy 31.893436 -409.867148) (xy 31.887668 -409.859988) (xy 31.865844 -409.834366)
			(xy 31.827894 -409.778775) (xy 31.796861 -409.719048) (xy 31.773189 -409.65604) (xy 31.757217 -409.590654)
			(xy 31.749176 -409.523827) (xy 30.62053 -409.523827) (xy 30.592066 -409.578598) (xy 30.554113 -409.634184)
			(xy 30.532324 -409.659836) (xy 30.526532 -409.666985) (xy 30.520014 -409.684172) (xy 30.519624 -409.693364)
			(xy 30.519624 -410.186632) (xy 30.520014 -410.195821) (xy 30.526541 -410.213006) (xy 30.532324 -410.22016)
			(xy 30.554097 -410.245825) (xy 30.592049 -410.301408) (xy 30.623085 -410.36113) (xy 30.64676 -410.424133)
			(xy 30.662735 -410.489514) (xy 30.670781 -410.556336) (xy 30.670783 -410.62364) (xy 30.670776 -410.623701)
			(xy 33.948822 -410.623701) (xy 33.948823 -410.556275) (xy 33.956901 -410.489336) (xy 33.972939 -410.423846)
			(xy 33.996705 -410.360748) (xy 34.027859 -410.300951) (xy 34.065951 -410.245317) (xy 34.087816 -410.219652)
			(xy 34.093617 -410.21251) (xy 34.100129 -410.195317) (xy 34.100516 -410.186124) (xy 34.100516 -409.693872)
			(xy 34.100116 -409.684684) (xy 34.093595 -409.6675) (xy 34.087816 -409.660344) (xy 34.065963 -409.634669)
			(xy 34.027873 -409.579037) (xy 33.996721 -409.519242) (xy 33.972955 -409.456146) (xy 33.956919 -409.390658)
			(xy 33.948842 -409.323721) (xy 33.948841 -409.256297) (xy 33.956915 -409.18936) (xy 33.97295 -409.123871)
			(xy 33.996714 -409.060775) (xy 34.027864 -409.000979) (xy 34.065952 -408.945345) (xy 34.087816 -408.91968)
			(xy 34.093605 -408.91253) (xy 34.100124 -408.895343) (xy 34.100516 -408.886152) (xy 34.100516 -408.728672)
			(xy 34.100962 -408.718559) (xy 34.108712 -408.699878) (xy 34.123021 -408.685583) (xy 34.141711 -408.677852)
			(xy 34.151824 -408.677364) (xy 34.868104 -408.677364) (xy 34.878209 -408.677881) (xy 34.89688 -408.685613)
			(xy 34.911173 -408.6999) (xy 34.918914 -408.718568) (xy 34.919412 -408.728672) (xy 34.919412 -408.886152)
			(xy 34.919842 -408.895337) (xy 34.926342 -408.912522) (xy 34.932112 -408.91968) (xy 34.953987 -408.945336)
			(xy 34.992075 -409.000972) (xy 35.023224 -409.06077) (xy 35.046987 -409.123868) (xy 35.063022 -409.189358)
			(xy 35.071096 -409.256297) (xy 35.071095 -409.323721) (xy 35.063018 -409.39066) (xy 35.046982 -409.45615)
			(xy 35.023217 -409.519247) (xy 35.0208 -409.523886) (xy 36.148969 -409.523886) (xy 36.148972 -409.45646)
			(xy 36.157051 -409.38952) (xy 36.173089 -409.324029) (xy 36.196856 -409.260931) (xy 36.228009 -409.201134)
			(xy 36.266099 -409.145498) (xy 36.287964 -409.119832) (xy 36.29378 -409.112701) (xy 36.300281 -409.095499)
			(xy 36.300664 -409.086304) (xy 36.300664 -408.594052) (xy 36.300215 -408.584869) (xy 36.293727 -408.567685)
			(xy 36.287964 -408.560524) (xy 36.266093 -408.534865) (xy 36.228007 -408.479228) (xy 36.196859 -408.419431)
			(xy 36.173097 -408.356334) (xy 36.157063 -408.290844) (xy 36.148988 -408.223906) (xy 36.148989 -408.156482)
			(xy 36.157065 -408.089544) (xy 36.1731 -408.024055) (xy 36.196864 -407.960958) (xy 36.228014 -407.901161)
			(xy 36.266101 -407.845526) (xy 36.287964 -407.81986) (xy 36.293768 -407.81272) (xy 36.300276 -407.795525)
			(xy 36.300664 -407.786332) (xy 36.300664 -407.628852) (xy 36.301145 -407.618745) (xy 36.308892 -407.600072)
			(xy 36.323189 -407.585781) (xy 36.341864 -407.578041) (xy 36.351972 -407.577544) (xy 37.068252 -407.577544)
			(xy 37.078351 -407.578123) (xy 37.097017 -407.585835) (xy 37.111312 -407.600102) (xy 37.119058 -407.618754)
			(xy 37.11956 -407.628852) (xy 37.11956 -407.786332) (xy 37.119964 -407.79552) (xy 37.126483 -407.812703)
			(xy 37.13226 -407.81986) (xy 37.154118 -407.845531) (xy 37.192209 -407.901164) (xy 37.223362 -407.960959)
			(xy 37.247129 -408.024055) (xy 37.263166 -408.089544) (xy 37.271243 -408.156482) (xy 37.271244 -408.223906)
			(xy 37.263168 -408.290844) (xy 37.247132 -408.356333) (xy 37.223367 -408.41943) (xy 37.192215 -408.479226)
			(xy 37.154125 -408.534859) (xy 37.13226 -408.560524) (xy 37.126466 -408.567671) (xy 37.119951 -408.58486)
			(xy 37.11956 -408.594052) (xy 37.11956 -409.086304) (xy 37.119977 -409.09549) (xy 37.126487 -409.112674)
			(xy 37.13226 -409.119832) (xy 37.15409 -409.145526) (xy 37.192182 -409.201155) (xy 37.223337 -409.260947)
			(xy 37.247105 -409.32404) (xy 37.263144 -409.389526) (xy 37.271223 -409.456462) (xy 37.271227 -409.523884)
			(xy 37.263154 -409.59082) (xy 37.247121 -409.656308) (xy 37.223359 -409.719403) (xy 37.19221 -409.779198)
			(xy 37.154123 -409.834831) (xy 37.13226 -409.860496) (xy 37.126478 -409.867651) (xy 37.119955 -409.884834)
			(xy 37.11956 -409.894024) (xy 37.11956 -410.051504) (xy 37.119186 -410.061632) (xy 37.111429 -410.080343)
			(xy 37.097099 -410.094659) (xy 37.07838 -410.102396) (xy 37.068252 -410.102812) (xy 36.351972 -410.102812)
			(xy 36.341863 -410.102338) (xy 36.323186 -410.094594) (xy 36.308893 -410.080293) (xy 36.301157 -410.061613)
			(xy 36.300664 -410.051504) (xy 36.300664 -409.894024) (xy 36.300228 -409.88484) (xy 36.293731 -409.867656)
			(xy 36.287964 -409.860496) (xy 36.266066 -409.834859) (xy 36.227981 -409.77922) (xy 36.196834 -409.719419)
			(xy 36.173073 -409.656319) (xy 36.157041 -409.590827) (xy 36.148969 -409.523886) (xy 35.0208 -409.523886)
			(xy 34.992066 -409.579044) (xy 34.953976 -409.634679) (xy 34.932112 -409.660344) (xy 34.926316 -409.667489)
			(xy 34.9198 -409.68468) (xy 34.919412 -409.693872) (xy 34.919412 -410.186124) (xy 34.919808 -410.195313)
			(xy 34.926331 -410.212497) (xy 34.932112 -410.219652) (xy 34.95396 -410.24533) (xy 34.992048 -410.300963)
			(xy 35.023199 -410.360758) (xy 35.046964 -410.423853) (xy 35.063 -410.48934) (xy 35.071077 -410.556277)
			(xy 35.071078 -410.623641) (xy 38.349141 -410.623641) (xy 38.349143 -410.556335) (xy 38.357188 -410.489512)
			(xy 38.373162 -410.424129) (xy 38.396835 -410.361124) (xy 38.427868 -410.3014) (xy 38.465816 -410.245813)
			(xy 38.487604 -410.22016) (xy 38.493401 -410.213015) (xy 38.499915 -410.195824) (xy 38.500304 -410.186632)
			(xy 38.500304 -409.693364) (xy 38.49991 -409.684175) (xy 38.493385 -409.666991) (xy 38.487604 -409.659836)
			(xy 38.465829 -409.634174) (xy 38.427882 -409.578588) (xy 38.39685 -409.518865) (xy 38.373178 -409.455862)
			(xy 38.357206 -409.390482) (xy 38.349161 -409.323661) (xy 38.34916 -409.256357) (xy 38.357202 -409.189536)
			(xy 38.373173 -409.124155) (xy 38.396843 -409.061151) (xy 38.427873 -409.001428) (xy 38.465818 -408.945841)
			(xy 38.487604 -408.920188) (xy 38.493389 -408.913034) (xy 38.49991 -408.89585) (xy 38.500304 -408.88666)
			(xy 38.500304 -408.728672) (xy 38.500699 -408.718516) (xy 38.508504 -408.699762) (xy 38.522909 -408.685439)
			(xy 38.541707 -408.677741) (xy 38.551866 -408.677364) (xy 39.268146 -408.677364) (xy 39.278279 -408.67779)
			(xy 39.297005 -408.685537) (xy 39.311361 -408.699842) (xy 39.319174 -408.718541) (xy 39.319708 -408.728672)
			(xy 39.319708 -408.88666) (xy 39.320136 -408.895845) (xy 39.326637 -408.91303) (xy 39.332408 -408.920188)
			(xy 39.354209 -408.94583) (xy 39.392161 -409.001416) (xy 39.423197 -409.061141) (xy 39.446871 -409.124147)
			(xy 39.462845 -409.189531) (xy 39.470889 -409.256356) (xy 39.470888 -409.323663) (xy 39.462842 -409.390487)
			(xy 39.446866 -409.45587) (xy 39.423189 -409.518876) (xy 39.420585 -409.523887) (xy 40.548735 -409.523887)
			(xy 40.548738 -409.456459) (xy 40.556818 -409.389518) (xy 40.572859 -409.324026) (xy 40.59663 -409.260927)
			(xy 40.627788 -409.20113) (xy 40.665884 -409.145496) (xy 40.687752 -409.119832) (xy 40.693566 -409.1127)
			(xy 40.700069 -409.095499) (xy 40.700452 -409.086304) (xy 40.700452 -408.594052) (xy 40.700005 -408.584869)
			(xy 40.693516 -408.567685) (xy 40.687752 -408.560524) (xy 40.665878 -408.534866) (xy 40.627786 -408.479232)
			(xy 40.596633 -408.419435) (xy 40.572867 -408.356337) (xy 40.556831 -408.290847) (xy 40.548755 -408.223907)
			(xy 40.548755 -408.156481) (xy 40.556833 -408.089542) (xy 40.572871 -408.024051) (xy 40.596638 -407.960954)
			(xy 40.627793 -407.901158) (xy 40.665886 -407.845524) (xy 40.687752 -407.81986) (xy 40.693554 -407.812719)
			(xy 40.700064 -407.795525) (xy 40.700452 -407.786332) (xy 40.700452 -407.628852) (xy 40.700945 -407.618746)
			(xy 40.708689 -407.600076) (xy 40.722983 -407.585785) (xy 40.741654 -407.578043) (xy 40.75176 -407.577544)
			(xy 41.46804 -407.577544) (xy 41.478144 -407.578051) (xy 41.496813 -407.585791) (xy 41.511104 -407.600081)
			(xy 41.518847 -407.618748) (xy 41.519348 -407.628852) (xy 41.519348 -407.786332) (xy 41.519755 -407.795519)
			(xy 41.526272 -407.812703) (xy 41.532048 -407.81986) (xy 41.553906 -407.845531) (xy 41.591998 -407.901163)
			(xy 41.623152 -407.960958) (xy 41.646919 -408.024055) (xy 41.662957 -408.089543) (xy 41.671034 -408.156482)
			(xy 41.671035 -408.223906) (xy 41.662959 -408.290845) (xy 41.646923 -408.356334) (xy 41.623157 -408.419431)
			(xy 41.592004 -408.479226) (xy 41.553913 -408.53486) (xy 41.532048 -408.560524) (xy 41.526252 -408.56767)
			(xy 41.519739 -408.58486) (xy 41.519348 -408.594052) (xy 41.519348 -409.086304) (xy 41.519768 -409.09549)
			(xy 41.526276 -409.112674) (xy 41.532048 -409.119832) (xy 41.553878 -409.145526) (xy 41.591972 -409.201155)
			(xy 41.623127 -409.260947) (xy 41.646895 -409.32404) (xy 41.662935 -409.389526) (xy 41.671014 -409.456462)
			(xy 41.671018 -409.523884) (xy 41.662945 -409.590821) (xy 41.646911 -409.656308) (xy 41.623149 -409.719404)
			(xy 41.591999 -409.779199) (xy 41.553912 -409.834832) (xy 41.532048 -409.860496) (xy 41.526264 -409.86765)
			(xy 41.519743 -409.884834) (xy 41.519348 -409.894024) (xy 41.519348 -410.051504) (xy 41.518819 -410.061607)
			(xy 41.511089 -410.080276) (xy 41.496806 -410.094569) (xy 41.478143 -410.102312) (xy 41.46804 -410.102812)
			(xy 40.75176 -410.102812) (xy 40.74165 -410.102348) (xy 40.722973 -410.094599) (xy 40.70868 -410.080296)
			(xy 40.700945 -410.061614) (xy 40.700452 -410.051504) (xy 40.700452 -409.894024) (xy 40.700019 -409.884839)
			(xy 40.69352 -409.867655) (xy 40.687752 -409.860496) (xy 40.665851 -409.834861) (xy 40.62776 -409.779223)
			(xy 40.596608 -409.719423) (xy 40.572843 -409.656322) (xy 40.556809 -409.590829) (xy 40.548735 -409.523887)
			(xy 39.420585 -409.523887) (xy 39.392152 -409.578599) (xy 39.354198 -409.634185) (xy 39.332408 -409.659836)
			(xy 39.326615 -409.666984) (xy 39.320098 -409.684172) (xy 39.319708 -409.693364) (xy 39.319708 -410.186632)
			(xy 39.320101 -410.195821) (xy 39.326626 -410.213005) (xy 39.332408 -410.22016) (xy 39.354182 -410.245824)
			(xy 39.392134 -410.301408) (xy 39.423171 -410.361129) (xy 39.446847 -410.424132) (xy 39.462823 -410.489513)
			(xy 39.470869 -410.556336) (xy 39.470871 -410.62364) (xy 39.470864 -410.6237) (xy 42.74891 -410.6237)
			(xy 42.748911 -410.556276) (xy 42.756989 -410.489336) (xy 42.773026 -410.423846) (xy 42.796792 -410.360749)
			(xy 42.827944 -410.300952) (xy 42.866035 -410.245317) (xy 42.8879 -410.219652) (xy 42.893699 -410.212509)
			(xy 42.900212 -410.195317) (xy 42.9006 -410.186124) (xy 42.9006 -409.693872) (xy 42.900204 -409.684683)
			(xy 42.89368 -409.667499) (xy 42.8879 -409.660344) (xy 42.866048 -409.634669) (xy 42.827959 -409.579036)
			(xy 42.796808 -409.519241) (xy 42.773043 -409.456145) (xy 42.757006 -409.390658) (xy 42.74893 -409.32372)
			(xy 42.748928 -409.256298) (xy 42.757003 -409.18936) (xy 42.773037 -409.123872) (xy 42.7968 -409.060775)
			(xy 42.827949 -409.00098) (xy 42.866037 -408.945345) (xy 42.8879 -408.91968) (xy 42.893688 -408.912528)
			(xy 42.900208 -408.895343) (xy 42.9006 -408.886152) (xy 42.9006 -408.728672) (xy 42.901062 -408.718561)
			(xy 42.908809 -408.699883) (xy 42.923113 -408.685589) (xy 42.941797 -408.677855) (xy 42.951908 -408.677364)
			(xy 43.668188 -408.677364) (xy 43.678292 -408.677894) (xy 43.696963 -408.685621) (xy 43.711257 -408.699904)
			(xy 43.718998 -408.718569) (xy 43.719496 -408.728672) (xy 43.719496 -408.886152) (xy 43.71993 -408.895337)
			(xy 43.726427 -408.912521) (xy 43.732196 -408.91968) (xy 43.754072 -408.945335) (xy 43.792161 -409.000971)
			(xy 43.823311 -409.060769) (xy 43.847075 -409.123867) (xy 43.863109 -409.189357) (xy 43.871184 -409.256297)
			(xy 43.871183 -409.323721) (xy 43.863106 -409.390661) (xy 43.847069 -409.45615) (xy 43.823304 -409.519248)
			(xy 43.792151 -409.579044) (xy 43.754061 -409.634679) (xy 43.732196 -409.660344) (xy 43.726398 -409.667488)
			(xy 43.719884 -409.684679) (xy 43.719496 -409.693872) (xy 43.719496 -410.186124) (xy 43.719895 -410.195312)
			(xy 43.726417 -410.212497) (xy 43.732196 -410.219652) (xy 43.754044 -410.24533) (xy 43.792134 -410.300963)
			(xy 43.823285 -410.360757) (xy 43.847051 -410.423852) (xy 43.863087 -410.48934) (xy 43.871165 -410.556277)
			(xy 43.871166 -410.623642) (xy 47.149205 -410.623642) (xy 47.149207 -410.556334) (xy 47.157253 -410.48951)
			(xy 47.173229 -410.424126) (xy 47.196906 -410.361121) (xy 47.227944 -410.301397) (xy 47.265898 -410.245812)
			(xy 47.287688 -410.22016) (xy 47.293483 -410.213013) (xy 47.299999 -410.195824) (xy 47.300388 -410.186632)
			(xy 47.300388 -409.693364) (xy 47.299998 -409.684175) (xy 47.293471 -409.66699) (xy 47.287688 -409.659836)
			(xy 47.265911 -409.634175) (xy 47.227958 -409.578591) (xy 47.196922 -409.518869) (xy 47.173246 -409.455866)
			(xy 47.157271 -409.390484) (xy 47.149225 -409.323662) (xy 47.149224 -409.256357) (xy 47.157268 -409.189534)
			(xy 47.173241 -409.124152) (xy 47.196914 -409.061148) (xy 47.227949 -409.001425) (xy 47.2659 -408.945839)
			(xy 47.287688 -408.920188) (xy 47.293471 -408.913033) (xy 47.299994 -408.89585) (xy 47.300388 -408.88666)
			(xy 47.300388 -408.728672) (xy 47.300798 -408.718518) (xy 47.308601 -408.699767) (xy 47.323001 -408.685445)
			(xy 47.341793 -408.677744) (xy 47.35195 -408.677364) (xy 48.06823 -408.677364) (xy 48.078362 -408.677803)
			(xy 48.097088 -408.685545) (xy 48.111444 -408.699846) (xy 48.119258 -408.718542) (xy 48.119792 -408.728672)
			(xy 48.119792 -408.88666) (xy 48.120223 -408.895845) (xy 48.126722 -408.913029) (xy 48.132492 -408.920188)
			(xy 48.154291 -408.945831) (xy 48.192237 -409.001419) (xy 48.223268 -409.061145) (xy 48.246939 -409.12415)
			(xy 48.26291 -409.189533) (xy 48.270953 -409.256356) (xy 48.270952 -409.323662) (xy 48.262907 -409.390485)
			(xy 48.246933 -409.455867) (xy 48.223261 -409.518872) (xy 48.192228 -409.578596) (xy 48.15428 -409.634183)
			(xy 48.132492 -409.659836) (xy 48.126697 -409.666982) (xy 48.120182 -409.684172) (xy 48.119792 -409.693364)
			(xy 48.119792 -410.186632) (xy 48.120188 -410.195821) (xy 48.126712 -410.213005) (xy 48.132492 -410.22016)
			(xy 48.154263 -410.245825) (xy 48.19221 -410.301411) (xy 48.223243 -410.361133) (xy 48.246915 -410.424135)
			(xy 48.262888 -410.489516) (xy 48.270933 -410.556336) (xy 48.270934 -410.62364) (xy 48.262892 -410.690461)
			(xy 48.246922 -410.755842) (xy 48.223252 -410.818845) (xy 48.192223 -410.878569) (xy 48.154278 -410.934155)
			(xy 48.132492 -410.959808) (xy 48.126709 -410.966963) (xy 48.120186 -410.984146) (xy 48.119792 -410.993336)
			(xy 48.119792 -411.151324) (xy 48.119398 -411.161481) (xy 48.111593 -411.180235) (xy 48.097188 -411.194558)
			(xy 48.078389 -411.202255) (xy 48.06823 -411.202632) (xy 47.35195 -411.202632) (xy 47.341823 -411.202132)
			(xy 47.323098 -411.194415) (xy 47.308739 -411.180132) (xy 47.300923 -411.161448) (xy 47.300388 -411.151324)
			(xy 47.300388 -410.993336) (xy 47.299963 -410.98415) (xy 47.29346 -410.966966) (xy 47.287688 -410.959808)
			(xy 47.265883 -410.934169) (xy 47.227932 -410.878582) (xy 47.196896 -410.818857) (xy 47.173222 -410.755851)
			(xy 47.157249 -410.690466) (xy 47.149205 -410.623642) (xy 43.871166 -410.623642) (xy 43.871166 -410.623699)
			(xy 43.863092 -410.690636) (xy 43.847058 -410.756125) (xy 43.823295 -410.819221) (xy 43.792146 -410.879017)
			(xy 43.754059 -410.934651) (xy 43.732196 -410.960316) (xy 43.72641 -410.967468) (xy 43.719889 -410.984653)
			(xy 43.719496 -410.993844) (xy 43.719496 -411.151324) (xy 43.719035 -411.161435) (xy 43.711288 -411.180114)
			(xy 43.696984 -411.194408) (xy 43.678299 -411.202142) (xy 43.668188 -411.202632) (xy 42.951908 -411.202632)
			(xy 42.941804 -411.202109) (xy 42.923132 -411.19438) (xy 42.908838 -411.180095) (xy 42.901097 -411.161428)
			(xy 42.9006 -411.151324) (xy 42.9006 -410.993844) (xy 42.900169 -410.984659) (xy 42.89367 -410.967474)
			(xy 42.8879 -410.960316) (xy 42.86602 -410.934664) (xy 42.827932 -410.879027) (xy 42.796782 -410.819229)
			(xy 42.773019 -410.756131) (xy 42.756984 -410.69064) (xy 42.74891 -410.6237) (xy 39.470864 -410.6237)
			(xy 39.462827 -410.690463) (xy 39.446854 -410.755845) (xy 39.423181 -410.818849) (xy 39.392147 -410.878572)
			(xy 39.354196 -410.934157) (xy 39.332408 -410.959808) (xy 39.326626 -410.966964) (xy 39.320103 -410.984146)
			(xy 39.319708 -410.993336) (xy 39.319708 -411.151324) (xy 39.319298 -411.161479) (xy 39.311496 -411.18023)
			(xy 39.297096 -411.194552) (xy 39.278303 -411.202253) (xy 39.268146 -411.202632) (xy 38.551866 -411.202632)
			(xy 38.541734 -411.202201) (xy 38.523006 -411.194456) (xy 38.50865 -411.180153) (xy 38.500837 -411.161454)
			(xy 38.500304 -411.151324) (xy 38.500304 -410.993336) (xy 38.499876 -410.984151) (xy 38.493375 -410.966966)
			(xy 38.487604 -410.959808) (xy 38.465802 -410.934168) (xy 38.427856 -410.878579) (xy 38.396825 -410.818854)
			(xy 38.373155 -410.755848) (xy 38.357184 -410.690464) (xy 38.349141 -410.623641) (xy 35.071078 -410.623641)
			(xy 35.071078 -410.623699) (xy 35.063004 -410.690636) (xy 35.046971 -410.756124) (xy 35.023209 -410.81922)
			(xy 34.992061 -410.879016) (xy 34.953975 -410.934651) (xy 34.932112 -410.960316) (xy 34.926328 -410.96747)
			(xy 34.919805 -410.984654) (xy 34.919412 -410.993844) (xy 34.919412 -411.151324) (xy 34.918935 -411.161433)
			(xy 34.911192 -411.180109) (xy 34.896893 -411.194403) (xy 34.878213 -411.202139) (xy 34.868104 -411.202632)
			(xy 34.151824 -411.202632) (xy 34.141721 -411.202096) (xy 34.123049 -411.194372) (xy 34.108755 -411.180091)
			(xy 34.101013 -411.161427) (xy 34.100516 -411.151324) (xy 34.100516 -410.993844) (xy 34.100081 -410.98466)
			(xy 34.093584 -410.967475) (xy 34.087816 -410.960316) (xy 34.065936 -410.934664) (xy 34.027846 -410.879028)
			(xy 33.996696 -410.81923) (xy 33.972932 -410.756131) (xy 33.956897 -410.690641) (xy 33.948822 -410.623701)
			(xy 30.670776 -410.623701) (xy 30.66274 -410.690462) (xy 30.646767 -410.755844) (xy 30.623095 -410.818848)
			(xy 30.592061 -410.878571) (xy 30.554112 -410.934156) (xy 30.532324 -410.959808) (xy 30.526544 -410.966965)
			(xy 30.520019 -410.984146) (xy 30.519624 -410.993336) (xy 30.519624 -411.151324) (xy 30.519199 -411.161477)
			(xy 30.5114 -411.180225) (xy 30.497005 -411.194547) (xy 30.478217 -411.20225) (xy 30.468062 -411.202632)
			(xy 29.751782 -411.202632) (xy 29.741651 -411.202188) (xy 29.722924 -411.194449) (xy 29.708567 -411.180149)
			(xy 29.700753 -411.161453) (xy 29.70022 -411.151324) (xy 29.70022 -410.993336) (xy 29.699788 -410.984151)
			(xy 29.693289 -410.966967) (xy 29.68752 -410.959808) (xy 29.665717 -410.934169) (xy 29.62777 -410.87858)
			(xy 29.596738 -410.818854) (xy 29.573067 -410.755848) (xy 29.557096 -410.690465) (xy 29.549054 -410.623641)
			(xy 10.301759 -410.623641) (xy 10.278298 -410.657848) (xy 10.156507 -410.821441) (xy 10.028464 -410.980189)
			(xy 9.894363 -411.133853) (xy 9.754403 -411.282201) (xy 9.608797 -411.42501) (xy 9.457763 -411.562067)
			(xy 9.301528 -411.693163) (xy 9.140327 -411.818103) (xy 8.974403 -411.936699) (xy 8.804005 -412.048772)
			(xy 8.629389 -412.154153) (xy 8.450819 -412.252684) (xy 8.268562 -412.344216) (xy 8.082893 -412.428613)
			(xy 7.894092 -412.505747) (xy 7.702441 -412.575502) (xy 7.50823 -412.637774) (xy 7.31175 -412.692468)
			(xy 7.113297 -412.739502) (xy 6.913169 -412.778805) (xy 6.711669 -412.81032) (xy 6.509097 -412.833997)
			(xy 6.30576 -412.849801) (xy 6.101963 -412.85771) (xy 5.999988 -412.858204) (xy 5.99948 -412.858204)
			(xy 5.894904 -412.857685) (xy 5.685917 -412.849357) (xy 5.477427 -412.832726) (xy 5.269763 -412.807817)
			(xy 5.063254 -412.774672) (xy 4.858226 -412.733341) (xy 4.655003 -412.68389) (xy 4.453908 -412.626398)
			(xy 4.255257 -412.560955) (xy 4.059366 -412.487665) (xy 3.866544 -412.406644) (xy 3.677096 -412.31802)
			(xy 3.491322 -412.221933) (xy 3.309516 -412.118536) (xy 3.131964 -412.00799) (xy 2.958949 -411.890473)
			(xy 2.790743 -411.766169) (xy 2.627613 -411.635274) (xy 2.469816 -411.497997) (xy 2.317603 -411.354554)
			(xy 2.171214 -411.205172) (xy 2.030881 -411.050088) (xy 1.896825 -410.889546) (xy 1.769258 -410.7238)
			(xy 1.708404 -410.638752) (xy 1.698752 -410.625036) (xy 1.66751 -410.614622) (xy 1.559306 -410.649166)
			(xy 1.549303 -410.652979) (xy 1.533375 -410.667242) (xy 1.5246 -410.686739) (xy 1.524 -410.697426)
			(xy 1.524 -416.589972) (xy 1.52451 -416.621137) (xy 1.532646 -416.682934) (xy 1.548778 -416.74314)
			(xy 1.572631 -416.800725) (xy 1.603796 -416.854705) (xy 1.64174 -416.904155) (xy 1.685814 -416.948229)
			(xy 1.735263 -416.986173) (xy 1.789243 -417.017338) (xy 1.846828 -417.041191) (xy 1.907034 -417.057324)
			(xy 1.968831 -417.06546) (xy 1.999996 -417.065968)
		)
		(stroke
			(width 0)
			(type solid)
		)
		(fill yes)
		(layer "In3.Cu")
		(net "P12V_AUX")
	)
	(gr_line
		(start 0.066802 -368.68354)
		(end 0.178054 -368.794792)
		(stroke
			(width 0.508)
			(type default)
		)
		(layer "In3.Cu")
	)
	(gr_line
		(start 0.066802 -368.322352)
		(end 0.066802 -368.68354)
		(stroke
			(width 0.508)
			(type default)
		)
		(layer "In3.Cu")
	)
	(gr_line
		(start 0.122174 -368.26698)
		(end 0.066802 -368.322352)
		(stroke
			(width 0.508)
			(type default)
		)
		(layer "In3.Cu")
	)
	(gr_line
		(start 0.122174 -368.26698)
		(end 204.102208 -368.26698)
		(stroke
			(width 0.635)
			(type default)
		)
		(layer "In3.Cu")
	)
	(gr_line
		(start 0.178054 -368.794792)
		(end 0.539242 -368.433604)
		(stroke
			(width 0.508)
			(type default)
		)
		(layer "In3.Cu")
	)
	(gr_line
		(start 0.289306 -367.961164)
		(end 0.011176 -367.961164)
		(stroke
			(width 0.508)
			(type default)
		)
		(layer "In3.Cu")
	)
	(gr_line
		(start 0.539242 -368.433604)
		(end 0.539242 -368.2111)
		(stroke
			(width 0.508)
			(type default)
		)
		(layer "In3.Cu")
	)
	(gr_line
		(start 0.539242 -368.2111)
		(end 0.289306 -367.961164)
		(stroke
			(width 0.508)
			(type default)
		)
		(layer "In3.Cu")
	)
	(gr_arc
		(start 0.585724 -245.074186)
		(mid 0.152244 -245.723085)
		(end 0 -246.488458)
		(stroke
			(width 3.048)
			(type default)
		)
		(layer "In3.Cu")
	)
	(gr_line
		(start 0.585724 -245.074186)
		(end 3.214116 -242.445794)
		(stroke
			(width 3.048)
			(type default)
		)
		(layer "In3.Cu")
	)
	(gr_arc
		(start 1.999996 0)
		(mid 0.585785 -0.585785)
		(end 0 -1.999996)
		(stroke
			(width 3.048)
			(type default)
		)
		(layer "In3.Cu")
	)
	(gr_line
		(start 1.999996 0)
		(end 5.964936 0)
		(stroke
			(width 3.048)
			(type default)
		)
		(layer "In3.Cu")
	)
	(gr_arc
		(start 3.214116 -242.445794)
		(mid 3.647762 -241.796936)
		(end 3.800094 -241.031522)
		(stroke
			(width 3.048)
			(type default)
		)
		(layer "In3.Cu")
	)
	(gr_line
		(start 3.214116 -86.174326)
		(end 0.585724 -83.54568)
		(stroke
			(width 3.048)
			(type default)
		)
		(layer "In3.Cu")
	)
	(gr_circle
		(center 3.499866 -311.410096)
		(end 5.607812 -311.410096)
		(stroke
			(width 0.2)
			(type default)
		)
		(fill no)
		(layer "In3.Cu")
	)
	(gr_line
		(start 3.800094 -241.031522)
		(end 3.800094 -87.588344)
		(stroke
			(width 3.048)
			(type default)
		)
		(layer "In3.Cu")
	)
	(gr_arc
		(start 3.800094 -87.588344)
		(mid 3.647755 -86.823047)
		(end 3.214116 -86.174326)
		(stroke
			(width 3.048)
			(type default)
		)
		(layer "In3.Cu")
	)
	(gr_line
		(start 5.199888 -400.699986)
		(end 6.800088 -400.699986)
		(stroke
			(width 0.2)
			(type default)
		)
		(layer "In3.Cu")
	)
	(gr_arc
		(start 5.199888 -395.500098)
		(mid 2.599944 -398.100042)
		(end 5.199888 -400.699986)
		(stroke
			(width 0.2)
			(type default)
		)
		(layer "In3.Cu")
	)
	(gr_circle
		(center 5.999988 -407.599896)
		(end 11.174984 -407.599896)
		(stroke
			(width 0.2)
			(type default)
		)
		(fill no)
		(layer "In3.Cu")
	)
	(gr_arc
		(start 6.800088 -400.699986)
		(mid 9.400032 -398.100042)
		(end 6.800088 -395.500098)
		(stroke
			(width 0.2)
			(type default)
		)
		(layer "In3.Cu")
	)
	(gr_line
		(start 6.800088 -395.500098)
		(end 5.199888 -395.500098)
		(stroke
			(width 0.2)
			(type default)
		)
		(layer "In3.Cu")
	)
	(gr_arc
		(start 7.964932 -11.850116)
		(mid 8.257825 -12.557221)
		(end 8.96493 -12.850114)
		(stroke
			(width 3.048)
			(type default)
		)
		(layer "In3.Cu")
	)
	(gr_arc
		(start 7.964932 -1.999996)
		(mid 7.379145 -0.585789)
		(end 5.964936 0)
		(stroke
			(width 3.048)
			(type default)
		)
		(layer "In3.Cu")
	)
	(gr_line
		(start 7.964932 -1.999996)
		(end 7.964932 -11.850116)
		(stroke
			(width 3.048)
			(type default)
		)
		(layer "In3.Cu")
	)
	(gr_line
		(start 8.96493 -12.850114)
		(end 16.964914 -12.850114)
		(stroke
			(width 3.048)
			(type default)
		)
		(layer "In3.Cu")
	)
	(gr_circle
		(center 15.80007 -194.360038)
		(end 20.975066 -194.360038)
		(stroke
			(width 0.2)
			(type default)
		)
		(fill no)
		(layer "In3.Cu")
	)
	(gr_arc
		(start 16.964914 -12.850114)
		(mid 17.672019 -12.557221)
		(end 17.964912 -11.850116)
		(stroke
			(width 3.048)
			(type default)
		)
		(layer "In3.Cu")
	)
	(gr_line
		(start 17.964912 -11.850116)
		(end 17.964912 -1.999996)
		(stroke
			(width 3.048)
			(type default)
		)
		(layer "In3.Cu")
	)
	(gr_circle
		(center 18.800064 -84.699856)
		(end 23.97506 -84.699856)
		(stroke
			(width 0.2)
			(type default)
		)
		(fill no)
		(layer "In3.Cu")
	)
	(gr_arc
		(start 19.964908 0)
		(mid 18.550691 -0.585782)
		(end 17.964912 -1.999996)
		(stroke
			(width 3.048)
			(type default)
		)
		(layer "In3.Cu")
	)
	(gr_line
		(start 19.964908 0)
		(end 31.964884 0)
		(stroke
			(width 3.048)
			(type default)
		)
		(layer "In3.Cu")
	)
	(gr_circle
		(center 20.14982 -301.410116)
		(end 22.257766 -301.410116)
		(stroke
			(width 0.2)
			(type default)
		)
		(fill no)
		(layer "In3.Cu")
	)
	(gr_circle
		(center 25.964896 -17.999964)
		(end 31.139892 -17.999964)
		(stroke
			(width 0.2)
			(type default)
		)
		(fill no)
		(layer "In3.Cu")
	)
	(gr_circle
		(center 29.649928 -320.900044)
		(end 34.285936 -320.900044)
		(stroke
			(width 0.2)
			(type default)
		)
		(fill no)
		(layer "In3.Cu")
	)
	(gr_circle
		(center 29.649928 -270.89989)
		(end 34.285936 -270.89989)
		(stroke
			(width 0.2)
			(type default)
		)
		(fill no)
		(layer "In3.Cu")
	)
	(gr_arc
		(start 33.96488 -11.850116)
		(mid 34.257773 -12.557221)
		(end 34.964878 -12.850114)
		(stroke
			(width 3.048)
			(type default)
		)
		(layer "In3.Cu")
	)
	(gr_arc
		(start 33.96488 -1.999996)
		(mid 33.379092 -0.585794)
		(end 31.964884 0)
		(stroke
			(width 3.048)
			(type default)
		)
		(layer "In3.Cu")
	)
	(gr_line
		(start 33.96488 -1.999996)
		(end 33.96488 -11.850116)
		(stroke
			(width 3.048)
			(type default)
		)
		(layer "In3.Cu")
	)
	(gr_line
		(start 34.964878 -12.850114)
		(end 42.965116 -12.850114)
		(stroke
			(width 3.048)
			(type default)
		)
		(layer "In3.Cu")
	)
	(gr_line
		(start 36.374578 -337.617562)
		(end 36.931854 -338.174838)
		(stroke
			(width 0.635)
			(type default)
		)
		(layer "In3.Cu")
	)
	(gr_line
		(start 36.374578 -326.62114)
		(end 36.374578 -286.87522)
		(stroke
			(width 0.508)
			(type default)
		)
		(layer "In3.Cu")
	)
	(gr_line
		(start 36.374578 -286.87522)
		(end 36.374578 -337.617562)
		(stroke
			(width 0.635)
			(type default)
		)
		(layer "In3.Cu")
	)
	(gr_line
		(start 36.374578 -272.53819)
		(end 36.374578 -286.87522)
		(stroke
			(width 0.635)
			(type default)
		)
		(layer "In3.Cu")
	)
	(gr_line
		(start 36.403788 -286.180022)
		(end 36.417504 -286.180022)
		(stroke
			(width 0.508)
			(type default)
		)
		(layer "In3.Cu")
	)
	(gr_line
		(start 36.403788 -285.940246)
		(end 36.403788 -286.180022)
		(stroke
			(width 0.508)
			(type default)
		)
		(layer "In3.Cu")
	)
	(gr_line
		(start 36.417504 -286.180022)
		(end 36.640008 -285.957518)
		(stroke
			(width 0.508)
			(type default)
		)
		(layer "In3.Cu")
	)
	(gr_line
		(start 36.441888 -285.902146)
		(end 36.403788 -285.940246)
		(stroke
			(width 0.508)
			(type default)
		)
		(layer "In3.Cu")
	)
	(gr_line
		(start 36.464494 -285.924752)
		(end 36.441888 -285.902146)
		(stroke
			(width 0.508)
			(type default)
		)
		(layer "In3.Cu")
	)
	(gr_line
		(start 36.640008 -285.957518)
		(end 36.640008 -285.891478)
		(stroke
			(width 0.508)
			(type default)
		)
		(layer "In3.Cu")
	)
	(gr_line
		(start 36.640008 -285.891478)
		(end 36.449 -285.70047)
		(stroke
			(width 0.508)
			(type default)
		)
		(layer "In3.Cu")
	)
	(gr_line
		(start 36.922964 -271.989804)
		(end 36.374578 -272.53819)
		(stroke
			(width 0.635)
			(type default)
		)
		(layer "In3.Cu")
	)
	(gr_line
		(start 36.931854 -338.174838)
		(end 197.785482 -338.174838)
		(stroke
			(width 0.635)
			(type default)
		)
		(layer "In3.Cu")
	)
	(gr_arc
		(start 42.965116 -12.850114)
		(mid 43.672221 -12.557221)
		(end 43.965114 -11.850116)
		(stroke
			(width 3.048)
			(type default)
		)
		(layer "In3.Cu")
	)
	(gr_line
		(start 43.965114 -11.850116)
		(end 43.965114 -1.999996)
		(stroke
			(width 3.048)
			(type default)
		)
		(layer "In3.Cu")
	)
	(gr_arc
		(start 45.96511 0)
		(mid 44.550891 -0.585781)
		(end 43.965114 -1.999996)
		(stroke
			(width 3.048)
			(type default)
		)
		(layer "In3.Cu")
	)
	(gr_line
		(start 45.96511 0)
		(end 57.965086 0)
		(stroke
			(width 3.048)
			(type default)
		)
		(layer "In3.Cu")
	)
	(gr_arc
		(start 59.965082 -11.850116)
		(mid 60.257975 -12.557221)
		(end 60.96508 -12.850114)
		(stroke
			(width 3.048)
			(type default)
		)
		(layer "In3.Cu")
	)
	(gr_arc
		(start 59.965082 -1.999996)
		(mid 59.379294 -0.585793)
		(end 57.965086 0)
		(stroke
			(width 3.048)
			(type default)
		)
		(layer "In3.Cu")
	)
	(gr_line
		(start 59.965082 -1.999996)
		(end 59.965082 -11.850116)
		(stroke
			(width 3.048)
			(type default)
		)
		(layer "In3.Cu")
	)
	(gr_line
		(start 60.96508 -12.850114)
		(end 68.965064 -12.850114)
		(stroke
			(width 3.048)
			(type default)
		)
		(layer "In3.Cu")
	)
	(gr_arc
		(start 68.965064 -12.850114)
		(mid 69.672169 -12.557221)
		(end 69.965062 -11.850116)
		(stroke
			(width 3.048)
			(type default)
		)
		(layer "In3.Cu")
	)
	(gr_line
		(start 69.965062 -11.850116)
		(end 69.965062 -1.999996)
		(stroke
			(width 3.048)
			(type default)
		)
		(layer "In3.Cu")
	)
	(gr_arc
		(start 71.965058 0)
		(mid 70.550873 -0.5858)
		(end 69.965062 -1.999996)
		(stroke
			(width 3.048)
			(type default)
		)
		(layer "In3.Cu")
	)
	(gr_line
		(start 71.965058 0)
		(end 83.965034 0)
		(stroke
			(width 3.048)
			(type default)
		)
		(layer "In3.Cu")
	)
	(gr_arc
		(start 85.96503 -11.850116)
		(mid 86.257923 -12.557221)
		(end 86.965028 -12.850114)
		(stroke
			(width 3.048)
			(type default)
		)
		(layer "In3.Cu")
	)
	(gr_arc
		(start 85.96503 -1.999996)
		(mid 85.379245 -0.585776)
		(end 83.965034 0)
		(stroke
			(width 3.048)
			(type default)
		)
		(layer "In3.Cu")
	)
	(gr_line
		(start 85.96503 -1.999996)
		(end 85.96503 -11.850116)
		(stroke
			(width 3.048)
			(type default)
		)
		(layer "In3.Cu")
	)
	(gr_line
		(start 86.965028 -12.850114)
		(end 94.965012 -12.850114)
		(stroke
			(width 3.048)
			(type default)
		)
		(layer "In3.Cu")
	)
	(gr_circle
		(center 89.650062 -320.900044)
		(end 94.28607 -320.900044)
		(stroke
			(width 0.2)
			(type default)
		)
		(fill no)
		(layer "In3.Cu")
	)
	(gr_circle
		(center 89.650062 -270.89989)
		(end 94.28607 -270.89989)
		(stroke
			(width 0.2)
			(type default)
		)
		(fill no)
		(layer "In3.Cu")
	)
	(gr_arc
		(start 94.965012 -12.850114)
		(mid 95.672117 -12.557221)
		(end 95.96501 -11.850116)
		(stroke
			(width 3.048)
			(type default)
		)
		(layer "In3.Cu")
	)
	(gr_line
		(start 95.96501 -11.850116)
		(end 95.96501 -1.999996)
		(stroke
			(width 3.048)
			(type default)
		)
		(layer "In3.Cu")
	)
	(gr_arc
		(start 97.965006 0)
		(mid 96.55079 -0.585783)
		(end 95.96501 -1.999996)
		(stroke
			(width 3.048)
			(type default)
		)
		(layer "In3.Cu")
	)
	(gr_line
		(start 97.965006 0)
		(end 122.065034 0)
		(stroke
			(width 3.048)
			(type default)
		)
		(layer "In3.Cu")
	)
	(gr_circle
		(center 99.149916 -289.820096)
		(end 101.257862 -289.820096)
		(stroke
			(width 0.2)
			(type default)
		)
		(fill no)
		(layer "In3.Cu")
	)
	(gr_line
		(start 99.914964 -285.924752)
		(end 36.464494 -285.924752)
		(stroke
			(width 0.508)
			(type default)
		)
		(layer "In3.Cu")
	)
	(gr_line
		(start 100.25253 -293.562786)
		(end 100.25253 -285.587186)
		(stroke
			(width 0.508)
			(type default)
		)
		(layer "In3.Cu")
	)
	(gr_line
		(start 100.25253 -285.587186)
		(end 99.914964 -285.924752)
		(stroke
			(width 0.508)
			(type default)
		)
		(layer "In3.Cu")
	)
	(gr_line
		(start 100.25253 -285.587186)
		(end 100.25253 -279.197562)
		(stroke
			(width 0.508)
			(type default)
		)
		(layer "In3.Cu")
	)
	(gr_line
		(start 100.25253 -279.197562)
		(end 101.0031 -278.446992)
		(stroke
			(width 0.508)
			(type default)
		)
		(layer "In3.Cu")
	)
	(gr_line
		(start 100.863908 -294.174164)
		(end 100.25253 -293.562786)
		(stroke
			(width 0.508)
			(type default)
		)
		(layer "In3.Cu")
	)
	(gr_line
		(start 101.0031 -278.446992)
		(end 134.85241 -278.446992)
		(stroke
			(width 0.508)
			(type default)
		)
		(layer "In3.Cu")
	)
	(gr_circle
		(center 104.009952 -407.599896)
		(end 109.184948 -407.599896)
		(stroke
			(width 0.2)
			(type default)
		)
		(fill no)
		(layer "In3.Cu")
	)
	(gr_circle
		(center 110.01502 -17.999964)
		(end 115.190016 -17.999964)
		(stroke
			(width 0.2)
			(type default)
		)
		(fill no)
		(layer "In3.Cu")
	)
	(gr_line
		(start 116.954808 -294.174164)
		(end 100.863908 -294.174164)
		(stroke
			(width 0.508)
			(type default)
		)
		(layer "In3.Cu")
	)
	(gr_line
		(start 117.4115 -294.250872)
		(end 117.675406 -294.514778)
		(stroke
			(width 0.508)
			(type default)
		)
		(layer "In3.Cu")
	)
	(gr_line
		(start 117.47373 -338.150454)
		(end 117.47373 -338.029804)
		(stroke
			(width 0.508)
			(type default)
		)
		(layer "In3.Cu")
	)
	(gr_line
		(start 117.47373 -338.029804)
		(end 117.763544 -337.73999)
		(stroke
			(width 0.508)
			(type default)
		)
		(layer "In3.Cu")
	)
	(gr_line
		(start 117.64264 -338.150454)
		(end 117.47373 -338.150454)
		(stroke
			(width 0.508)
			(type default)
		)
		(layer "In3.Cu")
	)
	(gr_line
		(start 117.675406 -294.514778)
		(end 117.4115 -294.250872)
		(stroke
			(width 0.508)
			(type default)
		)
		(layer "In3.Cu")
	)
	(gr_line
		(start 117.675406 -294.514778)
		(end 117.75186 -294.514778)
		(stroke
			(width 0.508)
			(type default)
		)
		(layer "In3.Cu")
	)
	(gr_circle
		(center 117.700044 -194.360038)
		(end 122.87504 -194.360038)
		(stroke
			(width 0.2)
			(type default)
		)
		(fill no)
		(layer "In3.Cu")
	)
	(gr_circle
		(center 117.700298 -72.700134)
		(end 122.875294 -72.700134)
		(stroke
			(width 0.2)
			(type default)
		)
		(fill no)
		(layer "In3.Cu")
	)
	(gr_line
		(start 117.730778 -338.062316)
		(end 117.64264 -338.150454)
		(stroke
			(width 0.508)
			(type default)
		)
		(layer "In3.Cu")
	)
	(gr_line
		(start 117.730778 -326.550528)
		(end 117.730778 -294.29964)
		(stroke
			(width 0.508)
			(type default)
		)
		(layer "In3.Cu")
	)
	(gr_line
		(start 117.730778 -294.29964)
		(end 117.730778 -338.062316)
		(stroke
			(width 0.508)
			(type default)
		)
		(layer "In3.Cu")
	)
	(gr_line
		(start 117.730778 -294.29964)
		(end 117.738144 -294.292274)
		(stroke
			(width 0.508)
			(type default)
		)
		(layer "In3.Cu")
	)
	(gr_line
		(start 117.738144 -294.58412)
		(end 117.738144 -294.292274)
		(stroke
			(width 0.508)
			(type default)
		)
		(layer "In3.Cu")
	)
	(gr_line
		(start 117.738144 -294.58412)
		(end 118.036848 -294.285416)
		(stroke
			(width 0.508)
			(type default)
		)
		(layer "In3.Cu")
	)
	(gr_line
		(start 117.738144 -294.292274)
		(end 117.730778 -294.29964)
		(stroke
			(width 0.508)
			(type default)
		)
		(layer "In3.Cu")
	)
	(gr_line
		(start 117.738144 -294.292274)
		(end 117.738144 -294.58412)
		(stroke
			(width 0.508)
			(type default)
		)
		(layer "In3.Cu")
	)
	(gr_line
		(start 117.75186 -294.514778)
		(end 117.675406 -294.514778)
		(stroke
			(width 0.508)
			(type default)
		)
		(layer "In3.Cu")
	)
	(gr_line
		(start 117.75186 -294.514778)
		(end 117.75186 -294.49395)
		(stroke
			(width 0.508)
			(type default)
		)
		(layer "In3.Cu")
	)
	(gr_line
		(start 117.75186 -294.49395)
		(end 117.75186 -294.514778)
		(stroke
			(width 0.508)
			(type default)
		)
		(layer "In3.Cu")
	)
	(gr_line
		(start 117.75186 -294.49395)
		(end 118.036848 -294.208962)
		(stroke
			(width 0.508)
			(type default)
		)
		(layer "In3.Cu")
	)
	(gr_line
		(start 117.763544 -337.73999)
		(end 118.029228 -338.005674)
		(stroke
			(width 0.508)
			(type default)
		)
		(layer "In3.Cu")
	)
	(gr_line
		(start 118.029228 -338.005674)
		(end 118.029228 -338.053934)
		(stroke
			(width 0.508)
			(type default)
		)
		(layer "In3.Cu")
	)
	(gr_line
		(start 118.036848 -294.285416)
		(end 117.738144 -294.58412)
		(stroke
			(width 0.508)
			(type default)
		)
		(layer "In3.Cu")
	)
	(gr_line
		(start 118.036848 -294.285416)
		(end 118.036848 -294.208962)
		(stroke
			(width 0.508)
			(type default)
		)
		(layer "In3.Cu")
	)
	(gr_line
		(start 118.036848 -294.208962)
		(end 117.75186 -294.49395)
		(stroke
			(width 0.508)
			(type default)
		)
		(layer "In3.Cu")
	)
	(gr_line
		(start 118.036848 -294.208962)
		(end 118.036848 -294.285416)
		(stroke
			(width 0.508)
			(type default)
		)
		(layer "In3.Cu")
	)
	(gr_arc
		(start 124.06503 -11.850116)
		(mid 124.357923 -12.557221)
		(end 125.065028 -12.850114)
		(stroke
			(width 3.048)
			(type default)
		)
		(layer "In3.Cu")
	)
	(gr_arc
		(start 124.06503 -1.999996)
		(mid 123.479245 -0.585776)
		(end 122.065034 0)
		(stroke
			(width 3.048)
			(type default)
		)
		(layer "In3.Cu")
	)
	(gr_line
		(start 124.06503 -1.999996)
		(end 124.06503 -11.850116)
		(stroke
			(width 3.048)
			(type default)
		)
		(layer "In3.Cu")
	)
	(gr_line
		(start 125.065028 -12.850114)
		(end 133.065012 -12.850114)
		(stroke
			(width 3.048)
			(type default)
		)
		(layer "In3.Cu")
	)
	(gr_line
		(start 130.785616 -271.989804)
		(end 36.922964 -271.989804)
		(stroke
			(width 0.635)
			(type default)
		)
		(layer "In3.Cu")
	)
	(gr_line
		(start 132.554726 -270.220694)
		(end 130.785616 -271.989804)
		(stroke
			(width 0.635)
			(type default)
		)
		(layer "In3.Cu")
	)
	(gr_arc
		(start 133.065012 -12.850114)
		(mid 133.772117 -12.557221)
		(end 134.06501 -11.850116)
		(stroke
			(width 3.048)
			(type default)
		)
		(layer "In3.Cu")
	)
	(gr_line
		(start 134.06501 -11.850116)
		(end 134.06501 -1.999996)
		(stroke
			(width 3.048)
			(type default)
		)
		(layer "In3.Cu")
	)
	(gr_line
		(start 134.85241 -278.446992)
		(end 135.489188 -279.08377)
		(stroke
			(width 0.508)
			(type default)
		)
		(layer "In3.Cu")
	)
	(gr_line
		(start 134.933436 -294.174164)
		(end 116.954808 -294.174164)
		(stroke
			(width 0.508)
			(type default)
		)
		(layer "In3.Cu")
	)
	(gr_line
		(start 135.489188 -293.618412)
		(end 134.933436 -294.174164)
		(stroke
			(width 0.508)
			(type default)
		)
		(layer "In3.Cu")
	)
	(gr_line
		(start 135.489188 -279.08377)
		(end 135.489188 -293.618412)
		(stroke
			(width 0.508)
			(type default)
		)
		(layer "In3.Cu")
	)
	(gr_line
		(start 135.489442 -286.086804)
		(end 135.76046 -286.357822)
		(stroke
			(width 0.508)
			(type default)
		)
		(layer "In3.Cu")
	)
	(gr_line
		(start 135.558784 -286.621728)
		(end 135.780526 -286.399986)
		(stroke
			(width 0.508)
			(type default)
		)
		(layer "In3.Cu")
	)
	(gr_line
		(start 135.56615 -286.621728)
		(end 135.558784 -286.621728)
		(stroke
			(width 0.508)
			(type default)
		)
		(layer "In3.Cu")
	)
	(gr_line
		(start 135.76046 -286.427418)
		(end 135.56615 -286.621728)
		(stroke
			(width 0.508)
			(type default)
		)
		(layer "In3.Cu")
	)
	(gr_line
		(start 135.76046 -286.357822)
		(end 135.76046 -286.427418)
		(stroke
			(width 0.508)
			(type default)
		)
		(layer "In3.Cu")
	)
	(gr_line
		(start 135.780526 -286.399986)
		(end 198.685912 -286.399986)
		(stroke
			(width 0.508)
			(type default)
		)
		(layer "In3.Cu")
	)
	(gr_arc
		(start 136.065006 0)
		(mid 134.65079 -0.585783)
		(end 134.06501 -1.999996)
		(stroke
			(width 3.048)
			(type default)
		)
		(layer "In3.Cu")
	)
	(gr_line
		(start 136.065006 0)
		(end 148.064982 0)
		(stroke
			(width 3.048)
			(type default)
		)
		(layer "In3.Cu")
	)
	(gr_circle
		(center 136.250172 -276.010116)
		(end 138.358118 -276.010116)
		(stroke
			(width 0.2)
			(type default)
		)
		(fill no)
		(layer "In3.Cu")
	)
	(gr_line
		(start 140.896086 -270.220694)
		(end 132.554726 -270.220694)
		(stroke
			(width 0.635)
			(type default)
		)
		(layer "In3.Cu")
	)
	(gr_line
		(start 142.484602 -271.989804)
		(end 142.484602 -271.80921)
		(stroke
			(width 0.635)
			(type default)
		)
		(layer "In3.Cu")
	)
	(gr_line
		(start 142.484602 -271.80921)
		(end 140.896086 -270.220694)
		(stroke
			(width 0.635)
			(type default)
		)
		(layer "In3.Cu")
	)
	(gr_circle
		(center 145.750026 -320.900044)
		(end 150.386034 -320.900044)
		(stroke
			(width 0.2)
			(type default)
		)
		(fill no)
		(layer "In3.Cu")
	)
	(gr_circle
		(center 145.750026 -270.89989)
		(end 150.386034 -270.89989)
		(stroke
			(width 0.2)
			(type default)
		)
		(fill no)
		(layer "In3.Cu")
	)
	(gr_arc
		(start 150.064978 -11.850116)
		(mid 150.357871 -12.557221)
		(end 151.064976 -12.850114)
		(stroke
			(width 3.048)
			(type default)
		)
		(layer "In3.Cu")
	)
	(gr_arc
		(start 150.064978 -1.999996)
		(mid 149.47919 -0.585794)
		(end 148.064982 0)
		(stroke
			(width 3.048)
			(type default)
		)
		(layer "In3.Cu")
	)
	(gr_line
		(start 150.064978 -1.999996)
		(end 150.064978 -11.850116)
		(stroke
			(width 3.048)
			(type default)
		)
		(layer "In3.Cu")
	)
	(gr_line
		(start 151.064976 -12.850114)
		(end 159.06496 -12.850114)
		(stroke
			(width 3.048)
			(type default)
		)
		(layer "In3.Cu")
	)
	(gr_arc
		(start 159.06496 -12.850114)
		(mid 159.772065 -12.557221)
		(end 160.064958 -11.850116)
		(stroke
			(width 3.048)
			(type default)
		)
		(layer "In3.Cu")
	)
	(gr_line
		(start 160.064958 -11.850116)
		(end 160.064958 -1.999996)
		(stroke
			(width 3.048)
			(type default)
		)
		(layer "In3.Cu")
	)
	(gr_arc
		(start 162.064954 0)
		(mid 160.650772 -0.585801)
		(end 160.064958 -1.999996)
		(stroke
			(width 3.048)
			(type default)
		)
		(layer "In3.Cu")
	)
	(gr_line
		(start 162.064954 0)
		(end 174.06493 0)
		(stroke
			(width 3.048)
			(type default)
		)
		(layer "In3.Cu")
	)
	(gr_circle
		(center 168.064942 -4.99999)
		(end 173.239938 -4.99999)
		(stroke
			(width 0.2)
			(type default)
		)
		(fill no)
		(layer "In3.Cu")
	)
	(gr_arc
		(start 176.064926 -11.850116)
		(mid 176.357819 -12.557221)
		(end 177.064924 -12.850114)
		(stroke
			(width 3.048)
			(type default)
		)
		(layer "In3.Cu")
	)
	(gr_arc
		(start 176.064926 -1.999996)
		(mid 175.479141 -0.585777)
		(end 174.06493 0)
		(stroke
			(width 3.048)
			(type default)
		)
		(layer "In3.Cu")
	)
	(gr_line
		(start 176.064926 -1.999996)
		(end 176.064926 -11.850116)
		(stroke
			(width 3.048)
			(type default)
		)
		(layer "In3.Cu")
	)
	(gr_line
		(start 177.064924 -12.850114)
		(end 185.064908 -12.850114)
		(stroke
			(width 3.048)
			(type default)
		)
		(layer "In3.Cu")
	)
	(gr_arc
		(start 185.064908 -12.850114)
		(mid 185.772013 -12.557221)
		(end 186.064906 -11.850116)
		(stroke
			(width 3.048)
			(type default)
		)
		(layer "In3.Cu")
	)
	(gr_line
		(start 186.064906 -11.850116)
		(end 186.064906 -1.999996)
		(stroke
			(width 3.048)
			(type default)
		)
		(layer "In3.Cu")
	)
	(gr_arc
		(start 188.064902 0)
		(mid 186.650689 -0.585784)
		(end 186.064906 -1.999996)
		(stroke
			(width 3.048)
			(type default)
		)
		(layer "In3.Cu")
	)
	(gr_line
		(start 188.064902 0)
		(end 200.064878 0)
		(stroke
			(width 3.048)
			(type default)
		)
		(layer "In3.Cu")
	)
	(gr_circle
		(center 195.699888 -378.70003)
		(end 200.874884 -378.70003)
		(stroke
			(width 0.2)
			(type default)
		)
		(fill no)
		(layer "In3.Cu")
	)
	(gr_line
		(start 197.785482 -338.174838)
		(end 199.025256 -336.935064)
		(stroke
			(width 0.635)
			(type default)
		)
		(layer "In3.Cu")
	)
	(gr_line
		(start 198.205344 -271.989804)
		(end 142.484602 -271.989804)
		(stroke
			(width 0.635)
			(type default)
		)
		(layer "In3.Cu")
	)
	(gr_line
		(start 198.21525 -271.99971)
		(end 198.205344 -271.989804)
		(stroke
			(width 0.635)
			(type default)
		)
		(layer "In3.Cu")
	)
	(gr_line
		(start 198.340472 -271.99971)
		(end 198.21525 -271.99971)
		(stroke
			(width 0.635)
			(type default)
		)
		(layer "In3.Cu")
	)
	(gr_line
		(start 198.685912 -286.399986)
		(end 199.019414 -286.733488)
		(stroke
			(width 0.508)
			(type default)
		)
		(layer "In3.Cu")
	)
	(gr_line
		(start 198.70674 -286.38627)
		(end 198.70674 -286.337502)
		(stroke
			(width 0.508)
			(type default)
		)
		(layer "In3.Cu")
	)
	(gr_line
		(start 198.70674 -286.337502)
		(end 198.984616 -286.059626)
		(stroke
			(width 0.508)
			(type default)
		)
		(layer "In3.Cu")
	)
	(gr_line
		(start 198.984616 -286.059626)
		(end 198.998586 -286.059626)
		(stroke
			(width 0.508)
			(type default)
		)
		(layer "In3.Cu")
	)
	(gr_line
		(start 199.019414 -286.733488)
		(end 199.019414 -286.698944)
		(stroke
			(width 0.508)
			(type default)
		)
		(layer "In3.Cu")
	)
	(gr_line
		(start 199.019414 -286.698944)
		(end 198.70674 -286.38627)
		(stroke
			(width 0.508)
			(type default)
		)
		(layer "In3.Cu")
	)
	(gr_line
		(start 199.025002 -318.224662)
		(end 199.025002 -272.68424)
		(stroke
			(width 0.635)
			(type default)
		)
		(layer "In3.Cu")
	)
	(gr_line
		(start 199.025002 -272.68424)
		(end 198.340472 -271.99971)
		(stroke
			(width 0.635)
			(type default)
		)
		(layer "In3.Cu")
	)
	(gr_line
		(start 199.025256 -336.935064)
		(end 199.025256 -326.572118)
		(stroke
			(width 0.635)
			(type default)
		)
		(layer "In3.Cu")
	)
	(gr_line
		(start 199.025256 -326.572118)
		(end 199.025256 -318.224916)
		(stroke
			(width 0.635)
			(type default)
		)
		(layer "In3.Cu")
	)
	(gr_line
		(start 199.025256 -318.224916)
		(end 199.025002 -318.224662)
		(stroke
			(width 0.635)
			(type default)
		)
		(layer "In3.Cu")
	)
	(gr_circle
		(center 199.399906 -393.100052)
		(end 204.574902 -393.100052)
		(stroke
			(width 0.2)
			(type default)
		)
		(fill no)
		(layer "In3.Cu")
	)
	(gr_line
		(start 200.481184 -418.589968)
		(end 1.999996 -418.589968)
		(stroke
			(width 3.048)
			(type default)
		)
		(layer "In3.Cu")
	)
	(gr_arc
		(start 200.481184 -418.589968)
		(mid 201.291806 -418.418339)
		(end 201.963274 -417.93287)
		(stroke
			(width 3.048)
			(type default)
		)
		(layer "In3.Cu")
	)
	(gr_arc
		(start 202.064874 -11.850116)
		(mid 202.357841 -12.557401)
		(end 203.065126 -12.850114)
		(stroke
			(width 3.048)
			(type default)
		)
		(layer "In3.Cu")
	)
	(gr_arc
		(start 202.064874 -1.999996)
		(mid 201.479086 -0.585796)
		(end 200.064878 0)
		(stroke
			(width 3.048)
			(type default)
		)
		(layer "In3.Cu")
	)
	(gr_line
		(start 202.064874 -1.999996)
		(end 202.064874 -11.850116)
		(stroke
			(width 3.048)
			(type default)
		)
		(layer "In3.Cu")
	)
	(gr_line
		(start 203.065126 -12.850114)
		(end 211.06511 -12.850114)
		(stroke
			(width 3.048)
			(type default)
		)
		(layer "In3.Cu")
	)
	(gr_arc
		(start 203.445364 -417.275772)
		(mid 202.634751 -417.447411)
		(end 201.963274 -417.93287)
		(stroke
			(width 3.048)
			(type default)
		)
		(layer "In3.Cu")
	)
	(gr_line
		(start 204.101954 -368.267234)
		(end 204.404214 -368.569494)
		(stroke
			(width 0.635)
			(type default)
		)
		(layer "In3.Cu")
	)
	(gr_line
		(start 204.102208 -368.26698)
		(end 204.404468 -367.96472)
		(stroke
			(width 0.635)
			(type default)
		)
		(layer "In3.Cu")
	)
	(gr_line
		(start 204.690218 -419.12413)
		(end 204.88275 -418.931598)
		(stroke
			(width 0.508)
			(type default)
		)
		(layer "In3.Cu")
	)
	(gr_circle
		(center 205.749906 -320.900044)
		(end 210.385914 -320.900044)
		(stroke
			(width 0.2)
			(type default)
		)
		(fill no)
		(layer "In3.Cu")
	)
	(gr_circle
		(center 205.749906 -270.89989)
		(end 210.385914 -270.89989)
		(stroke
			(width 0.2)
			(type default)
		)
		(fill no)
		(layer "In3.Cu")
	)
	(gr_circle
		(center 208.300066 -98.700082)
		(end 213.475062 -98.700082)
		(stroke
			(width 0.2)
			(type default)
		)
		(fill no)
		(layer "In3.Cu")
	)
	(gr_arc
		(start 211.06511 -12.850114)
		(mid 211.772215 -12.557221)
		(end 212.065108 -11.850116)
		(stroke
			(width 3.048)
			(type default)
		)
		(layer "In3.Cu")
	)
	(gr_line
		(start 212.065108 -11.850116)
		(end 212.065108 -1.999996)
		(stroke
			(width 3.048)
			(type default)
		)
		(layer "In3.Cu")
	)
	(gr_arc
		(start 214.065104 0)
		(mid 212.650889 -0.585784)
		(end 212.065108 -1.999996)
		(stroke
			(width 3.048)
			(type default)
		)
		(layer "In3.Cu")
	)
	(gr_line
		(start 214.065104 0)
		(end 238.164878 0)
		(stroke
			(width 3.048)
			(type default)
		)
		(layer "In3.Cu")
	)
	(gr_circle
		(center 216.990168 -311.179972)
		(end 219.098114 -311.179972)
		(stroke
			(width 0.2)
			(type default)
		)
		(fill no)
		(layer "In3.Cu")
	)
	(gr_circle
		(center 226.115118 -4.99999)
		(end 231.290114 -4.99999)
		(stroke
			(width 0.2)
			(type default)
		)
		(fill no)
		(layer "In3.Cu")
	)
	(gr_circle
		(center 233.800142 -194.359784)
		(end 238.975138 -194.359784)
		(stroke
			(width 0.2)
			(type default)
		)
		(fill no)
		(layer "In3.Cu")
	)
	(gr_arc
		(start 240.164874 -11.850116)
		(mid 240.457841 -12.557401)
		(end 241.165126 -12.850114)
		(stroke
			(width 3.048)
			(type default)
		)
		(layer "In3.Cu")
	)
	(gr_arc
		(start 240.164874 -1.999996)
		(mid 239.579086 -0.585796)
		(end 238.164878 0)
		(stroke
			(width 3.048)
			(type default)
		)
		(layer "In3.Cu")
	)
	(gr_line
		(start 240.164874 -1.999996)
		(end 240.164874 -11.850116)
		(stroke
			(width 3.048)
			(type default)
		)
		(layer "In3.Cu")
	)
	(gr_line
		(start 241.165126 -12.850114)
		(end 249.16511 -12.850114)
		(stroke
			(width 3.048)
			(type default)
		)
		(layer "In3.Cu")
	)
	(gr_arc
		(start 249.16511 -12.850114)
		(mid 249.872215 -12.557221)
		(end 250.165108 -11.850116)
		(stroke
			(width 3.048)
			(type default)
		)
		(layer "In3.Cu")
	)
	(gr_line
		(start 250.165108 -11.850116)
		(end 250.165108 -1.999996)
		(stroke
			(width 3.048)
			(type default)
		)
		(layer "In3.Cu")
	)
	(gr_arc
		(start 252.165104 0)
		(mid 250.750889 -0.585784)
		(end 250.165108 -1.999996)
		(stroke
			(width 3.048)
			(type default)
		)
		(layer "In3.Cu")
	)
	(gr_line
		(start 252.165104 0)
		(end 264.16508 0)
		(stroke
			(width 3.048)
			(type default)
		)
		(layer "In3.Cu")
	)
	(gr_circle
		(center 252.350016 -297.369992)
		(end 254.457962 -297.369992)
		(stroke
			(width 0.2)
			(type default)
		)
		(fill no)
		(layer "In3.Cu")
	)
	(gr_circle
		(center 259.299964 -98.700082)
		(end 264.47496 -98.700082)
		(stroke
			(width 0.2)
			(type default)
		)
		(fill no)
		(layer "In3.Cu")
	)
	(gr_circle
		(center 261.850124 -320.900044)
		(end 266.486132 -320.900044)
		(stroke
			(width 0.2)
			(type default)
		)
		(fill no)
		(layer "In3.Cu")
	)
	(gr_circle
		(center 261.850124 -270.89989)
		(end 266.486132 -270.89989)
		(stroke
			(width 0.2)
			(type default)
		)
		(fill no)
		(layer "In3.Cu")
	)
	(gr_line
		(start 266.112498 -368.670332)
		(end 266.57808 -368.20475)
		(stroke
			(width 0.635)
			(type default)
		)
		(layer "In3.Cu")
	)
	(gr_arc
		(start 266.165076 -11.850116)
		(mid 266.457969 -12.557221)
		(end 267.165074 -12.850114)
		(stroke
			(width 3.048)
			(type default)
		)
		(layer "In3.Cu")
	)
	(gr_arc
		(start 266.165076 -1.999996)
		(mid 265.579288 -0.585795)
		(end 264.16508 0)
		(stroke
			(width 3.048)
			(type default)
		)
		(layer "In3.Cu")
	)
	(gr_line
		(start 266.165076 -1.999996)
		(end 266.165076 -11.850116)
		(stroke
			(width 3.048)
			(type default)
		)
		(layer "In3.Cu")
	)
	(gr_line
		(start 266.893802 -368.179604)
		(end 265.631168 -368.179604)
		(stroke
			(width 0.635)
			(type default)
		)
		(layer "In3.Cu")
	)
	(gr_line
		(start 267.165074 -12.850114)
		(end 275.165058 -12.850114)
		(stroke
			(width 3.048)
			(type default)
		)
		(layer "In3.Cu")
	)
	(gr_line
		(start 267.890244 -367.183162)
		(end 266.893802 -368.179604)
		(stroke
			(width 0.635)
			(type default)
		)
		(layer "In3.Cu")
	)
	(gr_circle
		(center 268.19987 -393.099798)
		(end 273.374866 -393.099798)
		(stroke
			(width 0.2)
			(type default)
		)
		(fill no)
		(layer "In3.Cu")
	)
	(gr_line
		(start 268.57452 -326.62114)
		(end 268.57452 -286.87522)
		(stroke
			(width 0.508)
			(type default)
		)
		(layer "In3.Cu")
	)
	(gr_line
		(start 268.57452 -272.53819)
		(end 268.57452 -286.87522)
		(stroke
			(width 0.635)
			(type default)
		)
		(layer "In3.Cu")
	)
	(gr_line
		(start 268.574774 -337.617562)
		(end 269.13205 -338.174838)
		(stroke
			(width 0.635)
			(type default)
		)
		(layer "In3.Cu")
	)
	(gr_line
		(start 268.574774 -286.87522)
		(end 268.574774 -337.617562)
		(stroke
			(width 0.635)
			(type default)
		)
		(layer "In3.Cu")
	)
	(gr_line
		(start 268.60373 -286.180022)
		(end 268.617446 -286.180022)
		(stroke
			(width 0.508)
			(type default)
		)
		(layer "In3.Cu")
	)
	(gr_line
		(start 268.60373 -285.940246)
		(end 268.60373 -286.180022)
		(stroke
			(width 0.508)
			(type default)
		)
		(layer "In3.Cu")
	)
	(gr_line
		(start 268.617446 -286.180022)
		(end 268.83995 -285.957518)
		(stroke
			(width 0.508)
			(type default)
		)
		(layer "In3.Cu")
	)
	(gr_line
		(start 268.64183 -285.902146)
		(end 268.60373 -285.940246)
		(stroke
			(width 0.508)
			(type default)
		)
		(layer "In3.Cu")
	)
	(gr_line
		(start 268.664436 -285.924752)
		(end 268.64183 -285.902146)
		(stroke
			(width 0.508)
			(type default)
		)
		(layer "In3.Cu")
	)
	(gr_line
		(start 268.83995 -285.957518)
		(end 268.83995 -285.891478)
		(stroke
			(width 0.508)
			(type default)
		)
		(layer "In3.Cu")
	)
	(gr_line
		(start 268.83995 -285.891478)
		(end 268.648942 -285.70047)
		(stroke
			(width 0.508)
			(type default)
		)
		(layer "In3.Cu")
	)
	(gr_line
		(start 269.122906 -271.989804)
		(end 268.57452 -272.53819)
		(stroke
			(width 0.635)
			(type default)
		)
		(layer "In3.Cu")
	)
	(gr_line
		(start 269.122906 -271.989804)
		(end 361.8484 -271.989804)
		(stroke
			(width 0.635)
			(type default)
		)
		(layer "In3.Cu")
	)
	(gr_line
		(start 269.12316 -271.989804)
		(end 361.8484 -271.989804)
		(stroke
			(width 0.635)
			(type default)
		)
		(layer "In3.Cu")
	)
	(gr_line
		(start 269.13205 -338.174838)
		(end 429.985678 -338.174838)
		(stroke
			(width 0.635)
			(type default)
		)
		(layer "In3.Cu")
	)
	(gr_line
		(start 271.794478 -417.275772)
		(end 203.445364 -417.275772)
		(stroke
			(width 3.048)
			(type default)
		)
		(layer "In3.Cu")
	)
	(gr_circle
		(center 271.899888 -378.70003)
		(end 277.074884 -378.70003)
		(stroke
			(width 0.2)
			(type default)
		)
		(fill no)
		(layer "In3.Cu")
	)
	(gr_arc
		(start 273.276568 -417.93287)
		(mid 272.605089 -417.447415)
		(end 271.794478 -417.275772)
		(stroke
			(width 3.048)
			(type default)
		)
		(layer "In3.Cu")
	)
	(gr_arc
		(start 273.276568 -417.93287)
		(mid 273.948042 -418.418346)
		(end 274.758658 -418.589968)
		(stroke
			(width 3.048)
			(type default)
		)
		(layer "In3.Cu")
	)
	(gr_arc
		(start 275.165058 -12.850114)
		(mid 275.872163 -12.557221)
		(end 276.165056 -11.850116)
		(stroke
			(width 3.048)
			(type default)
		)
		(layer "In3.Cu")
	)
	(gr_line
		(start 276.165056 -11.850116)
		(end 276.165056 -1.999996)
		(stroke
			(width 3.048)
			(type default)
		)
		(layer "In3.Cu")
	)
	(gr_arc
		(start 278.165052 0)
		(mid 276.750871 -0.585802)
		(end 276.165056 -1.999996)
		(stroke
			(width 3.048)
			(type default)
		)
		(layer "In3.Cu")
	)
	(gr_line
		(start 278.165052 0)
		(end 290.165028 0)
		(stroke
			(width 3.048)
			(type default)
		)
		(layer "In3.Cu")
	)
	(gr_circle
		(center 284.16504 -4.99999)
		(end 289.340036 -4.99999)
		(stroke
			(width 0.2)
			(type default)
		)
		(fill no)
		(layer "In3.Cu")
	)
	(gr_arc
		(start 292.165024 -11.850116)
		(mid 292.457917 -12.557221)
		(end 293.165022 -12.850114)
		(stroke
			(width 3.048)
			(type default)
		)
		(layer "In3.Cu")
	)
	(gr_arc
		(start 292.165024 -1.999996)
		(mid 291.579239 -0.585778)
		(end 290.165028 0)
		(stroke
			(width 3.048)
			(type default)
		)
		(layer "In3.Cu")
	)
	(gr_line
		(start 292.165024 -1.999996)
		(end 292.165024 -11.850116)
		(stroke
			(width 3.048)
			(type default)
		)
		(layer "In3.Cu")
	)
	(gr_line
		(start 293.165022 -12.850114)
		(end 301.165006 -12.850114)
		(stroke
			(width 3.048)
			(type default)
		)
		(layer "In3.Cu")
	)
	(gr_arc
		(start 301.165006 -12.850114)
		(mid 301.872111 -12.557221)
		(end 302.165004 -11.850116)
		(stroke
			(width 3.048)
			(type default)
		)
		(layer "In3.Cu")
	)
	(gr_line
		(start 302.165004 -11.850116)
		(end 302.165004 -1.999996)
		(stroke
			(width 3.048)
			(type default)
		)
		(layer "In3.Cu")
	)
	(gr_arc
		(start 304.165 0)
		(mid 302.750788 -0.585785)
		(end 302.165004 -1.999996)
		(stroke
			(width 3.048)
			(type default)
		)
		(layer "In3.Cu")
	)
	(gr_line
		(start 304.165 0)
		(end 316.164976 0)
		(stroke
			(width 3.048)
			(type default)
		)
		(layer "In3.Cu")
	)
	(gr_arc
		(start 318.164972 -11.850116)
		(mid 318.457865 -12.557221)
		(end 319.16497 -12.850114)
		(stroke
			(width 3.048)
			(type default)
		)
		(layer "In3.Cu")
	)
	(gr_arc
		(start 318.164972 -1.999996)
		(mid 317.579184 -0.585796)
		(end 316.164976 0)
		(stroke
			(width 3.048)
			(type default)
		)
		(layer "In3.Cu")
	)
	(gr_line
		(start 318.164972 -1.999996)
		(end 318.164972 -11.850116)
		(stroke
			(width 3.048)
			(type default)
		)
		(layer "In3.Cu")
	)
	(gr_line
		(start 319.16497 -12.850114)
		(end 327.164954 -12.850114)
		(stroke
			(width 3.048)
			(type default)
		)
		(layer "In3.Cu")
	)
	(gr_circle
		(center 321.850004 -320.900044)
		(end 326.486012 -320.900044)
		(stroke
			(width 0.2)
			(type default)
		)
		(fill no)
		(layer "In3.Cu")
	)
	(gr_circle
		(center 321.850004 -270.89989)
		(end 326.486012 -270.89989)
		(stroke
			(width 0.2)
			(type default)
		)
		(fill no)
		(layer "In3.Cu")
	)
	(gr_arc
		(start 327.164954 -12.850114)
		(mid 327.872059 -12.557221)
		(end 328.164952 -11.850116)
		(stroke
			(width 3.048)
			(type default)
		)
		(layer "In3.Cu")
	)
	(gr_line
		(start 328.164952 -11.850116)
		(end 328.164952 -1.999996)
		(stroke
			(width 3.048)
			(type default)
		)
		(layer "In3.Cu")
	)
	(gr_arc
		(start 330.164948 0)
		(mid 328.750705 -0.585768)
		(end 328.164952 -1.999996)
		(stroke
			(width 3.048)
			(type default)
		)
		(layer "In3.Cu")
	)
	(gr_line
		(start 330.164948 0)
		(end 354.264976 0)
		(stroke
			(width 3.048)
			(type default)
		)
		(layer "In3.Cu")
	)
	(gr_circle
		(center 331.350112 -289.820096)
		(end 333.458058 -289.820096)
		(stroke
			(width 0.2)
			(type default)
		)
		(fill no)
		(layer "In3.Cu")
	)
	(gr_line
		(start 332.114906 -285.924752)
		(end 268.664436 -285.924752)
		(stroke
			(width 0.508)
			(type default)
		)
		(layer "In3.Cu")
	)
	(gr_line
		(start 332.452472 -293.562786)
		(end 332.452472 -285.587186)
		(stroke
			(width 0.508)
			(type default)
		)
		(layer "In3.Cu")
	)
	(gr_line
		(start 332.452472 -285.587186)
		(end 332.114906 -285.924752)
		(stroke
			(width 0.508)
			(type default)
		)
		(layer "In3.Cu")
	)
	(gr_line
		(start 332.452472 -285.587186)
		(end 332.452472 -279.197562)
		(stroke
			(width 0.508)
			(type default)
		)
		(layer "In3.Cu")
	)
	(gr_line
		(start 332.452472 -279.197562)
		(end 333.203042 -278.446992)
		(stroke
			(width 0.508)
			(type default)
		)
		(layer "In3.Cu")
	)
	(gr_line
		(start 333.06385 -294.174164)
		(end 332.452472 -293.562786)
		(stroke
			(width 0.508)
			(type default)
		)
		(layer "In3.Cu")
	)
	(gr_line
		(start 333.203042 -278.446992)
		(end 367.052352 -278.446992)
		(stroke
			(width 0.508)
			(type default)
		)
		(layer "In3.Cu")
	)
	(gr_circle
		(center 342.214962 -17.999964)
		(end 347.389958 -17.999964)
		(stroke
			(width 0.2)
			(type default)
		)
		(fill no)
		(layer "In3.Cu")
	)
	(gr_line
		(start 349.15475 -294.174164)
		(end 333.06385 -294.174164)
		(stroke
			(width 0.508)
			(type default)
		)
		(layer "In3.Cu")
	)
	(gr_line
		(start 349.611696 -294.250872)
		(end 349.875602 -294.514778)
		(stroke
			(width 0.508)
			(type default)
		)
		(layer "In3.Cu")
	)
	(gr_line
		(start 349.673926 -338.150454)
		(end 349.673926 -338.029804)
		(stroke
			(width 0.508)
			(type default)
		)
		(layer "In3.Cu")
	)
	(gr_line
		(start 349.673926 -338.029804)
		(end 349.96374 -337.73999)
		(stroke
			(width 0.508)
			(type default)
		)
		(layer "In3.Cu")
	)
	(gr_line
		(start 349.842836 -338.150454)
		(end 349.673926 -338.150454)
		(stroke
			(width 0.508)
			(type default)
		)
		(layer "In3.Cu")
	)
	(gr_line
		(start 349.875348 -294.514778)
		(end 349.611442 -294.250872)
		(stroke
			(width 0.508)
			(type default)
		)
		(layer "In3.Cu")
	)
	(gr_line
		(start 349.875602 -294.514778)
		(end 349.952056 -294.514778)
		(stroke
			(width 0.508)
			(type default)
		)
		(layer "In3.Cu")
	)
	(gr_circle
		(center 349.899986 -194.360038)
		(end 355.074982 -194.360038)
		(stroke
			(width 0.2)
			(type default)
		)
		(fill no)
		(layer "In3.Cu")
	)
	(gr_circle
		(center 349.899986 -72.69988)
		(end 355.074982 -72.69988)
		(stroke
			(width 0.2)
			(type default)
		)
		(fill no)
		(layer "In3.Cu")
	)
	(gr_line
		(start 349.93072 -326.550528)
		(end 349.93072 -294.29964)
		(stroke
			(width 0.508)
			(type default)
		)
		(layer "In3.Cu")
	)
	(gr_line
		(start 349.93072 -294.29964)
		(end 349.938086 -294.292274)
		(stroke
			(width 0.508)
			(type default)
		)
		(layer "In3.Cu")
	)
	(gr_line
		(start 349.930974 -338.062316)
		(end 349.842836 -338.150454)
		(stroke
			(width 0.508)
			(type default)
		)
		(layer "In3.Cu")
	)
	(gr_line
		(start 349.930974 -294.29964)
		(end 349.930974 -338.062316)
		(stroke
			(width 0.508)
			(type default)
		)
		(layer "In3.Cu")
	)
	(gr_line
		(start 349.938086 -294.58412)
		(end 350.23679 -294.285416)
		(stroke
			(width 0.508)
			(type default)
		)
		(layer "In3.Cu")
	)
	(gr_line
		(start 349.938086 -294.292274)
		(end 349.938086 -294.58412)
		(stroke
			(width 0.508)
			(type default)
		)
		(layer "In3.Cu")
	)
	(gr_line
		(start 349.93834 -294.58412)
		(end 349.93834 -294.292274)
		(stroke
			(width 0.508)
			(type default)
		)
		(layer "In3.Cu")
	)
	(gr_line
		(start 349.93834 -294.292274)
		(end 349.930974 -294.29964)
		(stroke
			(width 0.508)
			(type default)
		)
		(layer "In3.Cu")
	)
	(gr_line
		(start 349.951802 -294.514778)
		(end 349.875348 -294.514778)
		(stroke
			(width 0.508)
			(type default)
		)
		(layer "In3.Cu")
	)
	(gr_line
		(start 349.951802 -294.49395)
		(end 349.951802 -294.514778)
		(stroke
			(width 0.508)
			(type default)
		)
		(layer "In3.Cu")
	)
	(gr_line
		(start 349.952056 -294.514778)
		(end 349.952056 -294.49395)
		(stroke
			(width 0.508)
			(type default)
		)
		(layer "In3.Cu")
	)
	(gr_line
		(start 349.952056 -294.49395)
		(end 350.237044 -294.208962)
		(stroke
			(width 0.508)
			(type default)
		)
		(layer "In3.Cu")
	)
	(gr_line
		(start 349.96374 -337.73999)
		(end 350.229424 -338.005674)
		(stroke
			(width 0.508)
			(type default)
		)
		(layer "In3.Cu")
	)
	(gr_line
		(start 350.229424 -338.005674)
		(end 350.229424 -338.053934)
		(stroke
			(width 0.508)
			(type default)
		)
		(layer "In3.Cu")
	)
	(gr_line
		(start 350.23679 -294.285416)
		(end 350.23679 -294.208962)
		(stroke
			(width 0.508)
			(type default)
		)
		(layer "In3.Cu")
	)
	(gr_line
		(start 350.23679 -294.208962)
		(end 349.951802 -294.49395)
		(stroke
			(width 0.508)
			(type default)
		)
		(layer "In3.Cu")
	)
	(gr_line
		(start 350.237044 -294.285416)
		(end 349.93834 -294.58412)
		(stroke
			(width 0.508)
			(type default)
		)
		(layer "In3.Cu")
	)
	(gr_line
		(start 350.237044 -294.208962)
		(end 350.237044 -294.285416)
		(stroke
			(width 0.508)
			(type default)
		)
		(layer "In3.Cu")
	)
	(gr_arc
		(start 356.264972 -11.850116)
		(mid 356.557865 -12.557221)
		(end 357.26497 -12.850114)
		(stroke
			(width 3.048)
			(type default)
		)
		(layer "In3.Cu")
	)
	(gr_arc
		(start 356.264972 -1.999996)
		(mid 355.679184 -0.585796)
		(end 354.264976 0)
		(stroke
			(width 3.048)
			(type default)
		)
		(layer "In3.Cu")
	)
	(gr_line
		(start 356.264972 -1.999996)
		(end 356.264972 -11.850116)
		(stroke
			(width 3.048)
			(type default)
		)
		(layer "In3.Cu")
	)
	(gr_line
		(start 357.26497 -12.850114)
		(end 365.264954 -12.850114)
		(stroke
			(width 3.048)
			(type default)
		)
		(layer "In3.Cu")
	)
	(gr_line
		(start 362.985812 -271.989804)
		(end 269.12316 -271.989804)
		(stroke
			(width 0.635)
			(type default)
		)
		(layer "In3.Cu")
	)
	(gr_circle
		(center 363.590078 -407.599896)
		(end 368.765074 -407.599896)
		(stroke
			(width 0.2)
			(type default)
		)
		(fill no)
		(layer "In3.Cu")
	)
	(gr_line
		(start 364.754922 -270.220694)
		(end 362.985812 -271.989804)
		(stroke
			(width 0.635)
			(type default)
		)
		(layer "In3.Cu")
	)
	(gr_line
		(start 364.754922 -270.220694)
		(end 363.830362 -271.145254)
		(stroke
			(width 0.508)
			(type default)
		)
		(layer "In3.Cu")
	)
	(gr_arc
		(start 365.264954 -12.850114)
		(mid 365.972059 -12.557221)
		(end 366.264952 -11.850116)
		(stroke
			(width 3.048)
			(type default)
		)
		(layer "In3.Cu")
	)
	(gr_line
		(start 366.264952 -11.850116)
		(end 366.264952 -1.999996)
		(stroke
			(width 3.048)
			(type default)
		)
		(layer "In3.Cu")
	)
	(gr_line
		(start 367.052352 -278.446992)
		(end 367.68913 -279.08377)
		(stroke
			(width 0.508)
			(type default)
		)
		(layer "In3.Cu")
	)
	(gr_line
		(start 367.133378 -294.174164)
		(end 349.15475 -294.174164)
		(stroke
			(width 0.508)
			(type default)
		)
		(layer "In3.Cu")
	)
	(gr_line
		(start 367.68913 -293.618412)
		(end 367.133378 -294.174164)
		(stroke
			(width 0.508)
			(type default)
		)
		(layer "In3.Cu")
	)
	(gr_line
		(start 367.68913 -279.08377)
		(end 367.68913 -293.618412)
		(stroke
			(width 0.508)
			(type default)
		)
		(layer "In3.Cu")
	)
	(gr_line
		(start 367.689384 -286.086804)
		(end 367.960402 -286.357822)
		(stroke
			(width 0.508)
			(type default)
		)
		(layer "In3.Cu")
	)
	(gr_line
		(start 367.758726 -286.621728)
		(end 367.980468 -286.399986)
		(stroke
			(width 0.508)
			(type default)
		)
		(layer "In3.Cu")
	)
	(gr_line
		(start 367.766092 -286.621728)
		(end 367.758726 -286.621728)
		(stroke
			(width 0.508)
			(type default)
		)
		(layer "In3.Cu")
	)
	(gr_line
		(start 367.960402 -286.427418)
		(end 367.766092 -286.621728)
		(stroke
			(width 0.508)
			(type default)
		)
		(layer "In3.Cu")
	)
	(gr_line
		(start 367.960402 -286.357822)
		(end 367.960402 -286.427418)
		(stroke
			(width 0.508)
			(type default)
		)
		(layer "In3.Cu")
	)
	(gr_line
		(start 367.980468 -286.399986)
		(end 430.885854 -286.399986)
		(stroke
			(width 0.508)
			(type default)
		)
		(layer "In3.Cu")
	)
	(gr_arc
		(start 368.264948 0)
		(mid 366.850705 -0.585768)
		(end 366.264952 -1.999996)
		(stroke
			(width 3.048)
			(type default)
		)
		(layer "In3.Cu")
	)
	(gr_line
		(start 368.264948 0)
		(end 380.264924 0)
		(stroke
			(width 3.048)
			(type default)
		)
		(layer "In3.Cu")
	)
	(gr_circle
		(center 368.44986 -276.010116)
		(end 370.557806 -276.010116)
		(stroke
			(width 0.2)
			(type default)
		)
		(fill no)
		(layer "In3.Cu")
	)
	(gr_line
		(start 373.096282 -270.220694)
		(end 364.754922 -270.220694)
		(stroke
			(width 0.635)
			(type default)
		)
		(layer "In3.Cu")
	)
	(gr_line
		(start 373.096282 -270.220694)
		(end 374.232678 -271.35709)
		(stroke
			(width 0.508)
			(type default)
		)
		(layer "In3.Cu")
	)
	(gr_line
		(start 374.684798 -271.989804)
		(end 374.684798 -271.80921)
		(stroke
			(width 0.635)
			(type default)
		)
		(layer "In3.Cu")
	)
	(gr_line
		(start 374.684798 -271.80921)
		(end 373.096282 -270.220694)
		(stroke
			(width 0.635)
			(type default)
		)
		(layer "In3.Cu")
	)
	(gr_circle
		(center 377.949968 -320.900044)
		(end 382.585976 -320.900044)
		(stroke
			(width 0.2)
			(type default)
		)
		(fill no)
		(layer "In3.Cu")
	)
	(gr_circle
		(center 377.949968 -270.89989)
		(end 382.585976 -270.89989)
		(stroke
			(width 0.2)
			(type default)
		)
		(fill no)
		(layer "In3.Cu")
	)
	(gr_arc
		(start 382.26492 -11.850116)
		(mid 382.557813 -12.557221)
		(end 383.264918 -12.850114)
		(stroke
			(width 3.048)
			(type default)
		)
		(layer "In3.Cu")
	)
	(gr_arc
		(start 382.26492 -1.999996)
		(mid 381.679135 -0.585779)
		(end 380.264924 0)
		(stroke
			(width 3.048)
			(type default)
		)
		(layer "In3.Cu")
	)
	(gr_line
		(start 382.26492 -1.999996)
		(end 382.26492 -11.850116)
		(stroke
			(width 3.048)
			(type default)
		)
		(layer "In3.Cu")
	)
	(gr_line
		(start 383.264918 -12.850114)
		(end 391.264902 -12.850114)
		(stroke
			(width 3.048)
			(type default)
		)
		(layer "In3.Cu")
	)
	(gr_arc
		(start 391.264902 -12.850114)
		(mid 391.972007 -12.557221)
		(end 392.2649 -11.850116)
		(stroke
			(width 3.048)
			(type default)
		)
		(layer "In3.Cu")
	)
	(gr_line
		(start 392.2649 -11.850116)
		(end 392.2649 -1.999996)
		(stroke
			(width 3.048)
			(type default)
		)
		(layer "In3.Cu")
	)
	(gr_arc
		(start 394.264896 0)
		(mid 392.850686 -0.585786)
		(end 392.2649 -1.999996)
		(stroke
			(width 3.048)
			(type default)
		)
		(layer "In3.Cu")
	)
	(gr_line
		(start 394.264896 0)
		(end 406.265126 0)
		(stroke
			(width 3.048)
			(type default)
		)
		(layer "In3.Cu")
	)
	(gr_circle
		(center 400.264884 -4.99999)
		(end 405.43988 -4.99999)
		(stroke
			(width 0.2)
			(type default)
		)
		(fill no)
		(layer "In3.Cu")
	)
	(gr_arc
		(start 408.265122 -11.850116)
		(mid 408.558015 -12.557221)
		(end 409.26512 -12.850114)
		(stroke
			(width 3.048)
			(type default)
		)
		(layer "In3.Cu")
	)
	(gr_arc
		(start 408.265122 -1.999996)
		(mid 407.679337 -0.585779)
		(end 406.265126 0)
		(stroke
			(width 3.048)
			(type default)
		)
		(layer "In3.Cu")
	)
	(gr_line
		(start 408.265122 -1.999996)
		(end 408.265122 -11.850116)
		(stroke
			(width 3.048)
			(type default)
		)
		(layer "In3.Cu")
	)
	(gr_line
		(start 409.26512 -12.850114)
		(end 417.265104 -12.850114)
		(stroke
			(width 3.048)
			(type default)
		)
		(layer "In3.Cu")
	)
	(gr_arc
		(start 417.265104 -12.850114)
		(mid 417.972209 -12.557221)
		(end 418.265102 -11.850116)
		(stroke
			(width 3.048)
			(type default)
		)
		(layer "In3.Cu")
	)
	(gr_line
		(start 418.265102 -11.850116)
		(end 418.265102 -1.999996)
		(stroke
			(width 3.048)
			(type default)
		)
		(layer "In3.Cu")
	)
	(gr_arc
		(start 420.265098 0)
		(mid 418.850887 -0.585786)
		(end 418.265102 -1.999996)
		(stroke
			(width 3.048)
			(type default)
		)
		(layer "In3.Cu")
	)
	(gr_line
		(start 420.265098 0)
		(end 432.265074 0)
		(stroke
			(width 3.048)
			(type default)
		)
		(layer "In3.Cu")
	)
	(gr_line
		(start 429.985678 -338.174838)
		(end 431.225452 -336.935064)
		(stroke
			(width 0.635)
			(type default)
		)
		(layer "In3.Cu")
	)
	(gr_line
		(start 430.405286 -271.989804)
		(end 375.017792 -271.989804)
		(stroke
			(width 0.635)
			(type default)
		)
		(layer "In3.Cu")
	)
	(gr_line
		(start 430.40554 -271.989804)
		(end 374.684798 -271.989804)
		(stroke
			(width 0.635)
			(type default)
		)
		(layer "In3.Cu")
	)
	(gr_line
		(start 430.40554 -271.989804)
		(end 375.017792 -271.989804)
		(stroke
			(width 0.635)
			(type default)
		)
		(layer "In3.Cu")
	)
	(gr_line
		(start 430.415192 -271.99971)
		(end 430.405286 -271.989804)
		(stroke
			(width 0.635)
			(type default)
		)
		(layer "In3.Cu")
	)
	(gr_line
		(start 430.540414 -271.99971)
		(end 430.415192 -271.99971)
		(stroke
			(width 0.635)
			(type default)
		)
		(layer "In3.Cu")
	)
	(gr_line
		(start 430.885854 -286.399986)
		(end 431.219356 -286.733488)
		(stroke
			(width 0.508)
			(type default)
		)
		(layer "In3.Cu")
	)
	(gr_line
		(start 430.906682 -286.38627)
		(end 430.906682 -286.337502)
		(stroke
			(width 0.508)
			(type default)
		)
		(layer "In3.Cu")
	)
	(gr_line
		(start 430.906682 -286.337502)
		(end 431.184558 -286.059626)
		(stroke
			(width 0.508)
			(type default)
		)
		(layer "In3.Cu")
	)
	(gr_line
		(start 431.184558 -286.059626)
		(end 431.198528 -286.059626)
		(stroke
			(width 0.508)
			(type default)
		)
		(layer "In3.Cu")
	)
	(gr_line
		(start 431.219356 -286.733488)
		(end 431.219356 -286.698944)
		(stroke
			(width 0.508)
			(type default)
		)
		(layer "In3.Cu")
	)
	(gr_line
		(start 431.219356 -286.698944)
		(end 430.906682 -286.38627)
		(stroke
			(width 0.508)
			(type default)
		)
		(layer "In3.Cu")
	)
	(gr_line
		(start 431.224944 -318.224662)
		(end 431.224944 -272.68424)
		(stroke
			(width 0.635)
			(type default)
		)
		(layer "In3.Cu")
	)
	(gr_line
		(start 431.224944 -272.68424)
		(end 430.540414 -271.99971)
		(stroke
			(width 0.635)
			(type default)
		)
		(layer "In3.Cu")
	)
	(gr_line
		(start 431.225198 -326.572118)
		(end 431.225198 -318.224916)
		(stroke
			(width 0.635)
			(type default)
		)
		(layer "In3.Cu")
	)
	(gr_line
		(start 431.225198 -318.224916)
		(end 431.224944 -318.224662)
		(stroke
			(width 0.635)
			(type default)
		)
		(layer "In3.Cu")
	)
	(gr_line
		(start 431.225452 -336.935064)
		(end 431.225452 -326.572118)
		(stroke
			(width 0.635)
			(type default)
		)
		(layer "In3.Cu")
	)
	(gr_arc
		(start 434.26507 -11.850116)
		(mid 434.557963 -12.557221)
		(end 435.265068 -12.850114)
		(stroke
			(width 3.048)
			(type default)
		)
		(layer "In3.Cu")
	)
	(gr_arc
		(start 434.26507 -1.999996)
		(mid 433.679282 -0.585797)
		(end 432.265074 0)
		(stroke
			(width 3.048)
			(type default)
		)
		(layer "In3.Cu")
	)
	(gr_line
		(start 434.26507 -1.999996)
		(end 434.26507 -11.850116)
		(stroke
			(width 3.048)
			(type default)
		)
		(layer "In3.Cu")
	)
	(gr_line
		(start 435.265068 -12.850114)
		(end 443.265052 -12.850114)
		(stroke
			(width 3.048)
			(type default)
		)
		(layer "In3.Cu")
	)
	(gr_circle
		(center 437.950102 -320.900044)
		(end 442.58611 -320.900044)
		(stroke
			(width 0.2)
			(type default)
		)
		(fill no)
		(layer "In3.Cu")
	)
	(gr_circle
		(center 437.950102 -270.89989)
		(end 442.58611 -270.89989)
		(stroke
			(width 0.2)
			(type default)
		)
		(fill no)
		(layer "In3.Cu")
	)
	(gr_arc
		(start 443.265052 -12.850114)
		(mid 443.972157 -12.557221)
		(end 444.26505 -11.850116)
		(stroke
			(width 3.048)
			(type default)
		)
		(layer "In3.Cu")
	)
	(gr_line
		(start 444.26505 -11.850116)
		(end 444.26505 -1.999996)
		(stroke
			(width 3.048)
			(type default)
		)
		(layer "In3.Cu")
	)
	(gr_line
		(start 445.85636 -242.24742)
		(end 447.06413 -243.45519)
		(stroke
			(width 0.635)
			(type default)
		)
		(layer "In3.Cu")
	)
	(gr_arc
		(start 446.265046 0)
		(mid 444.850804 -0.585769)
		(end 444.26505 -1.999996)
		(stroke
			(width 3.048)
			(type default)
		)
		(layer "In3.Cu")
	)
	(gr_line
		(start 446.265046 0)
		(end 465.600034 0)
		(stroke
			(width 3.048)
			(type default)
		)
		(layer "In3.Cu")
	)
	(gr_line
		(start 447.06413 -243.45519)
		(end 463.376264 -243.45519)
		(stroke
			(width 0.635)
			(type default)
		)
		(layer "In3.Cu")
	)
	(gr_circle
		(center 447.449702 -308.61)
		(end 449.557648 -308.61)
		(stroke
			(width 0.2)
			(type default)
		)
		(fill no)
		(layer "In3.Cu")
	)
	(gr_circle
		(center 448.799966 -84.699856)
		(end 453.974962 -84.699856)
		(stroke
			(width 0.2)
			(type default)
		)
		(fill no)
		(layer "In3.Cu")
	)
	(gr_circle
		(center 451.79996 -194.360038)
		(end 456.974956 -194.360038)
		(stroke
			(width 0.2)
			(type default)
		)
		(fill no)
		(layer "In3.Cu")
	)
	(gr_circle
		(center 455.93254 -4.99999)
		(end 461.107536 -4.99999)
		(stroke
			(width 0.2)
			(type default)
		)
		(fill no)
		(layer "In3.Cu")
	)
	(gr_circle
		(center 461.600042 -407.599896)
		(end 466.775038 -407.599896)
		(stroke
			(width 0.2)
			(type default)
		)
		(fill no)
		(layer "In3.Cu")
	)
	(gr_line
		(start 463.376264 -243.45519)
		(end 464.38566 -242.445794)
		(stroke
			(width 0.508)
			(type default)
		)
		(layer "In3.Cu")
	)
	(gr_arc
		(start 463.799936 -241.031522)
		(mid 463.952177 -241.796887)
		(end 464.38566 -242.445794)
		(stroke
			(width 3.048)
			(type default)
		)
		(layer "In3.Cu")
	)
	(gr_line
		(start 463.799936 -87.588344)
		(end 463.799936 -241.031522)
		(stroke
			(width 3.048)
			(type default)
		)
		(layer "In3.Cu")
	)
	(gr_circle
		(center 464.100164 -313.85002)
		(end 466.20811 -313.85002)
		(stroke
			(width 0.2)
			(type default)
		)
		(fill no)
		(layer "In3.Cu")
	)
	(gr_line
		(start 464.38566 -242.445794)
		(end 467.014306 -245.074186)
		(stroke
			(width 3.048)
			(type default)
		)
		(layer "In3.Cu")
	)
	(gr_arc
		(start 464.38566 -86.174326)
		(mid 463.952174 -86.823083)
		(end 463.799936 -87.588344)
		(stroke
			(width 3.048)
			(type default)
		)
		(layer "In3.Cu")
	)
	(gr_line
		(start 465.600034 -418.589968)
		(end 274.758658 -418.589968)
		(stroke
			(width 3.048)
			(type default)
		)
		(layer "In3.Cu")
	)
	(gr_arc
		(start 465.600034 -418.589968)
		(mid 467.014213 -418.004169)
		(end 467.60003 -416.589972)
		(stroke
			(width 3.048)
			(type default)
		)
		(layer "In3.Cu")
	)
	(gr_line
		(start 467.007448 -367.183162)
		(end 267.890244 -367.183162)
		(stroke
			(width 0.635)
			(type default)
		)
		(layer "In3.Cu")
	)
	(gr_line
		(start 467.014306 -83.54568)
		(end 464.38566 -86.174326)
		(stroke
			(width 3.048)
			(type default)
		)
		(layer "In3.Cu")
	)
	(gr_arc
		(start 467.014306 -83.54568)
		(mid 467.447803 -82.896927)
		(end 467.60003 -82.131662)
		(stroke
			(width 3.048)
			(type default)
		)
		(layer "In3.Cu")
	)
	(gr_line
		(start 467.146386 -367.238788)
		(end 467.590886 -367.683288)
		(stroke
			(width 0.635)
			(type default)
		)
		(layer "In3.Cu")
	)
	(gr_line
		(start 467.590886 -367.7666)
		(end 467.007448 -367.183162)
		(stroke
			(width 0.635)
			(type default)
		)
		(layer "In3.Cu")
	)
	(gr_line
		(start 467.590886 -367.683288)
		(end 467.590886 -367.7666)
		(stroke
			(width 0.635)
			(type default)
		)
		(layer "In3.Cu")
	)
	(gr_arc
		(start 467.60003 -246.488458)
		(mid 467.447879 -245.723043)
		(end 467.014306 -245.074186)
		(stroke
			(width 3.048)
			(type default)
		)
		(layer "In3.Cu")
	)
	(gr_line
		(start 467.60003 -246.488458)
		(end 467.60003 -416.589972)
		(stroke
			(width 3.048)
			(type default)
		)
		(layer "In3.Cu")
	)
	(gr_arc
		(start 467.60003 -1.999996)
		(mid 467.014245 -0.585776)
		(end 465.600034 0)
		(stroke
			(width 3.048)
			(type default)
		)
		(layer "In3.Cu")
	)
	(gr_line
		(start 467.60003 -1.999996)
		(end 467.60003 -82.131662)
		(stroke
			(width 3.048)
			(type default)
		)
		(layer "In3.Cu")
	)
	(gr_line
		(start 467.618826 -366.766348)
		(end 467.146386 -367.238788)
		(stroke
			(width 0.635)
			(type default)
		)
		(layer "In3.Cu")
	)
	(gr_line
		(start 467.702138 -366.766348)
		(end 467.618826 -366.766348)
		(stroke
			(width 0.635)
			(type default)
		)
		(layer "In3.Cu")
	)
	(gr_poly
		(pts
			(arc
				(start 265.615928 -377.679966)
				(mid 265.635451 -377.676065)
				(end 265.651996 -377.66498)
			)
			(arc
				(start 265.851386 -377.46559)
				(mid 265.862497 -377.449056)
				(end 265.866372 -377.429522)
			)
			(arc
				(start 265.866372 -368.884962)
				(mid 265.862471 -368.865439)
				(end 265.851386 -368.848894)
			)
			(arc
				(start 265.514582 -368.51209)
				(mid 265.498048 -368.500979)
				(end 265.478514 -368.497104)
			)
			(arc
				(start 242.901216 -368.497104)
				(mid 242.881693 -368.501005)
				(end 242.865148 -368.51209)
			)
			(arc
				(start 242.760754 -368.616484)
				(mid 242.749643 -368.633018)
				(end 242.745768 -368.652552)
			)
			(arc
				(start 242.745768 -377.268994)
				(mid 242.749669 -377.288517)
				(end 242.760754 -377.305062)
			)
			(arc
				(start 243.120672 -377.66498)
				(mid 243.137206 -377.676091)
				(end 243.15674 -377.679966)
			)
		)
		(stroke
			(width 0)
			(type solid)
		)
		(fill yes)
		(layer "In4.Cu")
		(net "P12V_STBY_R2")
	)
	(gr_poly
		(pts
			(arc
				(start 37.053012 -316.799722)
				(mid 36.646612 -316.799722)
				(end 37.053012 -316.799722)
			)
		)
		(stroke
			(width 0)
			(type solid)
		)
		(fill yes)
		(layer "In4.Cu")
		(net "P5E_PEX0_STN7_RX_DN<122>")
	)
	(gr_poly
		(pts
			(arc
				(start 37.053012 -314.899802)
				(mid 36.646612 -314.899802)
				(end 37.053012 -314.899802)
			)
		)
		(stroke
			(width 0)
			(type solid)
		)
		(fill yes)
		(layer "In4.Cu")
		(net "P5E_PEX0_STN7_TX_DN<122>")
	)
	(gr_poly
		(pts
			(arc
				(start 37.053012 -312.049922)
				(mid 36.646612 -312.049922)
				(end 37.053012 -312.049922)
			)
		)
		(stroke
			(width 0)
			(type solid)
		)
		(fill yes)
		(layer "In4.Cu")
		(net "P5E_PEX0_STN7_TX_DN<121>")
	)
	(gr_poly
		(pts
			(arc
				(start 37.053012 -310.149748)
				(mid 36.646612 -310.149748)
				(end 37.053012 -310.149748)
			)
		)
		(stroke
			(width 0)
			(type solid)
		)
		(fill yes)
		(layer "In4.Cu")
		(net "P5E_PEX0_STN7_RX_DN<121>")
	)
	(gr_poly
		(pts
			(arc
				(start 37.053012 -308.249828)
				(mid 36.646612 -308.249828)
				(end 37.053012 -308.249828)
			)
		)
		(stroke
			(width 0)
			(type solid)
		)
		(fill yes)
		(layer "In4.Cu")
		(net "P5E_PEX0_STN7_RX_DN<119>")
	)
	(gr_poly
		(pts
			(arc
				(start 37.053012 -306.349908)
				(mid 36.646612 -306.349908)
				(end 37.053012 -306.349908)
			)
		)
		(stroke
			(width 0)
			(type solid)
		)
		(fill yes)
		(layer "In4.Cu")
		(net "P5E_PEX0_STN7_RX_DN<117>")
	)
	(gr_poly
		(pts
			(arc
				(start 37.053012 -304.449734)
				(mid 36.646612 -304.449734)
				(end 37.053012 -304.449734)
			)
		)
		(stroke
			(width 0)
			(type solid)
		)
		(fill yes)
		(layer "In4.Cu")
		(net "P5E_PEX0_STN7_RX_DN<115>")
	)
	(gr_poly
		(pts
			(arc
				(start 37.053012 -302.549814)
				(mid 36.646612 -302.549814)
				(end 37.053012 -302.549814)
			)
		)
		(stroke
			(width 0)
			(type solid)
		)
		(fill yes)
		(layer "In4.Cu")
		(net "P5E_PEX0_STN7_RX_DN<113>")
	)
	(gr_poly
		(pts
			(arc
				(start 38.002972 -316.799722)
				(mid 37.596572 -316.799722)
				(end 38.002972 -316.799722)
			)
		)
		(stroke
			(width 0)
			(type solid)
		)
		(fill yes)
		(layer "In4.Cu")
		(net "P5E_PEX0_STN7_RX_DP<122>")
	)
	(gr_poly
		(pts
			(arc
				(start 38.002972 -314.899802)
				(mid 37.596572 -314.899802)
				(end 38.002972 -314.899802)
			)
		)
		(stroke
			(width 0)
			(type solid)
		)
		(fill yes)
		(layer "In4.Cu")
		(net "P5E_PEX0_STN7_TX_DP<122>")
	)
	(gr_poly
		(pts
			(arc
				(start 38.002972 -312.049922)
				(mid 37.596572 -312.049922)
				(end 38.002972 -312.049922)
			)
		)
		(stroke
			(width 0)
			(type solid)
		)
		(fill yes)
		(layer "In4.Cu")
		(net "P5E_PEX0_STN7_TX_DP<121>")
	)
	(gr_poly
		(pts
			(arc
				(start 38.002972 -310.149748)
				(mid 37.596572 -310.149748)
				(end 38.002972 -310.149748)
			)
		)
		(stroke
			(width 0)
			(type solid)
		)
		(fill yes)
		(layer "In4.Cu")
		(net "P5E_PEX0_STN7_RX_DP<121>")
	)
	(gr_poly
		(pts
			(arc
				(start 38.002972 -308.249828)
				(mid 37.596572 -308.249828)
				(end 38.002972 -308.249828)
			)
		)
		(stroke
			(width 0)
			(type solid)
		)
		(fill yes)
		(layer "In4.Cu")
		(net "P5E_PEX0_STN7_RX_DP<119>")
	)
	(gr_poly
		(pts
			(arc
				(start 38.002972 -306.349908)
				(mid 37.596572 -306.349908)
				(end 38.002972 -306.349908)
			)
		)
		(stroke
			(width 0)
			(type solid)
		)
		(fill yes)
		(layer "In4.Cu")
		(net "P5E_PEX0_STN7_RX_DP<117>")
	)
	(gr_poly
		(pts
			(arc
				(start 38.002972 -304.449734)
				(mid 37.596572 -304.449734)
				(end 38.002972 -304.449734)
			)
		)
		(stroke
			(width 0)
			(type solid)
		)
		(fill yes)
		(layer "In4.Cu")
		(net "P5E_PEX0_STN7_RX_DP<115>")
	)
	(gr_poly
		(pts
			(arc
				(start 38.002972 -302.549814)
				(mid 37.596572 -302.549814)
				(end 38.002972 -302.549814)
			)
		)
		(stroke
			(width 0)
			(type solid)
		)
		(fill yes)
		(layer "In4.Cu")
		(net "P5E_PEX0_STN7_RX_DP<113>")
	)
	(gr_poly
		(pts
			(arc
				(start 38.953186 -318.699896)
				(mid 38.546786 -318.699896)
				(end 38.953186 -318.699896)
			)
		)
		(stroke
			(width 0)
			(type solid)
		)
		(fill yes)
		(layer "In4.Cu")
		(net "P5E_PEX0_STN7_RX_DN<123>")
	)
	(gr_poly
		(pts
			(arc
				(start 38.953186 -317.749936)
				(mid 38.546786 -317.749936)
				(end 38.953186 -317.749936)
			)
		)
		(stroke
			(width 0)
			(type solid)
		)
		(fill yes)
		(layer "In4.Cu")
		(net "P5E_PEX0_STN7_RX_DP<123>")
	)
	(gr_poly
		(pts
			(arc
				(start 38.953186 -313.949842)
				(mid 38.546786 -313.949842)
				(end 38.953186 -313.949842)
			)
		)
		(stroke
			(width 0)
			(type solid)
		)
		(fill yes)
		(layer "In4.Cu")
		(net "P5E_PEX0_STN7_TX_DN<123>")
	)
	(gr_poly
		(pts
			(arc
				(start 38.953186 -312.999882)
				(mid 38.546786 -312.999882)
				(end 38.953186 -312.999882)
			)
		)
		(stroke
			(width 0)
			(type solid)
		)
		(fill yes)
		(layer "In4.Cu")
		(net "P5E_PEX0_STN7_TX_DP<123>")
	)
	(gr_poly
		(pts
			(arc
				(start 38.953186 -309.199788)
				(mid 38.546786 -309.199788)
				(end 38.953186 -309.199788)
			)
		)
		(stroke
			(width 0)
			(type solid)
		)
		(fill yes)
		(layer "In4.Cu")
		(net "P5E_PEX0_STN7_RX_DN<120>")
	)
	(gr_poly
		(pts
			(arc
				(start 38.953186 -307.299868)
				(mid 38.546786 -307.299868)
				(end 38.953186 -307.299868)
			)
		)
		(stroke
			(width 0)
			(type solid)
		)
		(fill yes)
		(layer "In4.Cu")
		(net "P5E_PEX0_STN7_RX_DN<118>")
	)
	(gr_poly
		(pts
			(arc
				(start 38.953186 -305.399948)
				(mid 38.546786 -305.399948)
				(end 38.953186 -305.399948)
			)
		)
		(stroke
			(width 0)
			(type solid)
		)
		(fill yes)
		(layer "In4.Cu")
		(net "P5E_PEX0_STN7_RX_DN<116>")
	)
	(gr_poly
		(pts
			(arc
				(start 38.953186 -303.499774)
				(mid 38.546786 -303.499774)
				(end 38.953186 -303.499774)
			)
		)
		(stroke
			(width 0)
			(type solid)
		)
		(fill yes)
		(layer "In4.Cu")
		(net "P5E_PEX0_STN7_RX_DN<114>")
	)
	(gr_poly
		(pts
			(arc
				(start 38.953186 -301.599854)
				(mid 38.546786 -301.599854)
				(end 38.953186 -301.599854)
			)
		)
		(stroke
			(width 0)
			(type solid)
		)
		(fill yes)
		(layer "In4.Cu")
		(net "P5E_PEX0_STN7_RX_DN<112>")
	)
	(gr_poly
		(pts
			(arc
				(start 39.903146 -316.799722)
				(mid 39.496746 -316.799722)
				(end 39.903146 -316.799722)
			)
		)
		(stroke
			(width 0)
			(type solid)
		)
		(fill yes)
		(layer "In4.Cu")
		(net "P5E_PEX0_STN7_RX_DN<124>")
	)
	(gr_poly
		(pts
			(arc
				(start 39.903146 -315.849762)
				(mid 39.496746 -315.849762)
				(end 39.903146 -315.849762)
			)
		)
		(stroke
			(width 0)
			(type solid)
		)
		(fill yes)
		(layer "In4.Cu")
		(net "P5E_PEX0_STN7_RX_DP<124>")
	)
	(gr_poly
		(pts
			(arc
				(start 39.903146 -312.049922)
				(mid 39.496746 -312.049922)
				(end 39.903146 -312.049922)
			)
		)
		(stroke
			(width 0)
			(type solid)
		)
		(fill yes)
		(layer "In4.Cu")
		(net "P5E_PEX0_STN7_TX_DN<124>")
	)
	(gr_poly
		(pts
			(arc
				(start 39.903146 -311.099962)
				(mid 39.496746 -311.099962)
				(end 39.903146 -311.099962)
			)
		)
		(stroke
			(width 0)
			(type solid)
		)
		(fill yes)
		(layer "In4.Cu")
		(net "P5E_PEX0_STN7_TX_DP<124>")
	)
	(gr_poly
		(pts
			(arc
				(start 39.903146 -309.199788)
				(mid 39.496746 -309.199788)
				(end 39.903146 -309.199788)
			)
		)
		(stroke
			(width 0)
			(type solid)
		)
		(fill yes)
		(layer "In4.Cu")
		(net "P5E_PEX0_STN7_RX_DP<120>")
	)
	(gr_poly
		(pts
			(arc
				(start 39.903146 -307.299868)
				(mid 39.496746 -307.299868)
				(end 39.903146 -307.299868)
			)
		)
		(stroke
			(width 0)
			(type solid)
		)
		(fill yes)
		(layer "In4.Cu")
		(net "P5E_PEX0_STN7_RX_DP<118>")
	)
	(gr_poly
		(pts
			(arc
				(start 39.903146 -305.399948)
				(mid 39.496746 -305.399948)
				(end 39.903146 -305.399948)
			)
		)
		(stroke
			(width 0)
			(type solid)
		)
		(fill yes)
		(layer "In4.Cu")
		(net "P5E_PEX0_STN7_RX_DP<116>")
	)
	(gr_poly
		(pts
			(arc
				(start 39.903146 -303.499774)
				(mid 39.496746 -303.499774)
				(end 39.903146 -303.499774)
			)
		)
		(stroke
			(width 0)
			(type solid)
		)
		(fill yes)
		(layer "In4.Cu")
		(net "P5E_PEX0_STN7_RX_DP<114>")
	)
	(gr_poly
		(pts
			(arc
				(start 39.903146 -301.599854)
				(mid 39.496746 -301.599854)
				(end 39.903146 -301.599854)
			)
		)
		(stroke
			(width 0)
			(type solid)
		)
		(fill yes)
		(layer "In4.Cu")
		(net "P5E_PEX0_STN7_RX_DP<112>")
	)
	(gr_poly
		(pts
			(arc
				(start 40.853106 -318.699896)
				(mid 40.446706 -318.699896)
				(end 40.853106 -318.699896)
			)
		)
		(stroke
			(width 0)
			(type solid)
		)
		(fill yes)
		(layer "In4.Cu")
		(net "P5E_PEX0_STN7_RX_DN<125>")
	)
	(gr_poly
		(pts
			(arc
				(start 40.853106 -317.749936)
				(mid 40.446706 -317.749936)
				(end 40.853106 -317.749936)
			)
		)
		(stroke
			(width 0)
			(type solid)
		)
		(fill yes)
		(layer "In4.Cu")
		(net "P5E_PEX0_STN7_RX_DP<125>")
	)
	(gr_poly
		(pts
			(arc
				(start 40.853106 -313.949842)
				(mid 40.446706 -313.949842)
				(end 40.853106 -313.949842)
			)
		)
		(stroke
			(width 0)
			(type solid)
		)
		(fill yes)
		(layer "In4.Cu")
		(net "P5E_PEX0_STN7_TX_DN<125>")
	)
	(gr_poly
		(pts
			(arc
				(start 40.853106 -312.999882)
				(mid 40.446706 -312.999882)
				(end 40.853106 -312.999882)
			)
		)
		(stroke
			(width 0)
			(type solid)
		)
		(fill yes)
		(layer "In4.Cu")
		(net "P5E_PEX0_STN7_TX_DP<125>")
	)
	(gr_poly
		(pts
			(arc
				(start 41.803066 -316.799722)
				(mid 41.396666 -316.799722)
				(end 41.803066 -316.799722)
			)
		)
		(stroke
			(width 0)
			(type solid)
		)
		(fill yes)
		(layer "In4.Cu")
		(net "P5E_PEX0_STN7_RX_DN<126>")
	)
	(gr_poly
		(pts
			(arc
				(start 41.803066 -315.849762)
				(mid 41.396666 -315.849762)
				(end 41.803066 -315.849762)
			)
		)
		(stroke
			(width 0)
			(type solid)
		)
		(fill yes)
		(layer "In4.Cu")
		(net "P5E_PEX0_STN7_RX_DP<126>")
	)
	(gr_poly
		(pts
			(arc
				(start 41.803066 -312.049922)
				(mid 41.396666 -312.049922)
				(end 41.803066 -312.049922)
			)
		)
		(stroke
			(width 0)
			(type solid)
		)
		(fill yes)
		(layer "In4.Cu")
		(net "P5E_PEX0_STN7_TX_DN<126>")
	)
	(gr_poly
		(pts
			(arc
				(start 41.803066 -311.099962)
				(mid 41.396666 -311.099962)
				(end 41.803066 -311.099962)
			)
		)
		(stroke
			(width 0)
			(type solid)
		)
		(fill yes)
		(layer "In4.Cu")
		(net "P5E_PEX0_STN7_TX_DP<126>")
	)
	(gr_poly
		(pts
			(arc
				(start 41.803066 -309.199788)
				(mid 41.396666 -309.199788)
				(end 41.803066 -309.199788)
			)
		)
		(stroke
			(width 0)
			(type solid)
		)
		(fill yes)
		(layer "In4.Cu")
		(net "P5E_PEX0_STN7_TX_DN<120>")
	)
	(gr_poly
		(pts
			(arc
				(start 41.803066 -307.299868)
				(mid 41.396666 -307.299868)
				(end 41.803066 -307.299868)
			)
		)
		(stroke
			(width 0)
			(type solid)
		)
		(fill yes)
		(layer "In4.Cu")
		(net "P5E_PEX0_STN7_TX_DN<118>")
	)
	(gr_poly
		(pts
			(arc
				(start 41.803066 -305.399948)
				(mid 41.396666 -305.399948)
				(end 41.803066 -305.399948)
			)
		)
		(stroke
			(width 0)
			(type solid)
		)
		(fill yes)
		(layer "In4.Cu")
		(net "P5E_PEX0_STN7_TX_DN<116>")
	)
	(gr_poly
		(pts
			(arc
				(start 41.803066 -303.499774)
				(mid 41.396666 -303.499774)
				(end 41.803066 -303.499774)
			)
		)
		(stroke
			(width 0)
			(type solid)
		)
		(fill yes)
		(layer "In4.Cu")
		(net "P5E_PEX0_STN7_TX_DN<114>")
	)
	(gr_poly
		(pts
			(arc
				(start 41.803066 -301.599854)
				(mid 41.396666 -301.599854)
				(end 41.803066 -301.599854)
			)
		)
		(stroke
			(width 0)
			(type solid)
		)
		(fill yes)
		(layer "In4.Cu")
		(net "P5E_PEX0_STN7_TX_DN<112>")
	)
	(gr_poly
		(pts
			(arc
				(start 42.753026 -318.699896)
				(mid 42.346626 -318.699896)
				(end 42.753026 -318.699896)
			)
		)
		(stroke
			(width 0)
			(type solid)
		)
		(fill yes)
		(layer "In4.Cu")
		(net "P5E_PEX0_STN7_RX_DN<127>")
	)
	(gr_poly
		(pts
			(arc
				(start 42.753026 -317.749936)
				(mid 42.346626 -317.749936)
				(end 42.753026 -317.749936)
			)
		)
		(stroke
			(width 0)
			(type solid)
		)
		(fill yes)
		(layer "In4.Cu")
		(net "P5E_PEX0_STN7_RX_DP<127>")
	)
	(gr_poly
		(pts
			(arc
				(start 42.753026 -313.949842)
				(mid 42.346626 -313.949842)
				(end 42.753026 -313.949842)
			)
		)
		(stroke
			(width 0)
			(type solid)
		)
		(fill yes)
		(layer "In4.Cu")
		(net "P5E_PEX0_STN7_TX_DN<127>")
	)
	(gr_poly
		(pts
			(arc
				(start 42.753026 -312.999882)
				(mid 42.346626 -312.999882)
				(end 42.753026 -312.999882)
			)
		)
		(stroke
			(width 0)
			(type solid)
		)
		(fill yes)
		(layer "In4.Cu")
		(net "P5E_PEX0_STN7_TX_DP<127>")
	)
	(gr_poly
		(pts
			(arc
				(start 42.753026 -309.199788)
				(mid 42.346626 -309.199788)
				(end 42.753026 -309.199788)
			)
		)
		(stroke
			(width 0)
			(type solid)
		)
		(fill yes)
		(layer "In4.Cu")
		(net "P5E_PEX0_STN7_TX_DP<120>")
	)
	(gr_poly
		(pts
			(arc
				(start 42.753026 -307.299868)
				(mid 42.346626 -307.299868)
				(end 42.753026 -307.299868)
			)
		)
		(stroke
			(width 0)
			(type solid)
		)
		(fill yes)
		(layer "In4.Cu")
		(net "P5E_PEX0_STN7_TX_DP<118>")
	)
	(gr_poly
		(pts
			(arc
				(start 42.753026 -305.399948)
				(mid 42.346626 -305.399948)
				(end 42.753026 -305.399948)
			)
		)
		(stroke
			(width 0)
			(type solid)
		)
		(fill yes)
		(layer "In4.Cu")
		(net "P5E_PEX0_STN7_TX_DP<116>")
	)
	(gr_poly
		(pts
			(arc
				(start 42.753026 -303.499774)
				(mid 42.346626 -303.499774)
				(end 42.753026 -303.499774)
			)
		)
		(stroke
			(width 0)
			(type solid)
		)
		(fill yes)
		(layer "In4.Cu")
		(net "P5E_PEX0_STN7_TX_DP<114>")
	)
	(gr_poly
		(pts
			(arc
				(start 42.753026 -301.599854)
				(mid 42.346626 -301.599854)
				(end 42.753026 -301.599854)
			)
		)
		(stroke
			(width 0)
			(type solid)
		)
		(fill yes)
		(layer "In4.Cu")
		(net "P5E_PEX0_STN7_TX_DP<112>")
	)
	(gr_poly
		(pts
			(arc
				(start 43.702986 -316.799722)
				(mid 43.296586 -316.799722)
				(end 43.702986 -316.799722)
			)
		)
		(stroke
			(width 0)
			(type solid)
		)
		(fill yes)
		(layer "In4.Cu")
		(net "P5E_PEX0_STN6_RX_DN<111>")
	)
	(gr_poly
		(pts
			(arc
				(start 43.702986 -315.849762)
				(mid 43.296586 -315.849762)
				(end 43.702986 -315.849762)
			)
		)
		(stroke
			(width 0)
			(type solid)
		)
		(fill yes)
		(layer "In4.Cu")
		(net "P5E_PEX0_STN6_RX_DP<111>")
	)
	(gr_poly
		(pts
			(arc
				(start 43.702986 -312.049922)
				(mid 43.296586 -312.049922)
				(end 43.702986 -312.049922)
			)
		)
		(stroke
			(width 0)
			(type solid)
		)
		(fill yes)
		(layer "In4.Cu")
		(net "P5E_PEX0_STN6_TX_DN<111>")
	)
	(gr_poly
		(pts
			(arc
				(start 43.702986 -311.099962)
				(mid 43.296586 -311.099962)
				(end 43.702986 -311.099962)
			)
		)
		(stroke
			(width 0)
			(type solid)
		)
		(fill yes)
		(layer "In4.Cu")
		(net "P5E_PEX0_STN6_TX_DP<111>")
	)
	(gr_poly
		(pts
			(arc
				(start 43.702986 -308.249828)
				(mid 43.296586 -308.249828)
				(end 43.702986 -308.249828)
			)
		)
		(stroke
			(width 0)
			(type solid)
		)
		(fill yes)
		(layer "In4.Cu")
		(net "P5E_PEX0_STN7_TX_DN<119>")
	)
	(gr_poly
		(pts
			(arc
				(start 43.702986 -306.349908)
				(mid 43.296586 -306.349908)
				(end 43.702986 -306.349908)
			)
		)
		(stroke
			(width 0)
			(type solid)
		)
		(fill yes)
		(layer "In4.Cu")
		(net "P5E_PEX0_STN7_TX_DN<117>")
	)
	(gr_poly
		(pts
			(arc
				(start 43.702986 -304.449734)
				(mid 43.296586 -304.449734)
				(end 43.702986 -304.449734)
			)
		)
		(stroke
			(width 0)
			(type solid)
		)
		(fill yes)
		(layer "In4.Cu")
		(net "P5E_PEX0_STN7_TX_DN<115>")
	)
	(gr_poly
		(pts
			(arc
				(start 43.702986 -302.549814)
				(mid 43.296586 -302.549814)
				(end 43.702986 -302.549814)
			)
		)
		(stroke
			(width 0)
			(type solid)
		)
		(fill yes)
		(layer "In4.Cu")
		(net "P5E_PEX0_STN7_TX_DN<113>")
	)
	(gr_poly
		(pts
			(arc
				(start 44.652946 -318.699896)
				(mid 44.246546 -318.699896)
				(end 44.652946 -318.699896)
			)
		)
		(stroke
			(width 0)
			(type solid)
		)
		(fill yes)
		(layer "In4.Cu")
		(net "P5E_PEX0_STN6_RX_DN<110>")
	)
	(gr_poly
		(pts
			(arc
				(start 44.652946 -317.749936)
				(mid 44.246546 -317.749936)
				(end 44.652946 -317.749936)
			)
		)
		(stroke
			(width 0)
			(type solid)
		)
		(fill yes)
		(layer "In4.Cu")
		(net "P5E_PEX0_STN6_RX_DP<110>")
	)
	(gr_poly
		(pts
			(arc
				(start 44.652946 -313.949842)
				(mid 44.246546 -313.949842)
				(end 44.652946 -313.949842)
			)
		)
		(stroke
			(width 0)
			(type solid)
		)
		(fill yes)
		(layer "In4.Cu")
		(net "P5E_PEX0_STN6_TX_DN<110>")
	)
	(gr_poly
		(pts
			(arc
				(start 44.652946 -312.999882)
				(mid 44.246546 -312.999882)
				(end 44.652946 -312.999882)
			)
		)
		(stroke
			(width 0)
			(type solid)
		)
		(fill yes)
		(layer "In4.Cu")
		(net "P5E_PEX0_STN6_TX_DP<110>")
	)
	(gr_poly
		(pts
			(arc
				(start 44.652946 -308.249828)
				(mid 44.246546 -308.249828)
				(end 44.652946 -308.249828)
			)
		)
		(stroke
			(width 0)
			(type solid)
		)
		(fill yes)
		(layer "In4.Cu")
		(net "P5E_PEX0_STN7_TX_DP<119>")
	)
	(gr_poly
		(pts
			(arc
				(start 44.652946 -306.349908)
				(mid 44.246546 -306.349908)
				(end 44.652946 -306.349908)
			)
		)
		(stroke
			(width 0)
			(type solid)
		)
		(fill yes)
		(layer "In4.Cu")
		(net "P5E_PEX0_STN7_TX_DP<117>")
	)
	(gr_poly
		(pts
			(arc
				(start 44.652946 -304.449734)
				(mid 44.246546 -304.449734)
				(end 44.652946 -304.449734)
			)
		)
		(stroke
			(width 0)
			(type solid)
		)
		(fill yes)
		(layer "In4.Cu")
		(net "P5E_PEX0_STN7_TX_DP<115>")
	)
	(gr_poly
		(pts
			(arc
				(start 44.652946 -302.549814)
				(mid 44.246546 -302.549814)
				(end 44.652946 -302.549814)
			)
		)
		(stroke
			(width 0)
			(type solid)
		)
		(fill yes)
		(layer "In4.Cu")
		(net "P5E_PEX0_STN7_TX_DP<113>")
	)
	(gr_poly
		(pts
			(arc
				(start 44.652946 -278.799798)
				(mid 44.246546 -278.799798)
				(end 44.652946 -278.799798)
			)
		)
		(stroke
			(width 0)
			(type solid)
		)
		(fill yes)
		(layer "In4.Cu")
		(net "P5E_PEX0_STN2_TX_DP<47>")
	)
	(gr_poly
		(pts
			(arc
				(start 44.652946 -277.849838)
				(mid 44.246546 -277.849838)
				(end 44.652946 -277.849838)
			)
		)
		(stroke
			(width 0)
			(type solid)
		)
		(fill yes)
		(layer "In4.Cu")
		(net "P5E_PEX0_STN2_TX_DN<47>")
	)
	(gr_poly
		(pts
			(arc
				(start 44.652946 -274.049744)
				(mid 44.246546 -274.049744)
				(end 44.652946 -274.049744)
			)
		)
		(stroke
			(width 0)
			(type solid)
		)
		(fill yes)
		(layer "In4.Cu")
		(net "P5E_PEX0_STN2_RX_DP<47>")
	)
	(gr_poly
		(pts
			(arc
				(start 44.652946 -273.099784)
				(mid 44.246546 -273.099784)
				(end 44.652946 -273.099784)
			)
		)
		(stroke
			(width 0)
			(type solid)
		)
		(fill yes)
		(layer "In4.Cu")
		(net "P5E_PEX0_STN2_RX_DN<47>")
	)
	(gr_poly
		(pts
			(arc
				(start 45.60316 -316.799722)
				(mid 45.19676 -316.799722)
				(end 45.60316 -316.799722)
			)
		)
		(stroke
			(width 0)
			(type solid)
		)
		(fill yes)
		(layer "In4.Cu")
		(net "P5E_PEX0_STN6_RX_DN<109>")
	)
	(gr_poly
		(pts
			(arc
				(start 45.60316 -315.849762)
				(mid 45.19676 -315.849762)
				(end 45.60316 -315.849762)
			)
		)
		(stroke
			(width 0)
			(type solid)
		)
		(fill yes)
		(layer "In4.Cu")
		(net "P5E_PEX0_STN6_RX_DP<109>")
	)
	(gr_poly
		(pts
			(arc
				(start 45.60316 -312.049922)
				(mid 45.19676 -312.049922)
				(end 45.60316 -312.049922)
			)
		)
		(stroke
			(width 0)
			(type solid)
		)
		(fill yes)
		(layer "In4.Cu")
		(net "P5E_PEX0_STN6_TX_DN<109>")
	)
	(gr_poly
		(pts
			(arc
				(start 45.60316 -311.099962)
				(mid 45.19676 -311.099962)
				(end 45.60316 -311.099962)
			)
		)
		(stroke
			(width 0)
			(type solid)
		)
		(fill yes)
		(layer "In4.Cu")
		(net "P5E_PEX0_STN6_TX_DP<109>")
	)
	(gr_poly
		(pts
			(arc
				(start 45.60316 -280.699718)
				(mid 45.19676 -280.699718)
				(end 45.60316 -280.699718)
			)
		)
		(stroke
			(width 0)
			(type solid)
		)
		(fill yes)
		(layer "In4.Cu")
		(net "P5E_PEX0_STN2_TX_DP<46>")
	)
	(gr_poly
		(pts
			(arc
				(start 45.60316 -279.749504)
				(mid 45.19676 -279.749504)
				(end 45.60316 -279.749504)
			)
		)
		(stroke
			(width 0)
			(type solid)
		)
		(fill yes)
		(layer "In4.Cu")
		(net "P5E_PEX0_STN2_TX_DN<46>")
	)
	(gr_poly
		(pts
			(arc
				(start 45.60316 -275.949918)
				(mid 45.19676 -275.949918)
				(end 45.60316 -275.949918)
			)
		)
		(stroke
			(width 0)
			(type solid)
		)
		(fill yes)
		(layer "In4.Cu")
		(net "P5E_PEX0_STN2_RX_DP<46>")
	)
	(gr_poly
		(pts
			(arc
				(start 45.60316 -274.999958)
				(mid 45.19676 -274.999958)
				(end 45.60316 -274.999958)
			)
		)
		(stroke
			(width 0)
			(type solid)
		)
		(fill yes)
		(layer "In4.Cu")
		(net "P5E_PEX0_STN2_RX_DN<46>")
	)
	(gr_poly
		(pts
			(arc
				(start 46.55312 -318.699896)
				(mid 46.14672 -318.699896)
				(end 46.55312 -318.699896)
			)
		)
		(stroke
			(width 0)
			(type solid)
		)
		(fill yes)
		(layer "In4.Cu")
		(net "P5E_PEX0_STN6_RX_DN<108>")
	)
	(gr_poly
		(pts
			(arc
				(start 46.55312 -317.749936)
				(mid 46.14672 -317.749936)
				(end 46.55312 -317.749936)
			)
		)
		(stroke
			(width 0)
			(type solid)
		)
		(fill yes)
		(layer "In4.Cu")
		(net "P5E_PEX0_STN6_RX_DP<108>")
	)
	(gr_poly
		(pts
			(arc
				(start 46.55312 -313.949842)
				(mid 46.14672 -313.949842)
				(end 46.55312 -313.949842)
			)
		)
		(stroke
			(width 0)
			(type solid)
		)
		(fill yes)
		(layer "In4.Cu")
		(net "P5E_PEX0_STN6_TX_DN<108>")
	)
	(gr_poly
		(pts
			(arc
				(start 46.55312 -312.999882)
				(mid 46.14672 -312.999882)
				(end 46.55312 -312.999882)
			)
		)
		(stroke
			(width 0)
			(type solid)
		)
		(fill yes)
		(layer "In4.Cu")
		(net "P5E_PEX0_STN6_TX_DP<108>")
	)
	(gr_poly
		(pts
			(arc
				(start 46.55312 -278.799798)
				(mid 46.14672 -278.799798)
				(end 46.55312 -278.799798)
			)
		)
		(stroke
			(width 0)
			(type solid)
		)
		(fill yes)
		(layer "In4.Cu")
		(net "P5E_PEX0_STN2_TX_DP<45>")
	)
	(gr_poly
		(pts
			(arc
				(start 46.55312 -277.849838)
				(mid 46.14672 -277.849838)
				(end 46.55312 -277.849838)
			)
		)
		(stroke
			(width 0)
			(type solid)
		)
		(fill yes)
		(layer "In4.Cu")
		(net "P5E_PEX0_STN2_TX_DN<45>")
	)
	(gr_poly
		(pts
			(arc
				(start 46.55312 -274.049744)
				(mid 46.14672 -274.049744)
				(end 46.55312 -274.049744)
			)
		)
		(stroke
			(width 0)
			(type solid)
		)
		(fill yes)
		(layer "In4.Cu")
		(net "P5E_PEX0_STN2_RX_DP<45>")
	)
	(gr_poly
		(pts
			(arc
				(start 46.55312 -273.099784)
				(mid 46.14672 -273.099784)
				(end 46.55312 -273.099784)
			)
		)
		(stroke
			(width 0)
			(type solid)
		)
		(fill yes)
		(layer "In4.Cu")
		(net "P5E_PEX0_STN2_RX_DN<45>")
	)
	(gr_poly
		(pts
			(arc
				(start 47.50308 -316.799722)
				(mid 47.09668 -316.799722)
				(end 47.50308 -316.799722)
			)
		)
		(stroke
			(width 0)
			(type solid)
		)
		(fill yes)
		(layer "In4.Cu")
		(net "P5E_PEX0_STN6_RX_DN<107>")
	)
	(gr_poly
		(pts
			(arc
				(start 47.50308 -315.849762)
				(mid 47.09668 -315.849762)
				(end 47.50308 -315.849762)
			)
		)
		(stroke
			(width 0)
			(type solid)
		)
		(fill yes)
		(layer "In4.Cu")
		(net "P5E_PEX0_STN6_RX_DP<107>")
	)
	(gr_poly
		(pts
			(arc
				(start 47.50308 -312.049922)
				(mid 47.09668 -312.049922)
				(end 47.50308 -312.049922)
			)
		)
		(stroke
			(width 0)
			(type solid)
		)
		(fill yes)
		(layer "In4.Cu")
		(net "P5E_PEX0_STN6_TX_DN<107>")
	)
	(gr_poly
		(pts
			(arc
				(start 47.50308 -311.099962)
				(mid 47.09668 -311.099962)
				(end 47.50308 -311.099962)
			)
		)
		(stroke
			(width 0)
			(type solid)
		)
		(fill yes)
		(layer "In4.Cu")
		(net "P5E_PEX0_STN6_TX_DP<107>")
	)
	(gr_poly
		(pts
			(arc
				(start 47.50308 -280.699718)
				(mid 47.09668 -280.699718)
				(end 47.50308 -280.699718)
			)
		)
		(stroke
			(width 0)
			(type solid)
		)
		(fill yes)
		(layer "In4.Cu")
		(net "P5E_PEX0_STN2_TX_DP<44>")
	)
	(gr_poly
		(pts
			(arc
				(start 47.50308 -279.749504)
				(mid 47.09668 -279.749504)
				(end 47.50308 -279.749504)
			)
		)
		(stroke
			(width 0)
			(type solid)
		)
		(fill yes)
		(layer "In4.Cu")
		(net "P5E_PEX0_STN2_TX_DN<44>")
	)
	(gr_poly
		(pts
			(arc
				(start 47.50308 -275.949918)
				(mid 47.09668 -275.949918)
				(end 47.50308 -275.949918)
			)
		)
		(stroke
			(width 0)
			(type solid)
		)
		(fill yes)
		(layer "In4.Cu")
		(net "P5E_PEX0_STN2_RX_DP<44>")
	)
	(gr_poly
		(pts
			(arc
				(start 47.50308 -274.999958)
				(mid 47.09668 -274.999958)
				(end 47.50308 -274.999958)
			)
		)
		(stroke
			(width 0)
			(type solid)
		)
		(fill yes)
		(layer "In4.Cu")
		(net "P5E_PEX0_STN2_RX_DN<44>")
	)
	(gr_poly
		(pts
			(arc
				(start 48.45304 -318.699896)
				(mid 48.04664 -318.699896)
				(end 48.45304 -318.699896)
			)
		)
		(stroke
			(width 0)
			(type solid)
		)
		(fill yes)
		(layer "In4.Cu")
		(net "P5E_PEX0_STN6_RX_DN<106>")
	)
	(gr_poly
		(pts
			(arc
				(start 48.45304 -317.749936)
				(mid 48.04664 -317.749936)
				(end 48.45304 -317.749936)
			)
		)
		(stroke
			(width 0)
			(type solid)
		)
		(fill yes)
		(layer "In4.Cu")
		(net "P5E_PEX0_STN6_RX_DP<106>")
	)
	(gr_poly
		(pts
			(arc
				(start 48.45304 -313.949842)
				(mid 48.04664 -313.949842)
				(end 48.45304 -313.949842)
			)
		)
		(stroke
			(width 0)
			(type solid)
		)
		(fill yes)
		(layer "In4.Cu")
		(net "P5E_PEX0_STN6_TX_DN<106>")
	)
	(gr_poly
		(pts
			(arc
				(start 48.45304 -312.999882)
				(mid 48.04664 -312.999882)
				(end 48.45304 -312.999882)
			)
		)
		(stroke
			(width 0)
			(type solid)
		)
		(fill yes)
		(layer "In4.Cu")
		(net "P5E_PEX0_STN6_TX_DP<106>")
	)
	(gr_poly
		(pts
			(arc
				(start 48.45304 -278.799798)
				(mid 48.04664 -278.799798)
				(end 48.45304 -278.799798)
			)
		)
		(stroke
			(width 0)
			(type solid)
		)
		(fill yes)
		(layer "In4.Cu")
		(net "P5E_PEX0_STN2_TX_DP<43>")
	)
	(gr_poly
		(pts
			(arc
				(start 48.45304 -277.849838)
				(mid 48.04664 -277.849838)
				(end 48.45304 -277.849838)
			)
		)
		(stroke
			(width 0)
			(type solid)
		)
		(fill yes)
		(layer "In4.Cu")
		(net "P5E_PEX0_STN2_TX_DN<43>")
	)
	(gr_poly
		(pts
			(arc
				(start 48.45304 -274.049744)
				(mid 48.04664 -274.049744)
				(end 48.45304 -274.049744)
			)
		)
		(stroke
			(width 0)
			(type solid)
		)
		(fill yes)
		(layer "In4.Cu")
		(net "P5E_PEX0_STN2_RX_DP<43>")
	)
	(gr_poly
		(pts
			(arc
				(start 48.45304 -273.099784)
				(mid 48.04664 -273.099784)
				(end 48.45304 -273.099784)
			)
		)
		(stroke
			(width 0)
			(type solid)
		)
		(fill yes)
		(layer "In4.Cu")
		(net "P5E_PEX0_STN2_RX_DN<43>")
	)
	(gr_poly
		(pts
			(arc
				(start 49.403 -316.799722)
				(mid 48.9966 -316.799722)
				(end 49.403 -316.799722)
			)
		)
		(stroke
			(width 0)
			(type solid)
		)
		(fill yes)
		(layer "In4.Cu")
		(net "P5E_PEX0_STN6_RX_DN<105>")
	)
	(gr_poly
		(pts
			(arc
				(start 49.403 -315.849762)
				(mid 48.9966 -315.849762)
				(end 49.403 -315.849762)
			)
		)
		(stroke
			(width 0)
			(type solid)
		)
		(fill yes)
		(layer "In4.Cu")
		(net "P5E_PEX0_STN6_RX_DP<105>")
	)
	(gr_poly
		(pts
			(arc
				(start 49.403 -312.049922)
				(mid 48.9966 -312.049922)
				(end 49.403 -312.049922)
			)
		)
		(stroke
			(width 0)
			(type solid)
		)
		(fill yes)
		(layer "In4.Cu")
		(net "P5E_PEX0_STN6_TX_DN<105>")
	)
	(gr_poly
		(pts
			(arc
				(start 49.403 -311.099962)
				(mid 48.9966 -311.099962)
				(end 49.403 -311.099962)
			)
		)
		(stroke
			(width 0)
			(type solid)
		)
		(fill yes)
		(layer "In4.Cu")
		(net "P5E_PEX0_STN6_TX_DP<105>")
	)
	(gr_poly
		(pts
			(arc
				(start 49.403 -280.699718)
				(mid 48.9966 -280.699718)
				(end 49.403 -280.699718)
			)
		)
		(stroke
			(width 0)
			(type solid)
		)
		(fill yes)
		(layer "In4.Cu")
		(net "P5E_PEX0_STN2_TX_DP<42>")
	)
	(gr_poly
		(pts
			(arc
				(start 49.403 -279.749504)
				(mid 48.9966 -279.749504)
				(end 49.403 -279.749504)
			)
		)
		(stroke
			(width 0)
			(type solid)
		)
		(fill yes)
		(layer "In4.Cu")
		(net "P5E_PEX0_STN2_TX_DN<42>")
	)
	(gr_poly
		(pts
			(arc
				(start 49.403 -275.949918)
				(mid 48.9966 -275.949918)
				(end 49.403 -275.949918)
			)
		)
		(stroke
			(width 0)
			(type solid)
		)
		(fill yes)
		(layer "In4.Cu")
		(net "P5E_PEX0_STN2_RX_DP<42>")
	)
	(gr_poly
		(pts
			(arc
				(start 49.403 -274.999958)
				(mid 48.9966 -274.999958)
				(end 49.403 -274.999958)
			)
		)
		(stroke
			(width 0)
			(type solid)
		)
		(fill yes)
		(layer "In4.Cu")
		(net "P5E_PEX0_STN2_RX_DN<42>")
	)
	(gr_poly
		(pts
			(arc
				(start 50.35296 -318.699896)
				(mid 49.94656 -318.699896)
				(end 50.35296 -318.699896)
			)
		)
		(stroke
			(width 0)
			(type solid)
		)
		(fill yes)
		(layer "In4.Cu")
		(net "P5E_PEX0_STN6_RX_DN<104>")
	)
	(gr_poly
		(pts
			(arc
				(start 50.35296 -317.749936)
				(mid 49.94656 -317.749936)
				(end 50.35296 -317.749936)
			)
		)
		(stroke
			(width 0)
			(type solid)
		)
		(fill yes)
		(layer "In4.Cu")
		(net "P5E_PEX0_STN6_RX_DP<104>")
	)
	(gr_poly
		(pts
			(arc
				(start 50.35296 -313.949842)
				(mid 49.94656 -313.949842)
				(end 50.35296 -313.949842)
			)
		)
		(stroke
			(width 0)
			(type solid)
		)
		(fill yes)
		(layer "In4.Cu")
		(net "P5E_PEX0_STN6_TX_DN<104>")
	)
	(gr_poly
		(pts
			(arc
				(start 50.35296 -312.999882)
				(mid 49.94656 -312.999882)
				(end 50.35296 -312.999882)
			)
		)
		(stroke
			(width 0)
			(type solid)
		)
		(fill yes)
		(layer "In4.Cu")
		(net "P5E_PEX0_STN6_TX_DP<104>")
	)
	(gr_poly
		(pts
			(arc
				(start 50.35296 -278.799798)
				(mid 49.94656 -278.799798)
				(end 50.35296 -278.799798)
			)
		)
		(stroke
			(width 0)
			(type solid)
		)
		(fill yes)
		(layer "In4.Cu")
		(net "P5E_PEX0_STN2_TX_DP<41>")
	)
	(gr_poly
		(pts
			(arc
				(start 50.35296 -277.849838)
				(mid 49.94656 -277.849838)
				(end 50.35296 -277.849838)
			)
		)
		(stroke
			(width 0)
			(type solid)
		)
		(fill yes)
		(layer "In4.Cu")
		(net "P5E_PEX0_STN2_TX_DN<41>")
	)
	(gr_poly
		(pts
			(arc
				(start 50.35296 -274.049744)
				(mid 49.94656 -274.049744)
				(end 50.35296 -274.049744)
			)
		)
		(stroke
			(width 0)
			(type solid)
		)
		(fill yes)
		(layer "In4.Cu")
		(net "P5E_PEX0_STN2_RX_DP<41>")
	)
	(gr_poly
		(pts
			(arc
				(start 50.35296 -273.099784)
				(mid 49.94656 -273.099784)
				(end 50.35296 -273.099784)
			)
		)
		(stroke
			(width 0)
			(type solid)
		)
		(fill yes)
		(layer "In4.Cu")
		(net "P5E_PEX0_STN2_RX_DN<41>")
	)
	(gr_poly
		(pts
			(arc
				(start 51.303174 -316.799722)
				(mid 50.896774 -316.799722)
				(end 51.303174 -316.799722)
			)
		)
		(stroke
			(width 0)
			(type solid)
		)
		(fill yes)
		(layer "In4.Cu")
		(net "P5E_PEX0_STN6_RX_DN<103>")
	)
	(gr_poly
		(pts
			(arc
				(start 51.303174 -315.849762)
				(mid 50.896774 -315.849762)
				(end 51.303174 -315.849762)
			)
		)
		(stroke
			(width 0)
			(type solid)
		)
		(fill yes)
		(layer "In4.Cu")
		(net "P5E_PEX0_STN6_RX_DP<103>")
	)
	(gr_poly
		(pts
			(arc
				(start 51.303174 -312.049922)
				(mid 50.896774 -312.049922)
				(end 51.303174 -312.049922)
			)
		)
		(stroke
			(width 0)
			(type solid)
		)
		(fill yes)
		(layer "In4.Cu")
		(net "P5E_PEX0_STN6_TX_DN<103>")
	)
	(gr_poly
		(pts
			(arc
				(start 51.303174 -311.099962)
				(mid 50.896774 -311.099962)
				(end 51.303174 -311.099962)
			)
		)
		(stroke
			(width 0)
			(type solid)
		)
		(fill yes)
		(layer "In4.Cu")
		(net "P5E_PEX0_STN6_TX_DP<103>")
	)
	(gr_poly
		(pts
			(arc
				(start 51.303174 -280.699718)
				(mid 50.896774 -280.699718)
				(end 51.303174 -280.699718)
			)
		)
		(stroke
			(width 0)
			(type solid)
		)
		(fill yes)
		(layer "In4.Cu")
		(net "P5E_PEX0_STN2_TX_DP<40>")
	)
	(gr_poly
		(pts
			(arc
				(start 51.303174 -279.749504)
				(mid 50.896774 -279.749504)
				(end 51.303174 -279.749504)
			)
		)
		(stroke
			(width 0)
			(type solid)
		)
		(fill yes)
		(layer "In4.Cu")
		(net "P5E_PEX0_STN2_TX_DN<40>")
	)
	(gr_poly
		(pts
			(arc
				(start 51.303174 -275.949918)
				(mid 50.896774 -275.949918)
				(end 51.303174 -275.949918)
			)
		)
		(stroke
			(width 0)
			(type solid)
		)
		(fill yes)
		(layer "In4.Cu")
		(net "P5E_PEX0_STN2_RX_DP<40>")
	)
	(gr_poly
		(pts
			(arc
				(start 51.303174 -274.999958)
				(mid 50.896774 -274.999958)
				(end 51.303174 -274.999958)
			)
		)
		(stroke
			(width 0)
			(type solid)
		)
		(fill yes)
		(layer "In4.Cu")
		(net "P5E_PEX0_STN2_RX_DN<40>")
	)
	(gr_poly
		(pts
			(arc
				(start 52.253134 -318.699896)
				(mid 51.846734 -318.699896)
				(end 52.253134 -318.699896)
			)
		)
		(stroke
			(width 0)
			(type solid)
		)
		(fill yes)
		(layer "In4.Cu")
		(net "P5E_PEX0_STN6_RX_DN<102>")
	)
	(gr_poly
		(pts
			(arc
				(start 52.253134 -317.749936)
				(mid 51.846734 -317.749936)
				(end 52.253134 -317.749936)
			)
		)
		(stroke
			(width 0)
			(type solid)
		)
		(fill yes)
		(layer "In4.Cu")
		(net "P5E_PEX0_STN6_RX_DP<102>")
	)
	(gr_poly
		(pts
			(arc
				(start 52.253134 -313.949842)
				(mid 51.846734 -313.949842)
				(end 52.253134 -313.949842)
			)
		)
		(stroke
			(width 0)
			(type solid)
		)
		(fill yes)
		(layer "In4.Cu")
		(net "P5E_PEX0_STN6_TX_DN<102>")
	)
	(gr_poly
		(pts
			(arc
				(start 52.253134 -312.999882)
				(mid 51.846734 -312.999882)
				(end 52.253134 -312.999882)
			)
		)
		(stroke
			(width 0)
			(type solid)
		)
		(fill yes)
		(layer "In4.Cu")
		(net "P5E_PEX0_STN6_TX_DP<102>")
	)
	(gr_poly
		(pts
			(arc
				(start 52.253134 -278.799798)
				(mid 51.846734 -278.799798)
				(end 52.253134 -278.799798)
			)
		)
		(stroke
			(width 0)
			(type solid)
		)
		(fill yes)
		(layer "In4.Cu")
		(net "P5E_PEX0_STN2_TX_DP<39>")
	)
	(gr_poly
		(pts
			(arc
				(start 52.253134 -277.849838)
				(mid 51.846734 -277.849838)
				(end 52.253134 -277.849838)
			)
		)
		(stroke
			(width 0)
			(type solid)
		)
		(fill yes)
		(layer "In4.Cu")
		(net "P5E_PEX0_STN2_TX_DN<39>")
	)
	(gr_poly
		(pts
			(arc
				(start 52.253134 -274.049744)
				(mid 51.846734 -274.049744)
				(end 52.253134 -274.049744)
			)
		)
		(stroke
			(width 0)
			(type solid)
		)
		(fill yes)
		(layer "In4.Cu")
		(net "P5E_PEX0_STN2_RX_DP<39>")
	)
	(gr_poly
		(pts
			(arc
				(start 52.253134 -273.099784)
				(mid 51.846734 -273.099784)
				(end 52.253134 -273.099784)
			)
		)
		(stroke
			(width 0)
			(type solid)
		)
		(fill yes)
		(layer "In4.Cu")
		(net "P5E_PEX0_STN2_RX_DN<39>")
	)
	(gr_poly
		(pts
			(arc
				(start 53.203094 -316.799722)
				(mid 52.796694 -316.799722)
				(end 53.203094 -316.799722)
			)
		)
		(stroke
			(width 0)
			(type solid)
		)
		(fill yes)
		(layer "In4.Cu")
		(net "P5E_PEX0_STN6_RX_DN<101>")
	)
	(gr_poly
		(pts
			(arc
				(start 53.203094 -315.849762)
				(mid 52.796694 -315.849762)
				(end 53.203094 -315.849762)
			)
		)
		(stroke
			(width 0)
			(type solid)
		)
		(fill yes)
		(layer "In4.Cu")
		(net "P5E_PEX0_STN6_RX_DP<101>")
	)
	(gr_poly
		(pts
			(arc
				(start 53.203094 -312.049922)
				(mid 52.796694 -312.049922)
				(end 53.203094 -312.049922)
			)
		)
		(stroke
			(width 0)
			(type solid)
		)
		(fill yes)
		(layer "In4.Cu")
		(net "P5E_PEX0_STN6_TX_DN<101>")
	)
	(gr_poly
		(pts
			(arc
				(start 53.203094 -311.099962)
				(mid 52.796694 -311.099962)
				(end 53.203094 -311.099962)
			)
		)
		(stroke
			(width 0)
			(type solid)
		)
		(fill yes)
		(layer "In4.Cu")
		(net "P5E_PEX0_STN6_TX_DP<101>")
	)
	(gr_poly
		(pts
			(arc
				(start 53.203094 -280.699718)
				(mid 52.796694 -280.699718)
				(end 53.203094 -280.699718)
			)
		)
		(stroke
			(width 0)
			(type solid)
		)
		(fill yes)
		(layer "In4.Cu")
		(net "P5E_PEX0_STN2_TX_DP<38>")
	)
	(gr_poly
		(pts
			(arc
				(start 53.203094 -279.749504)
				(mid 52.796694 -279.749504)
				(end 53.203094 -279.749504)
			)
		)
		(stroke
			(width 0)
			(type solid)
		)
		(fill yes)
		(layer "In4.Cu")
		(net "P5E_PEX0_STN2_TX_DN<38>")
	)
	(gr_poly
		(pts
			(arc
				(start 53.203094 -275.949918)
				(mid 52.796694 -275.949918)
				(end 53.203094 -275.949918)
			)
		)
		(stroke
			(width 0)
			(type solid)
		)
		(fill yes)
		(layer "In4.Cu")
		(net "P5E_PEX0_STN2_RX_DP<38>")
	)
	(gr_poly
		(pts
			(arc
				(start 53.203094 -274.999958)
				(mid 52.796694 -274.999958)
				(end 53.203094 -274.999958)
			)
		)
		(stroke
			(width 0)
			(type solid)
		)
		(fill yes)
		(layer "In4.Cu")
		(net "P5E_PEX0_STN2_RX_DN<38>")
	)
	(gr_poly
		(pts
			(arc
				(start 54.153054 -318.699896)
				(mid 53.746654 -318.699896)
				(end 54.153054 -318.699896)
			)
		)
		(stroke
			(width 0)
			(type solid)
		)
		(fill yes)
		(layer "In4.Cu")
		(net "P5E_PEX0_STN6_RX_DN<100>")
	)
	(gr_poly
		(pts
			(arc
				(start 54.153054 -317.749936)
				(mid 53.746654 -317.749936)
				(end 54.153054 -317.749936)
			)
		)
		(stroke
			(width 0)
			(type solid)
		)
		(fill yes)
		(layer "In4.Cu")
		(net "P5E_PEX0_STN6_RX_DP<100>")
	)
	(gr_poly
		(pts
			(arc
				(start 54.153054 -313.949842)
				(mid 53.746654 -313.949842)
				(end 54.153054 -313.949842)
			)
		)
		(stroke
			(width 0)
			(type solid)
		)
		(fill yes)
		(layer "In4.Cu")
		(net "P5E_PEX0_STN6_TX_DN<100>")
	)
	(gr_poly
		(pts
			(arc
				(start 54.153054 -312.999882)
				(mid 53.746654 -312.999882)
				(end 54.153054 -312.999882)
			)
		)
		(stroke
			(width 0)
			(type solid)
		)
		(fill yes)
		(layer "In4.Cu")
		(net "P5E_PEX0_STN6_TX_DP<100>")
	)
	(gr_poly
		(pts
			(arc
				(start 54.153054 -278.799798)
				(mid 53.746654 -278.799798)
				(end 54.153054 -278.799798)
			)
		)
		(stroke
			(width 0)
			(type solid)
		)
		(fill yes)
		(layer "In4.Cu")
		(net "P5E_PEX0_STN2_TX_DP<37>")
	)
	(gr_poly
		(pts
			(arc
				(start 54.153054 -277.849838)
				(mid 53.746654 -277.849838)
				(end 54.153054 -277.849838)
			)
		)
		(stroke
			(width 0)
			(type solid)
		)
		(fill yes)
		(layer "In4.Cu")
		(net "P5E_PEX0_STN2_TX_DN<37>")
	)
	(gr_poly
		(pts
			(arc
				(start 54.153054 -274.049744)
				(mid 53.746654 -274.049744)
				(end 54.153054 -274.049744)
			)
		)
		(stroke
			(width 0)
			(type solid)
		)
		(fill yes)
		(layer "In4.Cu")
		(net "P5E_PEX0_STN2_RX_DP<37>")
	)
	(gr_poly
		(pts
			(arc
				(start 54.153054 -273.099784)
				(mid 53.746654 -273.099784)
				(end 54.153054 -273.099784)
			)
		)
		(stroke
			(width 0)
			(type solid)
		)
		(fill yes)
		(layer "In4.Cu")
		(net "P5E_PEX0_STN2_RX_DN<37>")
	)
	(gr_poly
		(pts
			(arc
				(start 55.103014 -316.799722)
				(mid 54.696614 -316.799722)
				(end 55.103014 -316.799722)
			)
		)
		(stroke
			(width 0)
			(type solid)
		)
		(fill yes)
		(layer "In4.Cu")
		(net "P5E_PEX0_STN6_RX_DN<99>")
	)
	(gr_poly
		(pts
			(arc
				(start 55.103014 -315.849762)
				(mid 54.696614 -315.849762)
				(end 55.103014 -315.849762)
			)
		)
		(stroke
			(width 0)
			(type solid)
		)
		(fill yes)
		(layer "In4.Cu")
		(net "P5E_PEX0_STN6_RX_DP<99>")
	)
	(gr_poly
		(pts
			(arc
				(start 55.103014 -312.049922)
				(mid 54.696614 -312.049922)
				(end 55.103014 -312.049922)
			)
		)
		(stroke
			(width 0)
			(type solid)
		)
		(fill yes)
		(layer "In4.Cu")
		(net "P5E_PEX0_STN6_TX_DN<99>")
	)
	(gr_poly
		(pts
			(arc
				(start 55.103014 -311.099962)
				(mid 54.696614 -311.099962)
				(end 55.103014 -311.099962)
			)
		)
		(stroke
			(width 0)
			(type solid)
		)
		(fill yes)
		(layer "In4.Cu")
		(net "P5E_PEX0_STN6_TX_DP<99>")
	)
	(gr_poly
		(pts
			(arc
				(start 55.103014 -280.699718)
				(mid 54.696614 -280.699718)
				(end 55.103014 -280.699718)
			)
		)
		(stroke
			(width 0)
			(type solid)
		)
		(fill yes)
		(layer "In4.Cu")
		(net "P5E_PEX0_STN2_TX_DP<36>")
	)
	(gr_poly
		(pts
			(arc
				(start 55.103014 -279.749504)
				(mid 54.696614 -279.749504)
				(end 55.103014 -279.749504)
			)
		)
		(stroke
			(width 0)
			(type solid)
		)
		(fill yes)
		(layer "In4.Cu")
		(net "P5E_PEX0_STN2_TX_DN<36>")
	)
	(gr_poly
		(pts
			(arc
				(start 55.103014 -275.949918)
				(mid 54.696614 -275.949918)
				(end 55.103014 -275.949918)
			)
		)
		(stroke
			(width 0)
			(type solid)
		)
		(fill yes)
		(layer "In4.Cu")
		(net "P5E_PEX0_STN2_RX_DP<36>")
	)
	(gr_poly
		(pts
			(arc
				(start 55.103014 -274.999958)
				(mid 54.696614 -274.999958)
				(end 55.103014 -274.999958)
			)
		)
		(stroke
			(width 0)
			(type solid)
		)
		(fill yes)
		(layer "In4.Cu")
		(net "P5E_PEX0_STN2_RX_DN<36>")
	)
	(gr_poly
		(pts
			(arc
				(start 56.052974 -318.699896)
				(mid 55.646574 -318.699896)
				(end 56.052974 -318.699896)
			)
		)
		(stroke
			(width 0)
			(type solid)
		)
		(fill yes)
		(layer "In4.Cu")
		(net "P5E_PEX0_STN6_RX_DN<98>")
	)
	(gr_poly
		(pts
			(arc
				(start 56.052974 -317.749936)
				(mid 55.646574 -317.749936)
				(end 56.052974 -317.749936)
			)
		)
		(stroke
			(width 0)
			(type solid)
		)
		(fill yes)
		(layer "In4.Cu")
		(net "P5E_PEX0_STN6_RX_DP<98>")
	)
	(gr_poly
		(pts
			(arc
				(start 56.052974 -313.949842)
				(mid 55.646574 -313.949842)
				(end 56.052974 -313.949842)
			)
		)
		(stroke
			(width 0)
			(type solid)
		)
		(fill yes)
		(layer "In4.Cu")
		(net "P5E_PEX0_STN6_TX_DN<98>")
	)
	(gr_poly
		(pts
			(arc
				(start 56.052974 -312.999882)
				(mid 55.646574 -312.999882)
				(end 56.052974 -312.999882)
			)
		)
		(stroke
			(width 0)
			(type solid)
		)
		(fill yes)
		(layer "In4.Cu")
		(net "P5E_PEX0_STN6_TX_DP<98>")
	)
	(gr_poly
		(pts
			(arc
				(start 56.052974 -278.799798)
				(mid 55.646574 -278.799798)
				(end 56.052974 -278.799798)
			)
		)
		(stroke
			(width 0)
			(type solid)
		)
		(fill yes)
		(layer "In4.Cu")
		(net "P5E_PEX0_STN2_TX_DP<35>")
	)
	(gr_poly
		(pts
			(arc
				(start 56.052974 -277.849838)
				(mid 55.646574 -277.849838)
				(end 56.052974 -277.849838)
			)
		)
		(stroke
			(width 0)
			(type solid)
		)
		(fill yes)
		(layer "In4.Cu")
		(net "P5E_PEX0_STN2_TX_DN<35>")
	)
	(gr_poly
		(pts
			(arc
				(start 56.052974 -274.049744)
				(mid 55.646574 -274.049744)
				(end 56.052974 -274.049744)
			)
		)
		(stroke
			(width 0)
			(type solid)
		)
		(fill yes)
		(layer "In4.Cu")
		(net "P5E_PEX0_STN2_RX_DP<35>")
	)
	(gr_poly
		(pts
			(arc
				(start 56.052974 -273.099784)
				(mid 55.646574 -273.099784)
				(end 56.052974 -273.099784)
			)
		)
		(stroke
			(width 0)
			(type solid)
		)
		(fill yes)
		(layer "In4.Cu")
		(net "P5E_PEX0_STN2_RX_DN<35>")
	)
	(gr_poly
		(pts
			(arc
				(start 57.002934 -280.699718)
				(mid 56.596534 -280.699718)
				(end 57.002934 -280.699718)
			)
		)
		(stroke
			(width 0)
			(type solid)
		)
		(fill yes)
		(layer "In4.Cu")
		(net "P5E_PEX0_STN2_TX_DP<34>")
	)
	(gr_poly
		(pts
			(arc
				(start 57.002934 -279.749504)
				(mid 56.596534 -279.749504)
				(end 57.002934 -279.749504)
			)
		)
		(stroke
			(width 0)
			(type solid)
		)
		(fill yes)
		(layer "In4.Cu")
		(net "P5E_PEX0_STN2_TX_DN<34>")
	)
	(gr_poly
		(pts
			(arc
				(start 57.003188 -316.799722)
				(mid 56.596788 -316.799722)
				(end 57.003188 -316.799722)
			)
		)
		(stroke
			(width 0)
			(type solid)
		)
		(fill yes)
		(layer "In4.Cu")
		(net "P5E_PEX0_STN6_RX_DN<97>")
	)
	(gr_poly
		(pts
			(arc
				(start 57.003188 -315.849762)
				(mid 56.596788 -315.849762)
				(end 57.003188 -315.849762)
			)
		)
		(stroke
			(width 0)
			(type solid)
		)
		(fill yes)
		(layer "In4.Cu")
		(net "P5E_PEX0_STN6_RX_DP<97>")
	)
	(gr_poly
		(pts
			(arc
				(start 57.003188 -312.049922)
				(mid 56.596788 -312.049922)
				(end 57.003188 -312.049922)
			)
		)
		(stroke
			(width 0)
			(type solid)
		)
		(fill yes)
		(layer "In4.Cu")
		(net "P5E_PEX0_STN6_TX_DN<97>")
	)
	(gr_poly
		(pts
			(arc
				(start 57.003188 -311.099962)
				(mid 56.596788 -311.099962)
				(end 57.003188 -311.099962)
			)
		)
		(stroke
			(width 0)
			(type solid)
		)
		(fill yes)
		(layer "In4.Cu")
		(net "P5E_PEX0_STN6_TX_DP<97>")
	)
	(gr_poly
		(pts
			(arc
				(start 57.003188 -275.949918)
				(mid 56.596788 -275.949918)
				(end 57.003188 -275.949918)
			)
		)
		(stroke
			(width 0)
			(type solid)
		)
		(fill yes)
		(layer "In4.Cu")
		(net "P5E_PEX0_STN2_RX_DP<34>")
	)
	(gr_poly
		(pts
			(arc
				(start 57.003188 -274.999958)
				(mid 56.596788 -274.999958)
				(end 57.003188 -274.999958)
			)
		)
		(stroke
			(width 0)
			(type solid)
		)
		(fill yes)
		(layer "In4.Cu")
		(net "P5E_PEX0_STN2_RX_DN<34>")
	)
	(gr_poly
		(pts
			(arc
				(start 57.953148 -318.699896)
				(mid 57.546748 -318.699896)
				(end 57.953148 -318.699896)
			)
		)
		(stroke
			(width 0)
			(type solid)
		)
		(fill yes)
		(layer "In4.Cu")
		(net "P5E_PEX0_STN6_RX_DN<96>")
	)
	(gr_poly
		(pts
			(arc
				(start 57.953148 -317.749936)
				(mid 57.546748 -317.749936)
				(end 57.953148 -317.749936)
			)
		)
		(stroke
			(width 0)
			(type solid)
		)
		(fill yes)
		(layer "In4.Cu")
		(net "P5E_PEX0_STN6_RX_DP<96>")
	)
	(gr_poly
		(pts
			(arc
				(start 57.953148 -313.949842)
				(mid 57.546748 -313.949842)
				(end 57.953148 -313.949842)
			)
		)
		(stroke
			(width 0)
			(type solid)
		)
		(fill yes)
		(layer "In4.Cu")
		(net "P5E_PEX0_STN6_TX_DN<96>")
	)
	(gr_poly
		(pts
			(arc
				(start 57.953148 -312.999882)
				(mid 57.546748 -312.999882)
				(end 57.953148 -312.999882)
			)
		)
		(stroke
			(width 0)
			(type solid)
		)
		(fill yes)
		(layer "In4.Cu")
		(net "P5E_PEX0_STN6_TX_DP<96>")
	)
	(gr_poly
		(pts
			(arc
				(start 57.953148 -278.799798)
				(mid 57.546748 -278.799798)
				(end 57.953148 -278.799798)
			)
		)
		(stroke
			(width 0)
			(type solid)
		)
		(fill yes)
		(layer "In4.Cu")
		(net "P5E_PEX0_STN2_TX_DP<33>")
	)
	(gr_poly
		(pts
			(arc
				(start 57.953148 -277.849838)
				(mid 57.546748 -277.849838)
				(end 57.953148 -277.849838)
			)
		)
		(stroke
			(width 0)
			(type solid)
		)
		(fill yes)
		(layer "In4.Cu")
		(net "P5E_PEX0_STN2_TX_DN<33>")
	)
	(gr_poly
		(pts
			(arc
				(start 57.953148 -274.049744)
				(mid 57.546748 -274.049744)
				(end 57.953148 -274.049744)
			)
		)
		(stroke
			(width 0)
			(type solid)
		)
		(fill yes)
		(layer "In4.Cu")
		(net "P5E_PEX0_STN2_RX_DP<33>")
	)
	(gr_poly
		(pts
			(arc
				(start 57.953148 -273.099784)
				(mid 57.546748 -273.099784)
				(end 57.953148 -273.099784)
			)
		)
		(stroke
			(width 0)
			(type solid)
		)
		(fill yes)
		(layer "In4.Cu")
		(net "P5E_PEX0_STN2_RX_DN<33>")
	)
	(gr_poly
		(pts
			(arc
				(start 58.903108 -316.799722)
				(mid 58.496708 -316.799722)
				(end 58.903108 -316.799722)
			)
		)
		(stroke
			(width 0)
			(type solid)
		)
		(fill yes)
		(layer "In4.Cu")
		(net "P5E_PEX0_STN5_RX_DN<80>")
	)
	(gr_poly
		(pts
			(arc
				(start 58.903108 -315.849762)
				(mid 58.496708 -315.849762)
				(end 58.903108 -315.849762)
			)
		)
		(stroke
			(width 0)
			(type solid)
		)
		(fill yes)
		(layer "In4.Cu")
		(net "P5E_PEX0_STN5_RX_DP<80>")
	)
	(gr_poly
		(pts
			(arc
				(start 58.903108 -312.049922)
				(mid 58.496708 -312.049922)
				(end 58.903108 -312.049922)
			)
		)
		(stroke
			(width 0)
			(type solid)
		)
		(fill yes)
		(layer "In4.Cu")
		(net "P5E_PEX0_STN5_TX_DN<80>")
	)
	(gr_poly
		(pts
			(arc
				(start 58.903108 -311.099962)
				(mid 58.496708 -311.099962)
				(end 58.903108 -311.099962)
			)
		)
		(stroke
			(width 0)
			(type solid)
		)
		(fill yes)
		(layer "In4.Cu")
		(net "P5E_PEX0_STN5_TX_DP<80>")
	)
	(gr_poly
		(pts
			(arc
				(start 58.903108 -280.699718)
				(mid 58.496708 -280.699718)
				(end 58.903108 -280.699718)
			)
		)
		(stroke
			(width 0)
			(type solid)
		)
		(fill yes)
		(layer "In4.Cu")
		(net "P5E_PEX0_STN2_TX_DP<32>")
	)
	(gr_poly
		(pts
			(arc
				(start 58.903108 -279.749504)
				(mid 58.496708 -279.749504)
				(end 58.903108 -279.749504)
			)
		)
		(stroke
			(width 0)
			(type solid)
		)
		(fill yes)
		(layer "In4.Cu")
		(net "P5E_PEX0_STN2_TX_DN<32>")
	)
	(gr_poly
		(pts
			(arc
				(start 58.903108 -275.949918)
				(mid 58.496708 -275.949918)
				(end 58.903108 -275.949918)
			)
		)
		(stroke
			(width 0)
			(type solid)
		)
		(fill yes)
		(layer "In4.Cu")
		(net "P5E_PEX0_STN2_RX_DP<32>")
	)
	(gr_poly
		(pts
			(arc
				(start 58.903108 -274.999958)
				(mid 58.496708 -274.999958)
				(end 58.903108 -274.999958)
			)
		)
		(stroke
			(width 0)
			(type solid)
		)
		(fill yes)
		(layer "In4.Cu")
		(net "P5E_PEX0_STN2_RX_DN<32>")
	)
	(gr_poly
		(pts
			(arc
				(start 59.852814 -278.799798)
				(mid 59.446414 -278.799798)
				(end 59.852814 -278.799798)
			)
		)
		(stroke
			(width 0)
			(type solid)
		)
		(fill yes)
		(layer "In4.Cu")
		(net "P5E_PEX0_STN1_TX_DP<16>")
	)
	(gr_poly
		(pts
			(arc
				(start 59.852814 -277.849838)
				(mid 59.446414 -277.849838)
				(end 59.852814 -277.849838)
			)
		)
		(stroke
			(width 0)
			(type solid)
		)
		(fill yes)
		(layer "In4.Cu")
		(net "P5E_PEX0_STN1_TX_DN<16>")
	)
	(gr_poly
		(pts
			(arc
				(start 59.852814 -274.04949)
				(mid 59.446414 -274.04949)
				(end 59.852814 -274.04949)
			)
		)
		(stroke
			(width 0)
			(type solid)
		)
		(fill yes)
		(layer "In4.Cu")
		(net "P5E_PEX0_STN1_RX_DP<16>")
	)
	(gr_poly
		(pts
			(arc
				(start 59.852814 -273.09953)
				(mid 59.446414 -273.09953)
				(end 59.852814 -273.09953)
			)
		)
		(stroke
			(width 0)
			(type solid)
		)
		(fill yes)
		(layer "In4.Cu")
		(net "P5E_PEX0_STN1_RX_DN<16>")
	)
	(gr_poly
		(pts
			(arc
				(start 59.853068 -318.699896)
				(mid 59.446668 -318.699896)
				(end 59.853068 -318.699896)
			)
		)
		(stroke
			(width 0)
			(type solid)
		)
		(fill yes)
		(layer "In4.Cu")
		(net "P5E_PEX0_STN5_RX_DN<81>")
	)
	(gr_poly
		(pts
			(arc
				(start 59.853068 -317.749936)
				(mid 59.446668 -317.749936)
				(end 59.853068 -317.749936)
			)
		)
		(stroke
			(width 0)
			(type solid)
		)
		(fill yes)
		(layer "In4.Cu")
		(net "P5E_PEX0_STN5_RX_DP<81>")
	)
	(gr_poly
		(pts
			(arc
				(start 59.853068 -313.949842)
				(mid 59.446668 -313.949842)
				(end 59.853068 -313.949842)
			)
		)
		(stroke
			(width 0)
			(type solid)
		)
		(fill yes)
		(layer "In4.Cu")
		(net "P5E_PEX0_STN5_TX_DN<81>")
	)
	(gr_poly
		(pts
			(arc
				(start 59.853068 -312.999882)
				(mid 59.446668 -312.999882)
				(end 59.853068 -312.999882)
			)
		)
		(stroke
			(width 0)
			(type solid)
		)
		(fill yes)
		(layer "In4.Cu")
		(net "P5E_PEX0_STN5_TX_DP<81>")
	)
	(gr_poly
		(pts
			(arc
				(start 60.802774 -275.949664)
				(mid 60.396374 -275.949664)
				(end 60.802774 -275.949664)
			)
		)
		(stroke
			(width 0)
			(type solid)
		)
		(fill yes)
		(layer "In4.Cu")
		(net "P5E_PEX0_STN1_RX_DP<17>")
	)
	(gr_poly
		(pts
			(arc
				(start 60.802774 -274.999704)
				(mid 60.396374 -274.999704)
				(end 60.802774 -274.999704)
			)
		)
		(stroke
			(width 0)
			(type solid)
		)
		(fill yes)
		(layer "In4.Cu")
		(net "P5E_PEX0_STN1_RX_DN<17>")
	)
	(gr_poly
		(pts
			(arc
				(start 60.803028 -316.799722)
				(mid 60.396628 -316.799722)
				(end 60.803028 -316.799722)
			)
		)
		(stroke
			(width 0)
			(type solid)
		)
		(fill yes)
		(layer "In4.Cu")
		(net "P5E_PEX0_STN5_RX_DN<82>")
	)
	(gr_poly
		(pts
			(arc
				(start 60.803028 -315.849762)
				(mid 60.396628 -315.849762)
				(end 60.803028 -315.849762)
			)
		)
		(stroke
			(width 0)
			(type solid)
		)
		(fill yes)
		(layer "In4.Cu")
		(net "P5E_PEX0_STN5_RX_DP<82>")
	)
	(gr_poly
		(pts
			(arc
				(start 60.803028 -312.049922)
				(mid 60.396628 -312.049922)
				(end 60.803028 -312.049922)
			)
		)
		(stroke
			(width 0)
			(type solid)
		)
		(fill yes)
		(layer "In4.Cu")
		(net "P5E_PEX0_STN5_TX_DN<82>")
	)
	(gr_poly
		(pts
			(arc
				(start 60.803028 -311.099962)
				(mid 60.396628 -311.099962)
				(end 60.803028 -311.099962)
			)
		)
		(stroke
			(width 0)
			(type solid)
		)
		(fill yes)
		(layer "In4.Cu")
		(net "P5E_PEX0_STN5_TX_DP<82>")
	)
	(gr_poly
		(pts
			(arc
				(start 60.803028 -280.699718)
				(mid 60.396628 -280.699718)
				(end 60.803028 -280.699718)
			)
		)
		(stroke
			(width 0)
			(type solid)
		)
		(fill yes)
		(layer "In4.Cu")
		(net "P5E_PEX0_STN1_TX_DN<17>")
	)
	(gr_poly
		(pts
			(arc
				(start 60.803028 -279.749504)
				(mid 60.396628 -279.749504)
				(end 60.803028 -279.749504)
			)
		)
		(stroke
			(width 0)
			(type solid)
		)
		(fill yes)
		(layer "In4.Cu")
		(net "P5E_PEX0_STN1_TX_DP<17>")
	)
	(gr_poly
		(pts
			(arc
				(start 61.752734 -278.799798)
				(mid 61.346334 -278.799798)
				(end 61.752734 -278.799798)
			)
		)
		(stroke
			(width 0)
			(type solid)
		)
		(fill yes)
		(layer "In4.Cu")
		(net "P5E_PEX0_STN1_TX_DP<18>")
	)
	(gr_poly
		(pts
			(arc
				(start 61.752734 -277.849838)
				(mid 61.346334 -277.849838)
				(end 61.752734 -277.849838)
			)
		)
		(stroke
			(width 0)
			(type solid)
		)
		(fill yes)
		(layer "In4.Cu")
		(net "P5E_PEX0_STN1_TX_DN<18>")
	)
	(gr_poly
		(pts
			(arc
				(start 61.752734 -274.049744)
				(mid 61.346334 -274.049744)
				(end 61.752734 -274.049744)
			)
		)
		(stroke
			(width 0)
			(type solid)
		)
		(fill yes)
		(layer "In4.Cu")
		(net "P5E_PEX0_STN1_RX_DP<18>")
	)
	(gr_poly
		(pts
			(arc
				(start 61.752734 -273.099784)
				(mid 61.346334 -273.099784)
				(end 61.752734 -273.099784)
			)
		)
		(stroke
			(width 0)
			(type solid)
		)
		(fill yes)
		(layer "In4.Cu")
		(net "P5E_PEX0_STN1_RX_DN<18>")
	)
	(gr_poly
		(pts
			(arc
				(start 61.752988 -318.699896)
				(mid 61.346588 -318.699896)
				(end 61.752988 -318.699896)
			)
		)
		(stroke
			(width 0)
			(type solid)
		)
		(fill yes)
		(layer "In4.Cu")
		(net "P5E_PEX0_STN5_RX_DN<83>")
	)
	(gr_poly
		(pts
			(arc
				(start 61.752988 -317.749936)
				(mid 61.346588 -317.749936)
				(end 61.752988 -317.749936)
			)
		)
		(stroke
			(width 0)
			(type solid)
		)
		(fill yes)
		(layer "In4.Cu")
		(net "P5E_PEX0_STN5_RX_DP<83>")
	)
	(gr_poly
		(pts
			(arc
				(start 61.752988 -313.949842)
				(mid 61.346588 -313.949842)
				(end 61.752988 -313.949842)
			)
		)
		(stroke
			(width 0)
			(type solid)
		)
		(fill yes)
		(layer "In4.Cu")
		(net "P5E_PEX0_STN5_TX_DN<83>")
	)
	(gr_poly
		(pts
			(arc
				(start 61.752988 -312.999882)
				(mid 61.346588 -312.999882)
				(end 61.752988 -312.999882)
			)
		)
		(stroke
			(width 0)
			(type solid)
		)
		(fill yes)
		(layer "In4.Cu")
		(net "P5E_PEX0_STN5_TX_DP<83>")
	)
	(gr_poly
		(pts
			(arc
				(start 62.702694 -275.949918)
				(mid 62.296294 -275.949918)
				(end 62.702694 -275.949918)
			)
		)
		(stroke
			(width 0)
			(type solid)
		)
		(fill yes)
		(layer "In4.Cu")
		(net "P5E_PEX0_STN1_RX_DP<19>")
	)
	(gr_poly
		(pts
			(arc
				(start 62.702694 -274.999958)
				(mid 62.296294 -274.999958)
				(end 62.702694 -274.999958)
			)
		)
		(stroke
			(width 0)
			(type solid)
		)
		(fill yes)
		(layer "In4.Cu")
		(net "P5E_PEX0_STN1_RX_DN<19>")
	)
	(gr_poly
		(pts
			(arc
				(start 62.702948 -316.799722)
				(mid 62.296548 -316.799722)
				(end 62.702948 -316.799722)
			)
		)
		(stroke
			(width 0)
			(type solid)
		)
		(fill yes)
		(layer "In4.Cu")
		(net "P5E_PEX0_STN5_RX_DN<84>")
	)
	(gr_poly
		(pts
			(arc
				(start 62.702948 -315.849762)
				(mid 62.296548 -315.849762)
				(end 62.702948 -315.849762)
			)
		)
		(stroke
			(width 0)
			(type solid)
		)
		(fill yes)
		(layer "In4.Cu")
		(net "P5E_PEX0_STN5_RX_DP<84>")
	)
	(gr_poly
		(pts
			(arc
				(start 62.702948 -312.049922)
				(mid 62.296548 -312.049922)
				(end 62.702948 -312.049922)
			)
		)
		(stroke
			(width 0)
			(type solid)
		)
		(fill yes)
		(layer "In4.Cu")
		(net "P5E_PEX0_STN5_TX_DN<84>")
	)
	(gr_poly
		(pts
			(arc
				(start 62.702948 -311.099962)
				(mid 62.296548 -311.099962)
				(end 62.702948 -311.099962)
			)
		)
		(stroke
			(width 0)
			(type solid)
		)
		(fill yes)
		(layer "In4.Cu")
		(net "P5E_PEX0_STN5_TX_DP<84>")
	)
	(gr_poly
		(pts
			(arc
				(start 62.702948 -280.699718)
				(mid 62.296548 -280.699718)
				(end 62.702948 -280.699718)
			)
		)
		(stroke
			(width 0)
			(type solid)
		)
		(fill yes)
		(layer "In4.Cu")
		(net "P5E_PEX0_STN1_TX_DN<19>")
	)
	(gr_poly
		(pts
			(arc
				(start 62.702948 -279.749504)
				(mid 62.296548 -279.749504)
				(end 62.702948 -279.749504)
			)
		)
		(stroke
			(width 0)
			(type solid)
		)
		(fill yes)
		(layer "In4.Cu")
		(net "P5E_PEX0_STN1_TX_DP<19>")
	)
	(gr_poly
		(pts
			(arc
				(start 63.652908 -278.799798)
				(mid 63.246508 -278.799798)
				(end 63.652908 -278.799798)
			)
		)
		(stroke
			(width 0)
			(type solid)
		)
		(fill yes)
		(layer "In4.Cu")
		(net "P5E_PEX0_STN1_TX_DP<20>")
	)
	(gr_poly
		(pts
			(arc
				(start 63.652908 -277.849838)
				(mid 63.246508 -277.849838)
				(end 63.652908 -277.849838)
			)
		)
		(stroke
			(width 0)
			(type solid)
		)
		(fill yes)
		(layer "In4.Cu")
		(net "P5E_PEX0_STN1_TX_DN<20>")
	)
	(gr_poly
		(pts
			(arc
				(start 63.652908 -274.049744)
				(mid 63.246508 -274.049744)
				(end 63.652908 -274.049744)
			)
		)
		(stroke
			(width 0)
			(type solid)
		)
		(fill yes)
		(layer "In4.Cu")
		(net "P5E_PEX0_STN1_RX_DP<20>")
	)
	(gr_poly
		(pts
			(arc
				(start 63.652908 -273.099784)
				(mid 63.246508 -273.099784)
				(end 63.652908 -273.099784)
			)
		)
		(stroke
			(width 0)
			(type solid)
		)
		(fill yes)
		(layer "In4.Cu")
		(net "P5E_PEX0_STN1_RX_DN<20>")
	)
	(gr_poly
		(pts
			(arc
				(start 63.653162 -318.699896)
				(mid 63.246762 -318.699896)
				(end 63.653162 -318.699896)
			)
		)
		(stroke
			(width 0)
			(type solid)
		)
		(fill yes)
		(layer "In4.Cu")
		(net "P5E_PEX0_STN5_RX_DN<85>")
	)
	(gr_poly
		(pts
			(arc
				(start 63.653162 -317.749936)
				(mid 63.246762 -317.749936)
				(end 63.653162 -317.749936)
			)
		)
		(stroke
			(width 0)
			(type solid)
		)
		(fill yes)
		(layer "In4.Cu")
		(net "P5E_PEX0_STN5_RX_DP<85>")
	)
	(gr_poly
		(pts
			(arc
				(start 63.653162 -313.949842)
				(mid 63.246762 -313.949842)
				(end 63.653162 -313.949842)
			)
		)
		(stroke
			(width 0)
			(type solid)
		)
		(fill yes)
		(layer "In4.Cu")
		(net "P5E_PEX0_STN5_TX_DN<85>")
	)
	(gr_poly
		(pts
			(arc
				(start 63.653162 -312.999882)
				(mid 63.246762 -312.999882)
				(end 63.653162 -312.999882)
			)
		)
		(stroke
			(width 0)
			(type solid)
		)
		(fill yes)
		(layer "In4.Cu")
		(net "P5E_PEX0_STN5_TX_DP<85>")
	)
	(gr_poly
		(pts
			(arc
				(start 64.602868 -275.949664)
				(mid 64.196468 -275.949664)
				(end 64.602868 -275.949664)
			)
		)
		(stroke
			(width 0)
			(type solid)
		)
		(fill yes)
		(layer "In4.Cu")
		(net "P5E_PEX0_STN1_RX_DP<21>")
	)
	(gr_poly
		(pts
			(arc
				(start 64.602868 -274.999704)
				(mid 64.196468 -274.999704)
				(end 64.602868 -274.999704)
			)
		)
		(stroke
			(width 0)
			(type solid)
		)
		(fill yes)
		(layer "In4.Cu")
		(net "P5E_PEX0_STN1_RX_DN<21>")
	)
	(gr_poly
		(pts
			(arc
				(start 64.603122 -316.799722)
				(mid 64.196722 -316.799722)
				(end 64.603122 -316.799722)
			)
		)
		(stroke
			(width 0)
			(type solid)
		)
		(fill yes)
		(layer "In4.Cu")
		(net "P5E_PEX0_STN5_RX_DN<86>")
	)
	(gr_poly
		(pts
			(arc
				(start 64.603122 -315.849762)
				(mid 64.196722 -315.849762)
				(end 64.603122 -315.849762)
			)
		)
		(stroke
			(width 0)
			(type solid)
		)
		(fill yes)
		(layer "In4.Cu")
		(net "P5E_PEX0_STN5_RX_DP<86>")
	)
	(gr_poly
		(pts
			(arc
				(start 64.603122 -312.049922)
				(mid 64.196722 -312.049922)
				(end 64.603122 -312.049922)
			)
		)
		(stroke
			(width 0)
			(type solid)
		)
		(fill yes)
		(layer "In4.Cu")
		(net "P5E_PEX0_STN5_TX_DN<86>")
	)
	(gr_poly
		(pts
			(arc
				(start 64.603122 -311.099962)
				(mid 64.196722 -311.099962)
				(end 64.603122 -311.099962)
			)
		)
		(stroke
			(width 0)
			(type solid)
		)
		(fill yes)
		(layer "In4.Cu")
		(net "P5E_PEX0_STN5_TX_DP<86>")
	)
	(gr_poly
		(pts
			(arc
				(start 64.603122 -280.699718)
				(mid 64.196722 -280.699718)
				(end 64.603122 -280.699718)
			)
		)
		(stroke
			(width 0)
			(type solid)
		)
		(fill yes)
		(layer "In4.Cu")
		(net "P5E_PEX0_STN1_TX_DN<21>")
	)
	(gr_poly
		(pts
			(arc
				(start 64.603122 -279.749504)
				(mid 64.196722 -279.749504)
				(end 64.603122 -279.749504)
			)
		)
		(stroke
			(width 0)
			(type solid)
		)
		(fill yes)
		(layer "In4.Cu")
		(net "P5E_PEX0_STN1_TX_DP<21>")
	)
	(gr_poly
		(pts
			(arc
				(start 65.552828 -278.799798)
				(mid 65.146428 -278.799798)
				(end 65.552828 -278.799798)
			)
		)
		(stroke
			(width 0)
			(type solid)
		)
		(fill yes)
		(layer "In4.Cu")
		(net "P5E_PEX0_STN1_TX_DP<22>")
	)
	(gr_poly
		(pts
			(arc
				(start 65.552828 -277.849838)
				(mid 65.146428 -277.849838)
				(end 65.552828 -277.849838)
			)
		)
		(stroke
			(width 0)
			(type solid)
		)
		(fill yes)
		(layer "In4.Cu")
		(net "P5E_PEX0_STN1_TX_DN<22>")
	)
	(gr_poly
		(pts
			(arc
				(start 65.552828 -274.049744)
				(mid 65.146428 -274.049744)
				(end 65.552828 -274.049744)
			)
		)
		(stroke
			(width 0)
			(type solid)
		)
		(fill yes)
		(layer "In4.Cu")
		(net "P5E_PEX0_STN1_RX_DP<22>")
	)
	(gr_poly
		(pts
			(arc
				(start 65.552828 -273.099784)
				(mid 65.146428 -273.099784)
				(end 65.552828 -273.099784)
			)
		)
		(stroke
			(width 0)
			(type solid)
		)
		(fill yes)
		(layer "In4.Cu")
		(net "P5E_PEX0_STN1_RX_DN<22>")
	)
	(gr_poly
		(pts
			(arc
				(start 65.553082 -318.699896)
				(mid 65.146682 -318.699896)
				(end 65.553082 -318.699896)
			)
		)
		(stroke
			(width 0)
			(type solid)
		)
		(fill yes)
		(layer "In4.Cu")
		(net "P5E_PEX0_STN5_RX_DN<87>")
	)
	(gr_poly
		(pts
			(arc
				(start 65.553082 -317.749936)
				(mid 65.146682 -317.749936)
				(end 65.553082 -317.749936)
			)
		)
		(stroke
			(width 0)
			(type solid)
		)
		(fill yes)
		(layer "In4.Cu")
		(net "P5E_PEX0_STN5_RX_DP<87>")
	)
	(gr_poly
		(pts
			(arc
				(start 65.553082 -313.949842)
				(mid 65.146682 -313.949842)
				(end 65.553082 -313.949842)
			)
		)
		(stroke
			(width 0)
			(type solid)
		)
		(fill yes)
		(layer "In4.Cu")
		(net "P5E_PEX0_STN5_TX_DN<87>")
	)
	(gr_poly
		(pts
			(arc
				(start 65.553082 -312.999882)
				(mid 65.146682 -312.999882)
				(end 65.553082 -312.999882)
			)
		)
		(stroke
			(width 0)
			(type solid)
		)
		(fill yes)
		(layer "In4.Cu")
		(net "P5E_PEX0_STN5_TX_DP<87>")
	)
	(gr_poly
		(pts
			(arc
				(start 66.502788 -275.949918)
				(mid 66.096388 -275.949918)
				(end 66.502788 -275.949918)
			)
		)
		(stroke
			(width 0)
			(type solid)
		)
		(fill yes)
		(layer "In4.Cu")
		(net "P5E_PEX0_STN1_RX_DP<23>")
	)
	(gr_poly
		(pts
			(arc
				(start 66.502788 -274.999958)
				(mid 66.096388 -274.999958)
				(end 66.502788 -274.999958)
			)
		)
		(stroke
			(width 0)
			(type solid)
		)
		(fill yes)
		(layer "In4.Cu")
		(net "P5E_PEX0_STN1_RX_DN<23>")
	)
	(gr_poly
		(pts
			(arc
				(start 66.503042 -316.799722)
				(mid 66.096642 -316.799722)
				(end 66.503042 -316.799722)
			)
		)
		(stroke
			(width 0)
			(type solid)
		)
		(fill yes)
		(layer "In4.Cu")
		(net "P5E_PEX0_STN5_RX_DN<88>")
	)
	(gr_poly
		(pts
			(arc
				(start 66.503042 -315.849762)
				(mid 66.096642 -315.849762)
				(end 66.503042 -315.849762)
			)
		)
		(stroke
			(width 0)
			(type solid)
		)
		(fill yes)
		(layer "In4.Cu")
		(net "P5E_PEX0_STN5_RX_DP<88>")
	)
	(gr_poly
		(pts
			(arc
				(start 66.503042 -312.049922)
				(mid 66.096642 -312.049922)
				(end 66.503042 -312.049922)
			)
		)
		(stroke
			(width 0)
			(type solid)
		)
		(fill yes)
		(layer "In4.Cu")
		(net "P5E_PEX0_STN5_TX_DN<88>")
	)
	(gr_poly
		(pts
			(arc
				(start 66.503042 -311.099962)
				(mid 66.096642 -311.099962)
				(end 66.503042 -311.099962)
			)
		)
		(stroke
			(width 0)
			(type solid)
		)
		(fill yes)
		(layer "In4.Cu")
		(net "P5E_PEX0_STN5_TX_DP<88>")
	)
	(gr_poly
		(pts
			(arc
				(start 66.503042 -280.699718)
				(mid 66.096642 -280.699718)
				(end 66.503042 -280.699718)
			)
		)
		(stroke
			(width 0)
			(type solid)
		)
		(fill yes)
		(layer "In4.Cu")
		(net "P5E_PEX0_STN1_TX_DN<23>")
	)
	(gr_poly
		(pts
			(arc
				(start 66.503042 -279.749504)
				(mid 66.096642 -279.749504)
				(end 66.503042 -279.749504)
			)
		)
		(stroke
			(width 0)
			(type solid)
		)
		(fill yes)
		(layer "In4.Cu")
		(net "P5E_PEX0_STN1_TX_DP<23>")
	)
	(gr_poly
		(pts
			(arc
				(start 67.452748 -278.799798)
				(mid 67.046348 -278.799798)
				(end 67.452748 -278.799798)
			)
		)
		(stroke
			(width 0)
			(type solid)
		)
		(fill yes)
		(layer "In4.Cu")
		(net "P5E_PEX0_STN1_TX_DP<24>")
	)
	(gr_poly
		(pts
			(arc
				(start 67.452748 -277.849838)
				(mid 67.046348 -277.849838)
				(end 67.452748 -277.849838)
			)
		)
		(stroke
			(width 0)
			(type solid)
		)
		(fill yes)
		(layer "In4.Cu")
		(net "P5E_PEX0_STN1_TX_DN<24>")
	)
	(gr_poly
		(pts
			(arc
				(start 67.452748 -274.049744)
				(mid 67.046348 -274.049744)
				(end 67.452748 -274.049744)
			)
		)
		(stroke
			(width 0)
			(type solid)
		)
		(fill yes)
		(layer "In4.Cu")
		(net "P5E_PEX0_STN1_RX_DP<24>")
	)
	(gr_poly
		(pts
			(arc
				(start 67.452748 -273.099784)
				(mid 67.046348 -273.099784)
				(end 67.452748 -273.099784)
			)
		)
		(stroke
			(width 0)
			(type solid)
		)
		(fill yes)
		(layer "In4.Cu")
		(net "P5E_PEX0_STN1_RX_DN<24>")
	)
	(gr_poly
		(pts
			(arc
				(start 67.453002 -318.699896)
				(mid 67.046602 -318.699896)
				(end 67.453002 -318.699896)
			)
		)
		(stroke
			(width 0)
			(type solid)
		)
		(fill yes)
		(layer "In4.Cu")
		(net "P5E_PEX0_STN5_RX_DN<89>")
	)
	(gr_poly
		(pts
			(arc
				(start 67.453002 -317.749936)
				(mid 67.046602 -317.749936)
				(end 67.453002 -317.749936)
			)
		)
		(stroke
			(width 0)
			(type solid)
		)
		(fill yes)
		(layer "In4.Cu")
		(net "P5E_PEX0_STN5_RX_DP<89>")
	)
	(gr_poly
		(pts
			(arc
				(start 67.453002 -313.949842)
				(mid 67.046602 -313.949842)
				(end 67.453002 -313.949842)
			)
		)
		(stroke
			(width 0)
			(type solid)
		)
		(fill yes)
		(layer "In4.Cu")
		(net "P5E_PEX0_STN5_TX_DN<89>")
	)
	(gr_poly
		(pts
			(arc
				(start 67.453002 -312.999882)
				(mid 67.046602 -312.999882)
				(end 67.453002 -312.999882)
			)
		)
		(stroke
			(width 0)
			(type solid)
		)
		(fill yes)
		(layer "In4.Cu")
		(net "P5E_PEX0_STN5_TX_DP<89>")
	)
	(gr_poly
		(pts
			(arc
				(start 68.402708 -275.949664)
				(mid 67.996308 -275.949664)
				(end 68.402708 -275.949664)
			)
		)
		(stroke
			(width 0)
			(type solid)
		)
		(fill yes)
		(layer "In4.Cu")
		(net "P5E_PEX0_STN1_RX_DP<25>")
	)
	(gr_poly
		(pts
			(arc
				(start 68.402708 -274.999704)
				(mid 67.996308 -274.999704)
				(end 68.402708 -274.999704)
			)
		)
		(stroke
			(width 0)
			(type solid)
		)
		(fill yes)
		(layer "In4.Cu")
		(net "P5E_PEX0_STN1_RX_DN<25>")
	)
	(gr_poly
		(pts
			(arc
				(start 68.402962 -316.799722)
				(mid 67.996562 -316.799722)
				(end 68.402962 -316.799722)
			)
		)
		(stroke
			(width 0)
			(type solid)
		)
		(fill yes)
		(layer "In4.Cu")
		(net "P5E_PEX0_STN5_RX_DN<90>")
	)
	(gr_poly
		(pts
			(arc
				(start 68.402962 -315.849762)
				(mid 67.996562 -315.849762)
				(end 68.402962 -315.849762)
			)
		)
		(stroke
			(width 0)
			(type solid)
		)
		(fill yes)
		(layer "In4.Cu")
		(net "P5E_PEX0_STN5_RX_DP<90>")
	)
	(gr_poly
		(pts
			(arc
				(start 68.402962 -312.049922)
				(mid 67.996562 -312.049922)
				(end 68.402962 -312.049922)
			)
		)
		(stroke
			(width 0)
			(type solid)
		)
		(fill yes)
		(layer "In4.Cu")
		(net "P5E_PEX0_STN5_TX_DN<90>")
	)
	(gr_poly
		(pts
			(arc
				(start 68.402962 -311.099962)
				(mid 67.996562 -311.099962)
				(end 68.402962 -311.099962)
			)
		)
		(stroke
			(width 0)
			(type solid)
		)
		(fill yes)
		(layer "In4.Cu")
		(net "P5E_PEX0_STN5_TX_DP<90>")
	)
	(gr_poly
		(pts
			(arc
				(start 68.402962 -280.699718)
				(mid 67.996562 -280.699718)
				(end 68.402962 -280.699718)
			)
		)
		(stroke
			(width 0)
			(type solid)
		)
		(fill yes)
		(layer "In4.Cu")
		(net "P5E_PEX0_STN1_TX_DN<25>")
	)
	(gr_poly
		(pts
			(arc
				(start 68.402962 -279.749504)
				(mid 67.996562 -279.749504)
				(end 68.402962 -279.749504)
			)
		)
		(stroke
			(width 0)
			(type solid)
		)
		(fill yes)
		(layer "In4.Cu")
		(net "P5E_PEX0_STN1_TX_DP<25>")
	)
	(gr_poly
		(pts
			(arc
				(start 69.352922 -278.799798)
				(mid 68.946522 -278.799798)
				(end 69.352922 -278.799798)
			)
		)
		(stroke
			(width 0)
			(type solid)
		)
		(fill yes)
		(layer "In4.Cu")
		(net "P5E_PEX0_STN1_TX_DP<26>")
	)
	(gr_poly
		(pts
			(arc
				(start 69.352922 -277.849838)
				(mid 68.946522 -277.849838)
				(end 69.352922 -277.849838)
			)
		)
		(stroke
			(width 0)
			(type solid)
		)
		(fill yes)
		(layer "In4.Cu")
		(net "P5E_PEX0_STN1_TX_DN<26>")
	)
	(gr_poly
		(pts
			(arc
				(start 69.352922 -274.049744)
				(mid 68.946522 -274.049744)
				(end 69.352922 -274.049744)
			)
		)
		(stroke
			(width 0)
			(type solid)
		)
		(fill yes)
		(layer "In4.Cu")
		(net "P5E_PEX0_STN1_RX_DP<26>")
	)
	(gr_poly
		(pts
			(arc
				(start 69.352922 -273.099784)
				(mid 68.946522 -273.099784)
				(end 69.352922 -273.099784)
			)
		)
		(stroke
			(width 0)
			(type solid)
		)
		(fill yes)
		(layer "In4.Cu")
		(net "P5E_PEX0_STN1_RX_DN<26>")
	)
	(gr_poly
		(pts
			(arc
				(start 69.353176 -318.699896)
				(mid 68.946776 -318.699896)
				(end 69.353176 -318.699896)
			)
		)
		(stroke
			(width 0)
			(type solid)
		)
		(fill yes)
		(layer "In4.Cu")
		(net "P5E_PEX0_STN5_RX_DN<91>")
	)
	(gr_poly
		(pts
			(arc
				(start 69.353176 -317.749936)
				(mid 68.946776 -317.749936)
				(end 69.353176 -317.749936)
			)
		)
		(stroke
			(width 0)
			(type solid)
		)
		(fill yes)
		(layer "In4.Cu")
		(net "P5E_PEX0_STN5_RX_DP<91>")
	)
	(gr_poly
		(pts
			(arc
				(start 69.353176 -313.949842)
				(mid 68.946776 -313.949842)
				(end 69.353176 -313.949842)
			)
		)
		(stroke
			(width 0)
			(type solid)
		)
		(fill yes)
		(layer "In4.Cu")
		(net "P5E_PEX0_STN5_TX_DN<91>")
	)
	(gr_poly
		(pts
			(arc
				(start 69.353176 -312.999882)
				(mid 68.946776 -312.999882)
				(end 69.353176 -312.999882)
			)
		)
		(stroke
			(width 0)
			(type solid)
		)
		(fill yes)
		(layer "In4.Cu")
		(net "P5E_PEX0_STN5_TX_DP<91>")
	)
	(gr_poly
		(pts
			(arc
				(start 70.302628 -275.949918)
				(mid 69.896228 -275.949918)
				(end 70.302628 -275.949918)
			)
		)
		(stroke
			(width 0)
			(type solid)
		)
		(fill yes)
		(layer "In4.Cu")
		(net "P5E_PEX0_STN1_RX_DP<27>")
	)
	(gr_poly
		(pts
			(arc
				(start 70.302628 -274.999958)
				(mid 69.896228 -274.999958)
				(end 70.302628 -274.999958)
			)
		)
		(stroke
			(width 0)
			(type solid)
		)
		(fill yes)
		(layer "In4.Cu")
		(net "P5E_PEX0_STN1_RX_DN<27>")
	)
	(gr_poly
		(pts
			(arc
				(start 70.303136 -316.799722)
				(mid 69.896736 -316.799722)
				(end 70.303136 -316.799722)
			)
		)
		(stroke
			(width 0)
			(type solid)
		)
		(fill yes)
		(layer "In4.Cu")
		(net "P5E_PEX0_STN5_RX_DN<92>")
	)
	(gr_poly
		(pts
			(arc
				(start 70.303136 -315.849762)
				(mid 69.896736 -315.849762)
				(end 70.303136 -315.849762)
			)
		)
		(stroke
			(width 0)
			(type solid)
		)
		(fill yes)
		(layer "In4.Cu")
		(net "P5E_PEX0_STN5_RX_DP<92>")
	)
	(gr_poly
		(pts
			(arc
				(start 70.303136 -312.049922)
				(mid 69.896736 -312.049922)
				(end 70.303136 -312.049922)
			)
		)
		(stroke
			(width 0)
			(type solid)
		)
		(fill yes)
		(layer "In4.Cu")
		(net "P5E_PEX0_STN5_TX_DN<92>")
	)
	(gr_poly
		(pts
			(arc
				(start 70.303136 -311.099962)
				(mid 69.896736 -311.099962)
				(end 70.303136 -311.099962)
			)
		)
		(stroke
			(width 0)
			(type solid)
		)
		(fill yes)
		(layer "In4.Cu")
		(net "P5E_PEX0_STN5_TX_DP<92>")
	)
	(gr_poly
		(pts
			(arc
				(start 70.303136 -280.699718)
				(mid 69.896736 -280.699718)
				(end 70.303136 -280.699718)
			)
		)
		(stroke
			(width 0)
			(type solid)
		)
		(fill yes)
		(layer "In4.Cu")
		(net "P5E_PEX0_STN1_TX_DN<27>")
	)
	(gr_poly
		(pts
			(arc
				(start 70.303136 -279.749504)
				(mid 69.896736 -279.749504)
				(end 70.303136 -279.749504)
			)
		)
		(stroke
			(width 0)
			(type solid)
		)
		(fill yes)
		(layer "In4.Cu")
		(net "P5E_PEX0_STN1_TX_DP<27>")
	)
	(gr_poly
		(pts
			(arc
				(start 71.252842 -278.799798)
				(mid 70.846442 -278.799798)
				(end 71.252842 -278.799798)
			)
		)
		(stroke
			(width 0)
			(type solid)
		)
		(fill yes)
		(layer "In4.Cu")
		(net "P5E_PEX0_STN1_TX_DP<28>")
	)
	(gr_poly
		(pts
			(arc
				(start 71.252842 -277.849838)
				(mid 70.846442 -277.849838)
				(end 71.252842 -277.849838)
			)
		)
		(stroke
			(width 0)
			(type solid)
		)
		(fill yes)
		(layer "In4.Cu")
		(net "P5E_PEX0_STN1_TX_DN<28>")
	)
	(gr_poly
		(pts
			(arc
				(start 71.252842 -274.049744)
				(mid 70.846442 -274.049744)
				(end 71.252842 -274.049744)
			)
		)
		(stroke
			(width 0)
			(type solid)
		)
		(fill yes)
		(layer "In4.Cu")
		(net "P5E_PEX0_STN1_RX_DP<28>")
	)
	(gr_poly
		(pts
			(arc
				(start 71.252842 -273.099784)
				(mid 70.846442 -273.099784)
				(end 71.252842 -273.099784)
			)
		)
		(stroke
			(width 0)
			(type solid)
		)
		(fill yes)
		(layer "In4.Cu")
		(net "P5E_PEX0_STN1_RX_DN<28>")
	)
	(gr_poly
		(pts
			(arc
				(start 71.253096 -318.699896)
				(mid 70.846696 -318.699896)
				(end 71.253096 -318.699896)
			)
		)
		(stroke
			(width 0)
			(type solid)
		)
		(fill yes)
		(layer "In4.Cu")
		(net "P5E_PEX0_STN5_RX_DN<93>")
	)
	(gr_poly
		(pts
			(arc
				(start 71.253096 -317.749936)
				(mid 70.846696 -317.749936)
				(end 71.253096 -317.749936)
			)
		)
		(stroke
			(width 0)
			(type solid)
		)
		(fill yes)
		(layer "In4.Cu")
		(net "P5E_PEX0_STN5_RX_DP<93>")
	)
	(gr_poly
		(pts
			(arc
				(start 71.253096 -313.949842)
				(mid 70.846696 -313.949842)
				(end 71.253096 -313.949842)
			)
		)
		(stroke
			(width 0)
			(type solid)
		)
		(fill yes)
		(layer "In4.Cu")
		(net "P5E_PEX0_STN5_TX_DN<93>")
	)
	(gr_poly
		(pts
			(arc
				(start 71.253096 -312.999882)
				(mid 70.846696 -312.999882)
				(end 71.253096 -312.999882)
			)
		)
		(stroke
			(width 0)
			(type solid)
		)
		(fill yes)
		(layer "In4.Cu")
		(net "P5E_PEX0_STN5_TX_DP<93>")
	)
	(gr_poly
		(pts
			(arc
				(start 72.202802 -275.949664)
				(mid 71.796402 -275.949664)
				(end 72.202802 -275.949664)
			)
		)
		(stroke
			(width 0)
			(type solid)
		)
		(fill yes)
		(layer "In4.Cu")
		(net "P5E_PEX0_STN1_RX_DP<29>")
	)
	(gr_poly
		(pts
			(arc
				(start 72.202802 -274.999704)
				(mid 71.796402 -274.999704)
				(end 72.202802 -274.999704)
			)
		)
		(stroke
			(width 0)
			(type solid)
		)
		(fill yes)
		(layer "In4.Cu")
		(net "P5E_PEX0_STN1_RX_DN<29>")
	)
	(gr_poly
		(pts
			(arc
				(start 72.203056 -316.799722)
				(mid 71.796656 -316.799722)
				(end 72.203056 -316.799722)
			)
		)
		(stroke
			(width 0)
			(type solid)
		)
		(fill yes)
		(layer "In4.Cu")
		(net "P5E_PEX0_STN5_RX_DN<94>")
	)
	(gr_poly
		(pts
			(arc
				(start 72.203056 -315.849762)
				(mid 71.796656 -315.849762)
				(end 72.203056 -315.849762)
			)
		)
		(stroke
			(width 0)
			(type solid)
		)
		(fill yes)
		(layer "In4.Cu")
		(net "P5E_PEX0_STN5_RX_DP<94>")
	)
	(gr_poly
		(pts
			(arc
				(start 72.203056 -312.049922)
				(mid 71.796656 -312.049922)
				(end 72.203056 -312.049922)
			)
		)
		(stroke
			(width 0)
			(type solid)
		)
		(fill yes)
		(layer "In4.Cu")
		(net "P5E_PEX0_STN5_TX_DN<94>")
	)
	(gr_poly
		(pts
			(arc
				(start 72.203056 -311.099962)
				(mid 71.796656 -311.099962)
				(end 72.203056 -311.099962)
			)
		)
		(stroke
			(width 0)
			(type solid)
		)
		(fill yes)
		(layer "In4.Cu")
		(net "P5E_PEX0_STN5_TX_DP<94>")
	)
	(gr_poly
		(pts
			(arc
				(start 72.203056 -280.699718)
				(mid 71.796656 -280.699718)
				(end 72.203056 -280.699718)
			)
		)
		(stroke
			(width 0)
			(type solid)
		)
		(fill yes)
		(layer "In4.Cu")
		(net "P5E_PEX0_STN1_TX_DN<29>")
	)
	(gr_poly
		(pts
			(arc
				(start 72.203056 -279.749504)
				(mid 71.796656 -279.749504)
				(end 72.203056 -279.749504)
			)
		)
		(stroke
			(width 0)
			(type solid)
		)
		(fill yes)
		(layer "In4.Cu")
		(net "P5E_PEX0_STN1_TX_DP<29>")
	)
	(gr_poly
		(pts
			(arc
				(start 73.152762 -278.799798)
				(mid 72.746362 -278.799798)
				(end 73.152762 -278.799798)
			)
		)
		(stroke
			(width 0)
			(type solid)
		)
		(fill yes)
		(layer "In4.Cu")
		(net "P5E_PEX0_STN1_TX_DP<30>")
	)
	(gr_poly
		(pts
			(arc
				(start 73.152762 -277.849838)
				(mid 72.746362 -277.849838)
				(end 73.152762 -277.849838)
			)
		)
		(stroke
			(width 0)
			(type solid)
		)
		(fill yes)
		(layer "In4.Cu")
		(net "P5E_PEX0_STN1_TX_DN<30>")
	)
	(gr_poly
		(pts
			(arc
				(start 73.152762 -274.049744)
				(mid 72.746362 -274.049744)
				(end 73.152762 -274.049744)
			)
		)
		(stroke
			(width 0)
			(type solid)
		)
		(fill yes)
		(layer "In4.Cu")
		(net "P5E_PEX0_STN1_RX_DP<30>")
	)
	(gr_poly
		(pts
			(arc
				(start 73.152762 -273.099784)
				(mid 72.746362 -273.099784)
				(end 73.152762 -273.099784)
			)
		)
		(stroke
			(width 0)
			(type solid)
		)
		(fill yes)
		(layer "In4.Cu")
		(net "P5E_PEX0_STN1_RX_DN<30>")
	)
	(gr_poly
		(pts
			(arc
				(start 73.153016 -318.699896)
				(mid 72.746616 -318.699896)
				(end 73.153016 -318.699896)
			)
		)
		(stroke
			(width 0)
			(type solid)
		)
		(fill yes)
		(layer "In4.Cu")
		(net "P5E_PEX0_STN5_RX_DN<95>")
	)
	(gr_poly
		(pts
			(arc
				(start 73.153016 -317.749936)
				(mid 72.746616 -317.749936)
				(end 73.153016 -317.749936)
			)
		)
		(stroke
			(width 0)
			(type solid)
		)
		(fill yes)
		(layer "In4.Cu")
		(net "P5E_PEX0_STN5_RX_DP<95>")
	)
	(gr_poly
		(pts
			(arc
				(start 73.153016 -313.949842)
				(mid 72.746616 -313.949842)
				(end 73.153016 -313.949842)
			)
		)
		(stroke
			(width 0)
			(type solid)
		)
		(fill yes)
		(layer "In4.Cu")
		(net "P5E_PEX0_STN5_TX_DN<95>")
	)
	(gr_poly
		(pts
			(arc
				(start 73.153016 -312.999882)
				(mid 72.746616 -312.999882)
				(end 73.153016 -312.999882)
			)
		)
		(stroke
			(width 0)
			(type solid)
		)
		(fill yes)
		(layer "In4.Cu")
		(net "P5E_PEX0_STN5_TX_DP<95>")
	)
	(gr_poly
		(pts
			(arc
				(start 74.102722 -275.949918)
				(mid 73.696322 -275.949918)
				(end 74.102722 -275.949918)
			)
		)
		(stroke
			(width 0)
			(type solid)
		)
		(fill yes)
		(layer "In4.Cu")
		(net "P5E_PEX0_STN1_RX_DP<31>")
	)
	(gr_poly
		(pts
			(arc
				(start 74.102722 -274.999958)
				(mid 73.696322 -274.999958)
				(end 74.102722 -274.999958)
			)
		)
		(stroke
			(width 0)
			(type solid)
		)
		(fill yes)
		(layer "In4.Cu")
		(net "P5E_PEX0_STN1_RX_DN<31>")
	)
	(gr_poly
		(pts
			(arc
				(start 74.102976 -316.799722)
				(mid 73.696576 -316.799722)
				(end 74.102976 -316.799722)
			)
		)
		(stroke
			(width 0)
			(type solid)
		)
		(fill yes)
		(layer "In4.Cu")
		(net "P5E_PEX0_STN4_RX_DN<79>")
	)
	(gr_poly
		(pts
			(arc
				(start 74.102976 -315.849762)
				(mid 73.696576 -315.849762)
				(end 74.102976 -315.849762)
			)
		)
		(stroke
			(width 0)
			(type solid)
		)
		(fill yes)
		(layer "In4.Cu")
		(net "P5E_PEX0_STN4_RX_DP<79>")
	)
	(gr_poly
		(pts
			(arc
				(start 74.102976 -312.049922)
				(mid 73.696576 -312.049922)
				(end 74.102976 -312.049922)
			)
		)
		(stroke
			(width 0)
			(type solid)
		)
		(fill yes)
		(layer "In4.Cu")
		(net "P5E_PEX0_STN4_TX_DN<79>")
	)
	(gr_poly
		(pts
			(arc
				(start 74.102976 -311.099962)
				(mid 73.696576 -311.099962)
				(end 74.102976 -311.099962)
			)
		)
		(stroke
			(width 0)
			(type solid)
		)
		(fill yes)
		(layer "In4.Cu")
		(net "P5E_PEX0_STN4_TX_DP<79>")
	)
	(gr_poly
		(pts
			(arc
				(start 74.102976 -280.699718)
				(mid 73.696576 -280.699718)
				(end 74.102976 -280.699718)
			)
		)
		(stroke
			(width 0)
			(type solid)
		)
		(fill yes)
		(layer "In4.Cu")
		(net "P5E_PEX0_STN1_TX_DN<31>")
	)
	(gr_poly
		(pts
			(arc
				(start 74.102976 -279.749504)
				(mid 73.696576 -279.749504)
				(end 74.102976 -279.749504)
			)
		)
		(stroke
			(width 0)
			(type solid)
		)
		(fill yes)
		(layer "In4.Cu")
		(net "P5E_PEX0_STN1_TX_DP<31>")
	)
	(gr_poly
		(pts
			(arc
				(start 75.052936 -287.349946)
				(mid 74.646536 -287.349946)
				(end 75.052936 -287.349946)
			)
		)
		(stroke
			(width 0)
			(type solid)
		)
		(fill yes)
		(layer "In4.Cu")
		(net "P5E_PEX0_STN0_TX_DP<1>")
	)
	(gr_poly
		(pts
			(arc
				(start 75.052936 -285.449772)
				(mid 74.646536 -285.449772)
				(end 75.052936 -285.449772)
			)
		)
		(stroke
			(width 0)
			(type solid)
		)
		(fill yes)
		(layer "In4.Cu")
		(net "P5E_PEX0_STN0_TX_DP<3>")
	)
	(gr_poly
		(pts
			(arc
				(start 75.052936 -283.549852)
				(mid 74.646536 -283.549852)
				(end 75.052936 -283.549852)
			)
		)
		(stroke
			(width 0)
			(type solid)
		)
		(fill yes)
		(layer "In4.Cu")
		(net "P5E_PEX0_STN0_TX_DP<5>")
	)
	(gr_poly
		(pts
			(arc
				(start 75.052936 -278.799798)
				(mid 74.646536 -278.799798)
				(end 75.052936 -278.799798)
			)
		)
		(stroke
			(width 0)
			(type solid)
		)
		(fill yes)
		(layer "In4.Cu")
		(net "P5E_PEX0_STN0_TX_DP<15>")
	)
	(gr_poly
		(pts
			(arc
				(start 75.052936 -277.849838)
				(mid 74.646536 -277.849838)
				(end 75.052936 -277.849838)
			)
		)
		(stroke
			(width 0)
			(type solid)
		)
		(fill yes)
		(layer "In4.Cu")
		(net "P5E_PEX0_STN0_TX_DN<15>")
	)
	(gr_poly
		(pts
			(arc
				(start 75.052936 -274.049744)
				(mid 74.646536 -274.049744)
				(end 75.052936 -274.049744)
			)
		)
		(stroke
			(width 0)
			(type solid)
		)
		(fill yes)
		(layer "In4.Cu")
		(net "P5E_PEX0_STN0_RX_DP<15>")
	)
	(gr_poly
		(pts
			(arc
				(start 75.052936 -273.099784)
				(mid 74.646536 -273.099784)
				(end 75.052936 -273.099784)
			)
		)
		(stroke
			(width 0)
			(type solid)
		)
		(fill yes)
		(layer "In4.Cu")
		(net "P5E_PEX0_STN0_RX_DN<15>")
	)
	(gr_poly
		(pts
			(arc
				(start 75.05319 -318.699896)
				(mid 74.64679 -318.699896)
				(end 75.05319 -318.699896)
			)
		)
		(stroke
			(width 0)
			(type solid)
		)
		(fill yes)
		(layer "In4.Cu")
		(net "P5E_PEX0_STN4_RX_DN<78>")
	)
	(gr_poly
		(pts
			(arc
				(start 75.05319 -317.749936)
				(mid 74.64679 -317.749936)
				(end 75.05319 -317.749936)
			)
		)
		(stroke
			(width 0)
			(type solid)
		)
		(fill yes)
		(layer "In4.Cu")
		(net "P5E_PEX0_STN4_RX_DP<78>")
	)
	(gr_poly
		(pts
			(arc
				(start 75.05319 -313.949842)
				(mid 74.64679 -313.949842)
				(end 75.05319 -313.949842)
			)
		)
		(stroke
			(width 0)
			(type solid)
		)
		(fill yes)
		(layer "In4.Cu")
		(net "P5E_PEX0_STN4_TX_DN<78>")
	)
	(gr_poly
		(pts
			(arc
				(start 75.05319 -312.999882)
				(mid 74.64679 -312.999882)
				(end 75.05319 -312.999882)
			)
		)
		(stroke
			(width 0)
			(type solid)
		)
		(fill yes)
		(layer "In4.Cu")
		(net "P5E_PEX0_STN4_TX_DP<78>")
	)
	(gr_poly
		(pts
			(arc
				(start 75.05319 -308.249828)
				(mid 74.64679 -308.249828)
				(end 75.05319 -308.249828)
			)
		)
		(stroke
			(width 0)
			(type solid)
		)
		(fill yes)
		(layer "In4.Cu")
		(net "P5E_PEX0_STN4_TX_DP<68>")
	)
	(gr_poly
		(pts
			(arc
				(start 75.05319 -306.349908)
				(mid 74.64679 -306.349908)
				(end 75.05319 -306.349908)
			)
		)
		(stroke
			(width 0)
			(type solid)
		)
		(fill yes)
		(layer "In4.Cu")
		(net "P5E_PEX0_STN4_TX_DP<66>")
	)
	(gr_poly
		(pts
			(arc
				(start 75.05319 -304.449734)
				(mid 74.64679 -304.449734)
				(end 75.05319 -304.449734)
			)
		)
		(stroke
			(width 0)
			(type solid)
		)
		(fill yes)
		(layer "In4.Cu")
		(net "P5E_PEX0_STN4_TX_DP<64>")
	)
	(gr_poly
		(pts
			(arc
				(start 76.002896 -275.949664)
				(mid 75.596496 -275.949664)
				(end 76.002896 -275.949664)
			)
		)
		(stroke
			(width 0)
			(type solid)
		)
		(fill yes)
		(layer "In4.Cu")
		(net "P5E_PEX0_STN0_RX_DP<14>")
	)
	(gr_poly
		(pts
			(arc
				(start 76.002896 -274.999704)
				(mid 75.596496 -274.999704)
				(end 76.002896 -274.999704)
			)
		)
		(stroke
			(width 0)
			(type solid)
		)
		(fill yes)
		(layer "In4.Cu")
		(net "P5E_PEX0_STN0_RX_DN<14>")
	)
	(gr_poly
		(pts
			(arc
				(start 76.00315 -316.799722)
				(mid 75.59675 -316.799722)
				(end 76.00315 -316.799722)
			)
		)
		(stroke
			(width 0)
			(type solid)
		)
		(fill yes)
		(layer "In4.Cu")
		(net "P5E_PEX0_STN4_RX_DN<77>")
	)
	(gr_poly
		(pts
			(arc
				(start 76.00315 -315.849762)
				(mid 75.59675 -315.849762)
				(end 76.00315 -315.849762)
			)
		)
		(stroke
			(width 0)
			(type solid)
		)
		(fill yes)
		(layer "In4.Cu")
		(net "P5E_PEX0_STN4_RX_DP<77>")
	)
	(gr_poly
		(pts
			(arc
				(start 76.00315 -312.049922)
				(mid 75.59675 -312.049922)
				(end 76.00315 -312.049922)
			)
		)
		(stroke
			(width 0)
			(type solid)
		)
		(fill yes)
		(layer "In4.Cu")
		(net "P5E_PEX0_STN4_TX_DN<77>")
	)
	(gr_poly
		(pts
			(arc
				(start 76.00315 -311.099962)
				(mid 75.59675 -311.099962)
				(end 76.00315 -311.099962)
			)
		)
		(stroke
			(width 0)
			(type solid)
		)
		(fill yes)
		(layer "In4.Cu")
		(net "P5E_PEX0_STN4_TX_DP<77>")
	)
	(gr_poly
		(pts
			(arc
				(start 76.00315 -308.249828)
				(mid 75.59675 -308.249828)
				(end 76.00315 -308.249828)
			)
		)
		(stroke
			(width 0)
			(type solid)
		)
		(fill yes)
		(layer "In4.Cu")
		(net "P5E_PEX0_STN4_TX_DN<68>")
	)
	(gr_poly
		(pts
			(arc
				(start 76.00315 -306.349908)
				(mid 75.59675 -306.349908)
				(end 76.00315 -306.349908)
			)
		)
		(stroke
			(width 0)
			(type solid)
		)
		(fill yes)
		(layer "In4.Cu")
		(net "P5E_PEX0_STN4_TX_DN<66>")
	)
	(gr_poly
		(pts
			(arc
				(start 76.00315 -304.449734)
				(mid 75.59675 -304.449734)
				(end 76.00315 -304.449734)
			)
		)
		(stroke
			(width 0)
			(type solid)
		)
		(fill yes)
		(layer "In4.Cu")
		(net "P5E_PEX0_STN4_TX_DN<64>")
	)
	(gr_poly
		(pts
			(arc
				(start 76.00315 -287.349946)
				(mid 75.59675 -287.349946)
				(end 76.00315 -287.349946)
			)
		)
		(stroke
			(width 0)
			(type solid)
		)
		(fill yes)
		(layer "In4.Cu")
		(net "P5E_PEX0_STN0_TX_DN<1>")
	)
	(gr_poly
		(pts
			(arc
				(start 76.00315 -285.449772)
				(mid 75.59675 -285.449772)
				(end 76.00315 -285.449772)
			)
		)
		(stroke
			(width 0)
			(type solid)
		)
		(fill yes)
		(layer "In4.Cu")
		(net "P5E_PEX0_STN0_TX_DN<3>")
	)
	(gr_poly
		(pts
			(arc
				(start 76.00315 -283.549852)
				(mid 75.59675 -283.549852)
				(end 76.00315 -283.549852)
			)
		)
		(stroke
			(width 0)
			(type solid)
		)
		(fill yes)
		(layer "In4.Cu")
		(net "P5E_PEX0_STN0_TX_DN<5>")
	)
	(gr_poly
		(pts
			(arc
				(start 76.00315 -280.699718)
				(mid 75.59675 -280.699718)
				(end 76.00315 -280.699718)
			)
		)
		(stroke
			(width 0)
			(type solid)
		)
		(fill yes)
		(layer "In4.Cu")
		(net "P5E_PEX0_STN0_TX_DN<14>")
	)
	(gr_poly
		(pts
			(arc
				(start 76.00315 -279.749504)
				(mid 75.59675 -279.749504)
				(end 76.00315 -279.749504)
			)
		)
		(stroke
			(width 0)
			(type solid)
		)
		(fill yes)
		(layer "In4.Cu")
		(net "P5E_PEX0_STN0_TX_DP<14>")
	)
	(gr_poly
		(pts
			(arc
				(start 76.952856 -278.799798)
				(mid 76.546456 -278.799798)
				(end 76.952856 -278.799798)
			)
		)
		(stroke
			(width 0)
			(type solid)
		)
		(fill yes)
		(layer "In4.Cu")
		(net "P5E_PEX0_STN0_TX_DP<13>")
	)
	(gr_poly
		(pts
			(arc
				(start 76.952856 -277.849838)
				(mid 76.546456 -277.849838)
				(end 76.952856 -277.849838)
			)
		)
		(stroke
			(width 0)
			(type solid)
		)
		(fill yes)
		(layer "In4.Cu")
		(net "P5E_PEX0_STN0_TX_DN<13>")
	)
	(gr_poly
		(pts
			(arc
				(start 76.952856 -274.049744)
				(mid 76.546456 -274.049744)
				(end 76.952856 -274.049744)
			)
		)
		(stroke
			(width 0)
			(type solid)
		)
		(fill yes)
		(layer "In4.Cu")
		(net "P5E_PEX0_STN0_RX_DP<13>")
	)
	(gr_poly
		(pts
			(arc
				(start 76.952856 -273.099784)
				(mid 76.546456 -273.099784)
				(end 76.952856 -273.099784)
			)
		)
		(stroke
			(width 0)
			(type solid)
		)
		(fill yes)
		(layer "In4.Cu")
		(net "P5E_PEX0_STN0_RX_DN<13>")
	)
	(gr_poly
		(pts
			(arc
				(start 76.95311 -318.699896)
				(mid 76.54671 -318.699896)
				(end 76.95311 -318.699896)
			)
		)
		(stroke
			(width 0)
			(type solid)
		)
		(fill yes)
		(layer "In4.Cu")
		(net "P5E_PEX0_STN4_RX_DN<76>")
	)
	(gr_poly
		(pts
			(arc
				(start 76.95311 -317.749936)
				(mid 76.54671 -317.749936)
				(end 76.95311 -317.749936)
			)
		)
		(stroke
			(width 0)
			(type solid)
		)
		(fill yes)
		(layer "In4.Cu")
		(net "P5E_PEX0_STN4_RX_DP<76>")
	)
	(gr_poly
		(pts
			(arc
				(start 76.95311 -313.949842)
				(mid 76.54671 -313.949842)
				(end 76.95311 -313.949842)
			)
		)
		(stroke
			(width 0)
			(type solid)
		)
		(fill yes)
		(layer "In4.Cu")
		(net "P5E_PEX0_STN4_TX_DN<76>")
	)
	(gr_poly
		(pts
			(arc
				(start 76.95311 -312.999882)
				(mid 76.54671 -312.999882)
				(end 76.95311 -312.999882)
			)
		)
		(stroke
			(width 0)
			(type solid)
		)
		(fill yes)
		(layer "In4.Cu")
		(net "P5E_PEX0_STN4_TX_DP<76>")
	)
	(gr_poly
		(pts
			(arc
				(start 76.95311 -309.199788)
				(mid 76.54671 -309.199788)
				(end 76.95311 -309.199788)
			)
		)
		(stroke
			(width 0)
			(type solid)
		)
		(fill yes)
		(layer "In4.Cu")
		(net "P5E_PEX0_STN4_TX_DP<69>")
	)
	(gr_poly
		(pts
			(arc
				(start 76.95311 -307.299868)
				(mid 76.54671 -307.299868)
				(end 76.95311 -307.299868)
			)
		)
		(stroke
			(width 0)
			(type solid)
		)
		(fill yes)
		(layer "In4.Cu")
		(net "P5E_PEX0_STN4_TX_DP<67>")
	)
	(gr_poly
		(pts
			(arc
				(start 76.95311 -305.399948)
				(mid 76.54671 -305.399948)
				(end 76.95311 -305.399948)
			)
		)
		(stroke
			(width 0)
			(type solid)
		)
		(fill yes)
		(layer "In4.Cu")
		(net "P5E_PEX0_STN4_TX_DP<65>")
	)
	(gr_poly
		(pts
			(arc
				(start 76.95311 -288.299906)
				(mid 76.54671 -288.299906)
				(end 76.95311 -288.299906)
			)
		)
		(stroke
			(width 0)
			(type solid)
		)
		(fill yes)
		(layer "In4.Cu")
		(net "P5E_PEX0_STN0_TX_DP<0>")
	)
	(gr_poly
		(pts
			(arc
				(start 76.95311 -286.399986)
				(mid 76.54671 -286.399986)
				(end 76.95311 -286.399986)
			)
		)
		(stroke
			(width 0)
			(type solid)
		)
		(fill yes)
		(layer "In4.Cu")
		(net "P5E_PEX0_STN0_TX_DP<2>")
	)
	(gr_poly
		(pts
			(arc
				(start 76.95311 -284.499812)
				(mid 76.54671 -284.499812)
				(end 76.95311 -284.499812)
			)
		)
		(stroke
			(width 0)
			(type solid)
		)
		(fill yes)
		(layer "In4.Cu")
		(net "P5E_PEX0_STN0_TX_DP<4>")
	)
	(gr_poly
		(pts
			(arc
				(start 76.95311 -282.599892)
				(mid 76.54671 -282.599892)
				(end 76.95311 -282.599892)
			)
		)
		(stroke
			(width 0)
			(type solid)
		)
		(fill yes)
		(layer "In4.Cu")
		(net "P5E_PEX0_STN0_TX_DP<6>")
	)
	(gr_poly
		(pts
			(arc
				(start 77.902816 -275.949918)
				(mid 77.496416 -275.949918)
				(end 77.902816 -275.949918)
			)
		)
		(stroke
			(width 0)
			(type solid)
		)
		(fill yes)
		(layer "In4.Cu")
		(net "P5E_PEX0_STN0_RX_DP<12>")
	)
	(gr_poly
		(pts
			(arc
				(start 77.902816 -274.999958)
				(mid 77.496416 -274.999958)
				(end 77.902816 -274.999958)
			)
		)
		(stroke
			(width 0)
			(type solid)
		)
		(fill yes)
		(layer "In4.Cu")
		(net "P5E_PEX0_STN0_RX_DN<12>")
	)
	(gr_poly
		(pts
			(arc
				(start 77.90307 -316.799722)
				(mid 77.49667 -316.799722)
				(end 77.90307 -316.799722)
			)
		)
		(stroke
			(width 0)
			(type solid)
		)
		(fill yes)
		(layer "In4.Cu")
		(net "P5E_PEX0_STN4_RX_DN<75>")
	)
	(gr_poly
		(pts
			(arc
				(start 77.90307 -315.849762)
				(mid 77.49667 -315.849762)
				(end 77.90307 -315.849762)
			)
		)
		(stroke
			(width 0)
			(type solid)
		)
		(fill yes)
		(layer "In4.Cu")
		(net "P5E_PEX0_STN4_RX_DP<75>")
	)
	(gr_poly
		(pts
			(arc
				(start 77.90307 -312.049922)
				(mid 77.49667 -312.049922)
				(end 77.90307 -312.049922)
			)
		)
		(stroke
			(width 0)
			(type solid)
		)
		(fill yes)
		(layer "In4.Cu")
		(net "P5E_PEX0_STN4_TX_DN<75>")
	)
	(gr_poly
		(pts
			(arc
				(start 77.90307 -311.099962)
				(mid 77.49667 -311.099962)
				(end 77.90307 -311.099962)
			)
		)
		(stroke
			(width 0)
			(type solid)
		)
		(fill yes)
		(layer "In4.Cu")
		(net "P5E_PEX0_STN4_TX_DP<75>")
	)
	(gr_poly
		(pts
			(arc
				(start 77.90307 -309.199788)
				(mid 77.49667 -309.199788)
				(end 77.90307 -309.199788)
			)
		)
		(stroke
			(width 0)
			(type solid)
		)
		(fill yes)
		(layer "In4.Cu")
		(net "P5E_PEX0_STN4_TX_DN<69>")
	)
	(gr_poly
		(pts
			(arc
				(start 77.90307 -307.299868)
				(mid 77.49667 -307.299868)
				(end 77.90307 -307.299868)
			)
		)
		(stroke
			(width 0)
			(type solid)
		)
		(fill yes)
		(layer "In4.Cu")
		(net "P5E_PEX0_STN4_TX_DN<67>")
	)
	(gr_poly
		(pts
			(arc
				(start 77.90307 -305.399948)
				(mid 77.49667 -305.399948)
				(end 77.90307 -305.399948)
			)
		)
		(stroke
			(width 0)
			(type solid)
		)
		(fill yes)
		(layer "In4.Cu")
		(net "P5E_PEX0_STN4_TX_DN<65>")
	)
	(gr_poly
		(pts
			(arc
				(start 77.90307 -288.299906)
				(mid 77.49667 -288.299906)
				(end 77.90307 -288.299906)
			)
		)
		(stroke
			(width 0)
			(type solid)
		)
		(fill yes)
		(layer "In4.Cu")
		(net "P5E_PEX0_STN0_TX_DN<0>")
	)
	(gr_poly
		(pts
			(arc
				(start 77.90307 -286.399986)
				(mid 77.49667 -286.399986)
				(end 77.90307 -286.399986)
			)
		)
		(stroke
			(width 0)
			(type solid)
		)
		(fill yes)
		(layer "In4.Cu")
		(net "P5E_PEX0_STN0_TX_DN<2>")
	)
	(gr_poly
		(pts
			(arc
				(start 77.90307 -284.499812)
				(mid 77.49667 -284.499812)
				(end 77.90307 -284.499812)
			)
		)
		(stroke
			(width 0)
			(type solid)
		)
		(fill yes)
		(layer "In4.Cu")
		(net "P5E_PEX0_STN0_TX_DN<4>")
	)
	(gr_poly
		(pts
			(arc
				(start 77.90307 -282.599892)
				(mid 77.49667 -282.599892)
				(end 77.90307 -282.599892)
			)
		)
		(stroke
			(width 0)
			(type solid)
		)
		(fill yes)
		(layer "In4.Cu")
		(net "P5E_PEX0_STN0_TX_DN<6>")
	)
	(gr_poly
		(pts
			(arc
				(start 77.90307 -280.699718)
				(mid 77.49667 -280.699718)
				(end 77.90307 -280.699718)
			)
		)
		(stroke
			(width 0)
			(type solid)
		)
		(fill yes)
		(layer "In4.Cu")
		(net "P5E_PEX0_STN0_TX_DN<12>")
	)
	(gr_poly
		(pts
			(arc
				(start 77.90307 -279.749504)
				(mid 77.49667 -279.749504)
				(end 77.90307 -279.749504)
			)
		)
		(stroke
			(width 0)
			(type solid)
		)
		(fill yes)
		(layer "In4.Cu")
		(net "P5E_PEX0_STN0_TX_DP<12>")
	)
	(gr_poly
		(pts
			(arc
				(start 78.852776 -278.799798)
				(mid 78.446376 -278.799798)
				(end 78.852776 -278.799798)
			)
		)
		(stroke
			(width 0)
			(type solid)
		)
		(fill yes)
		(layer "In4.Cu")
		(net "P5E_PEX0_STN0_TX_DP<11>")
	)
	(gr_poly
		(pts
			(arc
				(start 78.852776 -277.849838)
				(mid 78.446376 -277.849838)
				(end 78.852776 -277.849838)
			)
		)
		(stroke
			(width 0)
			(type solid)
		)
		(fill yes)
		(layer "In4.Cu")
		(net "P5E_PEX0_STN0_TX_DN<11>")
	)
	(gr_poly
		(pts
			(arc
				(start 78.852776 -274.049744)
				(mid 78.446376 -274.049744)
				(end 78.852776 -274.049744)
			)
		)
		(stroke
			(width 0)
			(type solid)
		)
		(fill yes)
		(layer "In4.Cu")
		(net "P5E_PEX0_STN0_RX_DP<11>")
	)
	(gr_poly
		(pts
			(arc
				(start 78.852776 -273.099784)
				(mid 78.446376 -273.099784)
				(end 78.852776 -273.099784)
			)
		)
		(stroke
			(width 0)
			(type solid)
		)
		(fill yes)
		(layer "In4.Cu")
		(net "P5E_PEX0_STN0_RX_DN<11>")
	)
	(gr_poly
		(pts
			(arc
				(start 78.85303 -318.699896)
				(mid 78.44663 -318.699896)
				(end 78.85303 -318.699896)
			)
		)
		(stroke
			(width 0)
			(type solid)
		)
		(fill yes)
		(layer "In4.Cu")
		(net "P5E_PEX0_STN4_RX_DN<74>")
	)
	(gr_poly
		(pts
			(arc
				(start 78.85303 -317.749936)
				(mid 78.44663 -317.749936)
				(end 78.85303 -317.749936)
			)
		)
		(stroke
			(width 0)
			(type solid)
		)
		(fill yes)
		(layer "In4.Cu")
		(net "P5E_PEX0_STN4_RX_DP<74>")
	)
	(gr_poly
		(pts
			(arc
				(start 78.85303 -313.949842)
				(mid 78.44663 -313.949842)
				(end 78.85303 -313.949842)
			)
		)
		(stroke
			(width 0)
			(type solid)
		)
		(fill yes)
		(layer "In4.Cu")
		(net "P5E_PEX0_STN4_TX_DN<74>")
	)
	(gr_poly
		(pts
			(arc
				(start 78.85303 -312.999882)
				(mid 78.44663 -312.999882)
				(end 78.85303 -312.999882)
			)
		)
		(stroke
			(width 0)
			(type solid)
		)
		(fill yes)
		(layer "In4.Cu")
		(net "P5E_PEX0_STN4_TX_DP<74>")
	)
	(gr_poly
		(pts
			(arc
				(start 79.802736 -275.949918)
				(mid 79.396336 -275.949918)
				(end 79.802736 -275.949918)
			)
		)
		(stroke
			(width 0)
			(type solid)
		)
		(fill yes)
		(layer "In4.Cu")
		(net "P5E_PEX0_STN0_RX_DP<10>")
	)
	(gr_poly
		(pts
			(arc
				(start 79.802736 -274.999958)
				(mid 79.396336 -274.999958)
				(end 79.802736 -274.999958)
			)
		)
		(stroke
			(width 0)
			(type solid)
		)
		(fill yes)
		(layer "In4.Cu")
		(net "P5E_PEX0_STN0_RX_DN<10>")
	)
	(gr_poly
		(pts
			(arc
				(start 79.80299 -316.799722)
				(mid 79.39659 -316.799722)
				(end 79.80299 -316.799722)
			)
		)
		(stroke
			(width 0)
			(type solid)
		)
		(fill yes)
		(layer "In4.Cu")
		(net "P5E_PEX0_STN4_RX_DN<73>")
	)
	(gr_poly
		(pts
			(arc
				(start 79.80299 -315.849762)
				(mid 79.39659 -315.849762)
				(end 79.80299 -315.849762)
			)
		)
		(stroke
			(width 0)
			(type solid)
		)
		(fill yes)
		(layer "In4.Cu")
		(net "P5E_PEX0_STN4_RX_DP<73>")
	)
	(gr_poly
		(pts
			(arc
				(start 79.80299 -312.049922)
				(mid 79.39659 -312.049922)
				(end 79.80299 -312.049922)
			)
		)
		(stroke
			(width 0)
			(type solid)
		)
		(fill yes)
		(layer "In4.Cu")
		(net "P5E_PEX0_STN4_TX_DN<73>")
	)
	(gr_poly
		(pts
			(arc
				(start 79.80299 -311.099962)
				(mid 79.39659 -311.099962)
				(end 79.80299 -311.099962)
			)
		)
		(stroke
			(width 0)
			(type solid)
		)
		(fill yes)
		(layer "In4.Cu")
		(net "P5E_PEX0_STN4_TX_DP<73>")
	)
	(gr_poly
		(pts
			(arc
				(start 79.80299 -309.199788)
				(mid 79.39659 -309.199788)
				(end 79.80299 -309.199788)
			)
		)
		(stroke
			(width 0)
			(type solid)
		)
		(fill yes)
		(layer "In4.Cu")
		(net "P5E_PEX0_STN4_RX_DP<69>")
	)
	(gr_poly
		(pts
			(arc
				(start 79.80299 -307.299868)
				(mid 79.39659 -307.299868)
				(end 79.80299 -307.299868)
			)
		)
		(stroke
			(width 0)
			(type solid)
		)
		(fill yes)
		(layer "In4.Cu")
		(net "P5E_PEX0_STN4_RX_DP<67>")
	)
	(gr_poly
		(pts
			(arc
				(start 79.80299 -305.399948)
				(mid 79.39659 -305.399948)
				(end 79.80299 -305.399948)
			)
		)
		(stroke
			(width 0)
			(type solid)
		)
		(fill yes)
		(layer "In4.Cu")
		(net "P5E_PEX0_STN4_RX_DP<65>")
	)
	(gr_poly
		(pts
			(arc
				(start 79.80299 -288.299906)
				(mid 79.39659 -288.299906)
				(end 79.80299 -288.299906)
			)
		)
		(stroke
			(width 0)
			(type solid)
		)
		(fill yes)
		(layer "In4.Cu")
		(net "P5E_PEX0_STN0_RX_DP<0>")
	)
	(gr_poly
		(pts
			(arc
				(start 79.80299 -286.399732)
				(mid 79.39659 -286.399732)
				(end 79.80299 -286.399732)
			)
		)
		(stroke
			(width 0)
			(type solid)
		)
		(fill yes)
		(layer "In4.Cu")
		(net "P5E_PEX0_STN0_RX_DP<2>")
	)
	(gr_poly
		(pts
			(arc
				(start 79.80299 -284.499812)
				(mid 79.39659 -284.499812)
				(end 79.80299 -284.499812)
			)
		)
		(stroke
			(width 0)
			(type solid)
		)
		(fill yes)
		(layer "In4.Cu")
		(net "P5E_PEX0_STN0_RX_DP<4>")
	)
	(gr_poly
		(pts
			(arc
				(start 79.80299 -282.599892)
				(mid 79.39659 -282.599892)
				(end 79.80299 -282.599892)
			)
		)
		(stroke
			(width 0)
			(type solid)
		)
		(fill yes)
		(layer "In4.Cu")
		(net "P5E_PEX0_STN0_RX_DP<6>")
	)
	(gr_poly
		(pts
			(arc
				(start 79.80299 -280.699718)
				(mid 79.39659 -280.699718)
				(end 79.80299 -280.699718)
			)
		)
		(stroke
			(width 0)
			(type solid)
		)
		(fill yes)
		(layer "In4.Cu")
		(net "P5E_PEX0_STN0_TX_DP<10>")
	)
	(gr_poly
		(pts
			(arc
				(start 79.80299 -279.749758)
				(mid 79.39659 -279.749758)
				(end 79.80299 -279.749758)
			)
		)
		(stroke
			(width 0)
			(type solid)
		)
		(fill yes)
		(layer "In4.Cu")
		(net "P5E_PEX0_STN0_TX_DN<10>")
	)
	(gr_poly
		(pts
			(arc
				(start 80.752696 -274.049744)
				(mid 80.346296 -274.049744)
				(end 80.752696 -274.049744)
			)
		)
		(stroke
			(width 0)
			(type solid)
		)
		(fill yes)
		(layer "In4.Cu")
		(net "P5E_PEX0_STN0_RX_DP<9>")
	)
	(gr_poly
		(pts
			(arc
				(start 80.752696 -273.099784)
				(mid 80.346296 -273.099784)
				(end 80.752696 -273.099784)
			)
		)
		(stroke
			(width 0)
			(type solid)
		)
		(fill yes)
		(layer "In4.Cu")
		(net "P5E_PEX0_STN0_RX_DN<9>")
	)
	(gr_poly
		(pts
			(arc
				(start 80.75295 -318.699896)
				(mid 80.34655 -318.699896)
				(end 80.75295 -318.699896)
			)
		)
		(stroke
			(width 0)
			(type solid)
		)
		(fill yes)
		(layer "In4.Cu")
		(net "P5E_PEX0_STN4_RX_DN<72>")
	)
	(gr_poly
		(pts
			(arc
				(start 80.75295 -317.749936)
				(mid 80.34655 -317.749936)
				(end 80.75295 -317.749936)
			)
		)
		(stroke
			(width 0)
			(type solid)
		)
		(fill yes)
		(layer "In4.Cu")
		(net "P5E_PEX0_STN4_RX_DP<72>")
	)
	(gr_poly
		(pts
			(arc
				(start 80.75295 -313.949842)
				(mid 80.34655 -313.949842)
				(end 80.75295 -313.949842)
			)
		)
		(stroke
			(width 0)
			(type solid)
		)
		(fill yes)
		(layer "In4.Cu")
		(net "P5E_PEX0_STN4_TX_DN<72>")
	)
	(gr_poly
		(pts
			(arc
				(start 80.75295 -312.999882)
				(mid 80.34655 -312.999882)
				(end 80.75295 -312.999882)
			)
		)
		(stroke
			(width 0)
			(type solid)
		)
		(fill yes)
		(layer "In4.Cu")
		(net "P5E_PEX0_STN4_TX_DP<72>")
	)
	(gr_poly
		(pts
			(arc
				(start 80.75295 -309.199788)
				(mid 80.34655 -309.199788)
				(end 80.75295 -309.199788)
			)
		)
		(stroke
			(width 0)
			(type solid)
		)
		(fill yes)
		(layer "In4.Cu")
		(net "P5E_PEX0_STN4_RX_DN<69>")
	)
	(gr_poly
		(pts
			(arc
				(start 80.75295 -307.299868)
				(mid 80.34655 -307.299868)
				(end 80.75295 -307.299868)
			)
		)
		(stroke
			(width 0)
			(type solid)
		)
		(fill yes)
		(layer "In4.Cu")
		(net "P5E_PEX0_STN4_RX_DN<67>")
	)
	(gr_poly
		(pts
			(arc
				(start 80.75295 -305.399948)
				(mid 80.34655 -305.399948)
				(end 80.75295 -305.399948)
			)
		)
		(stroke
			(width 0)
			(type solid)
		)
		(fill yes)
		(layer "In4.Cu")
		(net "P5E_PEX0_STN4_RX_DN<65>")
	)
	(gr_poly
		(pts
			(arc
				(start 80.75295 -288.299906)
				(mid 80.34655 -288.299906)
				(end 80.75295 -288.299906)
			)
		)
		(stroke
			(width 0)
			(type solid)
		)
		(fill yes)
		(layer "In4.Cu")
		(net "P5E_PEX0_STN0_RX_DN<0>")
	)
	(gr_poly
		(pts
			(arc
				(start 80.75295 -286.399732)
				(mid 80.34655 -286.399732)
				(end 80.75295 -286.399732)
			)
		)
		(stroke
			(width 0)
			(type solid)
		)
		(fill yes)
		(layer "In4.Cu")
		(net "P5E_PEX0_STN0_RX_DN<2>")
	)
	(gr_poly
		(pts
			(arc
				(start 80.75295 -284.499812)
				(mid 80.34655 -284.499812)
				(end 80.75295 -284.499812)
			)
		)
		(stroke
			(width 0)
			(type solid)
		)
		(fill yes)
		(layer "In4.Cu")
		(net "P5E_PEX0_STN0_RX_DN<4>")
	)
	(gr_poly
		(pts
			(arc
				(start 80.75295 -282.599892)
				(mid 80.34655 -282.599892)
				(end 80.75295 -282.599892)
			)
		)
		(stroke
			(width 0)
			(type solid)
		)
		(fill yes)
		(layer "In4.Cu")
		(net "P5E_PEX0_STN0_RX_DN<6>")
	)
	(gr_poly
		(pts
			(arc
				(start 80.75295 -278.799798)
				(mid 80.34655 -278.799798)
				(end 80.75295 -278.799798)
			)
		)
		(stroke
			(width 0)
			(type solid)
		)
		(fill yes)
		(layer "In4.Cu")
		(net "P5E_PEX0_STN0_TX_DP<9>")
	)
	(gr_poly
		(pts
			(arc
				(start 80.75295 -277.849838)
				(mid 80.34655 -277.849838)
				(end 80.75295 -277.849838)
			)
		)
		(stroke
			(width 0)
			(type solid)
		)
		(fill yes)
		(layer "In4.Cu")
		(net "P5E_PEX0_STN0_TX_DN<9>")
	)
	(gr_poly
		(pts
			(arc
				(start 81.703164 -316.799722)
				(mid 81.296764 -316.799722)
				(end 81.703164 -316.799722)
			)
		)
		(stroke
			(width 0)
			(type solid)
		)
		(fill yes)
		(layer "In4.Cu")
		(net "P5E_PEX0_STN4_RX_DP<71>")
	)
	(gr_poly
		(pts
			(arc
				(start 81.703164 -314.899802)
				(mid 81.296764 -314.899802)
				(end 81.703164 -314.899802)
			)
		)
		(stroke
			(width 0)
			(type solid)
		)
		(fill yes)
		(layer "In4.Cu")
		(net "P5E_PEX0_STN4_TX_DP<71>")
	)
	(gr_poly
		(pts
			(arc
				(start 81.703164 -312.049922)
				(mid 81.296764 -312.049922)
				(end 81.703164 -312.049922)
			)
		)
		(stroke
			(width 0)
			(type solid)
		)
		(fill yes)
		(layer "In4.Cu")
		(net "P5E_PEX0_STN4_TX_DP<70>")
	)
	(gr_poly
		(pts
			(arc
				(start 81.703164 -310.149748)
				(mid 81.296764 -310.149748)
				(end 81.703164 -310.149748)
			)
		)
		(stroke
			(width 0)
			(type solid)
		)
		(fill yes)
		(layer "In4.Cu")
		(net "P5E_PEX0_STN4_RX_DP<70>")
	)
	(gr_poly
		(pts
			(arc
				(start 81.703164 -308.249828)
				(mid 81.296764 -308.249828)
				(end 81.703164 -308.249828)
			)
		)
		(stroke
			(width 0)
			(type solid)
		)
		(fill yes)
		(layer "In4.Cu")
		(net "P5E_PEX0_STN4_RX_DP<68>")
	)
	(gr_poly
		(pts
			(arc
				(start 81.703164 -306.349908)
				(mid 81.296764 -306.349908)
				(end 81.703164 -306.349908)
			)
		)
		(stroke
			(width 0)
			(type solid)
		)
		(fill yes)
		(layer "In4.Cu")
		(net "P5E_PEX0_STN4_RX_DP<66>")
	)
	(gr_poly
		(pts
			(arc
				(start 81.703164 -304.449734)
				(mid 81.296764 -304.449734)
				(end 81.703164 -304.449734)
			)
		)
		(stroke
			(width 0)
			(type solid)
		)
		(fill yes)
		(layer "In4.Cu")
		(net "P5E_PEX0_STN4_RX_DP<64>")
	)
	(gr_poly
		(pts
			(arc
				(start 81.703164 -287.349946)
				(mid 81.296764 -287.349946)
				(end 81.703164 -287.349946)
			)
		)
		(stroke
			(width 0)
			(type solid)
		)
		(fill yes)
		(layer "In4.Cu")
		(net "P5E_PEX0_STN0_RX_DP<1>")
	)
	(gr_poly
		(pts
			(arc
				(start 81.703164 -285.449772)
				(mid 81.296764 -285.449772)
				(end 81.703164 -285.449772)
			)
		)
		(stroke
			(width 0)
			(type solid)
		)
		(fill yes)
		(layer "In4.Cu")
		(net "P5E_PEX0_STN0_RX_DP<3>")
	)
	(gr_poly
		(pts
			(arc
				(start 81.703164 -283.549852)
				(mid 81.296764 -283.549852)
				(end 81.703164 -283.549852)
			)
		)
		(stroke
			(width 0)
			(type solid)
		)
		(fill yes)
		(layer "In4.Cu")
		(net "P5E_PEX0_STN0_RX_DP<5>")
	)
	(gr_poly
		(pts
			(arc
				(start 81.703164 -281.649932)
				(mid 81.296764 -281.649932)
				(end 81.703164 -281.649932)
			)
		)
		(stroke
			(width 0)
			(type solid)
		)
		(fill yes)
		(layer "In4.Cu")
		(net "P5E_PEX0_STN0_RX_DP<7>")
	)
	(gr_poly
		(pts
			(arc
				(start 81.703164 -279.749758)
				(mid 81.296764 -279.749758)
				(end 81.703164 -279.749758)
			)
		)
		(stroke
			(width 0)
			(type solid)
		)
		(fill yes)
		(layer "In4.Cu")
		(net "P5E_PEX0_STN0_TX_DP<7>")
	)
	(gr_poly
		(pts
			(arc
				(start 81.703164 -276.899878)
				(mid 81.296764 -276.899878)
				(end 81.703164 -276.899878)
			)
		)
		(stroke
			(width 0)
			(type solid)
		)
		(fill yes)
		(layer "In4.Cu")
		(net "P5E_PEX0_STN0_TX_DP<8>")
	)
	(gr_poly
		(pts
			(arc
				(start 81.703164 -274.999704)
				(mid 81.296764 -274.999704)
				(end 81.703164 -274.999704)
			)
		)
		(stroke
			(width 0)
			(type solid)
		)
		(fill yes)
		(layer "In4.Cu")
		(net "P5E_PEX0_STN0_RX_DP<8>")
	)
	(gr_poly
		(pts
			(arc
				(start 82.653124 -316.799722)
				(mid 82.246724 -316.799722)
				(end 82.653124 -316.799722)
			)
		)
		(stroke
			(width 0)
			(type solid)
		)
		(fill yes)
		(layer "In4.Cu")
		(net "P5E_PEX0_STN4_RX_DN<71>")
	)
	(gr_poly
		(pts
			(arc
				(start 82.653124 -314.899802)
				(mid 82.246724 -314.899802)
				(end 82.653124 -314.899802)
			)
		)
		(stroke
			(width 0)
			(type solid)
		)
		(fill yes)
		(layer "In4.Cu")
		(net "P5E_PEX0_STN4_TX_DN<71>")
	)
	(gr_poly
		(pts
			(arc
				(start 82.653124 -312.049922)
				(mid 82.246724 -312.049922)
				(end 82.653124 -312.049922)
			)
		)
		(stroke
			(width 0)
			(type solid)
		)
		(fill yes)
		(layer "In4.Cu")
		(net "P5E_PEX0_STN4_TX_DN<70>")
	)
	(gr_poly
		(pts
			(arc
				(start 82.653124 -310.149748)
				(mid 82.246724 -310.149748)
				(end 82.653124 -310.149748)
			)
		)
		(stroke
			(width 0)
			(type solid)
		)
		(fill yes)
		(layer "In4.Cu")
		(net "P5E_PEX0_STN4_RX_DN<70>")
	)
	(gr_poly
		(pts
			(arc
				(start 82.653124 -308.249828)
				(mid 82.246724 -308.249828)
				(end 82.653124 -308.249828)
			)
		)
		(stroke
			(width 0)
			(type solid)
		)
		(fill yes)
		(layer "In4.Cu")
		(net "P5E_PEX0_STN4_RX_DN<68>")
	)
	(gr_poly
		(pts
			(arc
				(start 82.653124 -306.349908)
				(mid 82.246724 -306.349908)
				(end 82.653124 -306.349908)
			)
		)
		(stroke
			(width 0)
			(type solid)
		)
		(fill yes)
		(layer "In4.Cu")
		(net "P5E_PEX0_STN4_RX_DN<66>")
	)
	(gr_poly
		(pts
			(arc
				(start 82.653124 -304.449734)
				(mid 82.246724 -304.449734)
				(end 82.653124 -304.449734)
			)
		)
		(stroke
			(width 0)
			(type solid)
		)
		(fill yes)
		(layer "In4.Cu")
		(net "P5E_PEX0_STN4_RX_DN<64>")
	)
	(gr_poly
		(pts
			(arc
				(start 82.653124 -287.349946)
				(mid 82.246724 -287.349946)
				(end 82.653124 -287.349946)
			)
		)
		(stroke
			(width 0)
			(type solid)
		)
		(fill yes)
		(layer "In4.Cu")
		(net "P5E_PEX0_STN0_RX_DN<1>")
	)
	(gr_poly
		(pts
			(arc
				(start 82.653124 -285.449772)
				(mid 82.246724 -285.449772)
				(end 82.653124 -285.449772)
			)
		)
		(stroke
			(width 0)
			(type solid)
		)
		(fill yes)
		(layer "In4.Cu")
		(net "P5E_PEX0_STN0_RX_DN<3>")
	)
	(gr_poly
		(pts
			(arc
				(start 82.653124 -283.549852)
				(mid 82.246724 -283.549852)
				(end 82.653124 -283.549852)
			)
		)
		(stroke
			(width 0)
			(type solid)
		)
		(fill yes)
		(layer "In4.Cu")
		(net "P5E_PEX0_STN0_RX_DN<5>")
	)
	(gr_poly
		(pts
			(arc
				(start 82.653124 -281.649932)
				(mid 82.246724 -281.649932)
				(end 82.653124 -281.649932)
			)
		)
		(stroke
			(width 0)
			(type solid)
		)
		(fill yes)
		(layer "In4.Cu")
		(net "P5E_PEX0_STN0_RX_DN<7>")
	)
	(gr_poly
		(pts
			(arc
				(start 82.653124 -279.749758)
				(mid 82.246724 -279.749758)
				(end 82.653124 -279.749758)
			)
		)
		(stroke
			(width 0)
			(type solid)
		)
		(fill yes)
		(layer "In4.Cu")
		(net "P5E_PEX0_STN0_TX_DN<7>")
	)
	(gr_poly
		(pts
			(arc
				(start 82.653124 -276.899878)
				(mid 82.246724 -276.899878)
				(end 82.653124 -276.899878)
			)
		)
		(stroke
			(width 0)
			(type solid)
		)
		(fill yes)
		(layer "In4.Cu")
		(net "P5E_PEX0_STN0_TX_DN<8>")
	)
	(gr_poly
		(pts
			(arc
				(start 82.653124 -274.999704)
				(mid 82.246724 -274.999704)
				(end 82.653124 -274.999704)
			)
		)
		(stroke
			(width 0)
			(type solid)
		)
		(fill yes)
		(layer "In4.Cu")
		(net "P5E_PEX0_STN0_RX_DN<8>")
	)
	(gr_poly
		(pts
			(arc
				(start 153.15311 -316.799722)
				(mid 152.74671 -316.799722)
				(end 153.15311 -316.799722)
			)
		)
		(stroke
			(width 0)
			(type solid)
		)
		(fill yes)
		(layer "In4.Cu")
		(net "P5E_PEX1_STN7_RX_DN<122>")
	)
	(gr_poly
		(pts
			(arc
				(start 153.15311 -314.899802)
				(mid 152.74671 -314.899802)
				(end 153.15311 -314.899802)
			)
		)
		(stroke
			(width 0)
			(type solid)
		)
		(fill yes)
		(layer "In4.Cu")
		(net "P5E_PEX1_STN7_TX_DN<122>")
	)
	(gr_poly
		(pts
			(arc
				(start 153.15311 -312.049922)
				(mid 152.74671 -312.049922)
				(end 153.15311 -312.049922)
			)
		)
		(stroke
			(width 0)
			(type solid)
		)
		(fill yes)
		(layer "In4.Cu")
		(net "P5E_PEX1_STN7_TX_DN<121>")
	)
	(gr_poly
		(pts
			(arc
				(start 153.15311 -310.149748)
				(mid 152.74671 -310.149748)
				(end 153.15311 -310.149748)
			)
		)
		(stroke
			(width 0)
			(type solid)
		)
		(fill yes)
		(layer "In4.Cu")
		(net "P5E_PEX1_STN7_RX_DN<121>")
	)
	(gr_poly
		(pts
			(arc
				(start 153.15311 -308.249828)
				(mid 152.74671 -308.249828)
				(end 153.15311 -308.249828)
			)
		)
		(stroke
			(width 0)
			(type solid)
		)
		(fill yes)
		(layer "In4.Cu")
		(net "P5E_PEX1_STN7_RX_DN<119>")
	)
	(gr_poly
		(pts
			(arc
				(start 153.15311 -306.349908)
				(mid 152.74671 -306.349908)
				(end 153.15311 -306.349908)
			)
		)
		(stroke
			(width 0)
			(type solid)
		)
		(fill yes)
		(layer "In4.Cu")
		(net "P5E_PEX1_STN7_RX_DN<117>")
	)
	(gr_poly
		(pts
			(arc
				(start 153.15311 -304.449734)
				(mid 152.74671 -304.449734)
				(end 153.15311 -304.449734)
			)
		)
		(stroke
			(width 0)
			(type solid)
		)
		(fill yes)
		(layer "In4.Cu")
		(net "P5E_PEX1_STN7_RX_DN<115>")
	)
	(gr_poly
		(pts
			(arc
				(start 153.15311 -302.549814)
				(mid 152.74671 -302.549814)
				(end 153.15311 -302.549814)
			)
		)
		(stroke
			(width 0)
			(type solid)
		)
		(fill yes)
		(layer "In4.Cu")
		(net "P5E_PEX1_STN7_RX_DN<113>")
	)
	(gr_poly
		(pts
			(arc
				(start 154.10307 -316.799722)
				(mid 153.69667 -316.799722)
				(end 154.10307 -316.799722)
			)
		)
		(stroke
			(width 0)
			(type solid)
		)
		(fill yes)
		(layer "In4.Cu")
		(net "P5E_PEX1_STN7_RX_DP<122>")
	)
	(gr_poly
		(pts
			(arc
				(start 154.10307 -314.899802)
				(mid 153.69667 -314.899802)
				(end 154.10307 -314.899802)
			)
		)
		(stroke
			(width 0)
			(type solid)
		)
		(fill yes)
		(layer "In4.Cu")
		(net "P5E_PEX1_STN7_TX_DP<122>")
	)
	(gr_poly
		(pts
			(arc
				(start 154.10307 -312.049922)
				(mid 153.69667 -312.049922)
				(end 154.10307 -312.049922)
			)
		)
		(stroke
			(width 0)
			(type solid)
		)
		(fill yes)
		(layer "In4.Cu")
		(net "P5E_PEX1_STN7_TX_DP<121>")
	)
	(gr_poly
		(pts
			(arc
				(start 154.10307 -310.149748)
				(mid 153.69667 -310.149748)
				(end 154.10307 -310.149748)
			)
		)
		(stroke
			(width 0)
			(type solid)
		)
		(fill yes)
		(layer "In4.Cu")
		(net "P5E_PEX1_STN7_RX_DP<121>")
	)
	(gr_poly
		(pts
			(arc
				(start 154.10307 -308.249828)
				(mid 153.69667 -308.249828)
				(end 154.10307 -308.249828)
			)
		)
		(stroke
			(width 0)
			(type solid)
		)
		(fill yes)
		(layer "In4.Cu")
		(net "P5E_PEX1_STN7_RX_DP<119>")
	)
	(gr_poly
		(pts
			(arc
				(start 154.10307 -306.349908)
				(mid 153.69667 -306.349908)
				(end 154.10307 -306.349908)
			)
		)
		(stroke
			(width 0)
			(type solid)
		)
		(fill yes)
		(layer "In4.Cu")
		(net "P5E_PEX1_STN7_RX_DP<117>")
	)
	(gr_poly
		(pts
			(arc
				(start 154.10307 -304.449734)
				(mid 153.69667 -304.449734)
				(end 154.10307 -304.449734)
			)
		)
		(stroke
			(width 0)
			(type solid)
		)
		(fill yes)
		(layer "In4.Cu")
		(net "P5E_PEX1_STN7_RX_DP<115>")
	)
	(gr_poly
		(pts
			(arc
				(start 154.10307 -302.549814)
				(mid 153.69667 -302.549814)
				(end 154.10307 -302.549814)
			)
		)
		(stroke
			(width 0)
			(type solid)
		)
		(fill yes)
		(layer "In4.Cu")
		(net "P5E_PEX1_STN7_RX_DP<113>")
	)
	(gr_poly
		(pts
			(arc
				(start 155.053284 -318.699896)
				(mid 154.646884 -318.699896)
				(end 155.053284 -318.699896)
			)
		)
		(stroke
			(width 0)
			(type solid)
		)
		(fill yes)
		(layer "In4.Cu")
		(net "P5E_PEX1_STN7_RX_DN<123>")
	)
	(gr_poly
		(pts
			(arc
				(start 155.053284 -317.749936)
				(mid 154.646884 -317.749936)
				(end 155.053284 -317.749936)
			)
		)
		(stroke
			(width 0)
			(type solid)
		)
		(fill yes)
		(layer "In4.Cu")
		(net "P5E_PEX1_STN7_RX_DP<123>")
	)
	(gr_poly
		(pts
			(arc
				(start 155.053284 -313.949842)
				(mid 154.646884 -313.949842)
				(end 155.053284 -313.949842)
			)
		)
		(stroke
			(width 0)
			(type solid)
		)
		(fill yes)
		(layer "In4.Cu")
		(net "P5E_PEX1_STN7_TX_DN<123>")
	)
	(gr_poly
		(pts
			(arc
				(start 155.053284 -312.999882)
				(mid 154.646884 -312.999882)
				(end 155.053284 -312.999882)
			)
		)
		(stroke
			(width 0)
			(type solid)
		)
		(fill yes)
		(layer "In4.Cu")
		(net "P5E_PEX1_STN7_TX_DP<123>")
	)
	(gr_poly
		(pts
			(arc
				(start 155.053284 -309.199788)
				(mid 154.646884 -309.199788)
				(end 155.053284 -309.199788)
			)
		)
		(stroke
			(width 0)
			(type solid)
		)
		(fill yes)
		(layer "In4.Cu")
		(net "P5E_PEX1_STN7_RX_DN<120>")
	)
	(gr_poly
		(pts
			(arc
				(start 155.053284 -307.299868)
				(mid 154.646884 -307.299868)
				(end 155.053284 -307.299868)
			)
		)
		(stroke
			(width 0)
			(type solid)
		)
		(fill yes)
		(layer "In4.Cu")
		(net "P5E_PEX1_STN7_RX_DN<118>")
	)
	(gr_poly
		(pts
			(arc
				(start 155.053284 -305.399948)
				(mid 154.646884 -305.399948)
				(end 155.053284 -305.399948)
			)
		)
		(stroke
			(width 0)
			(type solid)
		)
		(fill yes)
		(layer "In4.Cu")
		(net "P5E_PEX1_STN7_RX_DN<116>")
	)
	(gr_poly
		(pts
			(arc
				(start 155.053284 -303.499774)
				(mid 154.646884 -303.499774)
				(end 155.053284 -303.499774)
			)
		)
		(stroke
			(width 0)
			(type solid)
		)
		(fill yes)
		(layer "In4.Cu")
		(net "P5E_PEX1_STN7_RX_DN<114>")
	)
	(gr_poly
		(pts
			(arc
				(start 155.053284 -301.599854)
				(mid 154.646884 -301.599854)
				(end 155.053284 -301.599854)
			)
		)
		(stroke
			(width 0)
			(type solid)
		)
		(fill yes)
		(layer "In4.Cu")
		(net "P5E_PEX1_STN7_RX_DN<112>")
	)
	(gr_poly
		(pts
			(arc
				(start 156.003244 -316.799722)
				(mid 155.596844 -316.799722)
				(end 156.003244 -316.799722)
			)
		)
		(stroke
			(width 0)
			(type solid)
		)
		(fill yes)
		(layer "In4.Cu")
		(net "P5E_PEX1_STN7_RX_DN<124>")
	)
	(gr_poly
		(pts
			(arc
				(start 156.003244 -315.849762)
				(mid 155.596844 -315.849762)
				(end 156.003244 -315.849762)
			)
		)
		(stroke
			(width 0)
			(type solid)
		)
		(fill yes)
		(layer "In4.Cu")
		(net "P5E_PEX1_STN7_RX_DP<124>")
	)
	(gr_poly
		(pts
			(arc
				(start 156.003244 -312.049922)
				(mid 155.596844 -312.049922)
				(end 156.003244 -312.049922)
			)
		)
		(stroke
			(width 0)
			(type solid)
		)
		(fill yes)
		(layer "In4.Cu")
		(net "P5E_PEX1_STN7_TX_DN<124>")
	)
	(gr_poly
		(pts
			(arc
				(start 156.003244 -311.099962)
				(mid 155.596844 -311.099962)
				(end 156.003244 -311.099962)
			)
		)
		(stroke
			(width 0)
			(type solid)
		)
		(fill yes)
		(layer "In4.Cu")
		(net "P5E_PEX1_STN7_TX_DP<124>")
	)
	(gr_poly
		(pts
			(arc
				(start 156.003244 -309.199788)
				(mid 155.596844 -309.199788)
				(end 156.003244 -309.199788)
			)
		)
		(stroke
			(width 0)
			(type solid)
		)
		(fill yes)
		(layer "In4.Cu")
		(net "P5E_PEX1_STN7_RX_DP<120>")
	)
	(gr_poly
		(pts
			(arc
				(start 156.003244 -307.299868)
				(mid 155.596844 -307.299868)
				(end 156.003244 -307.299868)
			)
		)
		(stroke
			(width 0)
			(type solid)
		)
		(fill yes)
		(layer "In4.Cu")
		(net "P5E_PEX1_STN7_RX_DP<118>")
	)
	(gr_poly
		(pts
			(arc
				(start 156.003244 -305.399948)
				(mid 155.596844 -305.399948)
				(end 156.003244 -305.399948)
			)
		)
		(stroke
			(width 0)
			(type solid)
		)
		(fill yes)
		(layer "In4.Cu")
		(net "P5E_PEX1_STN7_RX_DP<116>")
	)
	(gr_poly
		(pts
			(arc
				(start 156.003244 -303.499774)
				(mid 155.596844 -303.499774)
				(end 156.003244 -303.499774)
			)
		)
		(stroke
			(width 0)
			(type solid)
		)
		(fill yes)
		(layer "In4.Cu")
		(net "P5E_PEX1_STN7_RX_DP<114>")
	)
	(gr_poly
		(pts
			(arc
				(start 156.003244 -301.599854)
				(mid 155.596844 -301.599854)
				(end 156.003244 -301.599854)
			)
		)
		(stroke
			(width 0)
			(type solid)
		)
		(fill yes)
		(layer "In4.Cu")
		(net "P5E_PEX1_STN7_RX_DP<112>")
	)
	(gr_poly
		(pts
			(arc
				(start 156.953204 -318.699896)
				(mid 156.546804 -318.699896)
				(end 156.953204 -318.699896)
			)
		)
		(stroke
			(width 0)
			(type solid)
		)
		(fill yes)
		(layer "In4.Cu")
		(net "P5E_PEX1_STN7_RX_DN<125>")
	)
	(gr_poly
		(pts
			(arc
				(start 156.953204 -317.749936)
				(mid 156.546804 -317.749936)
				(end 156.953204 -317.749936)
			)
		)
		(stroke
			(width 0)
			(type solid)
		)
		(fill yes)
		(layer "In4.Cu")
		(net "P5E_PEX1_STN7_RX_DP<125>")
	)
	(gr_poly
		(pts
			(arc
				(start 156.953204 -313.949842)
				(mid 156.546804 -313.949842)
				(end 156.953204 -313.949842)
			)
		)
		(stroke
			(width 0)
			(type solid)
		)
		(fill yes)
		(layer "In4.Cu")
		(net "P5E_PEX1_STN7_TX_DN<125>")
	)
	(gr_poly
		(pts
			(arc
				(start 156.953204 -312.999882)
				(mid 156.546804 -312.999882)
				(end 156.953204 -312.999882)
			)
		)
		(stroke
			(width 0)
			(type solid)
		)
		(fill yes)
		(layer "In4.Cu")
		(net "P5E_PEX1_STN7_TX_DP<125>")
	)
	(gr_poly
		(pts
			(arc
				(start 157.903164 -316.799722)
				(mid 157.496764 -316.799722)
				(end 157.903164 -316.799722)
			)
		)
		(stroke
			(width 0)
			(type solid)
		)
		(fill yes)
		(layer "In4.Cu")
		(net "P5E_PEX1_STN7_RX_DN<126>")
	)
	(gr_poly
		(pts
			(arc
				(start 157.903164 -315.849762)
				(mid 157.496764 -315.849762)
				(end 157.903164 -315.849762)
			)
		)
		(stroke
			(width 0)
			(type solid)
		)
		(fill yes)
		(layer "In4.Cu")
		(net "P5E_PEX1_STN7_RX_DP<126>")
	)
	(gr_poly
		(pts
			(arc
				(start 157.903164 -312.049922)
				(mid 157.496764 -312.049922)
				(end 157.903164 -312.049922)
			)
		)
		(stroke
			(width 0)
			(type solid)
		)
		(fill yes)
		(layer "In4.Cu")
		(net "P5E_PEX1_STN7_TX_DN<126>")
	)
	(gr_poly
		(pts
			(arc
				(start 157.903164 -311.099962)
				(mid 157.496764 -311.099962)
				(end 157.903164 -311.099962)
			)
		)
		(stroke
			(width 0)
			(type solid)
		)
		(fill yes)
		(layer "In4.Cu")
		(net "P5E_PEX1_STN7_TX_DP<126>")
	)
	(gr_poly
		(pts
			(arc
				(start 157.903164 -309.199788)
				(mid 157.496764 -309.199788)
				(end 157.903164 -309.199788)
			)
		)
		(stroke
			(width 0)
			(type solid)
		)
		(fill yes)
		(layer "In4.Cu")
		(net "P5E_PEX1_STN7_TX_DN<120>")
	)
	(gr_poly
		(pts
			(arc
				(start 157.903164 -307.299868)
				(mid 157.496764 -307.299868)
				(end 157.903164 -307.299868)
			)
		)
		(stroke
			(width 0)
			(type solid)
		)
		(fill yes)
		(layer "In4.Cu")
		(net "P5E_PEX1_STN7_TX_DN<118>")
	)
	(gr_poly
		(pts
			(arc
				(start 157.903164 -305.399948)
				(mid 157.496764 -305.399948)
				(end 157.903164 -305.399948)
			)
		)
		(stroke
			(width 0)
			(type solid)
		)
		(fill yes)
		(layer "In4.Cu")
		(net "P5E_PEX1_STN7_TX_DN<116>")
	)
	(gr_poly
		(pts
			(arc
				(start 157.903164 -303.499774)
				(mid 157.496764 -303.499774)
				(end 157.903164 -303.499774)
			)
		)
		(stroke
			(width 0)
			(type solid)
		)
		(fill yes)
		(layer "In4.Cu")
		(net "P5E_PEX1_STN7_TX_DN<114>")
	)
	(gr_poly
		(pts
			(arc
				(start 157.903164 -301.599854)
				(mid 157.496764 -301.599854)
				(end 157.903164 -301.599854)
			)
		)
		(stroke
			(width 0)
			(type solid)
		)
		(fill yes)
		(layer "In4.Cu")
		(net "P5E_PEX1_STN7_TX_DN<112>")
	)
	(gr_poly
		(pts
			(arc
				(start 158.853124 -318.699896)
				(mid 158.446724 -318.699896)
				(end 158.853124 -318.699896)
			)
		)
		(stroke
			(width 0)
			(type solid)
		)
		(fill yes)
		(layer "In4.Cu")
		(net "P5E_PEX1_STN7_RX_DN<127>")
	)
	(gr_poly
		(pts
			(arc
				(start 158.853124 -317.749936)
				(mid 158.446724 -317.749936)
				(end 158.853124 -317.749936)
			)
		)
		(stroke
			(width 0)
			(type solid)
		)
		(fill yes)
		(layer "In4.Cu")
		(net "P5E_PEX1_STN7_RX_DP<127>")
	)
	(gr_poly
		(pts
			(arc
				(start 158.853124 -313.949842)
				(mid 158.446724 -313.949842)
				(end 158.853124 -313.949842)
			)
		)
		(stroke
			(width 0)
			(type solid)
		)
		(fill yes)
		(layer "In4.Cu")
		(net "P5E_PEX1_STN7_TX_DN<127>")
	)
	(gr_poly
		(pts
			(arc
				(start 158.853124 -312.999882)
				(mid 158.446724 -312.999882)
				(end 158.853124 -312.999882)
			)
		)
		(stroke
			(width 0)
			(type solid)
		)
		(fill yes)
		(layer "In4.Cu")
		(net "P5E_PEX1_STN7_TX_DP<127>")
	)
	(gr_poly
		(pts
			(arc
				(start 158.853124 -309.199788)
				(mid 158.446724 -309.199788)
				(end 158.853124 -309.199788)
			)
		)
		(stroke
			(width 0)
			(type solid)
		)
		(fill yes)
		(layer "In4.Cu")
		(net "P5E_PEX1_STN7_TX_DP<120>")
	)
	(gr_poly
		(pts
			(arc
				(start 158.853124 -307.299868)
				(mid 158.446724 -307.299868)
				(end 158.853124 -307.299868)
			)
		)
		(stroke
			(width 0)
			(type solid)
		)
		(fill yes)
		(layer "In4.Cu")
		(net "P5E_PEX1_STN7_TX_DP<118>")
	)
	(gr_poly
		(pts
			(arc
				(start 158.853124 -305.399948)
				(mid 158.446724 -305.399948)
				(end 158.853124 -305.399948)
			)
		)
		(stroke
			(width 0)
			(type solid)
		)
		(fill yes)
		(layer "In4.Cu")
		(net "P5E_PEX1_STN7_TX_DP<116>")
	)
	(gr_poly
		(pts
			(arc
				(start 158.853124 -303.499774)
				(mid 158.446724 -303.499774)
				(end 158.853124 -303.499774)
			)
		)
		(stroke
			(width 0)
			(type solid)
		)
		(fill yes)
		(layer "In4.Cu")
		(net "P5E_PEX1_STN7_TX_DP<114>")
	)
	(gr_poly
		(pts
			(arc
				(start 158.853124 -301.599854)
				(mid 158.446724 -301.599854)
				(end 158.853124 -301.599854)
			)
		)
		(stroke
			(width 0)
			(type solid)
		)
		(fill yes)
		(layer "In4.Cu")
		(net "P5E_PEX1_STN7_TX_DP<112>")
	)
	(gr_poly
		(pts
			(arc
				(start 159.803084 -316.799722)
				(mid 159.396684 -316.799722)
				(end 159.803084 -316.799722)
			)
		)
		(stroke
			(width 0)
			(type solid)
		)
		(fill yes)
		(layer "In4.Cu")
		(net "P5E_PEX1_STN6_RX_DN<111>")
	)
	(gr_poly
		(pts
			(arc
				(start 159.803084 -315.849762)
				(mid 159.396684 -315.849762)
				(end 159.803084 -315.849762)
			)
		)
		(stroke
			(width 0)
			(type solid)
		)
		(fill yes)
		(layer "In4.Cu")
		(net "P5E_PEX1_STN6_RX_DP<111>")
	)
	(gr_poly
		(pts
			(arc
				(start 159.803084 -312.049922)
				(mid 159.396684 -312.049922)
				(end 159.803084 -312.049922)
			)
		)
		(stroke
			(width 0)
			(type solid)
		)
		(fill yes)
		(layer "In4.Cu")
		(net "P5E_PEX1_STN6_TX_DN<111>")
	)
	(gr_poly
		(pts
			(arc
				(start 159.803084 -311.099962)
				(mid 159.396684 -311.099962)
				(end 159.803084 -311.099962)
			)
		)
		(stroke
			(width 0)
			(type solid)
		)
		(fill yes)
		(layer "In4.Cu")
		(net "P5E_PEX1_STN6_TX_DP<111>")
	)
	(gr_poly
		(pts
			(arc
				(start 159.803084 -308.249828)
				(mid 159.396684 -308.249828)
				(end 159.803084 -308.249828)
			)
		)
		(stroke
			(width 0)
			(type solid)
		)
		(fill yes)
		(layer "In4.Cu")
		(net "P5E_PEX1_STN7_TX_DN<119>")
	)
	(gr_poly
		(pts
			(arc
				(start 159.803084 -306.349908)
				(mid 159.396684 -306.349908)
				(end 159.803084 -306.349908)
			)
		)
		(stroke
			(width 0)
			(type solid)
		)
		(fill yes)
		(layer "In4.Cu")
		(net "P5E_PEX1_STN7_TX_DN<117>")
	)
	(gr_poly
		(pts
			(arc
				(start 159.803084 -304.449734)
				(mid 159.396684 -304.449734)
				(end 159.803084 -304.449734)
			)
		)
		(stroke
			(width 0)
			(type solid)
		)
		(fill yes)
		(layer "In4.Cu")
		(net "P5E_PEX1_STN7_TX_DN<115>")
	)
	(gr_poly
		(pts
			(arc
				(start 159.803084 -302.549814)
				(mid 159.396684 -302.549814)
				(end 159.803084 -302.549814)
			)
		)
		(stroke
			(width 0)
			(type solid)
		)
		(fill yes)
		(layer "In4.Cu")
		(net "P5E_PEX1_STN7_TX_DN<113>")
	)
	(gr_poly
		(pts
			(arc
				(start 160.753044 -318.699896)
				(mid 160.346644 -318.699896)
				(end 160.753044 -318.699896)
			)
		)
		(stroke
			(width 0)
			(type solid)
		)
		(fill yes)
		(layer "In4.Cu")
		(net "P5E_PEX1_STN6_RX_DN<110>")
	)
	(gr_poly
		(pts
			(arc
				(start 160.753044 -317.749936)
				(mid 160.346644 -317.749936)
				(end 160.753044 -317.749936)
			)
		)
		(stroke
			(width 0)
			(type solid)
		)
		(fill yes)
		(layer "In4.Cu")
		(net "P5E_PEX1_STN6_RX_DP<110>")
	)
	(gr_poly
		(pts
			(arc
				(start 160.753044 -313.949842)
				(mid 160.346644 -313.949842)
				(end 160.753044 -313.949842)
			)
		)
		(stroke
			(width 0)
			(type solid)
		)
		(fill yes)
		(layer "In4.Cu")
		(net "P5E_PEX1_STN6_TX_DN<110>")
	)
	(gr_poly
		(pts
			(arc
				(start 160.753044 -312.999882)
				(mid 160.346644 -312.999882)
				(end 160.753044 -312.999882)
			)
		)
		(stroke
			(width 0)
			(type solid)
		)
		(fill yes)
		(layer "In4.Cu")
		(net "P5E_PEX1_STN6_TX_DP<110>")
	)
	(gr_poly
		(pts
			(arc
				(start 160.753044 -308.249828)
				(mid 160.346644 -308.249828)
				(end 160.753044 -308.249828)
			)
		)
		(stroke
			(width 0)
			(type solid)
		)
		(fill yes)
		(layer "In4.Cu")
		(net "P5E_PEX1_STN7_TX_DP<119>")
	)
	(gr_poly
		(pts
			(arc
				(start 160.753044 -306.349908)
				(mid 160.346644 -306.349908)
				(end 160.753044 -306.349908)
			)
		)
		(stroke
			(width 0)
			(type solid)
		)
		(fill yes)
		(layer "In4.Cu")
		(net "P5E_PEX1_STN7_TX_DP<117>")
	)
	(gr_poly
		(pts
			(arc
				(start 160.753044 -304.449734)
				(mid 160.346644 -304.449734)
				(end 160.753044 -304.449734)
			)
		)
		(stroke
			(width 0)
			(type solid)
		)
		(fill yes)
		(layer "In4.Cu")
		(net "P5E_PEX1_STN7_TX_DP<115>")
	)
	(gr_poly
		(pts
			(arc
				(start 160.753044 -302.549814)
				(mid 160.346644 -302.549814)
				(end 160.753044 -302.549814)
			)
		)
		(stroke
			(width 0)
			(type solid)
		)
		(fill yes)
		(layer "In4.Cu")
		(net "P5E_PEX1_STN7_TX_DP<113>")
	)
	(gr_poly
		(pts
			(arc
				(start 160.753044 -278.799798)
				(mid 160.346644 -278.799798)
				(end 160.753044 -278.799798)
			)
		)
		(stroke
			(width 0)
			(type solid)
		)
		(fill yes)
		(layer "In4.Cu")
		(net "P5E_PEX1_STN2_TX_DP<47>")
	)
	(gr_poly
		(pts
			(arc
				(start 160.753044 -277.849838)
				(mid 160.346644 -277.849838)
				(end 160.753044 -277.849838)
			)
		)
		(stroke
			(width 0)
			(type solid)
		)
		(fill yes)
		(layer "In4.Cu")
		(net "P5E_PEX1_STN2_TX_DN<47>")
	)
	(gr_poly
		(pts
			(arc
				(start 160.753044 -274.049744)
				(mid 160.346644 -274.049744)
				(end 160.753044 -274.049744)
			)
		)
		(stroke
			(width 0)
			(type solid)
		)
		(fill yes)
		(layer "In4.Cu")
		(net "P5E_PEX1_STN2_RX_DP<47>")
	)
	(gr_poly
		(pts
			(arc
				(start 160.753044 -273.099784)
				(mid 160.346644 -273.099784)
				(end 160.753044 -273.099784)
			)
		)
		(stroke
			(width 0)
			(type solid)
		)
		(fill yes)
		(layer "In4.Cu")
		(net "P5E_PEX1_STN2_RX_DN<47>")
	)
	(gr_poly
		(pts
			(arc
				(start 161.703258 -316.799722)
				(mid 161.296858 -316.799722)
				(end 161.703258 -316.799722)
			)
		)
		(stroke
			(width 0)
			(type solid)
		)
		(fill yes)
		(layer "In4.Cu")
		(net "P5E_PEX1_STN6_RX_DN<109>")
	)
	(gr_poly
		(pts
			(arc
				(start 161.703258 -315.849762)
				(mid 161.296858 -315.849762)
				(end 161.703258 -315.849762)
			)
		)
		(stroke
			(width 0)
			(type solid)
		)
		(fill yes)
		(layer "In4.Cu")
		(net "P5E_PEX1_STN6_RX_DP<109>")
	)
	(gr_poly
		(pts
			(arc
				(start 161.703258 -312.049922)
				(mid 161.296858 -312.049922)
				(end 161.703258 -312.049922)
			)
		)
		(stroke
			(width 0)
			(type solid)
		)
		(fill yes)
		(layer "In4.Cu")
		(net "P5E_PEX1_STN6_TX_DN<109>")
	)
	(gr_poly
		(pts
			(arc
				(start 161.703258 -311.099962)
				(mid 161.296858 -311.099962)
				(end 161.703258 -311.099962)
			)
		)
		(stroke
			(width 0)
			(type solid)
		)
		(fill yes)
		(layer "In4.Cu")
		(net "P5E_PEX1_STN6_TX_DP<109>")
	)
	(gr_poly
		(pts
			(arc
				(start 161.703258 -280.699718)
				(mid 161.296858 -280.699718)
				(end 161.703258 -280.699718)
			)
		)
		(stroke
			(width 0)
			(type solid)
		)
		(fill yes)
		(layer "In4.Cu")
		(net "P5E_PEX1_STN2_TX_DP<46>")
	)
	(gr_poly
		(pts
			(arc
				(start 161.703258 -279.749504)
				(mid 161.296858 -279.749504)
				(end 161.703258 -279.749504)
			)
		)
		(stroke
			(width 0)
			(type solid)
		)
		(fill yes)
		(layer "In4.Cu")
		(net "P5E_PEX1_STN2_TX_DN<46>")
	)
	(gr_poly
		(pts
			(arc
				(start 161.703258 -275.949918)
				(mid 161.296858 -275.949918)
				(end 161.703258 -275.949918)
			)
		)
		(stroke
			(width 0)
			(type solid)
		)
		(fill yes)
		(layer "In4.Cu")
		(net "P5E_PEX1_STN2_RX_DP<46>")
	)
	(gr_poly
		(pts
			(arc
				(start 161.703258 -274.999958)
				(mid 161.296858 -274.999958)
				(end 161.703258 -274.999958)
			)
		)
		(stroke
			(width 0)
			(type solid)
		)
		(fill yes)
		(layer "In4.Cu")
		(net "P5E_PEX1_STN2_RX_DN<46>")
	)
	(gr_poly
		(pts
			(arc
				(start 162.653218 -318.699896)
				(mid 162.246818 -318.699896)
				(end 162.653218 -318.699896)
			)
		)
		(stroke
			(width 0)
			(type solid)
		)
		(fill yes)
		(layer "In4.Cu")
		(net "P5E_PEX1_STN6_RX_DN<108>")
	)
	(gr_poly
		(pts
			(arc
				(start 162.653218 -317.749936)
				(mid 162.246818 -317.749936)
				(end 162.653218 -317.749936)
			)
		)
		(stroke
			(width 0)
			(type solid)
		)
		(fill yes)
		(layer "In4.Cu")
		(net "P5E_PEX1_STN6_RX_DP<108>")
	)
	(gr_poly
		(pts
			(arc
				(start 162.653218 -313.949842)
				(mid 162.246818 -313.949842)
				(end 162.653218 -313.949842)
			)
		)
		(stroke
			(width 0)
			(type solid)
		)
		(fill yes)
		(layer "In4.Cu")
		(net "P5E_PEX1_STN6_TX_DN<108>")
	)
	(gr_poly
		(pts
			(arc
				(start 162.653218 -312.999882)
				(mid 162.246818 -312.999882)
				(end 162.653218 -312.999882)
			)
		)
		(stroke
			(width 0)
			(type solid)
		)
		(fill yes)
		(layer "In4.Cu")
		(net "P5E_PEX1_STN6_TX_DP<108>")
	)
	(gr_poly
		(pts
			(arc
				(start 162.653218 -278.799798)
				(mid 162.246818 -278.799798)
				(end 162.653218 -278.799798)
			)
		)
		(stroke
			(width 0)
			(type solid)
		)
		(fill yes)
		(layer "In4.Cu")
		(net "P5E_PEX1_STN2_TX_DP<45>")
	)
	(gr_poly
		(pts
			(arc
				(start 162.653218 -277.849838)
				(mid 162.246818 -277.849838)
				(end 162.653218 -277.849838)
			)
		)
		(stroke
			(width 0)
			(type solid)
		)
		(fill yes)
		(layer "In4.Cu")
		(net "P5E_PEX1_STN2_TX_DN<45>")
	)
	(gr_poly
		(pts
			(arc
				(start 162.653218 -274.049744)
				(mid 162.246818 -274.049744)
				(end 162.653218 -274.049744)
			)
		)
		(stroke
			(width 0)
			(type solid)
		)
		(fill yes)
		(layer "In4.Cu")
		(net "P5E_PEX1_STN2_RX_DP<45>")
	)
	(gr_poly
		(pts
			(arc
				(start 162.653218 -273.099784)
				(mid 162.246818 -273.099784)
				(end 162.653218 -273.099784)
			)
		)
		(stroke
			(width 0)
			(type solid)
		)
		(fill yes)
		(layer "In4.Cu")
		(net "P5E_PEX1_STN2_RX_DN<45>")
	)
	(gr_poly
		(pts
			(arc
				(start 163.603178 -316.799722)
				(mid 163.196778 -316.799722)
				(end 163.603178 -316.799722)
			)
		)
		(stroke
			(width 0)
			(type solid)
		)
		(fill yes)
		(layer "In4.Cu")
		(net "P5E_PEX1_STN6_RX_DN<107>")
	)
	(gr_poly
		(pts
			(arc
				(start 163.603178 -315.849762)
				(mid 163.196778 -315.849762)
				(end 163.603178 -315.849762)
			)
		)
		(stroke
			(width 0)
			(type solid)
		)
		(fill yes)
		(layer "In4.Cu")
		(net "P5E_PEX1_STN6_RX_DP<107>")
	)
	(gr_poly
		(pts
			(arc
				(start 163.603178 -312.049922)
				(mid 163.196778 -312.049922)
				(end 163.603178 -312.049922)
			)
		)
		(stroke
			(width 0)
			(type solid)
		)
		(fill yes)
		(layer "In4.Cu")
		(net "P5E_PEX1_STN6_TX_DN<107>")
	)
	(gr_poly
		(pts
			(arc
				(start 163.603178 -311.099962)
				(mid 163.196778 -311.099962)
				(end 163.603178 -311.099962)
			)
		)
		(stroke
			(width 0)
			(type solid)
		)
		(fill yes)
		(layer "In4.Cu")
		(net "P5E_PEX1_STN6_TX_DP<107>")
	)
	(gr_poly
		(pts
			(arc
				(start 163.603178 -280.699718)
				(mid 163.196778 -280.699718)
				(end 163.603178 -280.699718)
			)
		)
		(stroke
			(width 0)
			(type solid)
		)
		(fill yes)
		(layer "In4.Cu")
		(net "P5E_PEX1_STN2_TX_DP<44>")
	)
	(gr_poly
		(pts
			(arc
				(start 163.603178 -279.749504)
				(mid 163.196778 -279.749504)
				(end 163.603178 -279.749504)
			)
		)
		(stroke
			(width 0)
			(type solid)
		)
		(fill yes)
		(layer "In4.Cu")
		(net "P5E_PEX1_STN2_TX_DN<44>")
	)
	(gr_poly
		(pts
			(arc
				(start 163.603178 -275.949918)
				(mid 163.196778 -275.949918)
				(end 163.603178 -275.949918)
			)
		)
		(stroke
			(width 0)
			(type solid)
		)
		(fill yes)
		(layer "In4.Cu")
		(net "P5E_PEX1_STN2_RX_DP<44>")
	)
	(gr_poly
		(pts
			(arc
				(start 163.603178 -274.999958)
				(mid 163.196778 -274.999958)
				(end 163.603178 -274.999958)
			)
		)
		(stroke
			(width 0)
			(type solid)
		)
		(fill yes)
		(layer "In4.Cu")
		(net "P5E_PEX1_STN2_RX_DN<44>")
	)
	(gr_poly
		(pts
			(arc
				(start 164.553138 -318.699896)
				(mid 164.146738 -318.699896)
				(end 164.553138 -318.699896)
			)
		)
		(stroke
			(width 0)
			(type solid)
		)
		(fill yes)
		(layer "In4.Cu")
		(net "P5E_PEX1_STN6_RX_DN<106>")
	)
	(gr_poly
		(pts
			(arc
				(start 164.553138 -317.749936)
				(mid 164.146738 -317.749936)
				(end 164.553138 -317.749936)
			)
		)
		(stroke
			(width 0)
			(type solid)
		)
		(fill yes)
		(layer "In4.Cu")
		(net "P5E_PEX1_STN6_RX_DP<106>")
	)
	(gr_poly
		(pts
			(arc
				(start 164.553138 -313.949842)
				(mid 164.146738 -313.949842)
				(end 164.553138 -313.949842)
			)
		)
		(stroke
			(width 0)
			(type solid)
		)
		(fill yes)
		(layer "In4.Cu")
		(net "P5E_PEX1_STN6_TX_DN<106>")
	)
	(gr_poly
		(pts
			(arc
				(start 164.553138 -312.999882)
				(mid 164.146738 -312.999882)
				(end 164.553138 -312.999882)
			)
		)
		(stroke
			(width 0)
			(type solid)
		)
		(fill yes)
		(layer "In4.Cu")
		(net "P5E_PEX1_STN6_TX_DP<106>")
	)
	(gr_poly
		(pts
			(arc
				(start 164.553138 -278.799798)
				(mid 164.146738 -278.799798)
				(end 164.553138 -278.799798)
			)
		)
		(stroke
			(width 0)
			(type solid)
		)
		(fill yes)
		(layer "In4.Cu")
		(net "P5E_PEX1_STN2_TX_DP<43>")
	)
	(gr_poly
		(pts
			(arc
				(start 164.553138 -277.849838)
				(mid 164.146738 -277.849838)
				(end 164.553138 -277.849838)
			)
		)
		(stroke
			(width 0)
			(type solid)
		)
		(fill yes)
		(layer "In4.Cu")
		(net "P5E_PEX1_STN2_TX_DN<43>")
	)
	(gr_poly
		(pts
			(arc
				(start 164.553138 -274.049744)
				(mid 164.146738 -274.049744)
				(end 164.553138 -274.049744)
			)
		)
		(stroke
			(width 0)
			(type solid)
		)
		(fill yes)
		(layer "In4.Cu")
		(net "P5E_PEX1_STN2_RX_DP<43>")
	)
	(gr_poly
		(pts
			(arc
				(start 164.553138 -273.099784)
				(mid 164.146738 -273.099784)
				(end 164.553138 -273.099784)
			)
		)
		(stroke
			(width 0)
			(type solid)
		)
		(fill yes)
		(layer "In4.Cu")
		(net "P5E_PEX1_STN2_RX_DN<43>")
	)
	(gr_poly
		(pts
			(arc
				(start 165.503098 -316.799722)
				(mid 165.096698 -316.799722)
				(end 165.503098 -316.799722)
			)
		)
		(stroke
			(width 0)
			(type solid)
		)
		(fill yes)
		(layer "In4.Cu")
		(net "P5E_PEX1_STN6_RX_DN<105>")
	)
	(gr_poly
		(pts
			(arc
				(start 165.503098 -315.849762)
				(mid 165.096698 -315.849762)
				(end 165.503098 -315.849762)
			)
		)
		(stroke
			(width 0)
			(type solid)
		)
		(fill yes)
		(layer "In4.Cu")
		(net "P5E_PEX1_STN6_RX_DP<105>")
	)
	(gr_poly
		(pts
			(arc
				(start 165.503098 -312.049922)
				(mid 165.096698 -312.049922)
				(end 165.503098 -312.049922)
			)
		)
		(stroke
			(width 0)
			(type solid)
		)
		(fill yes)
		(layer "In4.Cu")
		(net "P5E_PEX1_STN6_TX_DN<105>")
	)
	(gr_poly
		(pts
			(arc
				(start 165.503098 -311.099962)
				(mid 165.096698 -311.099962)
				(end 165.503098 -311.099962)
			)
		)
		(stroke
			(width 0)
			(type solid)
		)
		(fill yes)
		(layer "In4.Cu")
		(net "P5E_PEX1_STN6_TX_DP<105>")
	)
	(gr_poly
		(pts
			(arc
				(start 165.503098 -280.699718)
				(mid 165.096698 -280.699718)
				(end 165.503098 -280.699718)
			)
		)
		(stroke
			(width 0)
			(type solid)
		)
		(fill yes)
		(layer "In4.Cu")
		(net "P5E_PEX1_STN2_TX_DP<42>")
	)
	(gr_poly
		(pts
			(arc
				(start 165.503098 -279.749504)
				(mid 165.096698 -279.749504)
				(end 165.503098 -279.749504)
			)
		)
		(stroke
			(width 0)
			(type solid)
		)
		(fill yes)
		(layer "In4.Cu")
		(net "P5E_PEX1_STN2_TX_DN<42>")
	)
	(gr_poly
		(pts
			(arc
				(start 165.503098 -275.949918)
				(mid 165.096698 -275.949918)
				(end 165.503098 -275.949918)
			)
		)
		(stroke
			(width 0)
			(type solid)
		)
		(fill yes)
		(layer "In4.Cu")
		(net "P5E_PEX1_STN2_RX_DP<42>")
	)
	(gr_poly
		(pts
			(arc
				(start 165.503098 -274.999958)
				(mid 165.096698 -274.999958)
				(end 165.503098 -274.999958)
			)
		)
		(stroke
			(width 0)
			(type solid)
		)
		(fill yes)
		(layer "In4.Cu")
		(net "P5E_PEX1_STN2_RX_DN<42>")
	)
	(gr_poly
		(pts
			(arc
				(start 166.453058 -318.699896)
				(mid 166.046658 -318.699896)
				(end 166.453058 -318.699896)
			)
		)
		(stroke
			(width 0)
			(type solid)
		)
		(fill yes)
		(layer "In4.Cu")
		(net "P5E_PEX1_STN6_RX_DN<104>")
	)
	(gr_poly
		(pts
			(arc
				(start 166.453058 -317.749936)
				(mid 166.046658 -317.749936)
				(end 166.453058 -317.749936)
			)
		)
		(stroke
			(width 0)
			(type solid)
		)
		(fill yes)
		(layer "In4.Cu")
		(net "P5E_PEX1_STN6_RX_DP<104>")
	)
	(gr_poly
		(pts
			(arc
				(start 166.453058 -313.949842)
				(mid 166.046658 -313.949842)
				(end 166.453058 -313.949842)
			)
		)
		(stroke
			(width 0)
			(type solid)
		)
		(fill yes)
		(layer "In4.Cu")
		(net "P5E_PEX1_STN6_TX_DN<104>")
	)
	(gr_poly
		(pts
			(arc
				(start 166.453058 -312.999882)
				(mid 166.046658 -312.999882)
				(end 166.453058 -312.999882)
			)
		)
		(stroke
			(width 0)
			(type solid)
		)
		(fill yes)
		(layer "In4.Cu")
		(net "P5E_PEX1_STN6_TX_DP<104>")
	)
	(gr_poly
		(pts
			(arc
				(start 166.453058 -278.799798)
				(mid 166.046658 -278.799798)
				(end 166.453058 -278.799798)
			)
		)
		(stroke
			(width 0)
			(type solid)
		)
		(fill yes)
		(layer "In4.Cu")
		(net "P5E_PEX1_STN2_TX_DP<41>")
	)
	(gr_poly
		(pts
			(arc
				(start 166.453058 -277.849838)
				(mid 166.046658 -277.849838)
				(end 166.453058 -277.849838)
			)
		)
		(stroke
			(width 0)
			(type solid)
		)
		(fill yes)
		(layer "In4.Cu")
		(net "P5E_PEX1_STN2_TX_DN<41>")
	)
	(gr_poly
		(pts
			(arc
				(start 166.453058 -274.049744)
				(mid 166.046658 -274.049744)
				(end 166.453058 -274.049744)
			)
		)
		(stroke
			(width 0)
			(type solid)
		)
		(fill yes)
		(layer "In4.Cu")
		(net "P5E_PEX1_STN2_RX_DP<41>")
	)
	(gr_poly
		(pts
			(arc
				(start 166.453058 -273.099784)
				(mid 166.046658 -273.099784)
				(end 166.453058 -273.099784)
			)
		)
		(stroke
			(width 0)
			(type solid)
		)
		(fill yes)
		(layer "In4.Cu")
		(net "P5E_PEX1_STN2_RX_DN<41>")
	)
	(gr_poly
		(pts
			(arc
				(start 167.403272 -316.799722)
				(mid 166.996872 -316.799722)
				(end 167.403272 -316.799722)
			)
		)
		(stroke
			(width 0)
			(type solid)
		)
		(fill yes)
		(layer "In4.Cu")
		(net "P5E_PEX1_STN6_RX_DN<103>")
	)
	(gr_poly
		(pts
			(arc
				(start 167.403272 -315.849762)
				(mid 166.996872 -315.849762)
				(end 167.403272 -315.849762)
			)
		)
		(stroke
			(width 0)
			(type solid)
		)
		(fill yes)
		(layer "In4.Cu")
		(net "P5E_PEX1_STN6_RX_DP<103>")
	)
	(gr_poly
		(pts
			(arc
				(start 167.403272 -312.049922)
				(mid 166.996872 -312.049922)
				(end 167.403272 -312.049922)
			)
		)
		(stroke
			(width 0)
			(type solid)
		)
		(fill yes)
		(layer "In4.Cu")
		(net "P5E_PEX1_STN6_TX_DN<103>")
	)
	(gr_poly
		(pts
			(arc
				(start 167.403272 -311.099962)
				(mid 166.996872 -311.099962)
				(end 167.403272 -311.099962)
			)
		)
		(stroke
			(width 0)
			(type solid)
		)
		(fill yes)
		(layer "In4.Cu")
		(net "P5E_PEX1_STN6_TX_DP<103>")
	)
	(gr_poly
		(pts
			(arc
				(start 167.403272 -280.699718)
				(mid 166.996872 -280.699718)
				(end 167.403272 -280.699718)
			)
		)
		(stroke
			(width 0)
			(type solid)
		)
		(fill yes)
		(layer "In4.Cu")
		(net "P5E_PEX1_STN2_TX_DP<40>")
	)
	(gr_poly
		(pts
			(arc
				(start 167.403272 -279.749504)
				(mid 166.996872 -279.749504)
				(end 167.403272 -279.749504)
			)
		)
		(stroke
			(width 0)
			(type solid)
		)
		(fill yes)
		(layer "In4.Cu")
		(net "P5E_PEX1_STN2_TX_DN<40>")
	)
	(gr_poly
		(pts
			(arc
				(start 167.403272 -275.949918)
				(mid 166.996872 -275.949918)
				(end 167.403272 -275.949918)
			)
		)
		(stroke
			(width 0)
			(type solid)
		)
		(fill yes)
		(layer "In4.Cu")
		(net "P5E_PEX1_STN2_RX_DP<40>")
	)
	(gr_poly
		(pts
			(arc
				(start 167.403272 -274.999958)
				(mid 166.996872 -274.999958)
				(end 167.403272 -274.999958)
			)
		)
		(stroke
			(width 0)
			(type solid)
		)
		(fill yes)
		(layer "In4.Cu")
		(net "P5E_PEX1_STN2_RX_DN<40>")
	)
	(gr_poly
		(pts
			(arc
				(start 168.353232 -318.699896)
				(mid 167.946832 -318.699896)
				(end 168.353232 -318.699896)
			)
		)
		(stroke
			(width 0)
			(type solid)
		)
		(fill yes)
		(layer "In4.Cu")
		(net "P5E_PEX1_STN6_RX_DN<102>")
	)
	(gr_poly
		(pts
			(arc
				(start 168.353232 -317.749936)
				(mid 167.946832 -317.749936)
				(end 168.353232 -317.749936)
			)
		)
		(stroke
			(width 0)
			(type solid)
		)
		(fill yes)
		(layer "In4.Cu")
		(net "P5E_PEX1_STN6_RX_DP<102>")
	)
	(gr_poly
		(pts
			(arc
				(start 168.353232 -313.949842)
				(mid 167.946832 -313.949842)
				(end 168.353232 -313.949842)
			)
		)
		(stroke
			(width 0)
			(type solid)
		)
		(fill yes)
		(layer "In4.Cu")
		(net "P5E_PEX1_STN6_TX_DN<102>")
	)
	(gr_poly
		(pts
			(arc
				(start 168.353232 -312.999882)
				(mid 167.946832 -312.999882)
				(end 168.353232 -312.999882)
			)
		)
		(stroke
			(width 0)
			(type solid)
		)
		(fill yes)
		(layer "In4.Cu")
		(net "P5E_PEX1_STN6_TX_DP<102>")
	)
	(gr_poly
		(pts
			(arc
				(start 168.353232 -278.799798)
				(mid 167.946832 -278.799798)
				(end 168.353232 -278.799798)
			)
		)
		(stroke
			(width 0)
			(type solid)
		)
		(fill yes)
		(layer "In4.Cu")
		(net "P5E_PEX1_STN2_TX_DP<39>")
	)
	(gr_poly
		(pts
			(arc
				(start 168.353232 -277.849838)
				(mid 167.946832 -277.849838)
				(end 168.353232 -277.849838)
			)
		)
		(stroke
			(width 0)
			(type solid)
		)
		(fill yes)
		(layer "In4.Cu")
		(net "P5E_PEX1_STN2_TX_DN<39>")
	)
	(gr_poly
		(pts
			(arc
				(start 168.353232 -274.049744)
				(mid 167.946832 -274.049744)
				(end 168.353232 -274.049744)
			)
		)
		(stroke
			(width 0)
			(type solid)
		)
		(fill yes)
		(layer "In4.Cu")
		(net "P5E_PEX1_STN2_RX_DP<39>")
	)
	(gr_poly
		(pts
			(arc
				(start 168.353232 -273.099784)
				(mid 167.946832 -273.099784)
				(end 168.353232 -273.099784)
			)
		)
		(stroke
			(width 0)
			(type solid)
		)
		(fill yes)
		(layer "In4.Cu")
		(net "P5E_PEX1_STN2_RX_DN<39>")
	)
	(gr_poly
		(pts
			(arc
				(start 169.303192 -316.799722)
				(mid 168.896792 -316.799722)
				(end 169.303192 -316.799722)
			)
		)
		(stroke
			(width 0)
			(type solid)
		)
		(fill yes)
		(layer "In4.Cu")
		(net "P5E_PEX1_STN6_RX_DN<101>")
	)
	(gr_poly
		(pts
			(arc
				(start 169.303192 -315.849762)
				(mid 168.896792 -315.849762)
				(end 169.303192 -315.849762)
			)
		)
		(stroke
			(width 0)
			(type solid)
		)
		(fill yes)
		(layer "In4.Cu")
		(net "P5E_PEX1_STN6_RX_DP<101>")
	)
	(gr_poly
		(pts
			(arc
				(start 169.303192 -312.049922)
				(mid 168.896792 -312.049922)
				(end 169.303192 -312.049922)
			)
		)
		(stroke
			(width 0)
			(type solid)
		)
		(fill yes)
		(layer "In4.Cu")
		(net "P5E_PEX1_STN6_TX_DN<101>")
	)
	(gr_poly
		(pts
			(arc
				(start 169.303192 -311.099962)
				(mid 168.896792 -311.099962)
				(end 169.303192 -311.099962)
			)
		)
		(stroke
			(width 0)
			(type solid)
		)
		(fill yes)
		(layer "In4.Cu")
		(net "P5E_PEX1_STN6_TX_DP<101>")
	)
	(gr_poly
		(pts
			(arc
				(start 169.303192 -280.699718)
				(mid 168.896792 -280.699718)
				(end 169.303192 -280.699718)
			)
		)
		(stroke
			(width 0)
			(type solid)
		)
		(fill yes)
		(layer "In4.Cu")
		(net "P5E_PEX1_STN2_TX_DP<38>")
	)
	(gr_poly
		(pts
			(arc
				(start 169.303192 -279.749504)
				(mid 168.896792 -279.749504)
				(end 169.303192 -279.749504)
			)
		)
		(stroke
			(width 0)
			(type solid)
		)
		(fill yes)
		(layer "In4.Cu")
		(net "P5E_PEX1_STN2_TX_DN<38>")
	)
	(gr_poly
		(pts
			(arc
				(start 169.303192 -275.949918)
				(mid 168.896792 -275.949918)
				(end 169.303192 -275.949918)
			)
		)
		(stroke
			(width 0)
			(type solid)
		)
		(fill yes)
		(layer "In4.Cu")
		(net "P5E_PEX1_STN2_RX_DP<38>")
	)
	(gr_poly
		(pts
			(arc
				(start 169.303192 -274.999958)
				(mid 168.896792 -274.999958)
				(end 169.303192 -274.999958)
			)
		)
		(stroke
			(width 0)
			(type solid)
		)
		(fill yes)
		(layer "In4.Cu")
		(net "P5E_PEX1_STN2_RX_DN<38>")
	)
	(gr_poly
		(pts
			(arc
				(start 170.253152 -318.699896)
				(mid 169.846752 -318.699896)
				(end 170.253152 -318.699896)
			)
		)
		(stroke
			(width 0)
			(type solid)
		)
		(fill yes)
		(layer "In4.Cu")
		(net "P5E_PEX1_STN6_RX_DN<100>")
	)
	(gr_poly
		(pts
			(arc
				(start 170.253152 -317.749936)
				(mid 169.846752 -317.749936)
				(end 170.253152 -317.749936)
			)
		)
		(stroke
			(width 0)
			(type solid)
		)
		(fill yes)
		(layer "In4.Cu")
		(net "P5E_PEX1_STN6_RX_DP<100>")
	)
	(gr_poly
		(pts
			(arc
				(start 170.253152 -313.949842)
				(mid 169.846752 -313.949842)
				(end 170.253152 -313.949842)
			)
		)
		(stroke
			(width 0)
			(type solid)
		)
		(fill yes)
		(layer "In4.Cu")
		(net "P5E_PEX1_STN6_TX_DN<100>")
	)
	(gr_poly
		(pts
			(arc
				(start 170.253152 -312.999882)
				(mid 169.846752 -312.999882)
				(end 170.253152 -312.999882)
			)
		)
		(stroke
			(width 0)
			(type solid)
		)
		(fill yes)
		(layer "In4.Cu")
		(net "P5E_PEX1_STN6_TX_DP<100>")
	)
	(gr_poly
		(pts
			(arc
				(start 170.253152 -278.799798)
				(mid 169.846752 -278.799798)
				(end 170.253152 -278.799798)
			)
		)
		(stroke
			(width 0)
			(type solid)
		)
		(fill yes)
		(layer "In4.Cu")
		(net "P5E_PEX1_STN2_TX_DP<37>")
	)
	(gr_poly
		(pts
			(arc
				(start 170.253152 -277.849838)
				(mid 169.846752 -277.849838)
				(end 170.253152 -277.849838)
			)
		)
		(stroke
			(width 0)
			(type solid)
		)
		(fill yes)
		(layer "In4.Cu")
		(net "P5E_PEX1_STN2_TX_DN<37>")
	)
	(gr_poly
		(pts
			(arc
				(start 170.253152 -274.049744)
				(mid 169.846752 -274.049744)
				(end 170.253152 -274.049744)
			)
		)
		(stroke
			(width 0)
			(type solid)
		)
		(fill yes)
		(layer "In4.Cu")
		(net "P5E_PEX1_STN2_RX_DP<37>")
	)
	(gr_poly
		(pts
			(arc
				(start 170.253152 -273.099784)
				(mid 169.846752 -273.099784)
				(end 170.253152 -273.099784)
			)
		)
		(stroke
			(width 0)
			(type solid)
		)
		(fill yes)
		(layer "In4.Cu")
		(net "P5E_PEX1_STN2_RX_DN<37>")
	)
	(gr_poly
		(pts
			(arc
				(start 171.203112 -316.799722)
				(mid 170.796712 -316.799722)
				(end 171.203112 -316.799722)
			)
		)
		(stroke
			(width 0)
			(type solid)
		)
		(fill yes)
		(layer "In4.Cu")
		(net "P5E_PEX1_STN6_RX_DN<99>")
	)
	(gr_poly
		(pts
			(arc
				(start 171.203112 -315.849762)
				(mid 170.796712 -315.849762)
				(end 171.203112 -315.849762)
			)
		)
		(stroke
			(width 0)
			(type solid)
		)
		(fill yes)
		(layer "In4.Cu")
		(net "P5E_PEX1_STN6_RX_DP<99>")
	)
	(gr_poly
		(pts
			(arc
				(start 171.203112 -312.049922)
				(mid 170.796712 -312.049922)
				(end 171.203112 -312.049922)
			)
		)
		(stroke
			(width 0)
			(type solid)
		)
		(fill yes)
		(layer "In4.Cu")
		(net "P5E_PEX1_STN6_TX_DN<99>")
	)
	(gr_poly
		(pts
			(arc
				(start 171.203112 -311.099962)
				(mid 170.796712 -311.099962)
				(end 171.203112 -311.099962)
			)
		)
		(stroke
			(width 0)
			(type solid)
		)
		(fill yes)
		(layer "In4.Cu")
		(net "P5E_PEX1_STN6_TX_DP<99>")
	)
	(gr_poly
		(pts
			(arc
				(start 171.203112 -280.699718)
				(mid 170.796712 -280.699718)
				(end 171.203112 -280.699718)
			)
		)
		(stroke
			(width 0)
			(type solid)
		)
		(fill yes)
		(layer "In4.Cu")
		(net "P5E_PEX1_STN2_TX_DP<36>")
	)
	(gr_poly
		(pts
			(arc
				(start 171.203112 -279.749504)
				(mid 170.796712 -279.749504)
				(end 171.203112 -279.749504)
			)
		)
		(stroke
			(width 0)
			(type solid)
		)
		(fill yes)
		(layer "In4.Cu")
		(net "P5E_PEX1_STN2_TX_DN<36>")
	)
	(gr_poly
		(pts
			(arc
				(start 171.203112 -275.949918)
				(mid 170.796712 -275.949918)
				(end 171.203112 -275.949918)
			)
		)
		(stroke
			(width 0)
			(type solid)
		)
		(fill yes)
		(layer "In4.Cu")
		(net "P5E_PEX1_STN2_RX_DP<36>")
	)
	(gr_poly
		(pts
			(arc
				(start 171.203112 -274.999958)
				(mid 170.796712 -274.999958)
				(end 171.203112 -274.999958)
			)
		)
		(stroke
			(width 0)
			(type solid)
		)
		(fill yes)
		(layer "In4.Cu")
		(net "P5E_PEX1_STN2_RX_DN<36>")
	)
	(gr_poly
		(pts
			(arc
				(start 172.153072 -318.699896)
				(mid 171.746672 -318.699896)
				(end 172.153072 -318.699896)
			)
		)
		(stroke
			(width 0)
			(type solid)
		)
		(fill yes)
		(layer "In4.Cu")
		(net "P5E_PEX1_STN6_RX_DN<98>")
	)
	(gr_poly
		(pts
			(arc
				(start 172.153072 -317.749936)
				(mid 171.746672 -317.749936)
				(end 172.153072 -317.749936)
			)
		)
		(stroke
			(width 0)
			(type solid)
		)
		(fill yes)
		(layer "In4.Cu")
		(net "P5E_PEX1_STN6_RX_DP<98>")
	)
	(gr_poly
		(pts
			(arc
				(start 172.153072 -313.949842)
				(mid 171.746672 -313.949842)
				(end 172.153072 -313.949842)
			)
		)
		(stroke
			(width 0)
			(type solid)
		)
		(fill yes)
		(layer "In4.Cu")
		(net "P5E_PEX1_STN6_TX_DN<98>")
	)
	(gr_poly
		(pts
			(arc
				(start 172.153072 -312.999882)
				(mid 171.746672 -312.999882)
				(end 172.153072 -312.999882)
			)
		)
		(stroke
			(width 0)
			(type solid)
		)
		(fill yes)
		(layer "In4.Cu")
		(net "P5E_PEX1_STN6_TX_DP<98>")
	)
	(gr_poly
		(pts
			(arc
				(start 172.153072 -278.799798)
				(mid 171.746672 -278.799798)
				(end 172.153072 -278.799798)
			)
		)
		(stroke
			(width 0)
			(type solid)
		)
		(fill yes)
		(layer "In4.Cu")
		(net "P5E_PEX1_STN2_TX_DP<35>")
	)
	(gr_poly
		(pts
			(arc
				(start 172.153072 -277.849838)
				(mid 171.746672 -277.849838)
				(end 172.153072 -277.849838)
			)
		)
		(stroke
			(width 0)
			(type solid)
		)
		(fill yes)
		(layer "In4.Cu")
		(net "P5E_PEX1_STN2_TX_DN<35>")
	)
	(gr_poly
		(pts
			(arc
				(start 172.153072 -274.049744)
				(mid 171.746672 -274.049744)
				(end 172.153072 -274.049744)
			)
		)
		(stroke
			(width 0)
			(type solid)
		)
		(fill yes)
		(layer "In4.Cu")
		(net "P5E_PEX1_STN2_RX_DP<35>")
	)
	(gr_poly
		(pts
			(arc
				(start 172.153072 -273.099784)
				(mid 171.746672 -273.099784)
				(end 172.153072 -273.099784)
			)
		)
		(stroke
			(width 0)
			(type solid)
		)
		(fill yes)
		(layer "In4.Cu")
		(net "P5E_PEX1_STN2_RX_DN<35>")
	)
	(gr_poly
		(pts
			(arc
				(start 173.103032 -280.699718)
				(mid 172.696632 -280.699718)
				(end 173.103032 -280.699718)
			)
		)
		(stroke
			(width 0)
			(type solid)
		)
		(fill yes)
		(layer "In4.Cu")
		(net "P5E_PEX1_STN2_TX_DP<34>")
	)
	(gr_poly
		(pts
			(arc
				(start 173.103032 -279.749504)
				(mid 172.696632 -279.749504)
				(end 173.103032 -279.749504)
			)
		)
		(stroke
			(width 0)
			(type solid)
		)
		(fill yes)
		(layer "In4.Cu")
		(net "P5E_PEX1_STN2_TX_DN<34>")
	)
	(gr_poly
		(pts
			(arc
				(start 173.103286 -316.799722)
				(mid 172.696886 -316.799722)
				(end 173.103286 -316.799722)
			)
		)
		(stroke
			(width 0)
			(type solid)
		)
		(fill yes)
		(layer "In4.Cu")
		(net "P5E_PEX1_STN6_RX_DN<97>")
	)
	(gr_poly
		(pts
			(arc
				(start 173.103286 -315.849762)
				(mid 172.696886 -315.849762)
				(end 173.103286 -315.849762)
			)
		)
		(stroke
			(width 0)
			(type solid)
		)
		(fill yes)
		(layer "In4.Cu")
		(net "P5E_PEX1_STN6_RX_DP<97>")
	)
	(gr_poly
		(pts
			(arc
				(start 173.103286 -312.049922)
				(mid 172.696886 -312.049922)
				(end 173.103286 -312.049922)
			)
		)
		(stroke
			(width 0)
			(type solid)
		)
		(fill yes)
		(layer "In4.Cu")
		(net "P5E_PEX1_STN6_TX_DN<97>")
	)
	(gr_poly
		(pts
			(arc
				(start 173.103286 -311.099962)
				(mid 172.696886 -311.099962)
				(end 173.103286 -311.099962)
			)
		)
		(stroke
			(width 0)
			(type solid)
		)
		(fill yes)
		(layer "In4.Cu")
		(net "P5E_PEX1_STN6_TX_DP<97>")
	)
	(gr_poly
		(pts
			(arc
				(start 173.103286 -275.949918)
				(mid 172.696886 -275.949918)
				(end 173.103286 -275.949918)
			)
		)
		(stroke
			(width 0)
			(type solid)
		)
		(fill yes)
		(layer "In4.Cu")
		(net "P5E_PEX1_STN2_RX_DP<34>")
	)
	(gr_poly
		(pts
			(arc
				(start 173.103286 -274.999958)
				(mid 172.696886 -274.999958)
				(end 173.103286 -274.999958)
			)
		)
		(stroke
			(width 0)
			(type solid)
		)
		(fill yes)
		(layer "In4.Cu")
		(net "P5E_PEX1_STN2_RX_DN<34>")
	)
	(gr_poly
		(pts
			(arc
				(start 174.053246 -318.699896)
				(mid 173.646846 -318.699896)
				(end 174.053246 -318.699896)
			)
		)
		(stroke
			(width 0)
			(type solid)
		)
		(fill yes)
		(layer "In4.Cu")
		(net "P5E_PEX1_STN6_RX_DN<96>")
	)
	(gr_poly
		(pts
			(arc
				(start 174.053246 -317.749936)
				(mid 173.646846 -317.749936)
				(end 174.053246 -317.749936)
			)
		)
		(stroke
			(width 0)
			(type solid)
		)
		(fill yes)
		(layer "In4.Cu")
		(net "P5E_PEX1_STN6_RX_DP<96>")
	)
	(gr_poly
		(pts
			(arc
				(start 174.053246 -313.949842)
				(mid 173.646846 -313.949842)
				(end 174.053246 -313.949842)
			)
		)
		(stroke
			(width 0)
			(type solid)
		)
		(fill yes)
		(layer "In4.Cu")
		(net "P5E_PEX1_STN6_TX_DN<96>")
	)
	(gr_poly
		(pts
			(arc
				(start 174.053246 -312.999882)
				(mid 173.646846 -312.999882)
				(end 174.053246 -312.999882)
			)
		)
		(stroke
			(width 0)
			(type solid)
		)
		(fill yes)
		(layer "In4.Cu")
		(net "P5E_PEX1_STN6_TX_DP<96>")
	)
	(gr_poly
		(pts
			(arc
				(start 174.053246 -278.799798)
				(mid 173.646846 -278.799798)
				(end 174.053246 -278.799798)
			)
		)
		(stroke
			(width 0)
			(type solid)
		)
		(fill yes)
		(layer "In4.Cu")
		(net "P5E_PEX1_STN2_TX_DP<33>")
	)
	(gr_poly
		(pts
			(arc
				(start 174.053246 -277.849838)
				(mid 173.646846 -277.849838)
				(end 174.053246 -277.849838)
			)
		)
		(stroke
			(width 0)
			(type solid)
		)
		(fill yes)
		(layer "In4.Cu")
		(net "P5E_PEX1_STN2_TX_DN<33>")
	)
	(gr_poly
		(pts
			(arc
				(start 174.053246 -274.049744)
				(mid 173.646846 -274.049744)
				(end 174.053246 -274.049744)
			)
		)
		(stroke
			(width 0)
			(type solid)
		)
		(fill yes)
		(layer "In4.Cu")
		(net "P5E_PEX1_STN2_RX_DP<33>")
	)
	(gr_poly
		(pts
			(arc
				(start 174.053246 -273.099784)
				(mid 173.646846 -273.099784)
				(end 174.053246 -273.099784)
			)
		)
		(stroke
			(width 0)
			(type solid)
		)
		(fill yes)
		(layer "In4.Cu")
		(net "P5E_PEX1_STN2_RX_DN<33>")
	)
	(gr_poly
		(pts
			(arc
				(start 175.003206 -316.799722)
				(mid 174.596806 -316.799722)
				(end 175.003206 -316.799722)
			)
		)
		(stroke
			(width 0)
			(type solid)
		)
		(fill yes)
		(layer "In4.Cu")
		(net "P5E_PEX1_STN5_RX_DN<80>")
	)
	(gr_poly
		(pts
			(arc
				(start 175.003206 -315.849762)
				(mid 174.596806 -315.849762)
				(end 175.003206 -315.849762)
			)
		)
		(stroke
			(width 0)
			(type solid)
		)
		(fill yes)
		(layer "In4.Cu")
		(net "P5E_PEX1_STN5_RX_DP<80>")
	)
	(gr_poly
		(pts
			(arc
				(start 175.003206 -312.049922)
				(mid 174.596806 -312.049922)
				(end 175.003206 -312.049922)
			)
		)
		(stroke
			(width 0)
			(type solid)
		)
		(fill yes)
		(layer "In4.Cu")
		(net "P5E_PEX1_STN5_TX_DN<80>")
	)
	(gr_poly
		(pts
			(arc
				(start 175.003206 -311.099962)
				(mid 174.596806 -311.099962)
				(end 175.003206 -311.099962)
			)
		)
		(stroke
			(width 0)
			(type solid)
		)
		(fill yes)
		(layer "In4.Cu")
		(net "P5E_PEX1_STN5_TX_DP<80>")
	)
	(gr_poly
		(pts
			(arc
				(start 175.003206 -280.699718)
				(mid 174.596806 -280.699718)
				(end 175.003206 -280.699718)
			)
		)
		(stroke
			(width 0)
			(type solid)
		)
		(fill yes)
		(layer "In4.Cu")
		(net "P5E_PEX1_STN2_TX_DP<32>")
	)
	(gr_poly
		(pts
			(arc
				(start 175.003206 -279.749504)
				(mid 174.596806 -279.749504)
				(end 175.003206 -279.749504)
			)
		)
		(stroke
			(width 0)
			(type solid)
		)
		(fill yes)
		(layer "In4.Cu")
		(net "P5E_PEX1_STN2_TX_DN<32>")
	)
	(gr_poly
		(pts
			(arc
				(start 175.003206 -275.949918)
				(mid 174.596806 -275.949918)
				(end 175.003206 -275.949918)
			)
		)
		(stroke
			(width 0)
			(type solid)
		)
		(fill yes)
		(layer "In4.Cu")
		(net "P5E_PEX1_STN2_RX_DP<32>")
	)
	(gr_poly
		(pts
			(arc
				(start 175.003206 -274.999958)
				(mid 174.596806 -274.999958)
				(end 175.003206 -274.999958)
			)
		)
		(stroke
			(width 0)
			(type solid)
		)
		(fill yes)
		(layer "In4.Cu")
		(net "P5E_PEX1_STN2_RX_DN<32>")
	)
	(gr_poly
		(pts
			(arc
				(start 175.952912 -278.799798)
				(mid 175.546512 -278.799798)
				(end 175.952912 -278.799798)
			)
		)
		(stroke
			(width 0)
			(type solid)
		)
		(fill yes)
		(layer "In4.Cu")
		(net "P5E_PEX1_STN1_TX_DP<16>")
	)
	(gr_poly
		(pts
			(arc
				(start 175.952912 -277.849838)
				(mid 175.546512 -277.849838)
				(end 175.952912 -277.849838)
			)
		)
		(stroke
			(width 0)
			(type solid)
		)
		(fill yes)
		(layer "In4.Cu")
		(net "P5E_PEX1_STN1_TX_DN<16>")
	)
	(gr_poly
		(pts
			(arc
				(start 175.952912 -274.04949)
				(mid 175.546512 -274.04949)
				(end 175.952912 -274.04949)
			)
		)
		(stroke
			(width 0)
			(type solid)
		)
		(fill yes)
		(layer "In4.Cu")
		(net "P5E_PEX1_STN1_RX_DP<16>")
	)
	(gr_poly
		(pts
			(arc
				(start 175.952912 -273.09953)
				(mid 175.546512 -273.09953)
				(end 175.952912 -273.09953)
			)
		)
		(stroke
			(width 0)
			(type solid)
		)
		(fill yes)
		(layer "In4.Cu")
		(net "P5E_PEX1_STN1_RX_DN<16>")
	)
	(gr_poly
		(pts
			(arc
				(start 175.953166 -318.699896)
				(mid 175.546766 -318.699896)
				(end 175.953166 -318.699896)
			)
		)
		(stroke
			(width 0)
			(type solid)
		)
		(fill yes)
		(layer "In4.Cu")
		(net "P5E_PEX1_STN5_RX_DN<81>")
	)
	(gr_poly
		(pts
			(arc
				(start 175.953166 -317.749936)
				(mid 175.546766 -317.749936)
				(end 175.953166 -317.749936)
			)
		)
		(stroke
			(width 0)
			(type solid)
		)
		(fill yes)
		(layer "In4.Cu")
		(net "P5E_PEX1_STN5_RX_DP<81>")
	)
	(gr_poly
		(pts
			(arc
				(start 175.953166 -313.949842)
				(mid 175.546766 -313.949842)
				(end 175.953166 -313.949842)
			)
		)
		(stroke
			(width 0)
			(type solid)
		)
		(fill yes)
		(layer "In4.Cu")
		(net "P5E_PEX1_STN5_TX_DN<81>")
	)
	(gr_poly
		(pts
			(arc
				(start 175.953166 -312.999882)
				(mid 175.546766 -312.999882)
				(end 175.953166 -312.999882)
			)
		)
		(stroke
			(width 0)
			(type solid)
		)
		(fill yes)
		(layer "In4.Cu")
		(net "P5E_PEX1_STN5_TX_DP<81>")
	)
	(gr_poly
		(pts
			(arc
				(start 176.902872 -275.949664)
				(mid 176.496472 -275.949664)
				(end 176.902872 -275.949664)
			)
		)
		(stroke
			(width 0)
			(type solid)
		)
		(fill yes)
		(layer "In4.Cu")
		(net "P5E_PEX1_STN1_RX_DP<17>")
	)
	(gr_poly
		(pts
			(arc
				(start 176.902872 -274.999704)
				(mid 176.496472 -274.999704)
				(end 176.902872 -274.999704)
			)
		)
		(stroke
			(width 0)
			(type solid)
		)
		(fill yes)
		(layer "In4.Cu")
		(net "P5E_PEX1_STN1_RX_DN<17>")
	)
	(gr_poly
		(pts
			(arc
				(start 176.903126 -316.799722)
				(mid 176.496726 -316.799722)
				(end 176.903126 -316.799722)
			)
		)
		(stroke
			(width 0)
			(type solid)
		)
		(fill yes)
		(layer "In4.Cu")
		(net "P5E_PEX1_STN5_RX_DN<82>")
	)
	(gr_poly
		(pts
			(arc
				(start 176.903126 -315.849762)
				(mid 176.496726 -315.849762)
				(end 176.903126 -315.849762)
			)
		)
		(stroke
			(width 0)
			(type solid)
		)
		(fill yes)
		(layer "In4.Cu")
		(net "P5E_PEX1_STN5_RX_DP<82>")
	)
	(gr_poly
		(pts
			(arc
				(start 176.903126 -312.049922)
				(mid 176.496726 -312.049922)
				(end 176.903126 -312.049922)
			)
		)
		(stroke
			(width 0)
			(type solid)
		)
		(fill yes)
		(layer "In4.Cu")
		(net "P5E_PEX1_STN5_TX_DN<82>")
	)
	(gr_poly
		(pts
			(arc
				(start 176.903126 -311.099962)
				(mid 176.496726 -311.099962)
				(end 176.903126 -311.099962)
			)
		)
		(stroke
			(width 0)
			(type solid)
		)
		(fill yes)
		(layer "In4.Cu")
		(net "P5E_PEX1_STN5_TX_DP<82>")
	)
	(gr_poly
		(pts
			(arc
				(start 176.903126 -280.699718)
				(mid 176.496726 -280.699718)
				(end 176.903126 -280.699718)
			)
		)
		(stroke
			(width 0)
			(type solid)
		)
		(fill yes)
		(layer "In4.Cu")
		(net "P5E_PEX1_STN1_TX_DN<17>")
	)
	(gr_poly
		(pts
			(arc
				(start 176.903126 -279.749504)
				(mid 176.496726 -279.749504)
				(end 176.903126 -279.749504)
			)
		)
		(stroke
			(width 0)
			(type solid)
		)
		(fill yes)
		(layer "In4.Cu")
		(net "P5E_PEX1_STN1_TX_DP<17>")
	)
	(gr_poly
		(pts
			(arc
				(start 177.852832 -278.799798)
				(mid 177.446432 -278.799798)
				(end 177.852832 -278.799798)
			)
		)
		(stroke
			(width 0)
			(type solid)
		)
		(fill yes)
		(layer "In4.Cu")
		(net "P5E_PEX1_STN1_TX_DP<18>")
	)
	(gr_poly
		(pts
			(arc
				(start 177.852832 -277.849838)
				(mid 177.446432 -277.849838)
				(end 177.852832 -277.849838)
			)
		)
		(stroke
			(width 0)
			(type solid)
		)
		(fill yes)
		(layer "In4.Cu")
		(net "P5E_PEX1_STN1_TX_DN<18>")
	)
	(gr_poly
		(pts
			(arc
				(start 177.852832 -274.049744)
				(mid 177.446432 -274.049744)
				(end 177.852832 -274.049744)
			)
		)
		(stroke
			(width 0)
			(type solid)
		)
		(fill yes)
		(layer "In4.Cu")
		(net "P5E_PEX1_STN1_RX_DP<18>")
	)
	(gr_poly
		(pts
			(arc
				(start 177.852832 -273.099784)
				(mid 177.446432 -273.099784)
				(end 177.852832 -273.099784)
			)
		)
		(stroke
			(width 0)
			(type solid)
		)
		(fill yes)
		(layer "In4.Cu")
		(net "P5E_PEX1_STN1_RX_DN<18>")
	)
	(gr_poly
		(pts
			(arc
				(start 177.853086 -318.699896)
				(mid 177.446686 -318.699896)
				(end 177.853086 -318.699896)
			)
		)
		(stroke
			(width 0)
			(type solid)
		)
		(fill yes)
		(layer "In4.Cu")
		(net "P5E_PEX1_STN5_RX_DN<83>")
	)
	(gr_poly
		(pts
			(arc
				(start 177.853086 -317.749936)
				(mid 177.446686 -317.749936)
				(end 177.853086 -317.749936)
			)
		)
		(stroke
			(width 0)
			(type solid)
		)
		(fill yes)
		(layer "In4.Cu")
		(net "P5E_PEX1_STN5_RX_DP<83>")
	)
	(gr_poly
		(pts
			(arc
				(start 177.853086 -313.949842)
				(mid 177.446686 -313.949842)
				(end 177.853086 -313.949842)
			)
		)
		(stroke
			(width 0)
			(type solid)
		)
		(fill yes)
		(layer "In4.Cu")
		(net "P5E_PEX1_STN5_TX_DN<83>")
	)
	(gr_poly
		(pts
			(arc
				(start 177.853086 -312.999882)
				(mid 177.446686 -312.999882)
				(end 177.853086 -312.999882)
			)
		)
		(stroke
			(width 0)
			(type solid)
		)
		(fill yes)
		(layer "In4.Cu")
		(net "P5E_PEX1_STN5_TX_DP<83>")
	)
	(gr_poly
		(pts
			(arc
				(start 178.802792 -275.949918)
				(mid 178.396392 -275.949918)
				(end 178.802792 -275.949918)
			)
		)
		(stroke
			(width 0)
			(type solid)
		)
		(fill yes)
		(layer "In4.Cu")
		(net "P5E_PEX1_STN1_RX_DP<19>")
	)
	(gr_poly
		(pts
			(arc
				(start 178.802792 -274.999958)
				(mid 178.396392 -274.999958)
				(end 178.802792 -274.999958)
			)
		)
		(stroke
			(width 0)
			(type solid)
		)
		(fill yes)
		(layer "In4.Cu")
		(net "P5E_PEX1_STN1_RX_DN<19>")
	)
	(gr_poly
		(pts
			(arc
				(start 178.803046 -316.799722)
				(mid 178.396646 -316.799722)
				(end 178.803046 -316.799722)
			)
		)
		(stroke
			(width 0)
			(type solid)
		)
		(fill yes)
		(layer "In4.Cu")
		(net "P5E_PEX1_STN5_RX_DN<84>")
	)
	(gr_poly
		(pts
			(arc
				(start 178.803046 -315.849762)
				(mid 178.396646 -315.849762)
				(end 178.803046 -315.849762)
			)
		)
		(stroke
			(width 0)
			(type solid)
		)
		(fill yes)
		(layer "In4.Cu")
		(net "P5E_PEX1_STN5_RX_DP<84>")
	)
	(gr_poly
		(pts
			(arc
				(start 178.803046 -312.049922)
				(mid 178.396646 -312.049922)
				(end 178.803046 -312.049922)
			)
		)
		(stroke
			(width 0)
			(type solid)
		)
		(fill yes)
		(layer "In4.Cu")
		(net "P5E_PEX1_STN5_TX_DN<84>")
	)
	(gr_poly
		(pts
			(arc
				(start 178.803046 -311.099962)
				(mid 178.396646 -311.099962)
				(end 178.803046 -311.099962)
			)
		)
		(stroke
			(width 0)
			(type solid)
		)
		(fill yes)
		(layer "In4.Cu")
		(net "P5E_PEX1_STN5_TX_DP<84>")
	)
	(gr_poly
		(pts
			(arc
				(start 178.803046 -280.699718)
				(mid 178.396646 -280.699718)
				(end 178.803046 -280.699718)
			)
		)
		(stroke
			(width 0)
			(type solid)
		)
		(fill yes)
		(layer "In4.Cu")
		(net "P5E_PEX1_STN1_TX_DN<19>")
	)
	(gr_poly
		(pts
			(arc
				(start 178.803046 -279.749504)
				(mid 178.396646 -279.749504)
				(end 178.803046 -279.749504)
			)
		)
		(stroke
			(width 0)
			(type solid)
		)
		(fill yes)
		(layer "In4.Cu")
		(net "P5E_PEX1_STN1_TX_DP<19>")
	)
	(gr_poly
		(pts
			(arc
				(start 179.753006 -278.799798)
				(mid 179.346606 -278.799798)
				(end 179.753006 -278.799798)
			)
		)
		(stroke
			(width 0)
			(type solid)
		)
		(fill yes)
		(layer "In4.Cu")
		(net "P5E_PEX1_STN1_TX_DP<20>")
	)
	(gr_poly
		(pts
			(arc
				(start 179.753006 -277.849838)
				(mid 179.346606 -277.849838)
				(end 179.753006 -277.849838)
			)
		)
		(stroke
			(width 0)
			(type solid)
		)
		(fill yes)
		(layer "In4.Cu")
		(net "P5E_PEX1_STN1_TX_DN<20>")
	)
	(gr_poly
		(pts
			(arc
				(start 179.753006 -274.049744)
				(mid 179.346606 -274.049744)
				(end 179.753006 -274.049744)
			)
		)
		(stroke
			(width 0)
			(type solid)
		)
		(fill yes)
		(layer "In4.Cu")
		(net "P5E_PEX1_STN1_RX_DP<20>")
	)
	(gr_poly
		(pts
			(arc
				(start 179.753006 -273.099784)
				(mid 179.346606 -273.099784)
				(end 179.753006 -273.099784)
			)
		)
		(stroke
			(width 0)
			(type solid)
		)
		(fill yes)
		(layer "In4.Cu")
		(net "P5E_PEX1_STN1_RX_DN<20>")
	)
	(gr_poly
		(pts
			(arc
				(start 179.75326 -318.699896)
				(mid 179.34686 -318.699896)
				(end 179.75326 -318.699896)
			)
		)
		(stroke
			(width 0)
			(type solid)
		)
		(fill yes)
		(layer "In4.Cu")
		(net "P5E_PEX1_STN5_RX_DN<85>")
	)
	(gr_poly
		(pts
			(arc
				(start 179.75326 -317.749936)
				(mid 179.34686 -317.749936)
				(end 179.75326 -317.749936)
			)
		)
		(stroke
			(width 0)
			(type solid)
		)
		(fill yes)
		(layer "In4.Cu")
		(net "P5E_PEX1_STN5_RX_DP<85>")
	)
	(gr_poly
		(pts
			(arc
				(start 179.75326 -313.949842)
				(mid 179.34686 -313.949842)
				(end 179.75326 -313.949842)
			)
		)
		(stroke
			(width 0)
			(type solid)
		)
		(fill yes)
		(layer "In4.Cu")
		(net "P5E_PEX1_STN5_TX_DN<85>")
	)
	(gr_poly
		(pts
			(arc
				(start 179.75326 -312.999882)
				(mid 179.34686 -312.999882)
				(end 179.75326 -312.999882)
			)
		)
		(stroke
			(width 0)
			(type solid)
		)
		(fill yes)
		(layer "In4.Cu")
		(net "P5E_PEX1_STN5_TX_DP<85>")
	)
	(gr_poly
		(pts
			(arc
				(start 180.702966 -275.949664)
				(mid 180.296566 -275.949664)
				(end 180.702966 -275.949664)
			)
		)
		(stroke
			(width 0)
			(type solid)
		)
		(fill yes)
		(layer "In4.Cu")
		(net "P5E_PEX1_STN1_RX_DP<21>")
	)
	(gr_poly
		(pts
			(arc
				(start 180.702966 -274.999704)
				(mid 180.296566 -274.999704)
				(end 180.702966 -274.999704)
			)
		)
		(stroke
			(width 0)
			(type solid)
		)
		(fill yes)
		(layer "In4.Cu")
		(net "P5E_PEX1_STN1_RX_DN<21>")
	)
	(gr_poly
		(pts
			(arc
				(start 180.70322 -316.799722)
				(mid 180.29682 -316.799722)
				(end 180.70322 -316.799722)
			)
		)
		(stroke
			(width 0)
			(type solid)
		)
		(fill yes)
		(layer "In4.Cu")
		(net "P5E_PEX1_STN5_RX_DN<86>")
	)
	(gr_poly
		(pts
			(arc
				(start 180.70322 -315.849762)
				(mid 180.29682 -315.849762)
				(end 180.70322 -315.849762)
			)
		)
		(stroke
			(width 0)
			(type solid)
		)
		(fill yes)
		(layer "In4.Cu")
		(net "P5E_PEX1_STN5_RX_DP<86>")
	)
	(gr_poly
		(pts
			(arc
				(start 180.70322 -312.049922)
				(mid 180.29682 -312.049922)
				(end 180.70322 -312.049922)
			)
		)
		(stroke
			(width 0)
			(type solid)
		)
		(fill yes)
		(layer "In4.Cu")
		(net "P5E_PEX1_STN5_TX_DN<86>")
	)
	(gr_poly
		(pts
			(arc
				(start 180.70322 -311.099962)
				(mid 180.29682 -311.099962)
				(end 180.70322 -311.099962)
			)
		)
		(stroke
			(width 0)
			(type solid)
		)
		(fill yes)
		(layer "In4.Cu")
		(net "P5E_PEX1_STN5_TX_DP<86>")
	)
	(gr_poly
		(pts
			(arc
				(start 180.70322 -280.699718)
				(mid 180.29682 -280.699718)
				(end 180.70322 -280.699718)
			)
		)
		(stroke
			(width 0)
			(type solid)
		)
		(fill yes)
		(layer "In4.Cu")
		(net "P5E_PEX1_STN1_TX_DN<21>")
	)
	(gr_poly
		(pts
			(arc
				(start 180.70322 -279.749504)
				(mid 180.29682 -279.749504)
				(end 180.70322 -279.749504)
			)
		)
		(stroke
			(width 0)
			(type solid)
		)
		(fill yes)
		(layer "In4.Cu")
		(net "P5E_PEX1_STN1_TX_DP<21>")
	)
	(gr_poly
		(pts
			(arc
				(start 181.652926 -278.799798)
				(mid 181.246526 -278.799798)
				(end 181.652926 -278.799798)
			)
		)
		(stroke
			(width 0)
			(type solid)
		)
		(fill yes)
		(layer "In4.Cu")
		(net "P5E_PEX1_STN1_TX_DP<22>")
	)
	(gr_poly
		(pts
			(arc
				(start 181.652926 -277.849838)
				(mid 181.246526 -277.849838)
				(end 181.652926 -277.849838)
			)
		)
		(stroke
			(width 0)
			(type solid)
		)
		(fill yes)
		(layer "In4.Cu")
		(net "P5E_PEX1_STN1_TX_DN<22>")
	)
	(gr_poly
		(pts
			(arc
				(start 181.652926 -274.049744)
				(mid 181.246526 -274.049744)
				(end 181.652926 -274.049744)
			)
		)
		(stroke
			(width 0)
			(type solid)
		)
		(fill yes)
		(layer "In4.Cu")
		(net "P5E_PEX1_STN1_RX_DP<22>")
	)
	(gr_poly
		(pts
			(arc
				(start 181.652926 -273.099784)
				(mid 181.246526 -273.099784)
				(end 181.652926 -273.099784)
			)
		)
		(stroke
			(width 0)
			(type solid)
		)
		(fill yes)
		(layer "In4.Cu")
		(net "P5E_PEX1_STN1_RX_DN<22>")
	)
	(gr_poly
		(pts
			(arc
				(start 181.65318 -318.699896)
				(mid 181.24678 -318.699896)
				(end 181.65318 -318.699896)
			)
		)
		(stroke
			(width 0)
			(type solid)
		)
		(fill yes)
		(layer "In4.Cu")
		(net "P5E_PEX1_STN5_RX_DN<87>")
	)
	(gr_poly
		(pts
			(arc
				(start 181.65318 -317.749936)
				(mid 181.24678 -317.749936)
				(end 181.65318 -317.749936)
			)
		)
		(stroke
			(width 0)
			(type solid)
		)
		(fill yes)
		(layer "In4.Cu")
		(net "P5E_PEX1_STN5_RX_DP<87>")
	)
	(gr_poly
		(pts
			(arc
				(start 181.65318 -313.949842)
				(mid 181.24678 -313.949842)
				(end 181.65318 -313.949842)
			)
		)
		(stroke
			(width 0)
			(type solid)
		)
		(fill yes)
		(layer "In4.Cu")
		(net "P5E_PEX1_STN5_TX_DN<87>")
	)
	(gr_poly
		(pts
			(arc
				(start 181.65318 -312.999882)
				(mid 181.24678 -312.999882)
				(end 181.65318 -312.999882)
			)
		)
		(stroke
			(width 0)
			(type solid)
		)
		(fill yes)
		(layer "In4.Cu")
		(net "P5E_PEX1_STN5_TX_DP<87>")
	)
	(gr_poly
		(pts
			(arc
				(start 182.602886 -275.949918)
				(mid 182.196486 -275.949918)
				(end 182.602886 -275.949918)
			)
		)
		(stroke
			(width 0)
			(type solid)
		)
		(fill yes)
		(layer "In4.Cu")
		(net "P5E_PEX1_STN1_RX_DP<23>")
	)
	(gr_poly
		(pts
			(arc
				(start 182.602886 -274.999958)
				(mid 182.196486 -274.999958)
				(end 182.602886 -274.999958)
			)
		)
		(stroke
			(width 0)
			(type solid)
		)
		(fill yes)
		(layer "In4.Cu")
		(net "P5E_PEX1_STN1_RX_DN<23>")
	)
	(gr_poly
		(pts
			(arc
				(start 182.60314 -316.799722)
				(mid 182.19674 -316.799722)
				(end 182.60314 -316.799722)
			)
		)
		(stroke
			(width 0)
			(type solid)
		)
		(fill yes)
		(layer "In4.Cu")
		(net "P5E_PEX1_STN5_RX_DN<88>")
	)
	(gr_poly
		(pts
			(arc
				(start 182.60314 -315.849762)
				(mid 182.19674 -315.849762)
				(end 182.60314 -315.849762)
			)
		)
		(stroke
			(width 0)
			(type solid)
		)
		(fill yes)
		(layer "In4.Cu")
		(net "P5E_PEX1_STN5_RX_DP<88>")
	)
	(gr_poly
		(pts
			(arc
				(start 182.60314 -312.049922)
				(mid 182.19674 -312.049922)
				(end 182.60314 -312.049922)
			)
		)
		(stroke
			(width 0)
			(type solid)
		)
		(fill yes)
		(layer "In4.Cu")
		(net "P5E_PEX1_STN5_TX_DN<88>")
	)
	(gr_poly
		(pts
			(arc
				(start 182.60314 -311.099962)
				(mid 182.19674 -311.099962)
				(end 182.60314 -311.099962)
			)
		)
		(stroke
			(width 0)
			(type solid)
		)
		(fill yes)
		(layer "In4.Cu")
		(net "P5E_PEX1_STN5_TX_DP<88>")
	)
	(gr_poly
		(pts
			(arc
				(start 182.60314 -280.699718)
				(mid 182.19674 -280.699718)
				(end 182.60314 -280.699718)
			)
		)
		(stroke
			(width 0)
			(type solid)
		)
		(fill yes)
		(layer "In4.Cu")
		(net "P5E_PEX1_STN1_TX_DN<23>")
	)
	(gr_poly
		(pts
			(arc
				(start 182.60314 -279.749504)
				(mid 182.19674 -279.749504)
				(end 182.60314 -279.749504)
			)
		)
		(stroke
			(width 0)
			(type solid)
		)
		(fill yes)
		(layer "In4.Cu")
		(net "P5E_PEX1_STN1_TX_DP<23>")
	)
	(gr_poly
		(pts
			(arc
				(start 183.552846 -278.799798)
				(mid 183.146446 -278.799798)
				(end 183.552846 -278.799798)
			)
		)
		(stroke
			(width 0)
			(type solid)
		)
		(fill yes)
		(layer "In4.Cu")
		(net "P5E_PEX1_STN1_TX_DP<24>")
	)
	(gr_poly
		(pts
			(arc
				(start 183.552846 -277.849838)
				(mid 183.146446 -277.849838)
				(end 183.552846 -277.849838)
			)
		)
		(stroke
			(width 0)
			(type solid)
		)
		(fill yes)
		(layer "In4.Cu")
		(net "P5E_PEX1_STN1_TX_DN<24>")
	)
	(gr_poly
		(pts
			(arc
				(start 183.552846 -274.049744)
				(mid 183.146446 -274.049744)
				(end 183.552846 -274.049744)
			)
		)
		(stroke
			(width 0)
			(type solid)
		)
		(fill yes)
		(layer "In4.Cu")
		(net "P5E_PEX1_STN1_RX_DP<24>")
	)
	(gr_poly
		(pts
			(arc
				(start 183.552846 -273.099784)
				(mid 183.146446 -273.099784)
				(end 183.552846 -273.099784)
			)
		)
		(stroke
			(width 0)
			(type solid)
		)
		(fill yes)
		(layer "In4.Cu")
		(net "P5E_PEX1_STN1_RX_DN<24>")
	)
	(gr_poly
		(pts
			(arc
				(start 183.5531 -318.699896)
				(mid 183.1467 -318.699896)
				(end 183.5531 -318.699896)
			)
		)
		(stroke
			(width 0)
			(type solid)
		)
		(fill yes)
		(layer "In4.Cu")
		(net "P5E_PEX1_STN5_RX_DN<89>")
	)
	(gr_poly
		(pts
			(arc
				(start 183.5531 -317.749936)
				(mid 183.1467 -317.749936)
				(end 183.5531 -317.749936)
			)
		)
		(stroke
			(width 0)
			(type solid)
		)
		(fill yes)
		(layer "In4.Cu")
		(net "P5E_PEX1_STN5_RX_DP<89>")
	)
	(gr_poly
		(pts
			(arc
				(start 183.5531 -313.949842)
				(mid 183.1467 -313.949842)
				(end 183.5531 -313.949842)
			)
		)
		(stroke
			(width 0)
			(type solid)
		)
		(fill yes)
		(layer "In4.Cu")
		(net "P5E_PEX1_STN5_TX_DN<89>")
	)
	(gr_poly
		(pts
			(arc
				(start 183.5531 -312.999882)
				(mid 183.1467 -312.999882)
				(end 183.5531 -312.999882)
			)
		)
		(stroke
			(width 0)
			(type solid)
		)
		(fill yes)
		(layer "In4.Cu")
		(net "P5E_PEX1_STN5_TX_DP<89>")
	)
	(gr_poly
		(pts
			(arc
				(start 184.502806 -275.949664)
				(mid 184.096406 -275.949664)
				(end 184.502806 -275.949664)
			)
		)
		(stroke
			(width 0)
			(type solid)
		)
		(fill yes)
		(layer "In4.Cu")
		(net "P5E_PEX1_STN1_RX_DP<25>")
	)
	(gr_poly
		(pts
			(arc
				(start 184.502806 -274.999704)
				(mid 184.096406 -274.999704)
				(end 184.502806 -274.999704)
			)
		)
		(stroke
			(width 0)
			(type solid)
		)
		(fill yes)
		(layer "In4.Cu")
		(net "P5E_PEX1_STN1_RX_DN<25>")
	)
	(gr_poly
		(pts
			(arc
				(start 184.50306 -316.799722)
				(mid 184.09666 -316.799722)
				(end 184.50306 -316.799722)
			)
		)
		(stroke
			(width 0)
			(type solid)
		)
		(fill yes)
		(layer "In4.Cu")
		(net "P5E_PEX1_STN5_RX_DN<90>")
	)
	(gr_poly
		(pts
			(arc
				(start 184.50306 -315.849762)
				(mid 184.09666 -315.849762)
				(end 184.50306 -315.849762)
			)
		)
		(stroke
			(width 0)
			(type solid)
		)
		(fill yes)
		(layer "In4.Cu")
		(net "P5E_PEX1_STN5_RX_DP<90>")
	)
	(gr_poly
		(pts
			(arc
				(start 184.50306 -312.049922)
				(mid 184.09666 -312.049922)
				(end 184.50306 -312.049922)
			)
		)
		(stroke
			(width 0)
			(type solid)
		)
		(fill yes)
		(layer "In4.Cu")
		(net "P5E_PEX1_STN5_TX_DN<90>")
	)
	(gr_poly
		(pts
			(arc
				(start 184.50306 -311.099962)
				(mid 184.09666 -311.099962)
				(end 184.50306 -311.099962)
			)
		)
		(stroke
			(width 0)
			(type solid)
		)
		(fill yes)
		(layer "In4.Cu")
		(net "P5E_PEX1_STN5_TX_DP<90>")
	)
	(gr_poly
		(pts
			(arc
				(start 184.50306 -280.699718)
				(mid 184.09666 -280.699718)
				(end 184.50306 -280.699718)
			)
		)
		(stroke
			(width 0)
			(type solid)
		)
		(fill yes)
		(layer "In4.Cu")
		(net "P5E_PEX1_STN1_TX_DN<25>")
	)
	(gr_poly
		(pts
			(arc
				(start 184.50306 -279.749504)
				(mid 184.09666 -279.749504)
				(end 184.50306 -279.749504)
			)
		)
		(stroke
			(width 0)
			(type solid)
		)
		(fill yes)
		(layer "In4.Cu")
		(net "P5E_PEX1_STN1_TX_DP<25>")
	)
	(gr_poly
		(pts
			(arc
				(start 185.45302 -278.799798)
				(mid 185.04662 -278.799798)
				(end 185.45302 -278.799798)
			)
		)
		(stroke
			(width 0)
			(type solid)
		)
		(fill yes)
		(layer "In4.Cu")
		(net "P5E_PEX1_STN1_TX_DP<26>")
	)
	(gr_poly
		(pts
			(arc
				(start 185.45302 -277.849838)
				(mid 185.04662 -277.849838)
				(end 185.45302 -277.849838)
			)
		)
		(stroke
			(width 0)
			(type solid)
		)
		(fill yes)
		(layer "In4.Cu")
		(net "P5E_PEX1_STN1_TX_DN<26>")
	)
	(gr_poly
		(pts
			(arc
				(start 185.45302 -274.049744)
				(mid 185.04662 -274.049744)
				(end 185.45302 -274.049744)
			)
		)
		(stroke
			(width 0)
			(type solid)
		)
		(fill yes)
		(layer "In4.Cu")
		(net "P5E_PEX1_STN1_RX_DP<26>")
	)
	(gr_poly
		(pts
			(arc
				(start 185.45302 -273.099784)
				(mid 185.04662 -273.099784)
				(end 185.45302 -273.099784)
			)
		)
		(stroke
			(width 0)
			(type solid)
		)
		(fill yes)
		(layer "In4.Cu")
		(net "P5E_PEX1_STN1_RX_DN<26>")
	)
	(gr_poly
		(pts
			(arc
				(start 185.453274 -318.699896)
				(mid 185.046874 -318.699896)
				(end 185.453274 -318.699896)
			)
		)
		(stroke
			(width 0)
			(type solid)
		)
		(fill yes)
		(layer "In4.Cu")
		(net "P5E_PEX1_STN5_RX_DN<91>")
	)
	(gr_poly
		(pts
			(arc
				(start 185.453274 -317.749936)
				(mid 185.046874 -317.749936)
				(end 185.453274 -317.749936)
			)
		)
		(stroke
			(width 0)
			(type solid)
		)
		(fill yes)
		(layer "In4.Cu")
		(net "P5E_PEX1_STN5_RX_DP<91>")
	)
	(gr_poly
		(pts
			(arc
				(start 185.453274 -313.949842)
				(mid 185.046874 -313.949842)
				(end 185.453274 -313.949842)
			)
		)
		(stroke
			(width 0)
			(type solid)
		)
		(fill yes)
		(layer "In4.Cu")
		(net "P5E_PEX1_STN5_TX_DN<91>")
	)
	(gr_poly
		(pts
			(arc
				(start 185.453274 -312.999882)
				(mid 185.046874 -312.999882)
				(end 185.453274 -312.999882)
			)
		)
		(stroke
			(width 0)
			(type solid)
		)
		(fill yes)
		(layer "In4.Cu")
		(net "P5E_PEX1_STN5_TX_DP<91>")
	)
	(gr_poly
		(pts
			(arc
				(start 186.402726 -275.949918)
				(mid 185.996326 -275.949918)
				(end 186.402726 -275.949918)
			)
		)
		(stroke
			(width 0)
			(type solid)
		)
		(fill yes)
		(layer "In4.Cu")
		(net "P5E_PEX1_STN1_RX_DP<27>")
	)
	(gr_poly
		(pts
			(arc
				(start 186.402726 -274.999958)
				(mid 185.996326 -274.999958)
				(end 186.402726 -274.999958)
			)
		)
		(stroke
			(width 0)
			(type solid)
		)
		(fill yes)
		(layer "In4.Cu")
		(net "P5E_PEX1_STN1_RX_DN<27>")
	)
	(gr_poly
		(pts
			(arc
				(start 186.403234 -316.799722)
				(mid 185.996834 -316.799722)
				(end 186.403234 -316.799722)
			)
		)
		(stroke
			(width 0)
			(type solid)
		)
		(fill yes)
		(layer "In4.Cu")
		(net "P5E_PEX1_STN5_RX_DN<92>")
	)
	(gr_poly
		(pts
			(arc
				(start 186.403234 -315.849762)
				(mid 185.996834 -315.849762)
				(end 186.403234 -315.849762)
			)
		)
		(stroke
			(width 0)
			(type solid)
		)
		(fill yes)
		(layer "In4.Cu")
		(net "P5E_PEX1_STN5_RX_DP<92>")
	)
	(gr_poly
		(pts
			(arc
				(start 186.403234 -312.049922)
				(mid 185.996834 -312.049922)
				(end 186.403234 -312.049922)
			)
		)
		(stroke
			(width 0)
			(type solid)
		)
		(fill yes)
		(layer "In4.Cu")
		(net "P5E_PEX1_STN5_TX_DN<92>")
	)
	(gr_poly
		(pts
			(arc
				(start 186.403234 -311.099962)
				(mid 185.996834 -311.099962)
				(end 186.403234 -311.099962)
			)
		)
		(stroke
			(width 0)
			(type solid)
		)
		(fill yes)
		(layer "In4.Cu")
		(net "P5E_PEX1_STN5_TX_DP<92>")
	)
	(gr_poly
		(pts
			(arc
				(start 186.403234 -280.699718)
				(mid 185.996834 -280.699718)
				(end 186.403234 -280.699718)
			)
		)
		(stroke
			(width 0)
			(type solid)
		)
		(fill yes)
		(layer "In4.Cu")
		(net "P5E_PEX1_STN1_TX_DN<27>")
	)
	(gr_poly
		(pts
			(arc
				(start 186.403234 -279.749504)
				(mid 185.996834 -279.749504)
				(end 186.403234 -279.749504)
			)
		)
		(stroke
			(width 0)
			(type solid)
		)
		(fill yes)
		(layer "In4.Cu")
		(net "P5E_PEX1_STN1_TX_DP<27>")
	)
	(gr_poly
		(pts
			(arc
				(start 187.35294 -278.799798)
				(mid 186.94654 -278.799798)
				(end 187.35294 -278.799798)
			)
		)
		(stroke
			(width 0)
			(type solid)
		)
		(fill yes)
		(layer "In4.Cu")
		(net "P5E_PEX1_STN1_TX_DP<28>")
	)
	(gr_poly
		(pts
			(arc
				(start 187.35294 -277.849838)
				(mid 186.94654 -277.849838)
				(end 187.35294 -277.849838)
			)
		)
		(stroke
			(width 0)
			(type solid)
		)
		(fill yes)
		(layer "In4.Cu")
		(net "P5E_PEX1_STN1_TX_DN<28>")
	)
	(gr_poly
		(pts
			(arc
				(start 187.35294 -274.049744)
				(mid 186.94654 -274.049744)
				(end 187.35294 -274.049744)
			)
		)
		(stroke
			(width 0)
			(type solid)
		)
		(fill yes)
		(layer "In4.Cu")
		(net "P5E_PEX1_STN1_RX_DP<28>")
	)
	(gr_poly
		(pts
			(arc
				(start 187.35294 -273.099784)
				(mid 186.94654 -273.099784)
				(end 187.35294 -273.099784)
			)
		)
		(stroke
			(width 0)
			(type solid)
		)
		(fill yes)
		(layer "In4.Cu")
		(net "P5E_PEX1_STN1_RX_DN<28>")
	)
	(gr_poly
		(pts
			(arc
				(start 187.353194 -318.699896)
				(mid 186.946794 -318.699896)
				(end 187.353194 -318.699896)
			)
		)
		(stroke
			(width 0)
			(type solid)
		)
		(fill yes)
		(layer "In4.Cu")
		(net "P5E_PEX1_STN5_RX_DN<93>")
	)
	(gr_poly
		(pts
			(arc
				(start 187.353194 -317.749936)
				(mid 186.946794 -317.749936)
				(end 187.353194 -317.749936)
			)
		)
		(stroke
			(width 0)
			(type solid)
		)
		(fill yes)
		(layer "In4.Cu")
		(net "P5E_PEX1_STN5_RX_DP<93>")
	)
	(gr_poly
		(pts
			(arc
				(start 187.353194 -313.949842)
				(mid 186.946794 -313.949842)
				(end 187.353194 -313.949842)
			)
		)
		(stroke
			(width 0)
			(type solid)
		)
		(fill yes)
		(layer "In4.Cu")
		(net "P5E_PEX1_STN5_TX_DN<93>")
	)
	(gr_poly
		(pts
			(arc
				(start 187.353194 -312.999882)
				(mid 186.946794 -312.999882)
				(end 187.353194 -312.999882)
			)
		)
		(stroke
			(width 0)
			(type solid)
		)
		(fill yes)
		(layer "In4.Cu")
		(net "P5E_PEX1_STN5_TX_DP<93>")
	)
	(gr_poly
		(pts
			(arc
				(start 188.3029 -275.949664)
				(mid 187.8965 -275.949664)
				(end 188.3029 -275.949664)
			)
		)
		(stroke
			(width 0)
			(type solid)
		)
		(fill yes)
		(layer "In4.Cu")
		(net "P5E_PEX1_STN1_RX_DP<29>")
	)
	(gr_poly
		(pts
			(arc
				(start 188.3029 -274.999704)
				(mid 187.8965 -274.999704)
				(end 188.3029 -274.999704)
			)
		)
		(stroke
			(width 0)
			(type solid)
		)
		(fill yes)
		(layer "In4.Cu")
		(net "P5E_PEX1_STN1_RX_DN<29>")
	)
	(gr_poly
		(pts
			(arc
				(start 188.303154 -316.799722)
				(mid 187.896754 -316.799722)
				(end 188.303154 -316.799722)
			)
		)
		(stroke
			(width 0)
			(type solid)
		)
		(fill yes)
		(layer "In4.Cu")
		(net "P5E_PEX1_STN5_RX_DN<94>")
	)
	(gr_poly
		(pts
			(arc
				(start 188.303154 -315.849762)
				(mid 187.896754 -315.849762)
				(end 188.303154 -315.849762)
			)
		)
		(stroke
			(width 0)
			(type solid)
		)
		(fill yes)
		(layer "In4.Cu")
		(net "P5E_PEX1_STN5_RX_DP<94>")
	)
	(gr_poly
		(pts
			(arc
				(start 188.303154 -312.049922)
				(mid 187.896754 -312.049922)
				(end 188.303154 -312.049922)
			)
		)
		(stroke
			(width 0)
			(type solid)
		)
		(fill yes)
		(layer "In4.Cu")
		(net "P5E_PEX1_STN5_TX_DN<94>")
	)
	(gr_poly
		(pts
			(arc
				(start 188.303154 -311.099962)
				(mid 187.896754 -311.099962)
				(end 188.303154 -311.099962)
			)
		)
		(stroke
			(width 0)
			(type solid)
		)
		(fill yes)
		(layer "In4.Cu")
		(net "P5E_PEX1_STN5_TX_DP<94>")
	)
	(gr_poly
		(pts
			(arc
				(start 188.303154 -280.699718)
				(mid 187.896754 -280.699718)
				(end 188.303154 -280.699718)
			)
		)
		(stroke
			(width 0)
			(type solid)
		)
		(fill yes)
		(layer "In4.Cu")
		(net "P5E_PEX1_STN1_TX_DN<29>")
	)
	(gr_poly
		(pts
			(arc
				(start 188.303154 -279.749504)
				(mid 187.896754 -279.749504)
				(end 188.303154 -279.749504)
			)
		)
		(stroke
			(width 0)
			(type solid)
		)
		(fill yes)
		(layer "In4.Cu")
		(net "P5E_PEX1_STN1_TX_DP<29>")
	)
	(gr_poly
		(pts
			(arc
				(start 189.25286 -278.799798)
				(mid 188.84646 -278.799798)
				(end 189.25286 -278.799798)
			)
		)
		(stroke
			(width 0)
			(type solid)
		)
		(fill yes)
		(layer "In4.Cu")
		(net "P5E_PEX1_STN1_TX_DP<30>")
	)
	(gr_poly
		(pts
			(arc
				(start 189.25286 -277.849838)
				(mid 188.84646 -277.849838)
				(end 189.25286 -277.849838)
			)
		)
		(stroke
			(width 0)
			(type solid)
		)
		(fill yes)
		(layer "In4.Cu")
		(net "P5E_PEX1_STN1_TX_DN<30>")
	)
	(gr_poly
		(pts
			(arc
				(start 189.25286 -274.049744)
				(mid 188.84646 -274.049744)
				(end 189.25286 -274.049744)
			)
		)
		(stroke
			(width 0)
			(type solid)
		)
		(fill yes)
		(layer "In4.Cu")
		(net "P5E_PEX1_STN1_RX_DP<30>")
	)
	(gr_poly
		(pts
			(arc
				(start 189.25286 -273.099784)
				(mid 188.84646 -273.099784)
				(end 189.25286 -273.099784)
			)
		)
		(stroke
			(width 0)
			(type solid)
		)
		(fill yes)
		(layer "In4.Cu")
		(net "P5E_PEX1_STN1_RX_DN<30>")
	)
	(gr_poly
		(pts
			(arc
				(start 189.253114 -318.699896)
				(mid 188.846714 -318.699896)
				(end 189.253114 -318.699896)
			)
		)
		(stroke
			(width 0)
			(type solid)
		)
		(fill yes)
		(layer "In4.Cu")
		(net "P5E_PEX1_STN5_RX_DN<95>")
	)
	(gr_poly
		(pts
			(arc
				(start 189.253114 -317.749936)
				(mid 188.846714 -317.749936)
				(end 189.253114 -317.749936)
			)
		)
		(stroke
			(width 0)
			(type solid)
		)
		(fill yes)
		(layer "In4.Cu")
		(net "P5E_PEX1_STN5_RX_DP<95>")
	)
	(gr_poly
		(pts
			(arc
				(start 189.253114 -313.949842)
				(mid 188.846714 -313.949842)
				(end 189.253114 -313.949842)
			)
		)
		(stroke
			(width 0)
			(type solid)
		)
		(fill yes)
		(layer "In4.Cu")
		(net "P5E_PEX1_STN5_TX_DN<95>")
	)
	(gr_poly
		(pts
			(arc
				(start 189.253114 -312.999882)
				(mid 188.846714 -312.999882)
				(end 189.253114 -312.999882)
			)
		)
		(stroke
			(width 0)
			(type solid)
		)
		(fill yes)
		(layer "In4.Cu")
		(net "P5E_PEX1_STN5_TX_DP<95>")
	)
	(gr_poly
		(pts
			(arc
				(start 190.20282 -275.949918)
				(mid 189.79642 -275.949918)
				(end 190.20282 -275.949918)
			)
		)
		(stroke
			(width 0)
			(type solid)
		)
		(fill yes)
		(layer "In4.Cu")
		(net "P5E_PEX1_STN1_RX_DP<31>")
	)
	(gr_poly
		(pts
			(arc
				(start 190.20282 -274.999958)
				(mid 189.79642 -274.999958)
				(end 190.20282 -274.999958)
			)
		)
		(stroke
			(width 0)
			(type solid)
		)
		(fill yes)
		(layer "In4.Cu")
		(net "P5E_PEX1_STN1_RX_DN<31>")
	)
	(gr_poly
		(pts
			(arc
				(start 190.203074 -316.799722)
				(mid 189.796674 -316.799722)
				(end 190.203074 -316.799722)
			)
		)
		(stroke
			(width 0)
			(type solid)
		)
		(fill yes)
		(layer "In4.Cu")
		(net "P5E_PEX1_STN4_RX_DN<79>")
	)
	(gr_poly
		(pts
			(arc
				(start 190.203074 -315.849762)
				(mid 189.796674 -315.849762)
				(end 190.203074 -315.849762)
			)
		)
		(stroke
			(width 0)
			(type solid)
		)
		(fill yes)
		(layer "In4.Cu")
		(net "P5E_PEX1_STN4_RX_DP<79>")
	)
	(gr_poly
		(pts
			(arc
				(start 190.203074 -312.049922)
				(mid 189.796674 -312.049922)
				(end 190.203074 -312.049922)
			)
		)
		(stroke
			(width 0)
			(type solid)
		)
		(fill yes)
		(layer "In4.Cu")
		(net "P5E_PEX1_STN4_TX_DN<79>")
	)
	(gr_poly
		(pts
			(arc
				(start 190.203074 -311.099962)
				(mid 189.796674 -311.099962)
				(end 190.203074 -311.099962)
			)
		)
		(stroke
			(width 0)
			(type solid)
		)
		(fill yes)
		(layer "In4.Cu")
		(net "P5E_PEX1_STN4_TX_DP<79>")
	)
	(gr_poly
		(pts
			(arc
				(start 190.203074 -280.699718)
				(mid 189.796674 -280.699718)
				(end 190.203074 -280.699718)
			)
		)
		(stroke
			(width 0)
			(type solid)
		)
		(fill yes)
		(layer "In4.Cu")
		(net "P5E_PEX1_STN1_TX_DN<31>")
	)
	(gr_poly
		(pts
			(arc
				(start 190.203074 -279.749504)
				(mid 189.796674 -279.749504)
				(end 190.203074 -279.749504)
			)
		)
		(stroke
			(width 0)
			(type solid)
		)
		(fill yes)
		(layer "In4.Cu")
		(net "P5E_PEX1_STN1_TX_DP<31>")
	)
	(gr_poly
		(pts
			(arc
				(start 191.153034 -287.349946)
				(mid 190.746634 -287.349946)
				(end 191.153034 -287.349946)
			)
		)
		(stroke
			(width 0)
			(type solid)
		)
		(fill yes)
		(layer "In4.Cu")
		(net "P5E_PEX1_STN0_TX_DP<1>")
	)
	(gr_poly
		(pts
			(arc
				(start 191.153034 -285.449772)
				(mid 190.746634 -285.449772)
				(end 191.153034 -285.449772)
			)
		)
		(stroke
			(width 0)
			(type solid)
		)
		(fill yes)
		(layer "In4.Cu")
		(net "P5E_PEX1_STN0_TX_DP<3>")
	)
	(gr_poly
		(pts
			(arc
				(start 191.153034 -283.549852)
				(mid 190.746634 -283.549852)
				(end 191.153034 -283.549852)
			)
		)
		(stroke
			(width 0)
			(type solid)
		)
		(fill yes)
		(layer "In4.Cu")
		(net "P5E_PEX1_STN0_TX_DP<5>")
	)
	(gr_poly
		(pts
			(arc
				(start 191.153034 -278.799798)
				(mid 190.746634 -278.799798)
				(end 191.153034 -278.799798)
			)
		)
		(stroke
			(width 0)
			(type solid)
		)
		(fill yes)
		(layer "In4.Cu")
		(net "P5E_PEX1_STN0_TX_DP<15>")
	)
	(gr_poly
		(pts
			(arc
				(start 191.153034 -277.849838)
				(mid 190.746634 -277.849838)
				(end 191.153034 -277.849838)
			)
		)
		(stroke
			(width 0)
			(type solid)
		)
		(fill yes)
		(layer "In4.Cu")
		(net "P5E_PEX1_STN0_TX_DN<15>")
	)
	(gr_poly
		(pts
			(arc
				(start 191.153034 -274.049744)
				(mid 190.746634 -274.049744)
				(end 191.153034 -274.049744)
			)
		)
		(stroke
			(width 0)
			(type solid)
		)
		(fill yes)
		(layer "In4.Cu")
		(net "P5E_PEX1_STN0_RX_DP<15>")
	)
	(gr_poly
		(pts
			(arc
				(start 191.153034 -273.099784)
				(mid 190.746634 -273.099784)
				(end 191.153034 -273.099784)
			)
		)
		(stroke
			(width 0)
			(type solid)
		)
		(fill yes)
		(layer "In4.Cu")
		(net "P5E_PEX1_STN0_RX_DN<15>")
	)
	(gr_poly
		(pts
			(arc
				(start 191.153288 -318.699896)
				(mid 190.746888 -318.699896)
				(end 191.153288 -318.699896)
			)
		)
		(stroke
			(width 0)
			(type solid)
		)
		(fill yes)
		(layer "In4.Cu")
		(net "P5E_PEX1_STN4_RX_DN<78>")
	)
	(gr_poly
		(pts
			(arc
				(start 191.153288 -317.749936)
				(mid 190.746888 -317.749936)
				(end 191.153288 -317.749936)
			)
		)
		(stroke
			(width 0)
			(type solid)
		)
		(fill yes)
		(layer "In4.Cu")
		(net "P5E_PEX1_STN4_RX_DP<78>")
	)
	(gr_poly
		(pts
			(arc
				(start 191.153288 -313.949842)
				(mid 190.746888 -313.949842)
				(end 191.153288 -313.949842)
			)
		)
		(stroke
			(width 0)
			(type solid)
		)
		(fill yes)
		(layer "In4.Cu")
		(net "P5E_PEX1_STN4_TX_DN<78>")
	)
	(gr_poly
		(pts
			(arc
				(start 191.153288 -312.999882)
				(mid 190.746888 -312.999882)
				(end 191.153288 -312.999882)
			)
		)
		(stroke
			(width 0)
			(type solid)
		)
		(fill yes)
		(layer "In4.Cu")
		(net "P5E_PEX1_STN4_TX_DP<78>")
	)
	(gr_poly
		(pts
			(arc
				(start 191.153288 -308.249828)
				(mid 190.746888 -308.249828)
				(end 191.153288 -308.249828)
			)
		)
		(stroke
			(width 0)
			(type solid)
		)
		(fill yes)
		(layer "In4.Cu")
		(net "P5E_PEX1_STN4_TX_DP<68>")
	)
	(gr_poly
		(pts
			(arc
				(start 191.153288 -306.349908)
				(mid 190.746888 -306.349908)
				(end 191.153288 -306.349908)
			)
		)
		(stroke
			(width 0)
			(type solid)
		)
		(fill yes)
		(layer "In4.Cu")
		(net "P5E_PEX1_STN4_TX_DP<66>")
	)
	(gr_poly
		(pts
			(arc
				(start 191.153288 -304.449734)
				(mid 190.746888 -304.449734)
				(end 191.153288 -304.449734)
			)
		)
		(stroke
			(width 0)
			(type solid)
		)
		(fill yes)
		(layer "In4.Cu")
		(net "P5E_PEX1_STN4_TX_DP<64>")
	)
	(gr_poly
		(pts
			(arc
				(start 192.102994 -275.949664)
				(mid 191.696594 -275.949664)
				(end 192.102994 -275.949664)
			)
		)
		(stroke
			(width 0)
			(type solid)
		)
		(fill yes)
		(layer "In4.Cu")
		(net "P5E_PEX1_STN0_RX_DP<14>")
	)
	(gr_poly
		(pts
			(arc
				(start 192.102994 -274.999704)
				(mid 191.696594 -274.999704)
				(end 192.102994 -274.999704)
			)
		)
		(stroke
			(width 0)
			(type solid)
		)
		(fill yes)
		(layer "In4.Cu")
		(net "P5E_PEX1_STN0_RX_DN<14>")
	)
	(gr_poly
		(pts
			(arc
				(start 192.103248 -316.799722)
				(mid 191.696848 -316.799722)
				(end 192.103248 -316.799722)
			)
		)
		(stroke
			(width 0)
			(type solid)
		)
		(fill yes)
		(layer "In4.Cu")
		(net "P5E_PEX1_STN4_RX_DN<77>")
	)
	(gr_poly
		(pts
			(arc
				(start 192.103248 -315.849762)
				(mid 191.696848 -315.849762)
				(end 192.103248 -315.849762)
			)
		)
		(stroke
			(width 0)
			(type solid)
		)
		(fill yes)
		(layer "In4.Cu")
		(net "P5E_PEX1_STN4_RX_DP<77>")
	)
	(gr_poly
		(pts
			(arc
				(start 192.103248 -312.049922)
				(mid 191.696848 -312.049922)
				(end 192.103248 -312.049922)
			)
		)
		(stroke
			(width 0)
			(type solid)
		)
		(fill yes)
		(layer "In4.Cu")
		(net "P5E_PEX1_STN4_TX_DN<77>")
	)
	(gr_poly
		(pts
			(arc
				(start 192.103248 -311.099962)
				(mid 191.696848 -311.099962)
				(end 192.103248 -311.099962)
			)
		)
		(stroke
			(width 0)
			(type solid)
		)
		(fill yes)
		(layer "In4.Cu")
		(net "P5E_PEX1_STN4_TX_DP<77>")
	)
	(gr_poly
		(pts
			(arc
				(start 192.103248 -308.249828)
				(mid 191.696848 -308.249828)
				(end 192.103248 -308.249828)
			)
		)
		(stroke
			(width 0)
			(type solid)
		)
		(fill yes)
		(layer "In4.Cu")
		(net "P5E_PEX1_STN4_TX_DN<68>")
	)
	(gr_poly
		(pts
			(arc
				(start 192.103248 -306.349908)
				(mid 191.696848 -306.349908)
				(end 192.103248 -306.349908)
			)
		)
		(stroke
			(width 0)
			(type solid)
		)
		(fill yes)
		(layer "In4.Cu")
		(net "P5E_PEX1_STN4_TX_DN<66>")
	)
	(gr_poly
		(pts
			(arc
				(start 192.103248 -304.449734)
				(mid 191.696848 -304.449734)
				(end 192.103248 -304.449734)
			)
		)
		(stroke
			(width 0)
			(type solid)
		)
		(fill yes)
		(layer "In4.Cu")
		(net "P5E_PEX1_STN4_TX_DN<64>")
	)
	(gr_poly
		(pts
			(arc
				(start 192.103248 -287.349946)
				(mid 191.696848 -287.349946)
				(end 192.103248 -287.349946)
			)
		)
		(stroke
			(width 0)
			(type solid)
		)
		(fill yes)
		(layer "In4.Cu")
		(net "P5E_PEX1_STN0_TX_DN<1>")
	)
	(gr_poly
		(pts
			(arc
				(start 192.103248 -285.449772)
				(mid 191.696848 -285.449772)
				(end 192.103248 -285.449772)
			)
		)
		(stroke
			(width 0)
			(type solid)
		)
		(fill yes)
		(layer "In4.Cu")
		(net "P5E_PEX1_STN0_TX_DN<3>")
	)
	(gr_poly
		(pts
			(arc
				(start 192.103248 -283.549852)
				(mid 191.696848 -283.549852)
				(end 192.103248 -283.549852)
			)
		)
		(stroke
			(width 0)
			(type solid)
		)
		(fill yes)
		(layer "In4.Cu")
		(net "P5E_PEX1_STN0_TX_DN<5>")
	)
	(gr_poly
		(pts
			(arc
				(start 192.103248 -280.699718)
				(mid 191.696848 -280.699718)
				(end 192.103248 -280.699718)
			)
		)
		(stroke
			(width 0)
			(type solid)
		)
		(fill yes)
		(layer "In4.Cu")
		(net "P5E_PEX1_STN0_TX_DN<14>")
	)
	(gr_poly
		(pts
			(arc
				(start 192.103248 -279.749504)
				(mid 191.696848 -279.749504)
				(end 192.103248 -279.749504)
			)
		)
		(stroke
			(width 0)
			(type solid)
		)
		(fill yes)
		(layer "In4.Cu")
		(net "P5E_PEX1_STN0_TX_DP<14>")
	)
	(gr_poly
		(pts
			(arc
				(start 193.052954 -278.799798)
				(mid 192.646554 -278.799798)
				(end 193.052954 -278.799798)
			)
		)
		(stroke
			(width 0)
			(type solid)
		)
		(fill yes)
		(layer "In4.Cu")
		(net "P5E_PEX1_STN0_TX_DP<13>")
	)
	(gr_poly
		(pts
			(arc
				(start 193.052954 -277.849838)
				(mid 192.646554 -277.849838)
				(end 193.052954 -277.849838)
			)
		)
		(stroke
			(width 0)
			(type solid)
		)
		(fill yes)
		(layer "In4.Cu")
		(net "P5E_PEX1_STN0_TX_DN<13>")
	)
	(gr_poly
		(pts
			(arc
				(start 193.052954 -274.049744)
				(mid 192.646554 -274.049744)
				(end 193.052954 -274.049744)
			)
		)
		(stroke
			(width 0)
			(type solid)
		)
		(fill yes)
		(layer "In4.Cu")
		(net "P5E_PEX1_STN0_RX_DP<13>")
	)
	(gr_poly
		(pts
			(arc
				(start 193.052954 -273.099784)
				(mid 192.646554 -273.099784)
				(end 193.052954 -273.099784)
			)
		)
		(stroke
			(width 0)
			(type solid)
		)
		(fill yes)
		(layer "In4.Cu")
		(net "P5E_PEX1_STN0_RX_DN<13>")
	)
	(gr_poly
		(pts
			(arc
				(start 193.053208 -318.699896)
				(mid 192.646808 -318.699896)
				(end 193.053208 -318.699896)
			)
		)
		(stroke
			(width 0)
			(type solid)
		)
		(fill yes)
		(layer "In4.Cu")
		(net "P5E_PEX1_STN4_RX_DN<76>")
	)
	(gr_poly
		(pts
			(arc
				(start 193.053208 -317.749936)
				(mid 192.646808 -317.749936)
				(end 193.053208 -317.749936)
			)
		)
		(stroke
			(width 0)
			(type solid)
		)
		(fill yes)
		(layer "In4.Cu")
		(net "P5E_PEX1_STN4_RX_DP<76>")
	)
	(gr_poly
		(pts
			(arc
				(start 193.053208 -313.949842)
				(mid 192.646808 -313.949842)
				(end 193.053208 -313.949842)
			)
		)
		(stroke
			(width 0)
			(type solid)
		)
		(fill yes)
		(layer "In4.Cu")
		(net "P5E_PEX1_STN4_TX_DN<76>")
	)
	(gr_poly
		(pts
			(arc
				(start 193.053208 -312.999882)
				(mid 192.646808 -312.999882)
				(end 193.053208 -312.999882)
			)
		)
		(stroke
			(width 0)
			(type solid)
		)
		(fill yes)
		(layer "In4.Cu")
		(net "P5E_PEX1_STN4_TX_DP<76>")
	)
	(gr_poly
		(pts
			(arc
				(start 193.053208 -309.199788)
				(mid 192.646808 -309.199788)
				(end 193.053208 -309.199788)
			)
		)
		(stroke
			(width 0)
			(type solid)
		)
		(fill yes)
		(layer "In4.Cu")
		(net "P5E_PEX1_STN4_TX_DP<69>")
	)
	(gr_poly
		(pts
			(arc
				(start 193.053208 -307.299868)
				(mid 192.646808 -307.299868)
				(end 193.053208 -307.299868)
			)
		)
		(stroke
			(width 0)
			(type solid)
		)
		(fill yes)
		(layer "In4.Cu")
		(net "P5E_PEX1_STN4_TX_DP<67>")
	)
	(gr_poly
		(pts
			(arc
				(start 193.053208 -305.399948)
				(mid 192.646808 -305.399948)
				(end 193.053208 -305.399948)
			)
		)
		(stroke
			(width 0)
			(type solid)
		)
		(fill yes)
		(layer "In4.Cu")
		(net "P5E_PEX1_STN4_TX_DP<65>")
	)
	(gr_poly
		(pts
			(arc
				(start 193.053208 -288.299906)
				(mid 192.646808 -288.299906)
				(end 193.053208 -288.299906)
			)
		)
		(stroke
			(width 0)
			(type solid)
		)
		(fill yes)
		(layer "In4.Cu")
		(net "P5E_PEX1_STN0_TX_DP<0>")
	)
	(gr_poly
		(pts
			(arc
				(start 193.053208 -286.399986)
				(mid 192.646808 -286.399986)
				(end 193.053208 -286.399986)
			)
		)
		(stroke
			(width 0)
			(type solid)
		)
		(fill yes)
		(layer "In4.Cu")
		(net "P5E_PEX1_STN0_TX_DP<2>")
	)
	(gr_poly
		(pts
			(arc
				(start 193.053208 -284.499812)
				(mid 192.646808 -284.499812)
				(end 193.053208 -284.499812)
			)
		)
		(stroke
			(width 0)
			(type solid)
		)
		(fill yes)
		(layer "In4.Cu")
		(net "P5E_PEX1_STN0_TX_DP<4>")
	)
	(gr_poly
		(pts
			(arc
				(start 193.053208 -282.599892)
				(mid 192.646808 -282.599892)
				(end 193.053208 -282.599892)
			)
		)
		(stroke
			(width 0)
			(type solid)
		)
		(fill yes)
		(layer "In4.Cu")
		(net "P5E_PEX1_STN0_TX_DP<6>")
	)
	(gr_poly
		(pts
			(arc
				(start 194.002914 -275.949918)
				(mid 193.596514 -275.949918)
				(end 194.002914 -275.949918)
			)
		)
		(stroke
			(width 0)
			(type solid)
		)
		(fill yes)
		(layer "In4.Cu")
		(net "P5E_PEX1_STN0_RX_DP<12>")
	)
	(gr_poly
		(pts
			(arc
				(start 194.002914 -274.999958)
				(mid 193.596514 -274.999958)
				(end 194.002914 -274.999958)
			)
		)
		(stroke
			(width 0)
			(type solid)
		)
		(fill yes)
		(layer "In4.Cu")
		(net "P5E_PEX1_STN0_RX_DN<12>")
	)
	(gr_poly
		(pts
			(arc
				(start 194.003168 -316.799722)
				(mid 193.596768 -316.799722)
				(end 194.003168 -316.799722)
			)
		)
		(stroke
			(width 0)
			(type solid)
		)
		(fill yes)
		(layer "In4.Cu")
		(net "P5E_PEX1_STN4_RX_DN<75>")
	)
	(gr_poly
		(pts
			(arc
				(start 194.003168 -315.849762)
				(mid 193.596768 -315.849762)
				(end 194.003168 -315.849762)
			)
		)
		(stroke
			(width 0)
			(type solid)
		)
		(fill yes)
		(layer "In4.Cu")
		(net "P5E_PEX1_STN4_RX_DP<75>")
	)
	(gr_poly
		(pts
			(arc
				(start 194.003168 -312.049922)
				(mid 193.596768 -312.049922)
				(end 194.003168 -312.049922)
			)
		)
		(stroke
			(width 0)
			(type solid)
		)
		(fill yes)
		(layer "In4.Cu")
		(net "P5E_PEX1_STN4_TX_DN<75>")
	)
	(gr_poly
		(pts
			(arc
				(start 194.003168 -311.099962)
				(mid 193.596768 -311.099962)
				(end 194.003168 -311.099962)
			)
		)
		(stroke
			(width 0)
			(type solid)
		)
		(fill yes)
		(layer "In4.Cu")
		(net "P5E_PEX1_STN4_TX_DP<75>")
	)
	(gr_poly
		(pts
			(arc
				(start 194.003168 -309.199788)
				(mid 193.596768 -309.199788)
				(end 194.003168 -309.199788)
			)
		)
		(stroke
			(width 0)
			(type solid)
		)
		(fill yes)
		(layer "In4.Cu")
		(net "P5E_PEX1_STN4_TX_DN<69>")
	)
	(gr_poly
		(pts
			(arc
				(start 194.003168 -307.299868)
				(mid 193.596768 -307.299868)
				(end 194.003168 -307.299868)
			)
		)
		(stroke
			(width 0)
			(type solid)
		)
		(fill yes)
		(layer "In4.Cu")
		(net "P5E_PEX1_STN4_TX_DN<67>")
	)
	(gr_poly
		(pts
			(arc
				(start 194.003168 -305.399948)
				(mid 193.596768 -305.399948)
				(end 194.003168 -305.399948)
			)
		)
		(stroke
			(width 0)
			(type solid)
		)
		(fill yes)
		(layer "In4.Cu")
		(net "P5E_PEX1_STN4_TX_DN<65>")
	)
	(gr_poly
		(pts
			(arc
				(start 194.003168 -288.299906)
				(mid 193.596768 -288.299906)
				(end 194.003168 -288.299906)
			)
		)
		(stroke
			(width 0)
			(type solid)
		)
		(fill yes)
		(layer "In4.Cu")
		(net "P5E_PEX1_STN0_TX_DN<0>")
	)
	(gr_poly
		(pts
			(arc
				(start 194.003168 -286.399986)
				(mid 193.596768 -286.399986)
				(end 194.003168 -286.399986)
			)
		)
		(stroke
			(width 0)
			(type solid)
		)
		(fill yes)
		(layer "In4.Cu")
		(net "P5E_PEX1_STN0_TX_DN<2>")
	)
	(gr_poly
		(pts
			(arc
				(start 194.003168 -284.499812)
				(mid 193.596768 -284.499812)
				(end 194.003168 -284.499812)
			)
		)
		(stroke
			(width 0)
			(type solid)
		)
		(fill yes)
		(layer "In4.Cu")
		(net "P5E_PEX1_STN0_TX_DN<4>")
	)
	(gr_poly
		(pts
			(arc
				(start 194.003168 -282.599892)
				(mid 193.596768 -282.599892)
				(end 194.003168 -282.599892)
			)
		)
		(stroke
			(width 0)
			(type solid)
		)
		(fill yes)
		(layer "In4.Cu")
		(net "P5E_PEX1_STN0_TX_DN<6>")
	)
	(gr_poly
		(pts
			(arc
				(start 194.003168 -280.699718)
				(mid 193.596768 -280.699718)
				(end 194.003168 -280.699718)
			)
		)
		(stroke
			(width 0)
			(type solid)
		)
		(fill yes)
		(layer "In4.Cu")
		(net "P5E_PEX1_STN0_TX_DN<12>")
	)
	(gr_poly
		(pts
			(arc
				(start 194.003168 -279.749504)
				(mid 193.596768 -279.749504)
				(end 194.003168 -279.749504)
			)
		)
		(stroke
			(width 0)
			(type solid)
		)
		(fill yes)
		(layer "In4.Cu")
		(net "P5E_PEX1_STN0_TX_DP<12>")
	)
	(gr_poly
		(pts
			(arc
				(start 194.952874 -278.799798)
				(mid 194.546474 -278.799798)
				(end 194.952874 -278.799798)
			)
		)
		(stroke
			(width 0)
			(type solid)
		)
		(fill yes)
		(layer "In4.Cu")
		(net "P5E_PEX1_STN0_TX_DP<11>")
	)
	(gr_poly
		(pts
			(arc
				(start 194.952874 -277.849838)
				(mid 194.546474 -277.849838)
				(end 194.952874 -277.849838)
			)
		)
		(stroke
			(width 0)
			(type solid)
		)
		(fill yes)
		(layer "In4.Cu")
		(net "P5E_PEX1_STN0_TX_DN<11>")
	)
	(gr_poly
		(pts
			(arc
				(start 194.952874 -274.049744)
				(mid 194.546474 -274.049744)
				(end 194.952874 -274.049744)
			)
		)
		(stroke
			(width 0)
			(type solid)
		)
		(fill yes)
		(layer "In4.Cu")
		(net "P5E_PEX1_STN0_RX_DP<11>")
	)
	(gr_poly
		(pts
			(arc
				(start 194.952874 -273.099784)
				(mid 194.546474 -273.099784)
				(end 194.952874 -273.099784)
			)
		)
		(stroke
			(width 0)
			(type solid)
		)
		(fill yes)
		(layer "In4.Cu")
		(net "P5E_PEX1_STN0_RX_DN<11>")
	)
	(gr_poly
		(pts
			(arc
				(start 194.953128 -318.699896)
				(mid 194.546728 -318.699896)
				(end 194.953128 -318.699896)
			)
		)
		(stroke
			(width 0)
			(type solid)
		)
		(fill yes)
		(layer "In4.Cu")
		(net "P5E_PEX1_STN4_RX_DN<74>")
	)
	(gr_poly
		(pts
			(arc
				(start 194.953128 -317.749936)
				(mid 194.546728 -317.749936)
				(end 194.953128 -317.749936)
			)
		)
		(stroke
			(width 0)
			(type solid)
		)
		(fill yes)
		(layer "In4.Cu")
		(net "P5E_PEX1_STN4_RX_DP<74>")
	)
	(gr_poly
		(pts
			(arc
				(start 194.953128 -313.949842)
				(mid 194.546728 -313.949842)
				(end 194.953128 -313.949842)
			)
		)
		(stroke
			(width 0)
			(type solid)
		)
		(fill yes)
		(layer "In4.Cu")
		(net "P5E_PEX1_STN4_TX_DN<74>")
	)
	(gr_poly
		(pts
			(arc
				(start 194.953128 -312.999882)
				(mid 194.546728 -312.999882)
				(end 194.953128 -312.999882)
			)
		)
		(stroke
			(width 0)
			(type solid)
		)
		(fill yes)
		(layer "In4.Cu")
		(net "P5E_PEX1_STN4_TX_DP<74>")
	)
	(gr_poly
		(pts
			(arc
				(start 195.902834 -275.949918)
				(mid 195.496434 -275.949918)
				(end 195.902834 -275.949918)
			)
		)
		(stroke
			(width 0)
			(type solid)
		)
		(fill yes)
		(layer "In4.Cu")
		(net "P5E_PEX1_STN0_RX_DP<10>")
	)
	(gr_poly
		(pts
			(arc
				(start 195.902834 -274.999958)
				(mid 195.496434 -274.999958)
				(end 195.902834 -274.999958)
			)
		)
		(stroke
			(width 0)
			(type solid)
		)
		(fill yes)
		(layer "In4.Cu")
		(net "P5E_PEX1_STN0_RX_DN<10>")
	)
	(gr_poly
		(pts
			(arc
				(start 195.903088 -316.799722)
				(mid 195.496688 -316.799722)
				(end 195.903088 -316.799722)
			)
		)
		(stroke
			(width 0)
			(type solid)
		)
		(fill yes)
		(layer "In4.Cu")
		(net "P5E_PEX1_STN4_RX_DN<73>")
	)
	(gr_poly
		(pts
			(arc
				(start 195.903088 -315.849762)
				(mid 195.496688 -315.849762)
				(end 195.903088 -315.849762)
			)
		)
		(stroke
			(width 0)
			(type solid)
		)
		(fill yes)
		(layer "In4.Cu")
		(net "P5E_PEX1_STN4_RX_DP<73>")
	)
	(gr_poly
		(pts
			(arc
				(start 195.903088 -312.049922)
				(mid 195.496688 -312.049922)
				(end 195.903088 -312.049922)
			)
		)
		(stroke
			(width 0)
			(type solid)
		)
		(fill yes)
		(layer "In4.Cu")
		(net "P5E_PEX1_STN4_TX_DN<73>")
	)
	(gr_poly
		(pts
			(arc
				(start 195.903088 -311.099962)
				(mid 195.496688 -311.099962)
				(end 195.903088 -311.099962)
			)
		)
		(stroke
			(width 0)
			(type solid)
		)
		(fill yes)
		(layer "In4.Cu")
		(net "P5E_PEX1_STN4_TX_DP<73>")
	)
	(gr_poly
		(pts
			(arc
				(start 195.903088 -309.199788)
				(mid 195.496688 -309.199788)
				(end 195.903088 -309.199788)
			)
		)
		(stroke
			(width 0)
			(type solid)
		)
		(fill yes)
		(layer "In4.Cu")
		(net "P5E_PEX1_STN4_RX_DP<69>")
	)
	(gr_poly
		(pts
			(arc
				(start 195.903088 -307.299868)
				(mid 195.496688 -307.299868)
				(end 195.903088 -307.299868)
			)
		)
		(stroke
			(width 0)
			(type solid)
		)
		(fill yes)
		(layer "In4.Cu")
		(net "P5E_PEX1_STN4_RX_DP<67>")
	)
	(gr_poly
		(pts
			(arc
				(start 195.903088 -305.399948)
				(mid 195.496688 -305.399948)
				(end 195.903088 -305.399948)
			)
		)
		(stroke
			(width 0)
			(type solid)
		)
		(fill yes)
		(layer "In4.Cu")
		(net "P5E_PEX1_STN4_RX_DP<65>")
	)
	(gr_poly
		(pts
			(arc
				(start 195.903088 -288.299906)
				(mid 195.496688 -288.299906)
				(end 195.903088 -288.299906)
			)
		)
		(stroke
			(width 0)
			(type solid)
		)
		(fill yes)
		(layer "In4.Cu")
		(net "P5E_PEX1_STN0_RX_DP<0>")
	)
	(gr_poly
		(pts
			(arc
				(start 195.903088 -286.399732)
				(mid 195.496688 -286.399732)
				(end 195.903088 -286.399732)
			)
		)
		(stroke
			(width 0)
			(type solid)
		)
		(fill yes)
		(layer "In4.Cu")
		(net "P5E_PEX1_STN0_RX_DP<2>")
	)
	(gr_poly
		(pts
			(arc
				(start 195.903088 -284.499812)
				(mid 195.496688 -284.499812)
				(end 195.903088 -284.499812)
			)
		)
		(stroke
			(width 0)
			(type solid)
		)
		(fill yes)
		(layer "In4.Cu")
		(net "P5E_PEX1_STN0_RX_DP<4>")
	)
	(gr_poly
		(pts
			(arc
				(start 195.903088 -282.599892)
				(mid 195.496688 -282.599892)
				(end 195.903088 -282.599892)
			)
		)
		(stroke
			(width 0)
			(type solid)
		)
		(fill yes)
		(layer "In4.Cu")
		(net "P5E_PEX1_STN0_RX_DP<6>")
	)
	(gr_poly
		(pts
			(arc
				(start 195.903088 -280.699718)
				(mid 195.496688 -280.699718)
				(end 195.903088 -280.699718)
			)
		)
		(stroke
			(width 0)
			(type solid)
		)
		(fill yes)
		(layer "In4.Cu")
		(net "P5E_PEX1_STN0_TX_DP<10>")
	)
	(gr_poly
		(pts
			(arc
				(start 195.903088 -279.749758)
				(mid 195.496688 -279.749758)
				(end 195.903088 -279.749758)
			)
		)
		(stroke
			(width 0)
			(type solid)
		)
		(fill yes)
		(layer "In4.Cu")
		(net "P5E_PEX1_STN0_TX_DN<10>")
	)
	(gr_poly
		(pts
			(arc
				(start 196.852794 -274.049744)
				(mid 196.446394 -274.049744)
				(end 196.852794 -274.049744)
			)
		)
		(stroke
			(width 0)
			(type solid)
		)
		(fill yes)
		(layer "In4.Cu")
		(net "P5E_PEX1_STN0_RX_DP<9>")
	)
	(gr_poly
		(pts
			(arc
				(start 196.852794 -273.099784)
				(mid 196.446394 -273.099784)
				(end 196.852794 -273.099784)
			)
		)
		(stroke
			(width 0)
			(type solid)
		)
		(fill yes)
		(layer "In4.Cu")
		(net "P5E_PEX1_STN0_RX_DN<9>")
	)
	(gr_poly
		(pts
			(arc
				(start 196.853048 -318.699896)
				(mid 196.446648 -318.699896)
				(end 196.853048 -318.699896)
			)
		)
		(stroke
			(width 0)
			(type solid)
		)
		(fill yes)
		(layer "In4.Cu")
		(net "P5E_PEX1_STN4_RX_DN<72>")
	)
	(gr_poly
		(pts
			(arc
				(start 196.853048 -317.749936)
				(mid 196.446648 -317.749936)
				(end 196.853048 -317.749936)
			)
		)
		(stroke
			(width 0)
			(type solid)
		)
		(fill yes)
		(layer "In4.Cu")
		(net "P5E_PEX1_STN4_RX_DP<72>")
	)
	(gr_poly
		(pts
			(arc
				(start 196.853048 -313.949842)
				(mid 196.446648 -313.949842)
				(end 196.853048 -313.949842)
			)
		)
		(stroke
			(width 0)
			(type solid)
		)
		(fill yes)
		(layer "In4.Cu")
		(net "P5E_PEX1_STN4_TX_DN<72>")
	)
	(gr_poly
		(pts
			(arc
				(start 196.853048 -312.999882)
				(mid 196.446648 -312.999882)
				(end 196.853048 -312.999882)
			)
		)
		(stroke
			(width 0)
			(type solid)
		)
		(fill yes)
		(layer "In4.Cu")
		(net "P5E_PEX1_STN4_TX_DP<72>")
	)
	(gr_poly
		(pts
			(arc
				(start 196.853048 -309.199788)
				(mid 196.446648 -309.199788)
				(end 196.853048 -309.199788)
			)
		)
		(stroke
			(width 0)
			(type solid)
		)
		(fill yes)
		(layer "In4.Cu")
		(net "P5E_PEX1_STN4_RX_DN<69>")
	)
	(gr_poly
		(pts
			(arc
				(start 196.853048 -307.299868)
				(mid 196.446648 -307.299868)
				(end 196.853048 -307.299868)
			)
		)
		(stroke
			(width 0)
			(type solid)
		)
		(fill yes)
		(layer "In4.Cu")
		(net "P5E_PEX1_STN4_RX_DN<67>")
	)
	(gr_poly
		(pts
			(arc
				(start 196.853048 -305.399948)
				(mid 196.446648 -305.399948)
				(end 196.853048 -305.399948)
			)
		)
		(stroke
			(width 0)
			(type solid)
		)
		(fill yes)
		(layer "In4.Cu")
		(net "P5E_PEX1_STN4_RX_DN<65>")
	)
	(gr_poly
		(pts
			(arc
				(start 196.853048 -288.299906)
				(mid 196.446648 -288.299906)
				(end 196.853048 -288.299906)
			)
		)
		(stroke
			(width 0)
			(type solid)
		)
		(fill yes)
		(layer "In4.Cu")
		(net "P5E_PEX1_STN0_RX_DN<0>")
	)
	(gr_poly
		(pts
			(arc
				(start 196.853048 -286.399732)
				(mid 196.446648 -286.399732)
				(end 196.853048 -286.399732)
			)
		)
		(stroke
			(width 0)
			(type solid)
		)
		(fill yes)
		(layer "In4.Cu")
		(net "P5E_PEX1_STN0_RX_DN<2>")
	)
	(gr_poly
		(pts
			(arc
				(start 196.853048 -284.499812)
				(mid 196.446648 -284.499812)
				(end 196.853048 -284.499812)
			)
		)
		(stroke
			(width 0)
			(type solid)
		)
		(fill yes)
		(layer "In4.Cu")
		(net "P5E_PEX1_STN0_RX_DN<4>")
	)
	(gr_poly
		(pts
			(arc
				(start 196.853048 -282.599892)
				(mid 196.446648 -282.599892)
				(end 196.853048 -282.599892)
			)
		)
		(stroke
			(width 0)
			(type solid)
		)
		(fill yes)
		(layer "In4.Cu")
		(net "P5E_PEX1_STN0_RX_DN<6>")
	)
	(gr_poly
		(pts
			(arc
				(start 196.853048 -278.799798)
				(mid 196.446648 -278.799798)
				(end 196.853048 -278.799798)
			)
		)
		(stroke
			(width 0)
			(type solid)
		)
		(fill yes)
		(layer "In4.Cu")
		(net "P5E_PEX1_STN0_TX_DP<9>")
	)
	(gr_poly
		(pts
			(arc
				(start 196.853048 -277.849838)
				(mid 196.446648 -277.849838)
				(end 196.853048 -277.849838)
			)
		)
		(stroke
			(width 0)
			(type solid)
		)
		(fill yes)
		(layer "In4.Cu")
		(net "P5E_PEX1_STN0_TX_DN<9>")
	)
	(gr_poly
		(pts
			(arc
				(start 197.803262 -316.799722)
				(mid 197.396862 -316.799722)
				(end 197.803262 -316.799722)
			)
		)
		(stroke
			(width 0)
			(type solid)
		)
		(fill yes)
		(layer "In4.Cu")
		(net "P5E_PEX1_STN4_RX_DP<71>")
	)
	(gr_poly
		(pts
			(arc
				(start 197.803262 -314.899802)
				(mid 197.396862 -314.899802)
				(end 197.803262 -314.899802)
			)
		)
		(stroke
			(width 0)
			(type solid)
		)
		(fill yes)
		(layer "In4.Cu")
		(net "P5E_PEX1_STN4_TX_DP<71>")
	)
	(gr_poly
		(pts
			(arc
				(start 197.803262 -312.049922)
				(mid 197.396862 -312.049922)
				(end 197.803262 -312.049922)
			)
		)
		(stroke
			(width 0)
			(type solid)
		)
		(fill yes)
		(layer "In4.Cu")
		(net "P5E_PEX1_STN4_TX_DP<70>")
	)
	(gr_poly
		(pts
			(arc
				(start 197.803262 -310.149748)
				(mid 197.396862 -310.149748)
				(end 197.803262 -310.149748)
			)
		)
		(stroke
			(width 0)
			(type solid)
		)
		(fill yes)
		(layer "In4.Cu")
		(net "P5E_PEX1_STN4_RX_DP<70>")
	)
	(gr_poly
		(pts
			(arc
				(start 197.803262 -308.249828)
				(mid 197.396862 -308.249828)
				(end 197.803262 -308.249828)
			)
		)
		(stroke
			(width 0)
			(type solid)
		)
		(fill yes)
		(layer "In4.Cu")
		(net "P5E_PEX1_STN4_RX_DP<68>")
	)
	(gr_poly
		(pts
			(arc
				(start 197.803262 -306.349908)
				(mid 197.396862 -306.349908)
				(end 197.803262 -306.349908)
			)
		)
		(stroke
			(width 0)
			(type solid)
		)
		(fill yes)
		(layer "In4.Cu")
		(net "P5E_PEX1_STN4_RX_DP<66>")
	)
	(gr_poly
		(pts
			(arc
				(start 197.803262 -304.449734)
				(mid 197.396862 -304.449734)
				(end 197.803262 -304.449734)
			)
		)
		(stroke
			(width 0)
			(type solid)
		)
		(fill yes)
		(layer "In4.Cu")
		(net "P5E_PEX1_STN4_RX_DP<64>")
	)
	(gr_poly
		(pts
			(arc
				(start 197.803262 -287.349946)
				(mid 197.396862 -287.349946)
				(end 197.803262 -287.349946)
			)
		)
		(stroke
			(width 0)
			(type solid)
		)
		(fill yes)
		(layer "In4.Cu")
		(net "P5E_PEX1_STN0_RX_DP<1>")
	)
	(gr_poly
		(pts
			(arc
				(start 197.803262 -285.449772)
				(mid 197.396862 -285.449772)
				(end 197.803262 -285.449772)
			)
		)
		(stroke
			(width 0)
			(type solid)
		)
		(fill yes)
		(layer "In4.Cu")
		(net "P5E_PEX1_STN0_RX_DP<3>")
	)
	(gr_poly
		(pts
			(arc
				(start 197.803262 -283.549852)
				(mid 197.396862 -283.549852)
				(end 197.803262 -283.549852)
			)
		)
		(stroke
			(width 0)
			(type solid)
		)
		(fill yes)
		(layer "In4.Cu")
		(net "P5E_PEX1_STN0_RX_DP<5>")
	)
	(gr_poly
		(pts
			(arc
				(start 197.803262 -281.649932)
				(mid 197.396862 -281.649932)
				(end 197.803262 -281.649932)
			)
		)
		(stroke
			(width 0)
			(type solid)
		)
		(fill yes)
		(layer "In4.Cu")
		(net "P5E_PEX1_STN0_RX_DP<7>")
	)
	(gr_poly
		(pts
			(arc
				(start 197.803262 -279.749758)
				(mid 197.396862 -279.749758)
				(end 197.803262 -279.749758)
			)
		)
		(stroke
			(width 0)
			(type solid)
		)
		(fill yes)
		(layer "In4.Cu")
		(net "P5E_PEX1_STN0_TX_DP<7>")
	)
	(gr_poly
		(pts
			(arc
				(start 197.803262 -276.899878)
				(mid 197.396862 -276.899878)
				(end 197.803262 -276.899878)
			)
		)
		(stroke
			(width 0)
			(type solid)
		)
		(fill yes)
		(layer "In4.Cu")
		(net "P5E_PEX1_STN0_TX_DP<8>")
	)
	(gr_poly
		(pts
			(arc
				(start 197.803262 -274.999704)
				(mid 197.396862 -274.999704)
				(end 197.803262 -274.999704)
			)
		)
		(stroke
			(width 0)
			(type solid)
		)
		(fill yes)
		(layer "In4.Cu")
		(net "P5E_PEX1_STN0_RX_DP<8>")
	)
	(gr_poly
		(pts
			(arc
				(start 198.753222 -316.799722)
				(mid 198.346822 -316.799722)
				(end 198.753222 -316.799722)
			)
		)
		(stroke
			(width 0)
			(type solid)
		)
		(fill yes)
		(layer "In4.Cu")
		(net "P5E_PEX1_STN4_RX_DN<71>")
	)
	(gr_poly
		(pts
			(arc
				(start 198.753222 -314.899802)
				(mid 198.346822 -314.899802)
				(end 198.753222 -314.899802)
			)
		)
		(stroke
			(width 0)
			(type solid)
		)
		(fill yes)
		(layer "In4.Cu")
		(net "P5E_PEX1_STN4_TX_DN<71>")
	)
	(gr_poly
		(pts
			(arc
				(start 198.753222 -312.049922)
				(mid 198.346822 -312.049922)
				(end 198.753222 -312.049922)
			)
		)
		(stroke
			(width 0)
			(type solid)
		)
		(fill yes)
		(layer "In4.Cu")
		(net "P5E_PEX1_STN4_TX_DN<70>")
	)
	(gr_poly
		(pts
			(arc
				(start 198.753222 -310.149748)
				(mid 198.346822 -310.149748)
				(end 198.753222 -310.149748)
			)
		)
		(stroke
			(width 0)
			(type solid)
		)
		(fill yes)
		(layer "In4.Cu")
		(net "P5E_PEX1_STN4_RX_DN<70>")
	)
	(gr_poly
		(pts
			(arc
				(start 198.753222 -308.249828)
				(mid 198.346822 -308.249828)
				(end 198.753222 -308.249828)
			)
		)
		(stroke
			(width 0)
			(type solid)
		)
		(fill yes)
		(layer "In4.Cu")
		(net "P5E_PEX1_STN4_RX_DN<68>")
	)
	(gr_poly
		(pts
			(arc
				(start 198.753222 -306.349908)
				(mid 198.346822 -306.349908)
				(end 198.753222 -306.349908)
			)
		)
		(stroke
			(width 0)
			(type solid)
		)
		(fill yes)
		(layer "In4.Cu")
		(net "P5E_PEX1_STN4_RX_DN<66>")
	)
	(gr_poly
		(pts
			(arc
				(start 198.753222 -304.449734)
				(mid 198.346822 -304.449734)
				(end 198.753222 -304.449734)
			)
		)
		(stroke
			(width 0)
			(type solid)
		)
		(fill yes)
		(layer "In4.Cu")
		(net "P5E_PEX1_STN4_RX_DN<64>")
	)
	(gr_poly
		(pts
			(arc
				(start 198.753222 -287.349946)
				(mid 198.346822 -287.349946)
				(end 198.753222 -287.349946)
			)
		)
		(stroke
			(width 0)
			(type solid)
		)
		(fill yes)
		(layer "In4.Cu")
		(net "P5E_PEX1_STN0_RX_DN<1>")
	)
	(gr_poly
		(pts
			(arc
				(start 198.753222 -285.449772)
				(mid 198.346822 -285.449772)
				(end 198.753222 -285.449772)
			)
		)
		(stroke
			(width 0)
			(type solid)
		)
		(fill yes)
		(layer "In4.Cu")
		(net "P5E_PEX1_STN0_RX_DN<3>")
	)
	(gr_poly
		(pts
			(arc
				(start 198.753222 -283.549852)
				(mid 198.346822 -283.549852)
				(end 198.753222 -283.549852)
			)
		)
		(stroke
			(width 0)
			(type solid)
		)
		(fill yes)
		(layer "In4.Cu")
		(net "P5E_PEX1_STN0_RX_DN<5>")
	)
	(gr_poly
		(pts
			(arc
				(start 198.753222 -281.649932)
				(mid 198.346822 -281.649932)
				(end 198.753222 -281.649932)
			)
		)
		(stroke
			(width 0)
			(type solid)
		)
		(fill yes)
		(layer "In4.Cu")
		(net "P5E_PEX1_STN0_RX_DN<7>")
	)
	(gr_poly
		(pts
			(arc
				(start 198.753222 -279.749758)
				(mid 198.346822 -279.749758)
				(end 198.753222 -279.749758)
			)
		)
		(stroke
			(width 0)
			(type solid)
		)
		(fill yes)
		(layer "In4.Cu")
		(net "P5E_PEX1_STN0_TX_DN<7>")
	)
	(gr_poly
		(pts
			(arc
				(start 198.753222 -276.899878)
				(mid 198.346822 -276.899878)
				(end 198.753222 -276.899878)
			)
		)
		(stroke
			(width 0)
			(type solid)
		)
		(fill yes)
		(layer "In4.Cu")
		(net "P5E_PEX1_STN0_TX_DN<8>")
	)
	(gr_poly
		(pts
			(arc
				(start 198.753222 -274.999704)
				(mid 198.346822 -274.999704)
				(end 198.753222 -274.999704)
			)
		)
		(stroke
			(width 0)
			(type solid)
		)
		(fill yes)
		(layer "In4.Cu")
		(net "P5E_PEX1_STN0_RX_DN<8>")
	)
	(gr_poly
		(pts
			(arc
				(start 269.252954 -316.799722)
				(mid 268.846554 -316.799722)
				(end 269.252954 -316.799722)
			)
		)
		(stroke
			(width 0)
			(type solid)
		)
		(fill yes)
		(layer "In4.Cu")
		(net "P5E_PEX2_STN7_RX_DN<122>")
	)
	(gr_poly
		(pts
			(arc
				(start 269.252954 -314.899802)
				(mid 268.846554 -314.899802)
				(end 269.252954 -314.899802)
			)
		)
		(stroke
			(width 0)
			(type solid)
		)
		(fill yes)
		(layer "In4.Cu")
		(net "P5E_PEX2_STN7_TX_DN<122>")
	)
	(gr_poly
		(pts
			(arc
				(start 269.252954 -312.049922)
				(mid 268.846554 -312.049922)
				(end 269.252954 -312.049922)
			)
		)
		(stroke
			(width 0)
			(type solid)
		)
		(fill yes)
		(layer "In4.Cu")
		(net "P5E_PEX2_STN7_TX_DN<121>")
	)
	(gr_poly
		(pts
			(arc
				(start 269.252954 -310.149748)
				(mid 268.846554 -310.149748)
				(end 269.252954 -310.149748)
			)
		)
		(stroke
			(width 0)
			(type solid)
		)
		(fill yes)
		(layer "In4.Cu")
		(net "P5E_PEX2_STN7_RX_DN<121>")
	)
	(gr_poly
		(pts
			(arc
				(start 269.252954 -308.249828)
				(mid 268.846554 -308.249828)
				(end 269.252954 -308.249828)
			)
		)
		(stroke
			(width 0)
			(type solid)
		)
		(fill yes)
		(layer "In4.Cu")
		(net "P5E_PEX2_STN7_RX_DN<119>")
	)
	(gr_poly
		(pts
			(arc
				(start 269.252954 -306.349908)
				(mid 268.846554 -306.349908)
				(end 269.252954 -306.349908)
			)
		)
		(stroke
			(width 0)
			(type solid)
		)
		(fill yes)
		(layer "In4.Cu")
		(net "P5E_PEX2_STN7_RX_DN<117>")
	)
	(gr_poly
		(pts
			(arc
				(start 269.252954 -304.449734)
				(mid 268.846554 -304.449734)
				(end 269.252954 -304.449734)
			)
		)
		(stroke
			(width 0)
			(type solid)
		)
		(fill yes)
		(layer "In4.Cu")
		(net "P5E_PEX2_STN7_RX_DN<115>")
	)
	(gr_poly
		(pts
			(arc
				(start 269.252954 -302.549814)
				(mid 268.846554 -302.549814)
				(end 269.252954 -302.549814)
			)
		)
		(stroke
			(width 0)
			(type solid)
		)
		(fill yes)
		(layer "In4.Cu")
		(net "P5E_PEX2_STN7_RX_DN<113>")
	)
	(gr_poly
		(pts
			(arc
				(start 270.202914 -316.799722)
				(mid 269.796514 -316.799722)
				(end 270.202914 -316.799722)
			)
		)
		(stroke
			(width 0)
			(type solid)
		)
		(fill yes)
		(layer "In4.Cu")
		(net "P5E_PEX2_STN7_RX_DP<122>")
	)
	(gr_poly
		(pts
			(arc
				(start 270.202914 -314.899802)
				(mid 269.796514 -314.899802)
				(end 270.202914 -314.899802)
			)
		)
		(stroke
			(width 0)
			(type solid)
		)
		(fill yes)
		(layer "In4.Cu")
		(net "P5E_PEX2_STN7_TX_DP<122>")
	)
	(gr_poly
		(pts
			(arc
				(start 270.202914 -312.049922)
				(mid 269.796514 -312.049922)
				(end 270.202914 -312.049922)
			)
		)
		(stroke
			(width 0)
			(type solid)
		)
		(fill yes)
		(layer "In4.Cu")
		(net "P5E_PEX2_STN7_TX_DP<121>")
	)
	(gr_poly
		(pts
			(arc
				(start 270.202914 -310.149748)
				(mid 269.796514 -310.149748)
				(end 270.202914 -310.149748)
			)
		)
		(stroke
			(width 0)
			(type solid)
		)
		(fill yes)
		(layer "In4.Cu")
		(net "P5E_PEX2_STN7_RX_DP<121>")
	)
	(gr_poly
		(pts
			(arc
				(start 270.202914 -308.249828)
				(mid 269.796514 -308.249828)
				(end 270.202914 -308.249828)
			)
		)
		(stroke
			(width 0)
			(type solid)
		)
		(fill yes)
		(layer "In4.Cu")
		(net "P5E_PEX2_STN7_RX_DP<119>")
	)
	(gr_poly
		(pts
			(arc
				(start 270.202914 -306.349908)
				(mid 269.796514 -306.349908)
				(end 270.202914 -306.349908)
			)
		)
		(stroke
			(width 0)
			(type solid)
		)
		(fill yes)
		(layer "In4.Cu")
		(net "P5E_PEX2_STN7_RX_DP<117>")
	)
	(gr_poly
		(pts
			(arc
				(start 270.202914 -304.449734)
				(mid 269.796514 -304.449734)
				(end 270.202914 -304.449734)
			)
		)
		(stroke
			(width 0)
			(type solid)
		)
		(fill yes)
		(layer "In4.Cu")
		(net "P5E_PEX2_STN7_RX_DP<115>")
	)
	(gr_poly
		(pts
			(arc
				(start 270.202914 -302.549814)
				(mid 269.796514 -302.549814)
				(end 270.202914 -302.549814)
			)
		)
		(stroke
			(width 0)
			(type solid)
		)
		(fill yes)
		(layer "In4.Cu")
		(net "P5E_PEX2_STN7_RX_DP<113>")
	)
	(gr_poly
		(pts
			(arc
				(start 271.153128 -318.699896)
				(mid 270.746728 -318.699896)
				(end 271.153128 -318.699896)
			)
		)
		(stroke
			(width 0)
			(type solid)
		)
		(fill yes)
		(layer "In4.Cu")
		(net "P5E_PEX2_STN7_RX_DN<123>")
	)
	(gr_poly
		(pts
			(arc
				(start 271.153128 -317.749936)
				(mid 270.746728 -317.749936)
				(end 271.153128 -317.749936)
			)
		)
		(stroke
			(width 0)
			(type solid)
		)
		(fill yes)
		(layer "In4.Cu")
		(net "P5E_PEX2_STN7_RX_DP<123>")
	)
	(gr_poly
		(pts
			(arc
				(start 271.153128 -313.949842)
				(mid 270.746728 -313.949842)
				(end 271.153128 -313.949842)
			)
		)
		(stroke
			(width 0)
			(type solid)
		)
		(fill yes)
		(layer "In4.Cu")
		(net "P5E_PEX2_STN7_TX_DN<123>")
	)
	(gr_poly
		(pts
			(arc
				(start 271.153128 -312.999882)
				(mid 270.746728 -312.999882)
				(end 271.153128 -312.999882)
			)
		)
		(stroke
			(width 0)
			(type solid)
		)
		(fill yes)
		(layer "In4.Cu")
		(net "P5E_PEX2_STN7_TX_DP<123>")
	)
	(gr_poly
		(pts
			(arc
				(start 271.153128 -309.199788)
				(mid 270.746728 -309.199788)
				(end 271.153128 -309.199788)
			)
		)
		(stroke
			(width 0)
			(type solid)
		)
		(fill yes)
		(layer "In4.Cu")
		(net "P5E_PEX2_STN7_RX_DN<120>")
	)
	(gr_poly
		(pts
			(arc
				(start 271.153128 -307.299868)
				(mid 270.746728 -307.299868)
				(end 271.153128 -307.299868)
			)
		)
		(stroke
			(width 0)
			(type solid)
		)
		(fill yes)
		(layer "In4.Cu")
		(net "P5E_PEX2_STN7_RX_DN<118>")
	)
	(gr_poly
		(pts
			(arc
				(start 271.153128 -305.399948)
				(mid 270.746728 -305.399948)
				(end 271.153128 -305.399948)
			)
		)
		(stroke
			(width 0)
			(type solid)
		)
		(fill yes)
		(layer "In4.Cu")
		(net "P5E_PEX2_STN7_RX_DN<116>")
	)
	(gr_poly
		(pts
			(arc
				(start 271.153128 -303.499774)
				(mid 270.746728 -303.499774)
				(end 271.153128 -303.499774)
			)
		)
		(stroke
			(width 0)
			(type solid)
		)
		(fill yes)
		(layer "In4.Cu")
		(net "P5E_PEX2_STN7_RX_DN<114>")
	)
	(gr_poly
		(pts
			(arc
				(start 271.153128 -301.599854)
				(mid 270.746728 -301.599854)
				(end 271.153128 -301.599854)
			)
		)
		(stroke
			(width 0)
			(type solid)
		)
		(fill yes)
		(layer "In4.Cu")
		(net "P5E_PEX2_STN7_RX_DN<112>")
	)
	(gr_poly
		(pts
			(arc
				(start 272.103088 -316.799722)
				(mid 271.696688 -316.799722)
				(end 272.103088 -316.799722)
			)
		)
		(stroke
			(width 0)
			(type solid)
		)
		(fill yes)
		(layer "In4.Cu")
		(net "P5E_PEX2_STN7_RX_DN<124>")
	)
	(gr_poly
		(pts
			(arc
				(start 272.103088 -315.849762)
				(mid 271.696688 -315.849762)
				(end 272.103088 -315.849762)
			)
		)
		(stroke
			(width 0)
			(type solid)
		)
		(fill yes)
		(layer "In4.Cu")
		(net "P5E_PEX2_STN7_RX_DP<124>")
	)
	(gr_poly
		(pts
			(arc
				(start 272.103088 -312.049922)
				(mid 271.696688 -312.049922)
				(end 272.103088 -312.049922)
			)
		)
		(stroke
			(width 0)
			(type solid)
		)
		(fill yes)
		(layer "In4.Cu")
		(net "P5E_PEX2_STN7_TX_DN<124>")
	)
	(gr_poly
		(pts
			(arc
				(start 272.103088 -311.099962)
				(mid 271.696688 -311.099962)
				(end 272.103088 -311.099962)
			)
		)
		(stroke
			(width 0)
			(type solid)
		)
		(fill yes)
		(layer "In4.Cu")
		(net "P5E_PEX2_STN7_TX_DP<124>")
	)
	(gr_poly
		(pts
			(arc
				(start 272.103088 -309.199788)
				(mid 271.696688 -309.199788)
				(end 272.103088 -309.199788)
			)
		)
		(stroke
			(width 0)
			(type solid)
		)
		(fill yes)
		(layer "In4.Cu")
		(net "P5E_PEX2_STN7_RX_DP<120>")
	)
	(gr_poly
		(pts
			(arc
				(start 272.103088 -307.299868)
				(mid 271.696688 -307.299868)
				(end 272.103088 -307.299868)
			)
		)
		(stroke
			(width 0)
			(type solid)
		)
		(fill yes)
		(layer "In4.Cu")
		(net "P5E_PEX2_STN7_RX_DP<118>")
	)
	(gr_poly
		(pts
			(arc
				(start 272.103088 -305.399948)
				(mid 271.696688 -305.399948)
				(end 272.103088 -305.399948)
			)
		)
		(stroke
			(width 0)
			(type solid)
		)
		(fill yes)
		(layer "In4.Cu")
		(net "P5E_PEX2_STN7_RX_DP<116>")
	)
	(gr_poly
		(pts
			(arc
				(start 272.103088 -303.499774)
				(mid 271.696688 -303.499774)
				(end 272.103088 -303.499774)
			)
		)
		(stroke
			(width 0)
			(type solid)
		)
		(fill yes)
		(layer "In4.Cu")
		(net "P5E_PEX2_STN7_RX_DP<114>")
	)
	(gr_poly
		(pts
			(arc
				(start 272.103088 -301.599854)
				(mid 271.696688 -301.599854)
				(end 272.103088 -301.599854)
			)
		)
		(stroke
			(width 0)
			(type solid)
		)
		(fill yes)
		(layer "In4.Cu")
		(net "P5E_PEX2_STN7_RX_DP<112>")
	)
	(gr_poly
		(pts
			(arc
				(start 273.053048 -318.699896)
				(mid 272.646648 -318.699896)
				(end 273.053048 -318.699896)
			)
		)
		(stroke
			(width 0)
			(type solid)
		)
		(fill yes)
		(layer "In4.Cu")
		(net "P5E_PEX2_STN7_RX_DN<125>")
	)
	(gr_poly
		(pts
			(arc
				(start 273.053048 -317.749936)
				(mid 272.646648 -317.749936)
				(end 273.053048 -317.749936)
			)
		)
		(stroke
			(width 0)
			(type solid)
		)
		(fill yes)
		(layer "In4.Cu")
		(net "P5E_PEX2_STN7_RX_DP<125>")
	)
	(gr_poly
		(pts
			(arc
				(start 273.053048 -313.949842)
				(mid 272.646648 -313.949842)
				(end 273.053048 -313.949842)
			)
		)
		(stroke
			(width 0)
			(type solid)
		)
		(fill yes)
		(layer "In4.Cu")
		(net "P5E_PEX2_STN7_TX_DN<125>")
	)
	(gr_poly
		(pts
			(arc
				(start 273.053048 -312.999882)
				(mid 272.646648 -312.999882)
				(end 273.053048 -312.999882)
			)
		)
		(stroke
			(width 0)
			(type solid)
		)
		(fill yes)
		(layer "In4.Cu")
		(net "P5E_PEX2_STN7_TX_DP<125>")
	)
	(gr_poly
		(pts
			(arc
				(start 274.003008 -316.799722)
				(mid 273.596608 -316.799722)
				(end 274.003008 -316.799722)
			)
		)
		(stroke
			(width 0)
			(type solid)
		)
		(fill yes)
		(layer "In4.Cu")
		(net "P5E_PEX2_STN7_RX_DN<126>")
	)
	(gr_poly
		(pts
			(arc
				(start 274.003008 -315.849762)
				(mid 273.596608 -315.849762)
				(end 274.003008 -315.849762)
			)
		)
		(stroke
			(width 0)
			(type solid)
		)
		(fill yes)
		(layer "In4.Cu")
		(net "P5E_PEX2_STN7_RX_DP<126>")
	)
	(gr_poly
		(pts
			(arc
				(start 274.003008 -312.049922)
				(mid 273.596608 -312.049922)
				(end 274.003008 -312.049922)
			)
		)
		(stroke
			(width 0)
			(type solid)
		)
		(fill yes)
		(layer "In4.Cu")
		(net "P5E_PEX2_STN7_TX_DN<126>")
	)
	(gr_poly
		(pts
			(arc
				(start 274.003008 -311.099962)
				(mid 273.596608 -311.099962)
				(end 274.003008 -311.099962)
			)
		)
		(stroke
			(width 0)
			(type solid)
		)
		(fill yes)
		(layer "In4.Cu")
		(net "P5E_PEX2_STN7_TX_DP<126>")
	)
	(gr_poly
		(pts
			(arc
				(start 274.003008 -309.199788)
				(mid 273.596608 -309.199788)
				(end 274.003008 -309.199788)
			)
		)
		(stroke
			(width 0)
			(type solid)
		)
		(fill yes)
		(layer "In4.Cu")
		(net "P5E_PEX2_STN7_TX_DN<120>")
	)
	(gr_poly
		(pts
			(arc
				(start 274.003008 -307.299868)
				(mid 273.596608 -307.299868)
				(end 274.003008 -307.299868)
			)
		)
		(stroke
			(width 0)
			(type solid)
		)
		(fill yes)
		(layer "In4.Cu")
		(net "P5E_PEX2_STN7_TX_DN<118>")
	)
	(gr_poly
		(pts
			(arc
				(start 274.003008 -305.399948)
				(mid 273.596608 -305.399948)
				(end 274.003008 -305.399948)
			)
		)
		(stroke
			(width 0)
			(type solid)
		)
		(fill yes)
		(layer "In4.Cu")
		(net "P5E_PEX2_STN7_TX_DN<116>")
	)
	(gr_poly
		(pts
			(arc
				(start 274.003008 -303.499774)
				(mid 273.596608 -303.499774)
				(end 274.003008 -303.499774)
			)
		)
		(stroke
			(width 0)
			(type solid)
		)
		(fill yes)
		(layer "In4.Cu")
		(net "P5E_PEX2_STN7_TX_DN<114>")
	)
	(gr_poly
		(pts
			(arc
				(start 274.003008 -301.599854)
				(mid 273.596608 -301.599854)
				(end 274.003008 -301.599854)
			)
		)
		(stroke
			(width 0)
			(type solid)
		)
		(fill yes)
		(layer "In4.Cu")
		(net "P5E_PEX2_STN7_TX_DN<112>")
	)
	(gr_poly
		(pts
			(arc
				(start 274.952968 -318.699896)
				(mid 274.546568 -318.699896)
				(end 274.952968 -318.699896)
			)
		)
		(stroke
			(width 0)
			(type solid)
		)
		(fill yes)
		(layer "In4.Cu")
		(net "P5E_PEX2_STN7_RX_DN<127>")
	)
	(gr_poly
		(pts
			(arc
				(start 274.952968 -317.749936)
				(mid 274.546568 -317.749936)
				(end 274.952968 -317.749936)
			)
		)
		(stroke
			(width 0)
			(type solid)
		)
		(fill yes)
		(layer "In4.Cu")
		(net "P5E_PEX2_STN7_RX_DP<127>")
	)
	(gr_poly
		(pts
			(arc
				(start 274.952968 -313.949842)
				(mid 274.546568 -313.949842)
				(end 274.952968 -313.949842)
			)
		)
		(stroke
			(width 0)
			(type solid)
		)
		(fill yes)
		(layer "In4.Cu")
		(net "P5E_PEX2_STN7_TX_DN<127>")
	)
	(gr_poly
		(pts
			(arc
				(start 274.952968 -312.999882)
				(mid 274.546568 -312.999882)
				(end 274.952968 -312.999882)
			)
		)
		(stroke
			(width 0)
			(type solid)
		)
		(fill yes)
		(layer "In4.Cu")
		(net "P5E_PEX2_STN7_TX_DP<127>")
	)
	(gr_poly
		(pts
			(arc
				(start 274.952968 -309.199788)
				(mid 274.546568 -309.199788)
				(end 274.952968 -309.199788)
			)
		)
		(stroke
			(width 0)
			(type solid)
		)
		(fill yes)
		(layer "In4.Cu")
		(net "P5E_PEX2_STN7_TX_DP<120>")
	)
	(gr_poly
		(pts
			(arc
				(start 274.952968 -307.299868)
				(mid 274.546568 -307.299868)
				(end 274.952968 -307.299868)
			)
		)
		(stroke
			(width 0)
			(type solid)
		)
		(fill yes)
		(layer "In4.Cu")
		(net "P5E_PEX2_STN7_TX_DP<118>")
	)
	(gr_poly
		(pts
			(arc
				(start 274.952968 -305.399948)
				(mid 274.546568 -305.399948)
				(end 274.952968 -305.399948)
			)
		)
		(stroke
			(width 0)
			(type solid)
		)
		(fill yes)
		(layer "In4.Cu")
		(net "P5E_PEX2_STN7_TX_DP<116>")
	)
	(gr_poly
		(pts
			(arc
				(start 274.952968 -303.499774)
				(mid 274.546568 -303.499774)
				(end 274.952968 -303.499774)
			)
		)
		(stroke
			(width 0)
			(type solid)
		)
		(fill yes)
		(layer "In4.Cu")
		(net "P5E_PEX2_STN7_TX_DP<114>")
	)
	(gr_poly
		(pts
			(arc
				(start 274.952968 -301.599854)
				(mid 274.546568 -301.599854)
				(end 274.952968 -301.599854)
			)
		)
		(stroke
			(width 0)
			(type solid)
		)
		(fill yes)
		(layer "In4.Cu")
		(net "P5E_PEX2_STN7_TX_DP<112>")
	)
	(gr_poly
		(pts
			(arc
				(start 275.902928 -316.799722)
				(mid 275.496528 -316.799722)
				(end 275.902928 -316.799722)
			)
		)
		(stroke
			(width 0)
			(type solid)
		)
		(fill yes)
		(layer "In4.Cu")
		(net "P5E_PEX2_STN6_RX_DN<111>")
	)
	(gr_poly
		(pts
			(arc
				(start 275.902928 -315.849762)
				(mid 275.496528 -315.849762)
				(end 275.902928 -315.849762)
			)
		)
		(stroke
			(width 0)
			(type solid)
		)
		(fill yes)
		(layer "In4.Cu")
		(net "P5E_PEX2_STN6_RX_DP<111>")
	)
	(gr_poly
		(pts
			(arc
				(start 275.902928 -312.049922)
				(mid 275.496528 -312.049922)
				(end 275.902928 -312.049922)
			)
		)
		(stroke
			(width 0)
			(type solid)
		)
		(fill yes)
		(layer "In4.Cu")
		(net "P5E_PEX2_STN6_TX_DN<111>")
	)
	(gr_poly
		(pts
			(arc
				(start 275.902928 -311.099962)
				(mid 275.496528 -311.099962)
				(end 275.902928 -311.099962)
			)
		)
		(stroke
			(width 0)
			(type solid)
		)
		(fill yes)
		(layer "In4.Cu")
		(net "P5E_PEX2_STN6_TX_DP<111>")
	)
	(gr_poly
		(pts
			(arc
				(start 275.902928 -308.249828)
				(mid 275.496528 -308.249828)
				(end 275.902928 -308.249828)
			)
		)
		(stroke
			(width 0)
			(type solid)
		)
		(fill yes)
		(layer "In4.Cu")
		(net "P5E_PEX2_STN7_TX_DN<119>")
	)
	(gr_poly
		(pts
			(arc
				(start 275.902928 -306.349908)
				(mid 275.496528 -306.349908)
				(end 275.902928 -306.349908)
			)
		)
		(stroke
			(width 0)
			(type solid)
		)
		(fill yes)
		(layer "In4.Cu")
		(net "P5E_PEX2_STN7_TX_DN<117>")
	)
	(gr_poly
		(pts
			(arc
				(start 275.902928 -304.449734)
				(mid 275.496528 -304.449734)
				(end 275.902928 -304.449734)
			)
		)
		(stroke
			(width 0)
			(type solid)
		)
		(fill yes)
		(layer "In4.Cu")
		(net "P5E_PEX2_STN7_TX_DN<115>")
	)
	(gr_poly
		(pts
			(arc
				(start 275.902928 -302.549814)
				(mid 275.496528 -302.549814)
				(end 275.902928 -302.549814)
			)
		)
		(stroke
			(width 0)
			(type solid)
		)
		(fill yes)
		(layer "In4.Cu")
		(net "P5E_PEX2_STN7_TX_DN<113>")
	)
	(gr_poly
		(pts
			(arc
				(start 276.852888 -318.699896)
				(mid 276.446488 -318.699896)
				(end 276.852888 -318.699896)
			)
		)
		(stroke
			(width 0)
			(type solid)
		)
		(fill yes)
		(layer "In4.Cu")
		(net "P5E_PEX2_STN6_RX_DN<110>")
	)
	(gr_poly
		(pts
			(arc
				(start 276.852888 -317.749936)
				(mid 276.446488 -317.749936)
				(end 276.852888 -317.749936)
			)
		)
		(stroke
			(width 0)
			(type solid)
		)
		(fill yes)
		(layer "In4.Cu")
		(net "P5E_PEX2_STN6_RX_DP<110>")
	)
	(gr_poly
		(pts
			(arc
				(start 276.852888 -313.949842)
				(mid 276.446488 -313.949842)
				(end 276.852888 -313.949842)
			)
		)
		(stroke
			(width 0)
			(type solid)
		)
		(fill yes)
		(layer "In4.Cu")
		(net "P5E_PEX2_STN6_TX_DN<110>")
	)
	(gr_poly
		(pts
			(arc
				(start 276.852888 -312.999882)
				(mid 276.446488 -312.999882)
				(end 276.852888 -312.999882)
			)
		)
		(stroke
			(width 0)
			(type solid)
		)
		(fill yes)
		(layer "In4.Cu")
		(net "P5E_PEX2_STN6_TX_DP<110>")
	)
	(gr_poly
		(pts
			(arc
				(start 276.852888 -308.249828)
				(mid 276.446488 -308.249828)
				(end 276.852888 -308.249828)
			)
		)
		(stroke
			(width 0)
			(type solid)
		)
		(fill yes)
		(layer "In4.Cu")
		(net "P5E_PEX2_STN7_TX_DP<119>")
	)
	(gr_poly
		(pts
			(arc
				(start 276.852888 -306.349908)
				(mid 276.446488 -306.349908)
				(end 276.852888 -306.349908)
			)
		)
		(stroke
			(width 0)
			(type solid)
		)
		(fill yes)
		(layer "In4.Cu")
		(net "P5E_PEX2_STN7_TX_DP<117>")
	)
	(gr_poly
		(pts
			(arc
				(start 276.852888 -304.449734)
				(mid 276.446488 -304.449734)
				(end 276.852888 -304.449734)
			)
		)
		(stroke
			(width 0)
			(type solid)
		)
		(fill yes)
		(layer "In4.Cu")
		(net "P5E_PEX2_STN7_TX_DP<115>")
	)
	(gr_poly
		(pts
			(arc
				(start 276.852888 -302.549814)
				(mid 276.446488 -302.549814)
				(end 276.852888 -302.549814)
			)
		)
		(stroke
			(width 0)
			(type solid)
		)
		(fill yes)
		(layer "In4.Cu")
		(net "P5E_PEX2_STN7_TX_DP<113>")
	)
	(gr_poly
		(pts
			(arc
				(start 276.852888 -278.799798)
				(mid 276.446488 -278.799798)
				(end 276.852888 -278.799798)
			)
		)
		(stroke
			(width 0)
			(type solid)
		)
		(fill yes)
		(layer "In4.Cu")
		(net "P5E_PEX2_STN2_TX_DP<47>")
	)
	(gr_poly
		(pts
			(arc
				(start 276.852888 -277.849838)
				(mid 276.446488 -277.849838)
				(end 276.852888 -277.849838)
			)
		)
		(stroke
			(width 0)
			(type solid)
		)
		(fill yes)
		(layer "In4.Cu")
		(net "P5E_PEX2_STN2_TX_DN<47>")
	)
	(gr_poly
		(pts
			(arc
				(start 276.852888 -274.049744)
				(mid 276.446488 -274.049744)
				(end 276.852888 -274.049744)
			)
		)
		(stroke
			(width 0)
			(type solid)
		)
		(fill yes)
		(layer "In4.Cu")
		(net "P5E_PEX2_STN2_RX_DP<47>")
	)
	(gr_poly
		(pts
			(arc
				(start 276.852888 -273.099784)
				(mid 276.446488 -273.099784)
				(end 276.852888 -273.099784)
			)
		)
		(stroke
			(width 0)
			(type solid)
		)
		(fill yes)
		(layer "In4.Cu")
		(net "P5E_PEX2_STN2_RX_DN<47>")
	)
	(gr_poly
		(pts
			(arc
				(start 277.803102 -316.799722)
				(mid 277.396702 -316.799722)
				(end 277.803102 -316.799722)
			)
		)
		(stroke
			(width 0)
			(type solid)
		)
		(fill yes)
		(layer "In4.Cu")
		(net "P5E_PEX2_STN6_RX_DN<109>")
	)
	(gr_poly
		(pts
			(arc
				(start 277.803102 -315.849762)
				(mid 277.396702 -315.849762)
				(end 277.803102 -315.849762)
			)
		)
		(stroke
			(width 0)
			(type solid)
		)
		(fill yes)
		(layer "In4.Cu")
		(net "P5E_PEX2_STN6_RX_DP<109>")
	)
	(gr_poly
		(pts
			(arc
				(start 277.803102 -312.049922)
				(mid 277.396702 -312.049922)
				(end 277.803102 -312.049922)
			)
		)
		(stroke
			(width 0)
			(type solid)
		)
		(fill yes)
		(layer "In4.Cu")
		(net "P5E_PEX2_STN6_TX_DN<109>")
	)
	(gr_poly
		(pts
			(arc
				(start 277.803102 -311.099962)
				(mid 277.396702 -311.099962)
				(end 277.803102 -311.099962)
			)
		)
		(stroke
			(width 0)
			(type solid)
		)
		(fill yes)
		(layer "In4.Cu")
		(net "P5E_PEX2_STN6_TX_DP<109>")
	)
	(gr_poly
		(pts
			(arc
				(start 277.803102 -280.699464)
				(mid 277.396702 -280.699464)
				(end 277.803102 -280.699464)
			)
		)
		(stroke
			(width 0)
			(type solid)
		)
		(fill yes)
		(layer "In4.Cu")
		(net "P5E_PEX2_STN2_TX_DP<46>")
	)
	(gr_poly
		(pts
			(arc
				(start 277.803102 -279.749504)
				(mid 277.396702 -279.749504)
				(end 277.803102 -279.749504)
			)
		)
		(stroke
			(width 0)
			(type solid)
		)
		(fill yes)
		(layer "In4.Cu")
		(net "P5E_PEX2_STN2_TX_DN<46>")
	)
	(gr_poly
		(pts
			(arc
				(start 277.803102 -275.949918)
				(mid 277.396702 -275.949918)
				(end 277.803102 -275.949918)
			)
		)
		(stroke
			(width 0)
			(type solid)
		)
		(fill yes)
		(layer "In4.Cu")
		(net "P5E_PEX2_STN2_RX_DP<46>")
	)
	(gr_poly
		(pts
			(arc
				(start 277.803102 -274.999958)
				(mid 277.396702 -274.999958)
				(end 277.803102 -274.999958)
			)
		)
		(stroke
			(width 0)
			(type solid)
		)
		(fill yes)
		(layer "In4.Cu")
		(net "P5E_PEX2_STN2_RX_DN<46>")
	)
	(gr_poly
		(pts
			(arc
				(start 278.753062 -318.699896)
				(mid 278.346662 -318.699896)
				(end 278.753062 -318.699896)
			)
		)
		(stroke
			(width 0)
			(type solid)
		)
		(fill yes)
		(layer "In4.Cu")
		(net "P5E_PEX2_STN6_RX_DN<108>")
	)
	(gr_poly
		(pts
			(arc
				(start 278.753062 -317.749936)
				(mid 278.346662 -317.749936)
				(end 278.753062 -317.749936)
			)
		)
		(stroke
			(width 0)
			(type solid)
		)
		(fill yes)
		(layer "In4.Cu")
		(net "P5E_PEX2_STN6_RX_DP<108>")
	)
	(gr_poly
		(pts
			(arc
				(start 278.753062 -313.949842)
				(mid 278.346662 -313.949842)
				(end 278.753062 -313.949842)
			)
		)
		(stroke
			(width 0)
			(type solid)
		)
		(fill yes)
		(layer "In4.Cu")
		(net "P5E_PEX2_STN6_TX_DN<108>")
	)
	(gr_poly
		(pts
			(arc
				(start 278.753062 -312.999882)
				(mid 278.346662 -312.999882)
				(end 278.753062 -312.999882)
			)
		)
		(stroke
			(width 0)
			(type solid)
		)
		(fill yes)
		(layer "In4.Cu")
		(net "P5E_PEX2_STN6_TX_DP<108>")
	)
	(gr_poly
		(pts
			(arc
				(start 278.753062 -278.799798)
				(mid 278.346662 -278.799798)
				(end 278.753062 -278.799798)
			)
		)
		(stroke
			(width 0)
			(type solid)
		)
		(fill yes)
		(layer "In4.Cu")
		(net "P5E_PEX2_STN2_TX_DP<45>")
	)
	(gr_poly
		(pts
			(arc
				(start 278.753062 -277.849838)
				(mid 278.346662 -277.849838)
				(end 278.753062 -277.849838)
			)
		)
		(stroke
			(width 0)
			(type solid)
		)
		(fill yes)
		(layer "In4.Cu")
		(net "P5E_PEX2_STN2_TX_DN<45>")
	)
	(gr_poly
		(pts
			(arc
				(start 278.753062 -274.049744)
				(mid 278.346662 -274.049744)
				(end 278.753062 -274.049744)
			)
		)
		(stroke
			(width 0)
			(type solid)
		)
		(fill yes)
		(layer "In4.Cu")
		(net "P5E_PEX2_STN2_RX_DP<45>")
	)
	(gr_poly
		(pts
			(arc
				(start 278.753062 -273.099784)
				(mid 278.346662 -273.099784)
				(end 278.753062 -273.099784)
			)
		)
		(stroke
			(width 0)
			(type solid)
		)
		(fill yes)
		(layer "In4.Cu")
		(net "P5E_PEX2_STN2_RX_DN<45>")
	)
	(gr_poly
		(pts
			(arc
				(start 279.703022 -316.799722)
				(mid 279.296622 -316.799722)
				(end 279.703022 -316.799722)
			)
		)
		(stroke
			(width 0)
			(type solid)
		)
		(fill yes)
		(layer "In4.Cu")
		(net "P5E_PEX2_STN6_RX_DN<107>")
	)
	(gr_poly
		(pts
			(arc
				(start 279.703022 -315.849762)
				(mid 279.296622 -315.849762)
				(end 279.703022 -315.849762)
			)
		)
		(stroke
			(width 0)
			(type solid)
		)
		(fill yes)
		(layer "In4.Cu")
		(net "P5E_PEX2_STN6_RX_DP<107>")
	)
	(gr_poly
		(pts
			(arc
				(start 279.703022 -312.049922)
				(mid 279.296622 -312.049922)
				(end 279.703022 -312.049922)
			)
		)
		(stroke
			(width 0)
			(type solid)
		)
		(fill yes)
		(layer "In4.Cu")
		(net "P5E_PEX2_STN6_TX_DN<107>")
	)
	(gr_poly
		(pts
			(arc
				(start 279.703022 -311.099962)
				(mid 279.296622 -311.099962)
				(end 279.703022 -311.099962)
			)
		)
		(stroke
			(width 0)
			(type solid)
		)
		(fill yes)
		(layer "In4.Cu")
		(net "P5E_PEX2_STN6_TX_DP<107>")
	)
	(gr_poly
		(pts
			(arc
				(start 279.703022 -280.699464)
				(mid 279.296622 -280.699464)
				(end 279.703022 -280.699464)
			)
		)
		(stroke
			(width 0)
			(type solid)
		)
		(fill yes)
		(layer "In4.Cu")
		(net "P5E_PEX2_STN2_TX_DP<44>")
	)
	(gr_poly
		(pts
			(arc
				(start 279.703022 -279.749504)
				(mid 279.296622 -279.749504)
				(end 279.703022 -279.749504)
			)
		)
		(stroke
			(width 0)
			(type solid)
		)
		(fill yes)
		(layer "In4.Cu")
		(net "P5E_PEX2_STN2_TX_DN<44>")
	)
	(gr_poly
		(pts
			(arc
				(start 279.703022 -275.949918)
				(mid 279.296622 -275.949918)
				(end 279.703022 -275.949918)
			)
		)
		(stroke
			(width 0)
			(type solid)
		)
		(fill yes)
		(layer "In4.Cu")
		(net "P5E_PEX2_STN2_RX_DP<44>")
	)
	(gr_poly
		(pts
			(arc
				(start 279.703022 -274.999958)
				(mid 279.296622 -274.999958)
				(end 279.703022 -274.999958)
			)
		)
		(stroke
			(width 0)
			(type solid)
		)
		(fill yes)
		(layer "In4.Cu")
		(net "P5E_PEX2_STN2_RX_DN<44>")
	)
	(gr_poly
		(pts
			(arc
				(start 280.652982 -318.699896)
				(mid 280.246582 -318.699896)
				(end 280.652982 -318.699896)
			)
		)
		(stroke
			(width 0)
			(type solid)
		)
		(fill yes)
		(layer "In4.Cu")
		(net "P5E_PEX2_STN6_RX_DN<106>")
	)
	(gr_poly
		(pts
			(arc
				(start 280.652982 -317.749936)
				(mid 280.246582 -317.749936)
				(end 280.652982 -317.749936)
			)
		)
		(stroke
			(width 0)
			(type solid)
		)
		(fill yes)
		(layer "In4.Cu")
		(net "P5E_PEX2_STN6_RX_DP<106>")
	)
	(gr_poly
		(pts
			(arc
				(start 280.652982 -313.949842)
				(mid 280.246582 -313.949842)
				(end 280.652982 -313.949842)
			)
		)
		(stroke
			(width 0)
			(type solid)
		)
		(fill yes)
		(layer "In4.Cu")
		(net "P5E_PEX2_STN6_TX_DN<106>")
	)
	(gr_poly
		(pts
			(arc
				(start 280.652982 -312.999882)
				(mid 280.246582 -312.999882)
				(end 280.652982 -312.999882)
			)
		)
		(stroke
			(width 0)
			(type solid)
		)
		(fill yes)
		(layer "In4.Cu")
		(net "P5E_PEX2_STN6_TX_DP<106>")
	)
	(gr_poly
		(pts
			(arc
				(start 280.652982 -278.799798)
				(mid 280.246582 -278.799798)
				(end 280.652982 -278.799798)
			)
		)
		(stroke
			(width 0)
			(type solid)
		)
		(fill yes)
		(layer "In4.Cu")
		(net "P5E_PEX2_STN2_TX_DP<43>")
	)
	(gr_poly
		(pts
			(arc
				(start 280.652982 -277.849838)
				(mid 280.246582 -277.849838)
				(end 280.652982 -277.849838)
			)
		)
		(stroke
			(width 0)
			(type solid)
		)
		(fill yes)
		(layer "In4.Cu")
		(net "P5E_PEX2_STN2_TX_DN<43>")
	)
	(gr_poly
		(pts
			(arc
				(start 280.652982 -274.049744)
				(mid 280.246582 -274.049744)
				(end 280.652982 -274.049744)
			)
		)
		(stroke
			(width 0)
			(type solid)
		)
		(fill yes)
		(layer "In4.Cu")
		(net "P5E_PEX2_STN2_RX_DP<43>")
	)
	(gr_poly
		(pts
			(arc
				(start 280.652982 -273.099784)
				(mid 280.246582 -273.099784)
				(end 280.652982 -273.099784)
			)
		)
		(stroke
			(width 0)
			(type solid)
		)
		(fill yes)
		(layer "In4.Cu")
		(net "P5E_PEX2_STN2_RX_DN<43>")
	)
	(gr_poly
		(pts
			(arc
				(start 281.602942 -316.799722)
				(mid 281.196542 -316.799722)
				(end 281.602942 -316.799722)
			)
		)
		(stroke
			(width 0)
			(type solid)
		)
		(fill yes)
		(layer "In4.Cu")
		(net "P5E_PEX2_STN6_RX_DN<105>")
	)
	(gr_poly
		(pts
			(arc
				(start 281.602942 -315.849762)
				(mid 281.196542 -315.849762)
				(end 281.602942 -315.849762)
			)
		)
		(stroke
			(width 0)
			(type solid)
		)
		(fill yes)
		(layer "In4.Cu")
		(net "P5E_PEX2_STN6_RX_DP<105>")
	)
	(gr_poly
		(pts
			(arc
				(start 281.602942 -312.049922)
				(mid 281.196542 -312.049922)
				(end 281.602942 -312.049922)
			)
		)
		(stroke
			(width 0)
			(type solid)
		)
		(fill yes)
		(layer "In4.Cu")
		(net "P5E_PEX2_STN6_TX_DN<105>")
	)
	(gr_poly
		(pts
			(arc
				(start 281.602942 -311.099962)
				(mid 281.196542 -311.099962)
				(end 281.602942 -311.099962)
			)
		)
		(stroke
			(width 0)
			(type solid)
		)
		(fill yes)
		(layer "In4.Cu")
		(net "P5E_PEX2_STN6_TX_DP<105>")
	)
	(gr_poly
		(pts
			(arc
				(start 281.602942 -280.699464)
				(mid 281.196542 -280.699464)
				(end 281.602942 -280.699464)
			)
		)
		(stroke
			(width 0)
			(type solid)
		)
		(fill yes)
		(layer "In4.Cu")
		(net "P5E_PEX2_STN2_TX_DP<42>")
	)
	(gr_poly
		(pts
			(arc
				(start 281.602942 -279.749504)
				(mid 281.196542 -279.749504)
				(end 281.602942 -279.749504)
			)
		)
		(stroke
			(width 0)
			(type solid)
		)
		(fill yes)
		(layer "In4.Cu")
		(net "P5E_PEX2_STN2_TX_DN<42>")
	)
	(gr_poly
		(pts
			(arc
				(start 281.602942 -275.949918)
				(mid 281.196542 -275.949918)
				(end 281.602942 -275.949918)
			)
		)
		(stroke
			(width 0)
			(type solid)
		)
		(fill yes)
		(layer "In4.Cu")
		(net "P5E_PEX2_STN2_RX_DP<42>")
	)
	(gr_poly
		(pts
			(arc
				(start 281.602942 -274.999958)
				(mid 281.196542 -274.999958)
				(end 281.602942 -274.999958)
			)
		)
		(stroke
			(width 0)
			(type solid)
		)
		(fill yes)
		(layer "In4.Cu")
		(net "P5E_PEX2_STN2_RX_DN<42>")
	)
	(gr_poly
		(pts
			(arc
				(start 282.552902 -318.699896)
				(mid 282.146502 -318.699896)
				(end 282.552902 -318.699896)
			)
		)
		(stroke
			(width 0)
			(type solid)
		)
		(fill yes)
		(layer "In4.Cu")
		(net "P5E_PEX2_STN6_RX_DN<104>")
	)
	(gr_poly
		(pts
			(arc
				(start 282.552902 -317.749936)
				(mid 282.146502 -317.749936)
				(end 282.552902 -317.749936)
			)
		)
		(stroke
			(width 0)
			(type solid)
		)
		(fill yes)
		(layer "In4.Cu")
		(net "P5E_PEX2_STN6_RX_DP<104>")
	)
	(gr_poly
		(pts
			(arc
				(start 282.552902 -313.949842)
				(mid 282.146502 -313.949842)
				(end 282.552902 -313.949842)
			)
		)
		(stroke
			(width 0)
			(type solid)
		)
		(fill yes)
		(layer "In4.Cu")
		(net "P5E_PEX2_STN6_TX_DN<104>")
	)
	(gr_poly
		(pts
			(arc
				(start 282.552902 -312.999882)
				(mid 282.146502 -312.999882)
				(end 282.552902 -312.999882)
			)
		)
		(stroke
			(width 0)
			(type solid)
		)
		(fill yes)
		(layer "In4.Cu")
		(net "P5E_PEX2_STN6_TX_DP<104>")
	)
	(gr_poly
		(pts
			(arc
				(start 282.552902 -278.799798)
				(mid 282.146502 -278.799798)
				(end 282.552902 -278.799798)
			)
		)
		(stroke
			(width 0)
			(type solid)
		)
		(fill yes)
		(layer "In4.Cu")
		(net "P5E_PEX2_STN2_TX_DP<41>")
	)
	(gr_poly
		(pts
			(arc
				(start 282.552902 -277.849838)
				(mid 282.146502 -277.849838)
				(end 282.552902 -277.849838)
			)
		)
		(stroke
			(width 0)
			(type solid)
		)
		(fill yes)
		(layer "In4.Cu")
		(net "P5E_PEX2_STN2_TX_DN<41>")
	)
	(gr_poly
		(pts
			(arc
				(start 282.552902 -274.049744)
				(mid 282.146502 -274.049744)
				(end 282.552902 -274.049744)
			)
		)
		(stroke
			(width 0)
			(type solid)
		)
		(fill yes)
		(layer "In4.Cu")
		(net "P5E_PEX2_STN2_RX_DP<41>")
	)
	(gr_poly
		(pts
			(arc
				(start 282.552902 -273.099784)
				(mid 282.146502 -273.099784)
				(end 282.552902 -273.099784)
			)
		)
		(stroke
			(width 0)
			(type solid)
		)
		(fill yes)
		(layer "In4.Cu")
		(net "P5E_PEX2_STN2_RX_DN<41>")
	)
	(gr_poly
		(pts
			(arc
				(start 283.503116 -316.799722)
				(mid 283.096716 -316.799722)
				(end 283.503116 -316.799722)
			)
		)
		(stroke
			(width 0)
			(type solid)
		)
		(fill yes)
		(layer "In4.Cu")
		(net "P5E_PEX2_STN6_RX_DN<103>")
	)
	(gr_poly
		(pts
			(arc
				(start 283.503116 -315.849762)
				(mid 283.096716 -315.849762)
				(end 283.503116 -315.849762)
			)
		)
		(stroke
			(width 0)
			(type solid)
		)
		(fill yes)
		(layer "In4.Cu")
		(net "P5E_PEX2_STN6_RX_DP<103>")
	)
	(gr_poly
		(pts
			(arc
				(start 283.503116 -312.049922)
				(mid 283.096716 -312.049922)
				(end 283.503116 -312.049922)
			)
		)
		(stroke
			(width 0)
			(type solid)
		)
		(fill yes)
		(layer "In4.Cu")
		(net "P5E_PEX2_STN6_TX_DN<103>")
	)
	(gr_poly
		(pts
			(arc
				(start 283.503116 -311.099962)
				(mid 283.096716 -311.099962)
				(end 283.503116 -311.099962)
			)
		)
		(stroke
			(width 0)
			(type solid)
		)
		(fill yes)
		(layer "In4.Cu")
		(net "P5E_PEX2_STN6_TX_DP<103>")
	)
	(gr_poly
		(pts
			(arc
				(start 283.503116 -280.699464)
				(mid 283.096716 -280.699464)
				(end 283.503116 -280.699464)
			)
		)
		(stroke
			(width 0)
			(type solid)
		)
		(fill yes)
		(layer "In4.Cu")
		(net "P5E_PEX2_STN2_TX_DP<40>")
	)
	(gr_poly
		(pts
			(arc
				(start 283.503116 -279.749504)
				(mid 283.096716 -279.749504)
				(end 283.503116 -279.749504)
			)
		)
		(stroke
			(width 0)
			(type solid)
		)
		(fill yes)
		(layer "In4.Cu")
		(net "P5E_PEX2_STN2_TX_DN<40>")
	)
	(gr_poly
		(pts
			(arc
				(start 283.503116 -275.949918)
				(mid 283.096716 -275.949918)
				(end 283.503116 -275.949918)
			)
		)
		(stroke
			(width 0)
			(type solid)
		)
		(fill yes)
		(layer "In4.Cu")
		(net "P5E_PEX2_STN2_RX_DP<40>")
	)
	(gr_poly
		(pts
			(arc
				(start 283.503116 -274.999958)
				(mid 283.096716 -274.999958)
				(end 283.503116 -274.999958)
			)
		)
		(stroke
			(width 0)
			(type solid)
		)
		(fill yes)
		(layer "In4.Cu")
		(net "P5E_PEX2_STN2_RX_DN<40>")
	)
	(gr_poly
		(pts
			(arc
				(start 284.453076 -318.699896)
				(mid 284.046676 -318.699896)
				(end 284.453076 -318.699896)
			)
		)
		(stroke
			(width 0)
			(type solid)
		)
		(fill yes)
		(layer "In4.Cu")
		(net "P5E_PEX2_STN6_RX_DN<102>")
	)
	(gr_poly
		(pts
			(arc
				(start 284.453076 -317.749936)
				(mid 284.046676 -317.749936)
				(end 284.453076 -317.749936)
			)
		)
		(stroke
			(width 0)
			(type solid)
		)
		(fill yes)
		(layer "In4.Cu")
		(net "P5E_PEX2_STN6_RX_DP<102>")
	)
	(gr_poly
		(pts
			(arc
				(start 284.453076 -313.949842)
				(mid 284.046676 -313.949842)
				(end 284.453076 -313.949842)
			)
		)
		(stroke
			(width 0)
			(type solid)
		)
		(fill yes)
		(layer "In4.Cu")
		(net "P5E_PEX2_STN6_TX_DN<102>")
	)
	(gr_poly
		(pts
			(arc
				(start 284.453076 -312.999882)
				(mid 284.046676 -312.999882)
				(end 284.453076 -312.999882)
			)
		)
		(stroke
			(width 0)
			(type solid)
		)
		(fill yes)
		(layer "In4.Cu")
		(net "P5E_PEX2_STN6_TX_DP<102>")
	)
	(gr_poly
		(pts
			(arc
				(start 284.453076 -278.799798)
				(mid 284.046676 -278.799798)
				(end 284.453076 -278.799798)
			)
		)
		(stroke
			(width 0)
			(type solid)
		)
		(fill yes)
		(layer "In4.Cu")
		(net "P5E_PEX2_STN2_TX_DP<39>")
	)
	(gr_poly
		(pts
			(arc
				(start 284.453076 -277.849838)
				(mid 284.046676 -277.849838)
				(end 284.453076 -277.849838)
			)
		)
		(stroke
			(width 0)
			(type solid)
		)
		(fill yes)
		(layer "In4.Cu")
		(net "P5E_PEX2_STN2_TX_DN<39>")
	)
	(gr_poly
		(pts
			(arc
				(start 284.453076 -274.049744)
				(mid 284.046676 -274.049744)
				(end 284.453076 -274.049744)
			)
		)
		(stroke
			(width 0)
			(type solid)
		)
		(fill yes)
		(layer "In4.Cu")
		(net "P5E_PEX2_STN2_RX_DP<39>")
	)
	(gr_poly
		(pts
			(arc
				(start 284.453076 -273.099784)
				(mid 284.046676 -273.099784)
				(end 284.453076 -273.099784)
			)
		)
		(stroke
			(width 0)
			(type solid)
		)
		(fill yes)
		(layer "In4.Cu")
		(net "P5E_PEX2_STN2_RX_DN<39>")
	)
	(gr_poly
		(pts
			(arc
				(start 285.403036 -316.799722)
				(mid 284.996636 -316.799722)
				(end 285.403036 -316.799722)
			)
		)
		(stroke
			(width 0)
			(type solid)
		)
		(fill yes)
		(layer "In4.Cu")
		(net "P5E_PEX2_STN6_RX_DN<101>")
	)
	(gr_poly
		(pts
			(arc
				(start 285.403036 -315.849762)
				(mid 284.996636 -315.849762)
				(end 285.403036 -315.849762)
			)
		)
		(stroke
			(width 0)
			(type solid)
		)
		(fill yes)
		(layer "In4.Cu")
		(net "P5E_PEX2_STN6_RX_DP<101>")
	)
	(gr_poly
		(pts
			(arc
				(start 285.403036 -312.049922)
				(mid 284.996636 -312.049922)
				(end 285.403036 -312.049922)
			)
		)
		(stroke
			(width 0)
			(type solid)
		)
		(fill yes)
		(layer "In4.Cu")
		(net "P5E_PEX2_STN6_TX_DN<101>")
	)
	(gr_poly
		(pts
			(arc
				(start 285.403036 -311.099962)
				(mid 284.996636 -311.099962)
				(end 285.403036 -311.099962)
			)
		)
		(stroke
			(width 0)
			(type solid)
		)
		(fill yes)
		(layer "In4.Cu")
		(net "P5E_PEX2_STN6_TX_DP<101>")
	)
	(gr_poly
		(pts
			(arc
				(start 285.403036 -280.699464)
				(mid 284.996636 -280.699464)
				(end 285.403036 -280.699464)
			)
		)
		(stroke
			(width 0)
			(type solid)
		)
		(fill yes)
		(layer "In4.Cu")
		(net "P5E_PEX2_STN2_TX_DP<38>")
	)
	(gr_poly
		(pts
			(arc
				(start 285.403036 -279.749504)
				(mid 284.996636 -279.749504)
				(end 285.403036 -279.749504)
			)
		)
		(stroke
			(width 0)
			(type solid)
		)
		(fill yes)
		(layer "In4.Cu")
		(net "P5E_PEX2_STN2_TX_DN<38>")
	)
	(gr_poly
		(pts
			(arc
				(start 285.403036 -275.949918)
				(mid 284.996636 -275.949918)
				(end 285.403036 -275.949918)
			)
		)
		(stroke
			(width 0)
			(type solid)
		)
		(fill yes)
		(layer "In4.Cu")
		(net "P5E_PEX2_STN2_RX_DP<38>")
	)
	(gr_poly
		(pts
			(arc
				(start 285.403036 -274.999958)
				(mid 284.996636 -274.999958)
				(end 285.403036 -274.999958)
			)
		)
		(stroke
			(width 0)
			(type solid)
		)
		(fill yes)
		(layer "In4.Cu")
		(net "P5E_PEX2_STN2_RX_DN<38>")
	)
	(gr_poly
		(pts
			(arc
				(start 286.352996 -318.699896)
				(mid 285.946596 -318.699896)
				(end 286.352996 -318.699896)
			)
		)
		(stroke
			(width 0)
			(type solid)
		)
		(fill yes)
		(layer "In4.Cu")
		(net "P5E_PEX2_STN6_RX_DN<100>")
	)
	(gr_poly
		(pts
			(arc
				(start 286.352996 -317.749936)
				(mid 285.946596 -317.749936)
				(end 286.352996 -317.749936)
			)
		)
		(stroke
			(width 0)
			(type solid)
		)
		(fill yes)
		(layer "In4.Cu")
		(net "P5E_PEX2_STN6_RX_DP<100>")
	)
	(gr_poly
		(pts
			(arc
				(start 286.352996 -313.949842)
				(mid 285.946596 -313.949842)
				(end 286.352996 -313.949842)
			)
		)
		(stroke
			(width 0)
			(type solid)
		)
		(fill yes)
		(layer "In4.Cu")
		(net "P5E_PEX2_STN6_TX_DN<100>")
	)
	(gr_poly
		(pts
			(arc
				(start 286.352996 -312.999882)
				(mid 285.946596 -312.999882)
				(end 286.352996 -312.999882)
			)
		)
		(stroke
			(width 0)
			(type solid)
		)
		(fill yes)
		(layer "In4.Cu")
		(net "P5E_PEX2_STN6_TX_DP<100>")
	)
	(gr_poly
		(pts
			(arc
				(start 286.352996 -278.799798)
				(mid 285.946596 -278.799798)
				(end 286.352996 -278.799798)
			)
		)
		(stroke
			(width 0)
			(type solid)
		)
		(fill yes)
		(layer "In4.Cu")
		(net "P5E_PEX2_STN2_TX_DP<37>")
	)
	(gr_poly
		(pts
			(arc
				(start 286.352996 -277.849838)
				(mid 285.946596 -277.849838)
				(end 286.352996 -277.849838)
			)
		)
		(stroke
			(width 0)
			(type solid)
		)
		(fill yes)
		(layer "In4.Cu")
		(net "P5E_PEX2_STN2_TX_DN<37>")
	)
	(gr_poly
		(pts
			(arc
				(start 286.352996 -274.049744)
				(mid 285.946596 -274.049744)
				(end 286.352996 -274.049744)
			)
		)
		(stroke
			(width 0)
			(type solid)
		)
		(fill yes)
		(layer "In4.Cu")
		(net "P5E_PEX2_STN2_RX_DP<37>")
	)
	(gr_poly
		(pts
			(arc
				(start 286.352996 -273.099784)
				(mid 285.946596 -273.099784)
				(end 286.352996 -273.099784)
			)
		)
		(stroke
			(width 0)
			(type solid)
		)
		(fill yes)
		(layer "In4.Cu")
		(net "P5E_PEX2_STN2_RX_DN<37>")
	)
	(gr_poly
		(pts
			(arc
				(start 287.302956 -316.799722)
				(mid 286.896556 -316.799722)
				(end 287.302956 -316.799722)
			)
		)
		(stroke
			(width 0)
			(type solid)
		)
		(fill yes)
		(layer "In4.Cu")
		(net "P5E_PEX2_STN6_RX_DN<99>")
	)
	(gr_poly
		(pts
			(arc
				(start 287.302956 -315.849762)
				(mid 286.896556 -315.849762)
				(end 287.302956 -315.849762)
			)
		)
		(stroke
			(width 0)
			(type solid)
		)
		(fill yes)
		(layer "In4.Cu")
		(net "P5E_PEX2_STN6_RX_DP<99>")
	)
	(gr_poly
		(pts
			(arc
				(start 287.302956 -312.049922)
				(mid 286.896556 -312.049922)
				(end 287.302956 -312.049922)
			)
		)
		(stroke
			(width 0)
			(type solid)
		)
		(fill yes)
		(layer "In4.Cu")
		(net "P5E_PEX2_STN6_TX_DN<99>")
	)
	(gr_poly
		(pts
			(arc
				(start 287.302956 -311.099962)
				(mid 286.896556 -311.099962)
				(end 287.302956 -311.099962)
			)
		)
		(stroke
			(width 0)
			(type solid)
		)
		(fill yes)
		(layer "In4.Cu")
		(net "P5E_PEX2_STN6_TX_DP<99>")
	)
	(gr_poly
		(pts
			(arc
				(start 287.302956 -280.699464)
				(mid 286.896556 -280.699464)
				(end 287.302956 -280.699464)
			)
		)
		(stroke
			(width 0)
			(type solid)
		)
		(fill yes)
		(layer "In4.Cu")
		(net "P5E_PEX2_STN2_TX_DP<36>")
	)
	(gr_poly
		(pts
			(arc
				(start 287.302956 -279.749504)
				(mid 286.896556 -279.749504)
				(end 287.302956 -279.749504)
			)
		)
		(stroke
			(width 0)
			(type solid)
		)
		(fill yes)
		(layer "In4.Cu")
		(net "P5E_PEX2_STN2_TX_DN<36>")
	)
	(gr_poly
		(pts
			(arc
				(start 287.302956 -275.949918)
				(mid 286.896556 -275.949918)
				(end 287.302956 -275.949918)
			)
		)
		(stroke
			(width 0)
			(type solid)
		)
		(fill yes)
		(layer "In4.Cu")
		(net "P5E_PEX2_STN2_RX_DP<36>")
	)
	(gr_poly
		(pts
			(arc
				(start 287.302956 -274.999958)
				(mid 286.896556 -274.999958)
				(end 287.302956 -274.999958)
			)
		)
		(stroke
			(width 0)
			(type solid)
		)
		(fill yes)
		(layer "In4.Cu")
		(net "P5E_PEX2_STN2_RX_DN<36>")
	)
	(gr_poly
		(pts
			(arc
				(start 288.252916 -318.699896)
				(mid 287.846516 -318.699896)
				(end 288.252916 -318.699896)
			)
		)
		(stroke
			(width 0)
			(type solid)
		)
		(fill yes)
		(layer "In4.Cu")
		(net "P5E_PEX2_STN6_RX_DN<98>")
	)
	(gr_poly
		(pts
			(arc
				(start 288.252916 -317.749936)
				(mid 287.846516 -317.749936)
				(end 288.252916 -317.749936)
			)
		)
		(stroke
			(width 0)
			(type solid)
		)
		(fill yes)
		(layer "In4.Cu")
		(net "P5E_PEX2_STN6_RX_DP<98>")
	)
	(gr_poly
		(pts
			(arc
				(start 288.252916 -313.949842)
				(mid 287.846516 -313.949842)
				(end 288.252916 -313.949842)
			)
		)
		(stroke
			(width 0)
			(type solid)
		)
		(fill yes)
		(layer "In4.Cu")
		(net "P5E_PEX2_STN6_TX_DN<98>")
	)
	(gr_poly
		(pts
			(arc
				(start 288.252916 -312.999882)
				(mid 287.846516 -312.999882)
				(end 288.252916 -312.999882)
			)
		)
		(stroke
			(width 0)
			(type solid)
		)
		(fill yes)
		(layer "In4.Cu")
		(net "P5E_PEX2_STN6_TX_DP<98>")
	)
	(gr_poly
		(pts
			(arc
				(start 288.252916 -278.799798)
				(mid 287.846516 -278.799798)
				(end 288.252916 -278.799798)
			)
		)
		(stroke
			(width 0)
			(type solid)
		)
		(fill yes)
		(layer "In4.Cu")
		(net "P5E_PEX2_STN2_TX_DP<35>")
	)
	(gr_poly
		(pts
			(arc
				(start 288.252916 -277.849838)
				(mid 287.846516 -277.849838)
				(end 288.252916 -277.849838)
			)
		)
		(stroke
			(width 0)
			(type solid)
		)
		(fill yes)
		(layer "In4.Cu")
		(net "P5E_PEX2_STN2_TX_DN<35>")
	)
	(gr_poly
		(pts
			(arc
				(start 288.252916 -274.049744)
				(mid 287.846516 -274.049744)
				(end 288.252916 -274.049744)
			)
		)
		(stroke
			(width 0)
			(type solid)
		)
		(fill yes)
		(layer "In4.Cu")
		(net "P5E_PEX2_STN2_RX_DP<35>")
	)
	(gr_poly
		(pts
			(arc
				(start 288.252916 -273.099784)
				(mid 287.846516 -273.099784)
				(end 288.252916 -273.099784)
			)
		)
		(stroke
			(width 0)
			(type solid)
		)
		(fill yes)
		(layer "In4.Cu")
		(net "P5E_PEX2_STN2_RX_DN<35>")
	)
	(gr_poly
		(pts
			(arc
				(start 289.202876 -280.699464)
				(mid 288.796476 -280.699464)
				(end 289.202876 -280.699464)
			)
		)
		(stroke
			(width 0)
			(type solid)
		)
		(fill yes)
		(layer "In4.Cu")
		(net "P5E_PEX2_STN2_TX_DP<34>")
	)
	(gr_poly
		(pts
			(arc
				(start 289.202876 -279.749504)
				(mid 288.796476 -279.749504)
				(end 289.202876 -279.749504)
			)
		)
		(stroke
			(width 0)
			(type solid)
		)
		(fill yes)
		(layer "In4.Cu")
		(net "P5E_PEX2_STN2_TX_DN<34>")
	)
	(gr_poly
		(pts
			(arc
				(start 289.20313 -316.799722)
				(mid 288.79673 -316.799722)
				(end 289.20313 -316.799722)
			)
		)
		(stroke
			(width 0)
			(type solid)
		)
		(fill yes)
		(layer "In4.Cu")
		(net "P5E_PEX2_STN6_RX_DN<97>")
	)
	(gr_poly
		(pts
			(arc
				(start 289.20313 -315.849762)
				(mid 288.79673 -315.849762)
				(end 289.20313 -315.849762)
			)
		)
		(stroke
			(width 0)
			(type solid)
		)
		(fill yes)
		(layer "In4.Cu")
		(net "P5E_PEX2_STN6_RX_DP<97>")
	)
	(gr_poly
		(pts
			(arc
				(start 289.20313 -312.049922)
				(mid 288.79673 -312.049922)
				(end 289.20313 -312.049922)
			)
		)
		(stroke
			(width 0)
			(type solid)
		)
		(fill yes)
		(layer "In4.Cu")
		(net "P5E_PEX2_STN6_TX_DN<97>")
	)
	(gr_poly
		(pts
			(arc
				(start 289.20313 -311.099962)
				(mid 288.79673 -311.099962)
				(end 289.20313 -311.099962)
			)
		)
		(stroke
			(width 0)
			(type solid)
		)
		(fill yes)
		(layer "In4.Cu")
		(net "P5E_PEX2_STN6_TX_DP<97>")
	)
	(gr_poly
		(pts
			(arc
				(start 289.20313 -275.949918)
				(mid 288.79673 -275.949918)
				(end 289.20313 -275.949918)
			)
		)
		(stroke
			(width 0)
			(type solid)
		)
		(fill yes)
		(layer "In4.Cu")
		(net "P5E_PEX2_STN2_RX_DP<34>")
	)
	(gr_poly
		(pts
			(arc
				(start 289.20313 -274.999958)
				(mid 288.79673 -274.999958)
				(end 289.20313 -274.999958)
			)
		)
		(stroke
			(width 0)
			(type solid)
		)
		(fill yes)
		(layer "In4.Cu")
		(net "P5E_PEX2_STN2_RX_DN<34>")
	)
	(gr_poly
		(pts
			(arc
				(start 290.15309 -318.699896)
				(mid 289.74669 -318.699896)
				(end 290.15309 -318.699896)
			)
		)
		(stroke
			(width 0)
			(type solid)
		)
		(fill yes)
		(layer "In4.Cu")
		(net "P5E_PEX2_STN6_RX_DN<96>")
	)
	(gr_poly
		(pts
			(arc
				(start 290.15309 -317.749936)
				(mid 289.74669 -317.749936)
				(end 290.15309 -317.749936)
			)
		)
		(stroke
			(width 0)
			(type solid)
		)
		(fill yes)
		(layer "In4.Cu")
		(net "P5E_PEX2_STN6_RX_DP<96>")
	)
	(gr_poly
		(pts
			(arc
				(start 290.15309 -313.949842)
				(mid 289.74669 -313.949842)
				(end 290.15309 -313.949842)
			)
		)
		(stroke
			(width 0)
			(type solid)
		)
		(fill yes)
		(layer "In4.Cu")
		(net "P5E_PEX2_STN6_TX_DN<96>")
	)
	(gr_poly
		(pts
			(arc
				(start 290.15309 -312.999882)
				(mid 289.74669 -312.999882)
				(end 290.15309 -312.999882)
			)
		)
		(stroke
			(width 0)
			(type solid)
		)
		(fill yes)
		(layer "In4.Cu")
		(net "P5E_PEX2_STN6_TX_DP<96>")
	)
	(gr_poly
		(pts
			(arc
				(start 290.15309 -278.799798)
				(mid 289.74669 -278.799798)
				(end 290.15309 -278.799798)
			)
		)
		(stroke
			(width 0)
			(type solid)
		)
		(fill yes)
		(layer "In4.Cu")
		(net "P5E_PEX2_STN2_TX_DP<33>")
	)
	(gr_poly
		(pts
			(arc
				(start 290.15309 -277.849838)
				(mid 289.74669 -277.849838)
				(end 290.15309 -277.849838)
			)
		)
		(stroke
			(width 0)
			(type solid)
		)
		(fill yes)
		(layer "In4.Cu")
		(net "P5E_PEX2_STN2_TX_DN<33>")
	)
	(gr_poly
		(pts
			(arc
				(start 290.15309 -274.049744)
				(mid 289.74669 -274.049744)
				(end 290.15309 -274.049744)
			)
		)
		(stroke
			(width 0)
			(type solid)
		)
		(fill yes)
		(layer "In4.Cu")
		(net "P5E_PEX2_STN2_RX_DP<33>")
	)
	(gr_poly
		(pts
			(arc
				(start 290.15309 -273.099784)
				(mid 289.74669 -273.099784)
				(end 290.15309 -273.099784)
			)
		)
		(stroke
			(width 0)
			(type solid)
		)
		(fill yes)
		(layer "In4.Cu")
		(net "P5E_PEX2_STN2_RX_DN<33>")
	)
	(gr_poly
		(pts
			(arc
				(start 291.10305 -316.799722)
				(mid 290.69665 -316.799722)
				(end 291.10305 -316.799722)
			)
		)
		(stroke
			(width 0)
			(type solid)
		)
		(fill yes)
		(layer "In4.Cu")
		(net "P5E_PEX2_STN5_RX_DN<80>")
	)
	(gr_poly
		(pts
			(arc
				(start 291.10305 -315.849762)
				(mid 290.69665 -315.849762)
				(end 291.10305 -315.849762)
			)
		)
		(stroke
			(width 0)
			(type solid)
		)
		(fill yes)
		(layer "In4.Cu")
		(net "P5E_PEX2_STN5_RX_DP<80>")
	)
	(gr_poly
		(pts
			(arc
				(start 291.10305 -312.049922)
				(mid 290.69665 -312.049922)
				(end 291.10305 -312.049922)
			)
		)
		(stroke
			(width 0)
			(type solid)
		)
		(fill yes)
		(layer "In4.Cu")
		(net "P5E_PEX2_STN5_TX_DN<80>")
	)
	(gr_poly
		(pts
			(arc
				(start 291.10305 -311.099962)
				(mid 290.69665 -311.099962)
				(end 291.10305 -311.099962)
			)
		)
		(stroke
			(width 0)
			(type solid)
		)
		(fill yes)
		(layer "In4.Cu")
		(net "P5E_PEX2_STN5_TX_DP<80>")
	)
	(gr_poly
		(pts
			(arc
				(start 291.10305 -280.699464)
				(mid 290.69665 -280.699464)
				(end 291.10305 -280.699464)
			)
		)
		(stroke
			(width 0)
			(type solid)
		)
		(fill yes)
		(layer "In4.Cu")
		(net "P5E_PEX2_STN2_TX_DP<32>")
	)
	(gr_poly
		(pts
			(arc
				(start 291.10305 -279.749504)
				(mid 290.69665 -279.749504)
				(end 291.10305 -279.749504)
			)
		)
		(stroke
			(width 0)
			(type solid)
		)
		(fill yes)
		(layer "In4.Cu")
		(net "P5E_PEX2_STN2_TX_DN<32>")
	)
	(gr_poly
		(pts
			(arc
				(start 291.10305 -275.949918)
				(mid 290.69665 -275.949918)
				(end 291.10305 -275.949918)
			)
		)
		(stroke
			(width 0)
			(type solid)
		)
		(fill yes)
		(layer "In4.Cu")
		(net "P5E_PEX2_STN2_RX_DP<32>")
	)
	(gr_poly
		(pts
			(arc
				(start 291.10305 -274.999958)
				(mid 290.69665 -274.999958)
				(end 291.10305 -274.999958)
			)
		)
		(stroke
			(width 0)
			(type solid)
		)
		(fill yes)
		(layer "In4.Cu")
		(net "P5E_PEX2_STN2_RX_DN<32>")
	)
	(gr_poly
		(pts
			(arc
				(start 292.052756 -278.799798)
				(mid 291.646356 -278.799798)
				(end 292.052756 -278.799798)
			)
		)
		(stroke
			(width 0)
			(type solid)
		)
		(fill yes)
		(layer "In4.Cu")
		(net "P5E_PEX2_STN1_TX_DP<16>")
	)
	(gr_poly
		(pts
			(arc
				(start 292.052756 -277.849838)
				(mid 291.646356 -277.849838)
				(end 292.052756 -277.849838)
			)
		)
		(stroke
			(width 0)
			(type solid)
		)
		(fill yes)
		(layer "In4.Cu")
		(net "P5E_PEX2_STN1_TX_DN<16>")
	)
	(gr_poly
		(pts
			(arc
				(start 292.052756 -274.04949)
				(mid 291.646356 -274.04949)
				(end 292.052756 -274.04949)
			)
		)
		(stroke
			(width 0)
			(type solid)
		)
		(fill yes)
		(layer "In4.Cu")
		(net "P5E_PEX2_STN1_RX_DP<16>")
	)
	(gr_poly
		(pts
			(arc
				(start 292.052756 -273.09953)
				(mid 291.646356 -273.09953)
				(end 292.052756 -273.09953)
			)
		)
		(stroke
			(width 0)
			(type solid)
		)
		(fill yes)
		(layer "In4.Cu")
		(net "P5E_PEX2_STN1_RX_DN<16>")
	)
	(gr_poly
		(pts
			(arc
				(start 292.05301 -318.699896)
				(mid 291.64661 -318.699896)
				(end 292.05301 -318.699896)
			)
		)
		(stroke
			(width 0)
			(type solid)
		)
		(fill yes)
		(layer "In4.Cu")
		(net "P5E_PEX2_STN5_RX_DN<81>")
	)
	(gr_poly
		(pts
			(arc
				(start 292.05301 -317.749936)
				(mid 291.64661 -317.749936)
				(end 292.05301 -317.749936)
			)
		)
		(stroke
			(width 0)
			(type solid)
		)
		(fill yes)
		(layer "In4.Cu")
		(net "P5E_PEX2_STN5_RX_DP<81>")
	)
	(gr_poly
		(pts
			(arc
				(start 292.05301 -313.949842)
				(mid 291.64661 -313.949842)
				(end 292.05301 -313.949842)
			)
		)
		(stroke
			(width 0)
			(type solid)
		)
		(fill yes)
		(layer "In4.Cu")
		(net "P5E_PEX2_STN5_TX_DN<81>")
	)
	(gr_poly
		(pts
			(arc
				(start 292.05301 -312.999882)
				(mid 291.64661 -312.999882)
				(end 292.05301 -312.999882)
			)
		)
		(stroke
			(width 0)
			(type solid)
		)
		(fill yes)
		(layer "In4.Cu")
		(net "P5E_PEX2_STN5_TX_DP<81>")
	)
	(gr_poly
		(pts
			(arc
				(start 293.002716 -275.949664)
				(mid 292.596316 -275.949664)
				(end 293.002716 -275.949664)
			)
		)
		(stroke
			(width 0)
			(type solid)
		)
		(fill yes)
		(layer "In4.Cu")
		(net "P5E_PEX2_STN1_RX_DP<17>")
	)
	(gr_poly
		(pts
			(arc
				(start 293.002716 -274.999704)
				(mid 292.596316 -274.999704)
				(end 293.002716 -274.999704)
			)
		)
		(stroke
			(width 0)
			(type solid)
		)
		(fill yes)
		(layer "In4.Cu")
		(net "P5E_PEX2_STN1_RX_DN<17>")
	)
	(gr_poly
		(pts
			(arc
				(start 293.00297 -316.799722)
				(mid 292.59657 -316.799722)
				(end 293.00297 -316.799722)
			)
		)
		(stroke
			(width 0)
			(type solid)
		)
		(fill yes)
		(layer "In4.Cu")
		(net "P5E_PEX2_STN5_RX_DN<82>")
	)
	(gr_poly
		(pts
			(arc
				(start 293.00297 -315.849762)
				(mid 292.59657 -315.849762)
				(end 293.00297 -315.849762)
			)
		)
		(stroke
			(width 0)
			(type solid)
		)
		(fill yes)
		(layer "In4.Cu")
		(net "P5E_PEX2_STN5_RX_DP<82>")
	)
	(gr_poly
		(pts
			(arc
				(start 293.00297 -312.049922)
				(mid 292.59657 -312.049922)
				(end 293.00297 -312.049922)
			)
		)
		(stroke
			(width 0)
			(type solid)
		)
		(fill yes)
		(layer "In4.Cu")
		(net "P5E_PEX2_STN5_TX_DN<82>")
	)
	(gr_poly
		(pts
			(arc
				(start 293.00297 -311.099962)
				(mid 292.59657 -311.099962)
				(end 293.00297 -311.099962)
			)
		)
		(stroke
			(width 0)
			(type solid)
		)
		(fill yes)
		(layer "In4.Cu")
		(net "P5E_PEX2_STN5_TX_DP<82>")
	)
	(gr_poly
		(pts
			(arc
				(start 293.00297 -280.699464)
				(mid 292.59657 -280.699464)
				(end 293.00297 -280.699464)
			)
		)
		(stroke
			(width 0)
			(type solid)
		)
		(fill yes)
		(layer "In4.Cu")
		(net "P5E_PEX2_STN1_TX_DN<17>")
	)
	(gr_poly
		(pts
			(arc
				(start 293.00297 -279.749504)
				(mid 292.59657 -279.749504)
				(end 293.00297 -279.749504)
			)
		)
		(stroke
			(width 0)
			(type solid)
		)
		(fill yes)
		(layer "In4.Cu")
		(net "P5E_PEX2_STN1_TX_DP<17>")
	)
	(gr_poly
		(pts
			(arc
				(start 293.952676 -278.799798)
				(mid 293.546276 -278.799798)
				(end 293.952676 -278.799798)
			)
		)
		(stroke
			(width 0)
			(type solid)
		)
		(fill yes)
		(layer "In4.Cu")
		(net "P5E_PEX2_STN1_TX_DP<18>")
	)
	(gr_poly
		(pts
			(arc
				(start 293.952676 -277.849838)
				(mid 293.546276 -277.849838)
				(end 293.952676 -277.849838)
			)
		)
		(stroke
			(width 0)
			(type solid)
		)
		(fill yes)
		(layer "In4.Cu")
		(net "P5E_PEX2_STN1_TX_DN<18>")
	)
	(gr_poly
		(pts
			(arc
				(start 293.952676 -274.049744)
				(mid 293.546276 -274.049744)
				(end 293.952676 -274.049744)
			)
		)
		(stroke
			(width 0)
			(type solid)
		)
		(fill yes)
		(layer "In4.Cu")
		(net "P5E_PEX2_STN1_RX_DP<18>")
	)
	(gr_poly
		(pts
			(arc
				(start 293.952676 -273.099784)
				(mid 293.546276 -273.099784)
				(end 293.952676 -273.099784)
			)
		)
		(stroke
			(width 0)
			(type solid)
		)
		(fill yes)
		(layer "In4.Cu")
		(net "P5E_PEX2_STN1_RX_DN<18>")
	)
	(gr_poly
		(pts
			(arc
				(start 293.95293 -318.699896)
				(mid 293.54653 -318.699896)
				(end 293.95293 -318.699896)
			)
		)
		(stroke
			(width 0)
			(type solid)
		)
		(fill yes)
		(layer "In4.Cu")
		(net "P5E_PEX2_STN5_RX_DN<83>")
	)
	(gr_poly
		(pts
			(arc
				(start 293.95293 -317.749936)
				(mid 293.54653 -317.749936)
				(end 293.95293 -317.749936)
			)
		)
		(stroke
			(width 0)
			(type solid)
		)
		(fill yes)
		(layer "In4.Cu")
		(net "P5E_PEX2_STN5_RX_DP<83>")
	)
	(gr_poly
		(pts
			(arc
				(start 293.95293 -313.949842)
				(mid 293.54653 -313.949842)
				(end 293.95293 -313.949842)
			)
		)
		(stroke
			(width 0)
			(type solid)
		)
		(fill yes)
		(layer "In4.Cu")
		(net "P5E_PEX2_STN5_TX_DN<83>")
	)
	(gr_poly
		(pts
			(arc
				(start 293.95293 -312.999882)
				(mid 293.54653 -312.999882)
				(end 293.95293 -312.999882)
			)
		)
		(stroke
			(width 0)
			(type solid)
		)
		(fill yes)
		(layer "In4.Cu")
		(net "P5E_PEX2_STN5_TX_DP<83>")
	)
	(gr_poly
		(pts
			(arc
				(start 294.902636 -275.949918)
				(mid 294.496236 -275.949918)
				(end 294.902636 -275.949918)
			)
		)
		(stroke
			(width 0)
			(type solid)
		)
		(fill yes)
		(layer "In4.Cu")
		(net "P5E_PEX2_STN1_RX_DP<19>")
	)
	(gr_poly
		(pts
			(arc
				(start 294.902636 -274.999958)
				(mid 294.496236 -274.999958)
				(end 294.902636 -274.999958)
			)
		)
		(stroke
			(width 0)
			(type solid)
		)
		(fill yes)
		(layer "In4.Cu")
		(net "P5E_PEX2_STN1_RX_DN<19>")
	)
	(gr_poly
		(pts
			(arc
				(start 294.90289 -316.799722)
				(mid 294.49649 -316.799722)
				(end 294.90289 -316.799722)
			)
		)
		(stroke
			(width 0)
			(type solid)
		)
		(fill yes)
		(layer "In4.Cu")
		(net "P5E_PEX2_STN5_RX_DN<84>")
	)
	(gr_poly
		(pts
			(arc
				(start 294.90289 -315.849762)
				(mid 294.49649 -315.849762)
				(end 294.90289 -315.849762)
			)
		)
		(stroke
			(width 0)
			(type solid)
		)
		(fill yes)
		(layer "In4.Cu")
		(net "P5E_PEX2_STN5_RX_DP<84>")
	)
	(gr_poly
		(pts
			(arc
				(start 294.90289 -312.049922)
				(mid 294.49649 -312.049922)
				(end 294.90289 -312.049922)
			)
		)
		(stroke
			(width 0)
			(type solid)
		)
		(fill yes)
		(layer "In4.Cu")
		(net "P5E_PEX2_STN5_TX_DN<84>")
	)
	(gr_poly
		(pts
			(arc
				(start 294.90289 -311.099962)
				(mid 294.49649 -311.099962)
				(end 294.90289 -311.099962)
			)
		)
		(stroke
			(width 0)
			(type solid)
		)
		(fill yes)
		(layer "In4.Cu")
		(net "P5E_PEX2_STN5_TX_DP<84>")
	)
	(gr_poly
		(pts
			(arc
				(start 294.90289 -280.699464)
				(mid 294.49649 -280.699464)
				(end 294.90289 -280.699464)
			)
		)
		(stroke
			(width 0)
			(type solid)
		)
		(fill yes)
		(layer "In4.Cu")
		(net "P5E_PEX2_STN1_TX_DN<19>")
	)
	(gr_poly
		(pts
			(arc
				(start 294.90289 -279.749504)
				(mid 294.49649 -279.749504)
				(end 294.90289 -279.749504)
			)
		)
		(stroke
			(width 0)
			(type solid)
		)
		(fill yes)
		(layer "In4.Cu")
		(net "P5E_PEX2_STN1_TX_DP<19>")
	)
	(gr_poly
		(pts
			(arc
				(start 295.85285 -278.799798)
				(mid 295.44645 -278.799798)
				(end 295.85285 -278.799798)
			)
		)
		(stroke
			(width 0)
			(type solid)
		)
		(fill yes)
		(layer "In4.Cu")
		(net "P5E_PEX2_STN1_TX_DP<20>")
	)
	(gr_poly
		(pts
			(arc
				(start 295.85285 -277.849838)
				(mid 295.44645 -277.849838)
				(end 295.85285 -277.849838)
			)
		)
		(stroke
			(width 0)
			(type solid)
		)
		(fill yes)
		(layer "In4.Cu")
		(net "P5E_PEX2_STN1_TX_DN<20>")
	)
	(gr_poly
		(pts
			(arc
				(start 295.85285 -274.049744)
				(mid 295.44645 -274.049744)
				(end 295.85285 -274.049744)
			)
		)
		(stroke
			(width 0)
			(type solid)
		)
		(fill yes)
		(layer "In4.Cu")
		(net "P5E_PEX2_STN1_RX_DP<20>")
	)
	(gr_poly
		(pts
			(arc
				(start 295.85285 -273.099784)
				(mid 295.44645 -273.099784)
				(end 295.85285 -273.099784)
			)
		)
		(stroke
			(width 0)
			(type solid)
		)
		(fill yes)
		(layer "In4.Cu")
		(net "P5E_PEX2_STN1_RX_DN<20>")
	)
	(gr_poly
		(pts
			(arc
				(start 295.853104 -318.699896)
				(mid 295.446704 -318.699896)
				(end 295.853104 -318.699896)
			)
		)
		(stroke
			(width 0)
			(type solid)
		)
		(fill yes)
		(layer "In4.Cu")
		(net "P5E_PEX2_STN5_RX_DN<85>")
	)
	(gr_poly
		(pts
			(arc
				(start 295.853104 -317.749936)
				(mid 295.446704 -317.749936)
				(end 295.853104 -317.749936)
			)
		)
		(stroke
			(width 0)
			(type solid)
		)
		(fill yes)
		(layer "In4.Cu")
		(net "P5E_PEX2_STN5_RX_DP<85>")
	)
	(gr_poly
		(pts
			(arc
				(start 295.853104 -313.949842)
				(mid 295.446704 -313.949842)
				(end 295.853104 -313.949842)
			)
		)
		(stroke
			(width 0)
			(type solid)
		)
		(fill yes)
		(layer "In4.Cu")
		(net "P5E_PEX2_STN5_TX_DN<85>")
	)
	(gr_poly
		(pts
			(arc
				(start 295.853104 -312.999882)
				(mid 295.446704 -312.999882)
				(end 295.853104 -312.999882)
			)
		)
		(stroke
			(width 0)
			(type solid)
		)
		(fill yes)
		(layer "In4.Cu")
		(net "P5E_PEX2_STN5_TX_DP<85>")
	)
	(gr_poly
		(pts
			(arc
				(start 296.80281 -275.949664)
				(mid 296.39641 -275.949664)
				(end 296.80281 -275.949664)
			)
		)
		(stroke
			(width 0)
			(type solid)
		)
		(fill yes)
		(layer "In4.Cu")
		(net "P5E_PEX2_STN1_RX_DP<21>")
	)
	(gr_poly
		(pts
			(arc
				(start 296.80281 -274.999704)
				(mid 296.39641 -274.999704)
				(end 296.80281 -274.999704)
			)
		)
		(stroke
			(width 0)
			(type solid)
		)
		(fill yes)
		(layer "In4.Cu")
		(net "P5E_PEX2_STN1_RX_DN<21>")
	)
	(gr_poly
		(pts
			(arc
				(start 296.803064 -316.799722)
				(mid 296.396664 -316.799722)
				(end 296.803064 -316.799722)
			)
		)
		(stroke
			(width 0)
			(type solid)
		)
		(fill yes)
		(layer "In4.Cu")
		(net "P5E_PEX2_STN5_RX_DN<86>")
	)
	(gr_poly
		(pts
			(arc
				(start 296.803064 -315.849762)
				(mid 296.396664 -315.849762)
				(end 296.803064 -315.849762)
			)
		)
		(stroke
			(width 0)
			(type solid)
		)
		(fill yes)
		(layer "In4.Cu")
		(net "P5E_PEX2_STN5_RX_DP<86>")
	)
	(gr_poly
		(pts
			(arc
				(start 296.803064 -312.049922)
				(mid 296.396664 -312.049922)
				(end 296.803064 -312.049922)
			)
		)
		(stroke
			(width 0)
			(type solid)
		)
		(fill yes)
		(layer "In4.Cu")
		(net "P5E_PEX2_STN5_TX_DN<86>")
	)
	(gr_poly
		(pts
			(arc
				(start 296.803064 -311.099962)
				(mid 296.396664 -311.099962)
				(end 296.803064 -311.099962)
			)
		)
		(stroke
			(width 0)
			(type solid)
		)
		(fill yes)
		(layer "In4.Cu")
		(net "P5E_PEX2_STN5_TX_DP<86>")
	)
	(gr_poly
		(pts
			(arc
				(start 296.803064 -280.699464)
				(mid 296.396664 -280.699464)
				(end 296.803064 -280.699464)
			)
		)
		(stroke
			(width 0)
			(type solid)
		)
		(fill yes)
		(layer "In4.Cu")
		(net "P5E_PEX2_STN1_TX_DN<21>")
	)
	(gr_poly
		(pts
			(arc
				(start 296.803064 -279.749504)
				(mid 296.396664 -279.749504)
				(end 296.803064 -279.749504)
			)
		)
		(stroke
			(width 0)
			(type solid)
		)
		(fill yes)
		(layer "In4.Cu")
		(net "P5E_PEX2_STN1_TX_DP<21>")
	)
	(gr_poly
		(pts
			(arc
				(start 297.75277 -278.799798)
				(mid 297.34637 -278.799798)
				(end 297.75277 -278.799798)
			)
		)
		(stroke
			(width 0)
			(type solid)
		)
		(fill yes)
		(layer "In4.Cu")
		(net "P5E_PEX2_STN1_TX_DP<22>")
	)
	(gr_poly
		(pts
			(arc
				(start 297.75277 -277.849838)
				(mid 297.34637 -277.849838)
				(end 297.75277 -277.849838)
			)
		)
		(stroke
			(width 0)
			(type solid)
		)
		(fill yes)
		(layer "In4.Cu")
		(net "P5E_PEX2_STN1_TX_DN<22>")
	)
	(gr_poly
		(pts
			(arc
				(start 297.75277 -274.049744)
				(mid 297.34637 -274.049744)
				(end 297.75277 -274.049744)
			)
		)
		(stroke
			(width 0)
			(type solid)
		)
		(fill yes)
		(layer "In4.Cu")
		(net "P5E_PEX2_STN1_RX_DP<22>")
	)
	(gr_poly
		(pts
			(arc
				(start 297.75277 -273.099784)
				(mid 297.34637 -273.099784)
				(end 297.75277 -273.099784)
			)
		)
		(stroke
			(width 0)
			(type solid)
		)
		(fill yes)
		(layer "In4.Cu")
		(net "P5E_PEX2_STN1_RX_DN<22>")
	)
	(gr_poly
		(pts
			(arc
				(start 297.753024 -318.699896)
				(mid 297.346624 -318.699896)
				(end 297.753024 -318.699896)
			)
		)
		(stroke
			(width 0)
			(type solid)
		)
		(fill yes)
		(layer "In4.Cu")
		(net "P5E_PEX2_STN5_RX_DN<87>")
	)
	(gr_poly
		(pts
			(arc
				(start 297.753024 -317.749936)
				(mid 297.346624 -317.749936)
				(end 297.753024 -317.749936)
			)
		)
		(stroke
			(width 0)
			(type solid)
		)
		(fill yes)
		(layer "In4.Cu")
		(net "P5E_PEX2_STN5_RX_DP<87>")
	)
	(gr_poly
		(pts
			(arc
				(start 297.753024 -313.949842)
				(mid 297.346624 -313.949842)
				(end 297.753024 -313.949842)
			)
		)
		(stroke
			(width 0)
			(type solid)
		)
		(fill yes)
		(layer "In4.Cu")
		(net "P5E_PEX2_STN5_TX_DN<87>")
	)
	(gr_poly
		(pts
			(arc
				(start 297.753024 -312.999882)
				(mid 297.346624 -312.999882)
				(end 297.753024 -312.999882)
			)
		)
		(stroke
			(width 0)
			(type solid)
		)
		(fill yes)
		(layer "In4.Cu")
		(net "P5E_PEX2_STN5_TX_DP<87>")
	)
	(gr_poly
		(pts
			(arc
				(start 298.70273 -275.949918)
				(mid 298.29633 -275.949918)
				(end 298.70273 -275.949918)
			)
		)
		(stroke
			(width 0)
			(type solid)
		)
		(fill yes)
		(layer "In4.Cu")
		(net "P5E_PEX2_STN1_RX_DP<23>")
	)
	(gr_poly
		(pts
			(arc
				(start 298.70273 -274.999958)
				(mid 298.29633 -274.999958)
				(end 298.70273 -274.999958)
			)
		)
		(stroke
			(width 0)
			(type solid)
		)
		(fill yes)
		(layer "In4.Cu")
		(net "P5E_PEX2_STN1_RX_DN<23>")
	)
	(gr_poly
		(pts
			(arc
				(start 298.702984 -316.799722)
				(mid 298.296584 -316.799722)
				(end 298.702984 -316.799722)
			)
		)
		(stroke
			(width 0)
			(type solid)
		)
		(fill yes)
		(layer "In4.Cu")
		(net "P5E_PEX2_STN5_RX_DN<88>")
	)
	(gr_poly
		(pts
			(arc
				(start 298.702984 -315.849762)
				(mid 298.296584 -315.849762)
				(end 298.702984 -315.849762)
			)
		)
		(stroke
			(width 0)
			(type solid)
		)
		(fill yes)
		(layer "In4.Cu")
		(net "P5E_PEX2_STN5_RX_DP<88>")
	)
	(gr_poly
		(pts
			(arc
				(start 298.702984 -312.049922)
				(mid 298.296584 -312.049922)
				(end 298.702984 -312.049922)
			)
		)
		(stroke
			(width 0)
			(type solid)
		)
		(fill yes)
		(layer "In4.Cu")
		(net "P5E_PEX2_STN5_TX_DN<88>")
	)
	(gr_poly
		(pts
			(arc
				(start 298.702984 -311.099962)
				(mid 298.296584 -311.099962)
				(end 298.702984 -311.099962)
			)
		)
		(stroke
			(width 0)
			(type solid)
		)
		(fill yes)
		(layer "In4.Cu")
		(net "P5E_PEX2_STN5_TX_DP<88>")
	)
	(gr_poly
		(pts
			(arc
				(start 298.702984 -280.699464)
				(mid 298.296584 -280.699464)
				(end 298.702984 -280.699464)
			)
		)
		(stroke
			(width 0)
			(type solid)
		)
		(fill yes)
		(layer "In4.Cu")
		(net "P5E_PEX2_STN1_TX_DN<23>")
	)
	(gr_poly
		(pts
			(arc
				(start 298.702984 -279.749504)
				(mid 298.296584 -279.749504)
				(end 298.702984 -279.749504)
			)
		)
		(stroke
			(width 0)
			(type solid)
		)
		(fill yes)
		(layer "In4.Cu")
		(net "P5E_PEX2_STN1_TX_DP<23>")
	)
	(gr_poly
		(pts
			(arc
				(start 299.65269 -278.799798)
				(mid 299.24629 -278.799798)
				(end 299.65269 -278.799798)
			)
		)
		(stroke
			(width 0)
			(type solid)
		)
		(fill yes)
		(layer "In4.Cu")
		(net "P5E_PEX2_STN1_TX_DP<24>")
	)
	(gr_poly
		(pts
			(arc
				(start 299.65269 -277.849838)
				(mid 299.24629 -277.849838)
				(end 299.65269 -277.849838)
			)
		)
		(stroke
			(width 0)
			(type solid)
		)
		(fill yes)
		(layer "In4.Cu")
		(net "P5E_PEX2_STN1_TX_DN<24>")
	)
	(gr_poly
		(pts
			(arc
				(start 299.65269 -274.049744)
				(mid 299.24629 -274.049744)
				(end 299.65269 -274.049744)
			)
		)
		(stroke
			(width 0)
			(type solid)
		)
		(fill yes)
		(layer "In4.Cu")
		(net "P5E_PEX2_STN1_RX_DP<24>")
	)
	(gr_poly
		(pts
			(arc
				(start 299.65269 -273.099784)
				(mid 299.24629 -273.099784)
				(end 299.65269 -273.099784)
			)
		)
		(stroke
			(width 0)
			(type solid)
		)
		(fill yes)
		(layer "In4.Cu")
		(net "P5E_PEX2_STN1_RX_DN<24>")
	)
	(gr_poly
		(pts
			(arc
				(start 299.652944 -318.699896)
				(mid 299.246544 -318.699896)
				(end 299.652944 -318.699896)
			)
		)
		(stroke
			(width 0)
			(type solid)
		)
		(fill yes)
		(layer "In4.Cu")
		(net "P5E_PEX2_STN5_RX_DN<89>")
	)
	(gr_poly
		(pts
			(arc
				(start 299.652944 -317.749936)
				(mid 299.246544 -317.749936)
				(end 299.652944 -317.749936)
			)
		)
		(stroke
			(width 0)
			(type solid)
		)
		(fill yes)
		(layer "In4.Cu")
		(net "P5E_PEX2_STN5_RX_DP<89>")
	)
	(gr_poly
		(pts
			(arc
				(start 299.652944 -313.949842)
				(mid 299.246544 -313.949842)
				(end 299.652944 -313.949842)
			)
		)
		(stroke
			(width 0)
			(type solid)
		)
		(fill yes)
		(layer "In4.Cu")
		(net "P5E_PEX2_STN5_TX_DN<89>")
	)
	(gr_poly
		(pts
			(arc
				(start 299.652944 -312.999882)
				(mid 299.246544 -312.999882)
				(end 299.652944 -312.999882)
			)
		)
		(stroke
			(width 0)
			(type solid)
		)
		(fill yes)
		(layer "In4.Cu")
		(net "P5E_PEX2_STN5_TX_DP<89>")
	)
	(gr_poly
		(pts
			(arc
				(start 300.60265 -275.949664)
				(mid 300.19625 -275.949664)
				(end 300.60265 -275.949664)
			)
		)
		(stroke
			(width 0)
			(type solid)
		)
		(fill yes)
		(layer "In4.Cu")
		(net "P5E_PEX2_STN1_RX_DP<25>")
	)
	(gr_poly
		(pts
			(arc
				(start 300.60265 -274.999704)
				(mid 300.19625 -274.999704)
				(end 300.60265 -274.999704)
			)
		)
		(stroke
			(width 0)
			(type solid)
		)
		(fill yes)
		(layer "In4.Cu")
		(net "P5E_PEX2_STN1_RX_DN<25>")
	)
	(gr_poly
		(pts
			(arc
				(start 300.602904 -316.799722)
				(mid 300.196504 -316.799722)
				(end 300.602904 -316.799722)
			)
		)
		(stroke
			(width 0)
			(type solid)
		)
		(fill yes)
		(layer "In4.Cu")
		(net "P5E_PEX2_STN5_RX_DN<90>")
	)
	(gr_poly
		(pts
			(arc
				(start 300.602904 -315.849762)
				(mid 300.196504 -315.849762)
				(end 300.602904 -315.849762)
			)
		)
		(stroke
			(width 0)
			(type solid)
		)
		(fill yes)
		(layer "In4.Cu")
		(net "P5E_PEX2_STN5_RX_DP<90>")
	)
	(gr_poly
		(pts
			(arc
				(start 300.602904 -312.049922)
				(mid 300.196504 -312.049922)
				(end 300.602904 -312.049922)
			)
		)
		(stroke
			(width 0)
			(type solid)
		)
		(fill yes)
		(layer "In4.Cu")
		(net "P5E_PEX2_STN5_TX_DN<90>")
	)
	(gr_poly
		(pts
			(arc
				(start 300.602904 -311.099962)
				(mid 300.196504 -311.099962)
				(end 300.602904 -311.099962)
			)
		)
		(stroke
			(width 0)
			(type solid)
		)
		(fill yes)
		(layer "In4.Cu")
		(net "P5E_PEX2_STN5_TX_DP<90>")
	)
	(gr_poly
		(pts
			(arc
				(start 300.602904 -280.699464)
				(mid 300.196504 -280.699464)
				(end 300.602904 -280.699464)
			)
		)
		(stroke
			(width 0)
			(type solid)
		)
		(fill yes)
		(layer "In4.Cu")
		(net "P5E_PEX2_STN1_TX_DN<25>")
	)
	(gr_poly
		(pts
			(arc
				(start 300.602904 -279.749504)
				(mid 300.196504 -279.749504)
				(end 300.602904 -279.749504)
			)
		)
		(stroke
			(width 0)
			(type solid)
		)
		(fill yes)
		(layer "In4.Cu")
		(net "P5E_PEX2_STN1_TX_DP<25>")
	)
	(gr_poly
		(pts
			(arc
				(start 301.552864 -278.799798)
				(mid 301.146464 -278.799798)
				(end 301.552864 -278.799798)
			)
		)
		(stroke
			(width 0)
			(type solid)
		)
		(fill yes)
		(layer "In4.Cu")
		(net "P5E_PEX2_STN1_TX_DP<26>")
	)
	(gr_poly
		(pts
			(arc
				(start 301.552864 -277.849838)
				(mid 301.146464 -277.849838)
				(end 301.552864 -277.849838)
			)
		)
		(stroke
			(width 0)
			(type solid)
		)
		(fill yes)
		(layer "In4.Cu")
		(net "P5E_PEX2_STN1_TX_DN<26>")
	)
	(gr_poly
		(pts
			(arc
				(start 301.552864 -274.049744)
				(mid 301.146464 -274.049744)
				(end 301.552864 -274.049744)
			)
		)
		(stroke
			(width 0)
			(type solid)
		)
		(fill yes)
		(layer "In4.Cu")
		(net "P5E_PEX2_STN1_RX_DP<26>")
	)
	(gr_poly
		(pts
			(arc
				(start 301.552864 -273.099784)
				(mid 301.146464 -273.099784)
				(end 301.552864 -273.099784)
			)
		)
		(stroke
			(width 0)
			(type solid)
		)
		(fill yes)
		(layer "In4.Cu")
		(net "P5E_PEX2_STN1_RX_DN<26>")
	)
	(gr_poly
		(pts
			(arc
				(start 301.553118 -318.699896)
				(mid 301.146718 -318.699896)
				(end 301.553118 -318.699896)
			)
		)
		(stroke
			(width 0)
			(type solid)
		)
		(fill yes)
		(layer "In4.Cu")
		(net "P5E_PEX2_STN5_RX_DN<91>")
	)
	(gr_poly
		(pts
			(arc
				(start 301.553118 -317.749936)
				(mid 301.146718 -317.749936)
				(end 301.553118 -317.749936)
			)
		)
		(stroke
			(width 0)
			(type solid)
		)
		(fill yes)
		(layer "In4.Cu")
		(net "P5E_PEX2_STN5_RX_DP<91>")
	)
	(gr_poly
		(pts
			(arc
				(start 301.553118 -313.949842)
				(mid 301.146718 -313.949842)
				(end 301.553118 -313.949842)
			)
		)
		(stroke
			(width 0)
			(type solid)
		)
		(fill yes)
		(layer "In4.Cu")
		(net "P5E_PEX2_STN5_TX_DN<91>")
	)
	(gr_poly
		(pts
			(arc
				(start 301.553118 -312.999882)
				(mid 301.146718 -312.999882)
				(end 301.553118 -312.999882)
			)
		)
		(stroke
			(width 0)
			(type solid)
		)
		(fill yes)
		(layer "In4.Cu")
		(net "P5E_PEX2_STN5_TX_DP<91>")
	)
	(gr_poly
		(pts
			(arc
				(start 302.50257 -275.949918)
				(mid 302.09617 -275.949918)
				(end 302.50257 -275.949918)
			)
		)
		(stroke
			(width 0)
			(type solid)
		)
		(fill yes)
		(layer "In4.Cu")
		(net "P5E_PEX2_STN1_RX_DP<27>")
	)
	(gr_poly
		(pts
			(arc
				(start 302.50257 -274.999958)
				(mid 302.09617 -274.999958)
				(end 302.50257 -274.999958)
			)
		)
		(stroke
			(width 0)
			(type solid)
		)
		(fill yes)
		(layer "In4.Cu")
		(net "P5E_PEX2_STN1_RX_DN<27>")
	)
	(gr_poly
		(pts
			(arc
				(start 302.503078 -316.799722)
				(mid 302.096678 -316.799722)
				(end 302.503078 -316.799722)
			)
		)
		(stroke
			(width 0)
			(type solid)
		)
		(fill yes)
		(layer "In4.Cu")
		(net "P5E_PEX2_STN5_RX_DN<92>")
	)
	(gr_poly
		(pts
			(arc
				(start 302.503078 -315.849762)
				(mid 302.096678 -315.849762)
				(end 302.503078 -315.849762)
			)
		)
		(stroke
			(width 0)
			(type solid)
		)
		(fill yes)
		(layer "In4.Cu")
		(net "P5E_PEX2_STN5_RX_DP<92>")
	)
	(gr_poly
		(pts
			(arc
				(start 302.503078 -312.049922)
				(mid 302.096678 -312.049922)
				(end 302.503078 -312.049922)
			)
		)
		(stroke
			(width 0)
			(type solid)
		)
		(fill yes)
		(layer "In4.Cu")
		(net "P5E_PEX2_STN5_TX_DN<92>")
	)
	(gr_poly
		(pts
			(arc
				(start 302.503078 -311.099962)
				(mid 302.096678 -311.099962)
				(end 302.503078 -311.099962)
			)
		)
		(stroke
			(width 0)
			(type solid)
		)
		(fill yes)
		(layer "In4.Cu")
		(net "P5E_PEX2_STN5_TX_DP<92>")
	)
	(gr_poly
		(pts
			(arc
				(start 302.503078 -280.699464)
				(mid 302.096678 -280.699464)
				(end 302.503078 -280.699464)
			)
		)
		(stroke
			(width 0)
			(type solid)
		)
		(fill yes)
		(layer "In4.Cu")
		(net "P5E_PEX2_STN1_TX_DN<27>")
	)
	(gr_poly
		(pts
			(arc
				(start 302.503078 -279.749504)
				(mid 302.096678 -279.749504)
				(end 302.503078 -279.749504)
			)
		)
		(stroke
			(width 0)
			(type solid)
		)
		(fill yes)
		(layer "In4.Cu")
		(net "P5E_PEX2_STN1_TX_DP<27>")
	)
	(gr_poly
		(pts
			(arc
				(start 303.452784 -278.799798)
				(mid 303.046384 -278.799798)
				(end 303.452784 -278.799798)
			)
		)
		(stroke
			(width 0)
			(type solid)
		)
		(fill yes)
		(layer "In4.Cu")
		(net "P5E_PEX2_STN1_TX_DP<28>")
	)
	(gr_poly
		(pts
			(arc
				(start 303.452784 -277.849838)
				(mid 303.046384 -277.849838)
				(end 303.452784 -277.849838)
			)
		)
		(stroke
			(width 0)
			(type solid)
		)
		(fill yes)
		(layer "In4.Cu")
		(net "P5E_PEX2_STN1_TX_DN<28>")
	)
	(gr_poly
		(pts
			(arc
				(start 303.452784 -274.049744)
				(mid 303.046384 -274.049744)
				(end 303.452784 -274.049744)
			)
		)
		(stroke
			(width 0)
			(type solid)
		)
		(fill yes)
		(layer "In4.Cu")
		(net "P5E_PEX2_STN1_RX_DP<28>")
	)
	(gr_poly
		(pts
			(arc
				(start 303.452784 -273.099784)
				(mid 303.046384 -273.099784)
				(end 303.452784 -273.099784)
			)
		)
		(stroke
			(width 0)
			(type solid)
		)
		(fill yes)
		(layer "In4.Cu")
		(net "P5E_PEX2_STN1_RX_DN<28>")
	)
	(gr_poly
		(pts
			(arc
				(start 303.453038 -318.699896)
				(mid 303.046638 -318.699896)
				(end 303.453038 -318.699896)
			)
		)
		(stroke
			(width 0)
			(type solid)
		)
		(fill yes)
		(layer "In4.Cu")
		(net "P5E_PEX2_STN5_RX_DN<93>")
	)
	(gr_poly
		(pts
			(arc
				(start 303.453038 -317.749936)
				(mid 303.046638 -317.749936)
				(end 303.453038 -317.749936)
			)
		)
		(stroke
			(width 0)
			(type solid)
		)
		(fill yes)
		(layer "In4.Cu")
		(net "P5E_PEX2_STN5_RX_DP<93>")
	)
	(gr_poly
		(pts
			(arc
				(start 303.453038 -313.949842)
				(mid 303.046638 -313.949842)
				(end 303.453038 -313.949842)
			)
		)
		(stroke
			(width 0)
			(type solid)
		)
		(fill yes)
		(layer "In4.Cu")
		(net "P5E_PEX2_STN5_TX_DN<93>")
	)
	(gr_poly
		(pts
			(arc
				(start 303.453038 -312.999882)
				(mid 303.046638 -312.999882)
				(end 303.453038 -312.999882)
			)
		)
		(stroke
			(width 0)
			(type solid)
		)
		(fill yes)
		(layer "In4.Cu")
		(net "P5E_PEX2_STN5_TX_DP<93>")
	)
	(gr_poly
		(pts
			(arc
				(start 304.402744 -275.949664)
				(mid 303.996344 -275.949664)
				(end 304.402744 -275.949664)
			)
		)
		(stroke
			(width 0)
			(type solid)
		)
		(fill yes)
		(layer "In4.Cu")
		(net "P5E_PEX2_STN1_RX_DP<29>")
	)
	(gr_poly
		(pts
			(arc
				(start 304.402744 -274.999704)
				(mid 303.996344 -274.999704)
				(end 304.402744 -274.999704)
			)
		)
		(stroke
			(width 0)
			(type solid)
		)
		(fill yes)
		(layer "In4.Cu")
		(net "P5E_PEX2_STN1_RX_DN<29>")
	)
	(gr_poly
		(pts
			(arc
				(start 304.402998 -316.799722)
				(mid 303.996598 -316.799722)
				(end 304.402998 -316.799722)
			)
		)
		(stroke
			(width 0)
			(type solid)
		)
		(fill yes)
		(layer "In4.Cu")
		(net "P5E_PEX2_STN5_RX_DN<94>")
	)
	(gr_poly
		(pts
			(arc
				(start 304.402998 -315.849762)
				(mid 303.996598 -315.849762)
				(end 304.402998 -315.849762)
			)
		)
		(stroke
			(width 0)
			(type solid)
		)
		(fill yes)
		(layer "In4.Cu")
		(net "P5E_PEX2_STN5_RX_DP<94>")
	)
	(gr_poly
		(pts
			(arc
				(start 304.402998 -312.049922)
				(mid 303.996598 -312.049922)
				(end 304.402998 -312.049922)
			)
		)
		(stroke
			(width 0)
			(type solid)
		)
		(fill yes)
		(layer "In4.Cu")
		(net "P5E_PEX2_STN5_TX_DN<94>")
	)
	(gr_poly
		(pts
			(arc
				(start 304.402998 -311.099962)
				(mid 303.996598 -311.099962)
				(end 304.402998 -311.099962)
			)
		)
		(stroke
			(width 0)
			(type solid)
		)
		(fill yes)
		(layer "In4.Cu")
		(net "P5E_PEX2_STN5_TX_DP<94>")
	)
	(gr_poly
		(pts
			(arc
				(start 304.402998 -280.699464)
				(mid 303.996598 -280.699464)
				(end 304.402998 -280.699464)
			)
		)
		(stroke
			(width 0)
			(type solid)
		)
		(fill yes)
		(layer "In4.Cu")
		(net "P5E_PEX2_STN1_TX_DN<29>")
	)
	(gr_poly
		(pts
			(arc
				(start 304.402998 -279.749504)
				(mid 303.996598 -279.749504)
				(end 304.402998 -279.749504)
			)
		)
		(stroke
			(width 0)
			(type solid)
		)
		(fill yes)
		(layer "In4.Cu")
		(net "P5E_PEX2_STN1_TX_DP<29>")
	)
	(gr_poly
		(pts
			(arc
				(start 305.352704 -278.799798)
				(mid 304.946304 -278.799798)
				(end 305.352704 -278.799798)
			)
		)
		(stroke
			(width 0)
			(type solid)
		)
		(fill yes)
		(layer "In4.Cu")
		(net "P5E_PEX2_STN1_TX_DP<30>")
	)
	(gr_poly
		(pts
			(arc
				(start 305.352704 -277.849838)
				(mid 304.946304 -277.849838)
				(end 305.352704 -277.849838)
			)
		)
		(stroke
			(width 0)
			(type solid)
		)
		(fill yes)
		(layer "In4.Cu")
		(net "P5E_PEX2_STN1_TX_DN<30>")
	)
	(gr_poly
		(pts
			(arc
				(start 305.352704 -274.049744)
				(mid 304.946304 -274.049744)
				(end 305.352704 -274.049744)
			)
		)
		(stroke
			(width 0)
			(type solid)
		)
		(fill yes)
		(layer "In4.Cu")
		(net "P5E_PEX2_STN1_RX_DP<30>")
	)
	(gr_poly
		(pts
			(arc
				(start 305.352704 -273.099784)
				(mid 304.946304 -273.099784)
				(end 305.352704 -273.099784)
			)
		)
		(stroke
			(width 0)
			(type solid)
		)
		(fill yes)
		(layer "In4.Cu")
		(net "P5E_PEX2_STN1_RX_DN<30>")
	)
	(gr_poly
		(pts
			(arc
				(start 305.352958 -318.699896)
				(mid 304.946558 -318.699896)
				(end 305.352958 -318.699896)
			)
		)
		(stroke
			(width 0)
			(type solid)
		)
		(fill yes)
		(layer "In4.Cu")
		(net "P5E_PEX2_STN5_RX_DN<95>")
	)
	(gr_poly
		(pts
			(arc
				(start 305.352958 -317.749936)
				(mid 304.946558 -317.749936)
				(end 305.352958 -317.749936)
			)
		)
		(stroke
			(width 0)
			(type solid)
		)
		(fill yes)
		(layer "In4.Cu")
		(net "P5E_PEX2_STN5_RX_DP<95>")
	)
	(gr_poly
		(pts
			(arc
				(start 305.352958 -313.949842)
				(mid 304.946558 -313.949842)
				(end 305.352958 -313.949842)
			)
		)
		(stroke
			(width 0)
			(type solid)
		)
		(fill yes)
		(layer "In4.Cu")
		(net "P5E_PEX2_STN5_TX_DN<95>")
	)
	(gr_poly
		(pts
			(arc
				(start 305.352958 -312.999882)
				(mid 304.946558 -312.999882)
				(end 305.352958 -312.999882)
			)
		)
		(stroke
			(width 0)
			(type solid)
		)
		(fill yes)
		(layer "In4.Cu")
		(net "P5E_PEX2_STN5_TX_DP<95>")
	)
	(gr_poly
		(pts
			(arc
				(start 306.302664 -275.949918)
				(mid 305.896264 -275.949918)
				(end 306.302664 -275.949918)
			)
		)
		(stroke
			(width 0)
			(type solid)
		)
		(fill yes)
		(layer "In4.Cu")
		(net "P5E_PEX2_STN1_RX_DP<31>")
	)
	(gr_poly
		(pts
			(arc
				(start 306.302664 -274.999958)
				(mid 305.896264 -274.999958)
				(end 306.302664 -274.999958)
			)
		)
		(stroke
			(width 0)
			(type solid)
		)
		(fill yes)
		(layer "In4.Cu")
		(net "P5E_PEX2_STN1_RX_DN<31>")
	)
	(gr_poly
		(pts
			(arc
				(start 306.302918 -316.799722)
				(mid 305.896518 -316.799722)
				(end 306.302918 -316.799722)
			)
		)
		(stroke
			(width 0)
			(type solid)
		)
		(fill yes)
		(layer "In4.Cu")
		(net "P5E_PEX2_STN4_RX_DN<79>")
	)
	(gr_poly
		(pts
			(arc
				(start 306.302918 -315.849762)
				(mid 305.896518 -315.849762)
				(end 306.302918 -315.849762)
			)
		)
		(stroke
			(width 0)
			(type solid)
		)
		(fill yes)
		(layer "In4.Cu")
		(net "P5E_PEX2_STN4_RX_DP<79>")
	)
	(gr_poly
		(pts
			(arc
				(start 306.302918 -312.049922)
				(mid 305.896518 -312.049922)
				(end 306.302918 -312.049922)
			)
		)
		(stroke
			(width 0)
			(type solid)
		)
		(fill yes)
		(layer "In4.Cu")
		(net "P5E_PEX2_STN4_TX_DN<79>")
	)
	(gr_poly
		(pts
			(arc
				(start 306.302918 -311.099962)
				(mid 305.896518 -311.099962)
				(end 306.302918 -311.099962)
			)
		)
		(stroke
			(width 0)
			(type solid)
		)
		(fill yes)
		(layer "In4.Cu")
		(net "P5E_PEX2_STN4_TX_DP<79>")
	)
	(gr_poly
		(pts
			(arc
				(start 306.302918 -280.699464)
				(mid 305.896518 -280.699464)
				(end 306.302918 -280.699464)
			)
		)
		(stroke
			(width 0)
			(type solid)
		)
		(fill yes)
		(layer "In4.Cu")
		(net "P5E_PEX2_STN1_TX_DN<31>")
	)
	(gr_poly
		(pts
			(arc
				(start 306.302918 -279.749504)
				(mid 305.896518 -279.749504)
				(end 306.302918 -279.749504)
			)
		)
		(stroke
			(width 0)
			(type solid)
		)
		(fill yes)
		(layer "In4.Cu")
		(net "P5E_PEX2_STN1_TX_DP<31>")
	)
	(gr_poly
		(pts
			(arc
				(start 307.252878 -278.799798)
				(mid 306.846478 -278.799798)
				(end 307.252878 -278.799798)
			)
		)
		(stroke
			(width 0)
			(type solid)
		)
		(fill yes)
		(layer "In4.Cu")
		(net "P5E_PEX2_STN0_TX_DP<15>")
	)
	(gr_poly
		(pts
			(arc
				(start 307.252878 -277.849838)
				(mid 306.846478 -277.849838)
				(end 307.252878 -277.849838)
			)
		)
		(stroke
			(width 0)
			(type solid)
		)
		(fill yes)
		(layer "In4.Cu")
		(net "P5E_PEX2_STN0_TX_DN<15>")
	)
	(gr_poly
		(pts
			(arc
				(start 307.252878 -274.049744)
				(mid 306.846478 -274.049744)
				(end 307.252878 -274.049744)
			)
		)
		(stroke
			(width 0)
			(type solid)
		)
		(fill yes)
		(layer "In4.Cu")
		(net "P5E_PEX2_STN0_RX_DP<15>")
	)
	(gr_poly
		(pts
			(arc
				(start 307.252878 -273.099784)
				(mid 306.846478 -273.099784)
				(end 307.252878 -273.099784)
			)
		)
		(stroke
			(width 0)
			(type solid)
		)
		(fill yes)
		(layer "In4.Cu")
		(net "P5E_PEX2_STN0_RX_DN<15>")
	)
	(gr_poly
		(pts
			(arc
				(start 307.253132 -318.699896)
				(mid 306.846732 -318.699896)
				(end 307.253132 -318.699896)
			)
		)
		(stroke
			(width 0)
			(type solid)
		)
		(fill yes)
		(layer "In4.Cu")
		(net "P5E_PEX2_STN4_RX_DN<78>")
	)
	(gr_poly
		(pts
			(arc
				(start 307.253132 -317.749936)
				(mid 306.846732 -317.749936)
				(end 307.253132 -317.749936)
			)
		)
		(stroke
			(width 0)
			(type solid)
		)
		(fill yes)
		(layer "In4.Cu")
		(net "P5E_PEX2_STN4_RX_DP<78>")
	)
	(gr_poly
		(pts
			(arc
				(start 307.253132 -313.949842)
				(mid 306.846732 -313.949842)
				(end 307.253132 -313.949842)
			)
		)
		(stroke
			(width 0)
			(type solid)
		)
		(fill yes)
		(layer "In4.Cu")
		(net "P5E_PEX2_STN4_TX_DN<78>")
	)
	(gr_poly
		(pts
			(arc
				(start 307.253132 -312.999882)
				(mid 306.846732 -312.999882)
				(end 307.253132 -312.999882)
			)
		)
		(stroke
			(width 0)
			(type solid)
		)
		(fill yes)
		(layer "In4.Cu")
		(net "P5E_PEX2_STN4_TX_DP<78>")
	)
	(gr_poly
		(pts
			(arc
				(start 307.253132 -308.249828)
				(mid 306.846732 -308.249828)
				(end 307.253132 -308.249828)
			)
		)
		(stroke
			(width 0)
			(type solid)
		)
		(fill yes)
		(layer "In4.Cu")
		(net "P5E_PEX2_STN4_TX_DP<68>")
	)
	(gr_poly
		(pts
			(arc
				(start 307.253132 -306.349908)
				(mid 306.846732 -306.349908)
				(end 307.253132 -306.349908)
			)
		)
		(stroke
			(width 0)
			(type solid)
		)
		(fill yes)
		(layer "In4.Cu")
		(net "P5E_PEX2_STN4_TX_DP<66>")
	)
	(gr_poly
		(pts
			(arc
				(start 307.253132 -304.449734)
				(mid 306.846732 -304.449734)
				(end 307.253132 -304.449734)
			)
		)
		(stroke
			(width 0)
			(type solid)
		)
		(fill yes)
		(layer "In4.Cu")
		(net "P5E_PEX2_STN4_TX_DP<64>")
	)
	(gr_poly
		(pts
			(arc
				(start 307.253132 -287.349946)
				(mid 306.846732 -287.349946)
				(end 307.253132 -287.349946)
			)
		)
		(stroke
			(width 0)
			(type solid)
		)
		(fill yes)
		(layer "In4.Cu")
		(net "P5E_PEX2_STN0_TX_DP<1>")
	)
	(gr_poly
		(pts
			(arc
				(start 307.253132 -285.449772)
				(mid 306.846732 -285.449772)
				(end 307.253132 -285.449772)
			)
		)
		(stroke
			(width 0)
			(type solid)
		)
		(fill yes)
		(layer "In4.Cu")
		(net "P5E_PEX2_STN0_TX_DP<3>")
	)
	(gr_poly
		(pts
			(arc
				(start 307.253132 -283.549852)
				(mid 306.846732 -283.549852)
				(end 307.253132 -283.549852)
			)
		)
		(stroke
			(width 0)
			(type solid)
		)
		(fill yes)
		(layer "In4.Cu")
		(net "P5E_PEX2_STN0_TX_DP<5>")
	)
	(gr_poly
		(pts
			(arc
				(start 308.202838 -275.949664)
				(mid 307.796438 -275.949664)
				(end 308.202838 -275.949664)
			)
		)
		(stroke
			(width 0)
			(type solid)
		)
		(fill yes)
		(layer "In4.Cu")
		(net "P5E_PEX2_STN0_RX_DP<14>")
	)
	(gr_poly
		(pts
			(arc
				(start 308.202838 -274.999704)
				(mid 307.796438 -274.999704)
				(end 308.202838 -274.999704)
			)
		)
		(stroke
			(width 0)
			(type solid)
		)
		(fill yes)
		(layer "In4.Cu")
		(net "P5E_PEX2_STN0_RX_DN<14>")
	)
	(gr_poly
		(pts
			(arc
				(start 308.203092 -316.799722)
				(mid 307.796692 -316.799722)
				(end 308.203092 -316.799722)
			)
		)
		(stroke
			(width 0)
			(type solid)
		)
		(fill yes)
		(layer "In4.Cu")
		(net "P5E_PEX2_STN4_RX_DN<77>")
	)
	(gr_poly
		(pts
			(arc
				(start 308.203092 -315.849762)
				(mid 307.796692 -315.849762)
				(end 308.203092 -315.849762)
			)
		)
		(stroke
			(width 0)
			(type solid)
		)
		(fill yes)
		(layer "In4.Cu")
		(net "P5E_PEX2_STN4_RX_DP<77>")
	)
	(gr_poly
		(pts
			(arc
				(start 308.203092 -312.049922)
				(mid 307.796692 -312.049922)
				(end 308.203092 -312.049922)
			)
		)
		(stroke
			(width 0)
			(type solid)
		)
		(fill yes)
		(layer "In4.Cu")
		(net "P5E_PEX2_STN4_TX_DN<77>")
	)
	(gr_poly
		(pts
			(arc
				(start 308.203092 -311.099962)
				(mid 307.796692 -311.099962)
				(end 308.203092 -311.099962)
			)
		)
		(stroke
			(width 0)
			(type solid)
		)
		(fill yes)
		(layer "In4.Cu")
		(net "P5E_PEX2_STN4_TX_DP<77>")
	)
	(gr_poly
		(pts
			(arc
				(start 308.203092 -308.249828)
				(mid 307.796692 -308.249828)
				(end 308.203092 -308.249828)
			)
		)
		(stroke
			(width 0)
			(type solid)
		)
		(fill yes)
		(layer "In4.Cu")
		(net "P5E_PEX2_STN4_TX_DN<68>")
	)
	(gr_poly
		(pts
			(arc
				(start 308.203092 -306.349908)
				(mid 307.796692 -306.349908)
				(end 308.203092 -306.349908)
			)
		)
		(stroke
			(width 0)
			(type solid)
		)
		(fill yes)
		(layer "In4.Cu")
		(net "P5E_PEX2_STN4_TX_DN<66>")
	)
	(gr_poly
		(pts
			(arc
				(start 308.203092 -304.449734)
				(mid 307.796692 -304.449734)
				(end 308.203092 -304.449734)
			)
		)
		(stroke
			(width 0)
			(type solid)
		)
		(fill yes)
		(layer "In4.Cu")
		(net "P5E_PEX2_STN4_TX_DN<64>")
	)
	(gr_poly
		(pts
			(arc
				(start 308.203092 -287.349946)
				(mid 307.796692 -287.349946)
				(end 308.203092 -287.349946)
			)
		)
		(stroke
			(width 0)
			(type solid)
		)
		(fill yes)
		(layer "In4.Cu")
		(net "P5E_PEX2_STN0_TX_DN<1>")
	)
	(gr_poly
		(pts
			(arc
				(start 308.203092 -285.449772)
				(mid 307.796692 -285.449772)
				(end 308.203092 -285.449772)
			)
		)
		(stroke
			(width 0)
			(type solid)
		)
		(fill yes)
		(layer "In4.Cu")
		(net "P5E_PEX2_STN0_TX_DN<3>")
	)
	(gr_poly
		(pts
			(arc
				(start 308.203092 -283.549852)
				(mid 307.796692 -283.549852)
				(end 308.203092 -283.549852)
			)
		)
		(stroke
			(width 0)
			(type solid)
		)
		(fill yes)
		(layer "In4.Cu")
		(net "P5E_PEX2_STN0_TX_DN<5>")
	)
	(gr_poly
		(pts
			(arc
				(start 308.203092 -280.699464)
				(mid 307.796692 -280.699464)
				(end 308.203092 -280.699464)
			)
		)
		(stroke
			(width 0)
			(type solid)
		)
		(fill yes)
		(layer "In4.Cu")
		(net "P5E_PEX2_STN0_TX_DN<14>")
	)
	(gr_poly
		(pts
			(arc
				(start 308.203092 -279.749504)
				(mid 307.796692 -279.749504)
				(end 308.203092 -279.749504)
			)
		)
		(stroke
			(width 0)
			(type solid)
		)
		(fill yes)
		(layer "In4.Cu")
		(net "P5E_PEX2_STN0_TX_DP<14>")
	)
	(gr_poly
		(pts
			(arc
				(start 309.152798 -278.799798)
				(mid 308.746398 -278.799798)
				(end 309.152798 -278.799798)
			)
		)
		(stroke
			(width 0)
			(type solid)
		)
		(fill yes)
		(layer "In4.Cu")
		(net "P5E_PEX2_STN0_TX_DP<13>")
	)
	(gr_poly
		(pts
			(arc
				(start 309.152798 -277.849838)
				(mid 308.746398 -277.849838)
				(end 309.152798 -277.849838)
			)
		)
		(stroke
			(width 0)
			(type solid)
		)
		(fill yes)
		(layer "In4.Cu")
		(net "P5E_PEX2_STN0_TX_DN<13>")
	)
	(gr_poly
		(pts
			(arc
				(start 309.152798 -274.049744)
				(mid 308.746398 -274.049744)
				(end 309.152798 -274.049744)
			)
		)
		(stroke
			(width 0)
			(type solid)
		)
		(fill yes)
		(layer "In4.Cu")
		(net "P5E_PEX2_STN0_RX_DP<13>")
	)
	(gr_poly
		(pts
			(arc
				(start 309.152798 -273.099784)
				(mid 308.746398 -273.099784)
				(end 309.152798 -273.099784)
			)
		)
		(stroke
			(width 0)
			(type solid)
		)
		(fill yes)
		(layer "In4.Cu")
		(net "P5E_PEX2_STN0_RX_DN<13>")
	)
	(gr_poly
		(pts
			(arc
				(start 309.153052 -318.699896)
				(mid 308.746652 -318.699896)
				(end 309.153052 -318.699896)
			)
		)
		(stroke
			(width 0)
			(type solid)
		)
		(fill yes)
		(layer "In4.Cu")
		(net "P5E_PEX2_STN4_RX_DN<76>")
	)
	(gr_poly
		(pts
			(arc
				(start 309.153052 -317.749936)
				(mid 308.746652 -317.749936)
				(end 309.153052 -317.749936)
			)
		)
		(stroke
			(width 0)
			(type solid)
		)
		(fill yes)
		(layer "In4.Cu")
		(net "P5E_PEX2_STN4_RX_DP<76>")
	)
	(gr_poly
		(pts
			(arc
				(start 309.153052 -313.949842)
				(mid 308.746652 -313.949842)
				(end 309.153052 -313.949842)
			)
		)
		(stroke
			(width 0)
			(type solid)
		)
		(fill yes)
		(layer "In4.Cu")
		(net "P5E_PEX2_STN4_TX_DN<76>")
	)
	(gr_poly
		(pts
			(arc
				(start 309.153052 -312.999882)
				(mid 308.746652 -312.999882)
				(end 309.153052 -312.999882)
			)
		)
		(stroke
			(width 0)
			(type solid)
		)
		(fill yes)
		(layer "In4.Cu")
		(net "P5E_PEX2_STN4_TX_DP<76>")
	)
	(gr_poly
		(pts
			(arc
				(start 309.153052 -309.199788)
				(mid 308.746652 -309.199788)
				(end 309.153052 -309.199788)
			)
		)
		(stroke
			(width 0)
			(type solid)
		)
		(fill yes)
		(layer "In4.Cu")
		(net "P5E_PEX2_STN4_TX_DP<69>")
	)
	(gr_poly
		(pts
			(arc
				(start 309.153052 -307.299868)
				(mid 308.746652 -307.299868)
				(end 309.153052 -307.299868)
			)
		)
		(stroke
			(width 0)
			(type solid)
		)
		(fill yes)
		(layer "In4.Cu")
		(net "P5E_PEX2_STN4_TX_DP<67>")
	)
	(gr_poly
		(pts
			(arc
				(start 309.153052 -305.399948)
				(mid 308.746652 -305.399948)
				(end 309.153052 -305.399948)
			)
		)
		(stroke
			(width 0)
			(type solid)
		)
		(fill yes)
		(layer "In4.Cu")
		(net "P5E_PEX2_STN4_TX_DP<65>")
	)
	(gr_poly
		(pts
			(arc
				(start 309.153052 -288.299906)
				(mid 308.746652 -288.299906)
				(end 309.153052 -288.299906)
			)
		)
		(stroke
			(width 0)
			(type solid)
		)
		(fill yes)
		(layer "In4.Cu")
		(net "P5E_PEX2_STN0_TX_DP<0>")
	)
	(gr_poly
		(pts
			(arc
				(start 309.153052 -286.399986)
				(mid 308.746652 -286.399986)
				(end 309.153052 -286.399986)
			)
		)
		(stroke
			(width 0)
			(type solid)
		)
		(fill yes)
		(layer "In4.Cu")
		(net "P5E_PEX2_STN0_TX_DP<2>")
	)
	(gr_poly
		(pts
			(arc
				(start 309.153052 -284.499812)
				(mid 308.746652 -284.499812)
				(end 309.153052 -284.499812)
			)
		)
		(stroke
			(width 0)
			(type solid)
		)
		(fill yes)
		(layer "In4.Cu")
		(net "P5E_PEX2_STN0_TX_DP<4>")
	)
	(gr_poly
		(pts
			(arc
				(start 309.153052 -282.599892)
				(mid 308.746652 -282.599892)
				(end 309.153052 -282.599892)
			)
		)
		(stroke
			(width 0)
			(type solid)
		)
		(fill yes)
		(layer "In4.Cu")
		(net "P5E_PEX2_STN0_TX_DP<6>")
	)
	(gr_poly
		(pts
			(arc
				(start 310.102758 -275.949918)
				(mid 309.696358 -275.949918)
				(end 310.102758 -275.949918)
			)
		)
		(stroke
			(width 0)
			(type solid)
		)
		(fill yes)
		(layer "In4.Cu")
		(net "P5E_PEX2_STN0_RX_DP<12>")
	)
	(gr_poly
		(pts
			(arc
				(start 310.102758 -274.999958)
				(mid 309.696358 -274.999958)
				(end 310.102758 -274.999958)
			)
		)
		(stroke
			(width 0)
			(type solid)
		)
		(fill yes)
		(layer "In4.Cu")
		(net "P5E_PEX2_STN0_RX_DN<12>")
	)
	(gr_poly
		(pts
			(arc
				(start 310.103012 -316.799722)
				(mid 309.696612 -316.799722)
				(end 310.103012 -316.799722)
			)
		)
		(stroke
			(width 0)
			(type solid)
		)
		(fill yes)
		(layer "In4.Cu")
		(net "P5E_PEX2_STN4_RX_DN<75>")
	)
	(gr_poly
		(pts
			(arc
				(start 310.103012 -315.849762)
				(mid 309.696612 -315.849762)
				(end 310.103012 -315.849762)
			)
		)
		(stroke
			(width 0)
			(type solid)
		)
		(fill yes)
		(layer "In4.Cu")
		(net "P5E_PEX2_STN4_RX_DP<75>")
	)
	(gr_poly
		(pts
			(arc
				(start 310.103012 -312.049922)
				(mid 309.696612 -312.049922)
				(end 310.103012 -312.049922)
			)
		)
		(stroke
			(width 0)
			(type solid)
		)
		(fill yes)
		(layer "In4.Cu")
		(net "P5E_PEX2_STN4_TX_DN<75>")
	)
	(gr_poly
		(pts
			(arc
				(start 310.103012 -311.099962)
				(mid 309.696612 -311.099962)
				(end 310.103012 -311.099962)
			)
		)
		(stroke
			(width 0)
			(type solid)
		)
		(fill yes)
		(layer "In4.Cu")
		(net "P5E_PEX2_STN4_TX_DP<75>")
	)
	(gr_poly
		(pts
			(arc
				(start 310.103012 -309.199788)
				(mid 309.696612 -309.199788)
				(end 310.103012 -309.199788)
			)
		)
		(stroke
			(width 0)
			(type solid)
		)
		(fill yes)
		(layer "In4.Cu")
		(net "P5E_PEX2_STN4_TX_DN<69>")
	)
	(gr_poly
		(pts
			(arc
				(start 310.103012 -307.299868)
				(mid 309.696612 -307.299868)
				(end 310.103012 -307.299868)
			)
		)
		(stroke
			(width 0)
			(type solid)
		)
		(fill yes)
		(layer "In4.Cu")
		(net "P5E_PEX2_STN4_TX_DN<67>")
	)
	(gr_poly
		(pts
			(arc
				(start 310.103012 -305.399948)
				(mid 309.696612 -305.399948)
				(end 310.103012 -305.399948)
			)
		)
		(stroke
			(width 0)
			(type solid)
		)
		(fill yes)
		(layer "In4.Cu")
		(net "P5E_PEX2_STN4_TX_DN<65>")
	)
	(gr_poly
		(pts
			(arc
				(start 310.103012 -288.299906)
				(mid 309.696612 -288.299906)
				(end 310.103012 -288.299906)
			)
		)
		(stroke
			(width 0)
			(type solid)
		)
		(fill yes)
		(layer "In4.Cu")
		(net "P5E_PEX2_STN0_TX_DN<0>")
	)
	(gr_poly
		(pts
			(arc
				(start 310.103012 -286.399986)
				(mid 309.696612 -286.399986)
				(end 310.103012 -286.399986)
			)
		)
		(stroke
			(width 0)
			(type solid)
		)
		(fill yes)
		(layer "In4.Cu")
		(net "P5E_PEX2_STN0_TX_DN<2>")
	)
	(gr_poly
		(pts
			(arc
				(start 310.103012 -284.499812)
				(mid 309.696612 -284.499812)
				(end 310.103012 -284.499812)
			)
		)
		(stroke
			(width 0)
			(type solid)
		)
		(fill yes)
		(layer "In4.Cu")
		(net "P5E_PEX2_STN0_TX_DN<4>")
	)
	(gr_poly
		(pts
			(arc
				(start 310.103012 -282.599892)
				(mid 309.696612 -282.599892)
				(end 310.103012 -282.599892)
			)
		)
		(stroke
			(width 0)
			(type solid)
		)
		(fill yes)
		(layer "In4.Cu")
		(net "P5E_PEX2_STN0_TX_DN<6>")
	)
	(gr_poly
		(pts
			(arc
				(start 310.103012 -280.699464)
				(mid 309.696612 -280.699464)
				(end 310.103012 -280.699464)
			)
		)
		(stroke
			(width 0)
			(type solid)
		)
		(fill yes)
		(layer "In4.Cu")
		(net "P5E_PEX2_STN0_TX_DN<12>")
	)
	(gr_poly
		(pts
			(arc
				(start 310.103012 -279.749504)
				(mid 309.696612 -279.749504)
				(end 310.103012 -279.749504)
			)
		)
		(stroke
			(width 0)
			(type solid)
		)
		(fill yes)
		(layer "In4.Cu")
		(net "P5E_PEX2_STN0_TX_DP<12>")
	)
	(gr_poly
		(pts
			(arc
				(start 311.052718 -278.799798)
				(mid 310.646318 -278.799798)
				(end 311.052718 -278.799798)
			)
		)
		(stroke
			(width 0)
			(type solid)
		)
		(fill yes)
		(layer "In4.Cu")
		(net "P5E_PEX2_STN0_TX_DP<11>")
	)
	(gr_poly
		(pts
			(arc
				(start 311.052718 -277.849838)
				(mid 310.646318 -277.849838)
				(end 311.052718 -277.849838)
			)
		)
		(stroke
			(width 0)
			(type solid)
		)
		(fill yes)
		(layer "In4.Cu")
		(net "P5E_PEX2_STN0_TX_DN<11>")
	)
	(gr_poly
		(pts
			(arc
				(start 311.052718 -274.049744)
				(mid 310.646318 -274.049744)
				(end 311.052718 -274.049744)
			)
		)
		(stroke
			(width 0)
			(type solid)
		)
		(fill yes)
		(layer "In4.Cu")
		(net "P5E_PEX2_STN0_RX_DP<11>")
	)
	(gr_poly
		(pts
			(arc
				(start 311.052718 -273.099784)
				(mid 310.646318 -273.099784)
				(end 311.052718 -273.099784)
			)
		)
		(stroke
			(width 0)
			(type solid)
		)
		(fill yes)
		(layer "In4.Cu")
		(net "P5E_PEX2_STN0_RX_DN<11>")
	)
	(gr_poly
		(pts
			(arc
				(start 311.052972 -318.699896)
				(mid 310.646572 -318.699896)
				(end 311.052972 -318.699896)
			)
		)
		(stroke
			(width 0)
			(type solid)
		)
		(fill yes)
		(layer "In4.Cu")
		(net "P5E_PEX2_STN4_RX_DN<74>")
	)
	(gr_poly
		(pts
			(arc
				(start 311.052972 -317.749936)
				(mid 310.646572 -317.749936)
				(end 311.052972 -317.749936)
			)
		)
		(stroke
			(width 0)
			(type solid)
		)
		(fill yes)
		(layer "In4.Cu")
		(net "P5E_PEX2_STN4_RX_DP<74>")
	)
	(gr_poly
		(pts
			(arc
				(start 311.052972 -313.949842)
				(mid 310.646572 -313.949842)
				(end 311.052972 -313.949842)
			)
		)
		(stroke
			(width 0)
			(type solid)
		)
		(fill yes)
		(layer "In4.Cu")
		(net "P5E_PEX2_STN4_TX_DN<74>")
	)
	(gr_poly
		(pts
			(arc
				(start 311.052972 -312.999882)
				(mid 310.646572 -312.999882)
				(end 311.052972 -312.999882)
			)
		)
		(stroke
			(width 0)
			(type solid)
		)
		(fill yes)
		(layer "In4.Cu")
		(net "P5E_PEX2_STN4_TX_DP<74>")
	)
	(gr_poly
		(pts
			(arc
				(start 312.002678 -275.949918)
				(mid 311.596278 -275.949918)
				(end 312.002678 -275.949918)
			)
		)
		(stroke
			(width 0)
			(type solid)
		)
		(fill yes)
		(layer "In4.Cu")
		(net "P5E_PEX2_STN0_RX_DP<10>")
	)
	(gr_poly
		(pts
			(arc
				(start 312.002678 -274.999958)
				(mid 311.596278 -274.999958)
				(end 312.002678 -274.999958)
			)
		)
		(stroke
			(width 0)
			(type solid)
		)
		(fill yes)
		(layer "In4.Cu")
		(net "P5E_PEX2_STN0_RX_DN<10>")
	)
	(gr_poly
		(pts
			(arc
				(start 312.002932 -316.799722)
				(mid 311.596532 -316.799722)
				(end 312.002932 -316.799722)
			)
		)
		(stroke
			(width 0)
			(type solid)
		)
		(fill yes)
		(layer "In4.Cu")
		(net "P5E_PEX2_STN4_RX_DN<73>")
	)
	(gr_poly
		(pts
			(arc
				(start 312.002932 -315.849762)
				(mid 311.596532 -315.849762)
				(end 312.002932 -315.849762)
			)
		)
		(stroke
			(width 0)
			(type solid)
		)
		(fill yes)
		(layer "In4.Cu")
		(net "P5E_PEX2_STN4_RX_DP<73>")
	)
	(gr_poly
		(pts
			(arc
				(start 312.002932 -312.049922)
				(mid 311.596532 -312.049922)
				(end 312.002932 -312.049922)
			)
		)
		(stroke
			(width 0)
			(type solid)
		)
		(fill yes)
		(layer "In4.Cu")
		(net "P5E_PEX2_STN4_TX_DN<73>")
	)
	(gr_poly
		(pts
			(arc
				(start 312.002932 -311.099962)
				(mid 311.596532 -311.099962)
				(end 312.002932 -311.099962)
			)
		)
		(stroke
			(width 0)
			(type solid)
		)
		(fill yes)
		(layer "In4.Cu")
		(net "P5E_PEX2_STN4_TX_DP<73>")
	)
	(gr_poly
		(pts
			(arc
				(start 312.002932 -309.199788)
				(mid 311.596532 -309.199788)
				(end 312.002932 -309.199788)
			)
		)
		(stroke
			(width 0)
			(type solid)
		)
		(fill yes)
		(layer "In4.Cu")
		(net "P5E_PEX2_STN4_RX_DP<69>")
	)
	(gr_poly
		(pts
			(arc
				(start 312.002932 -307.299868)
				(mid 311.596532 -307.299868)
				(end 312.002932 -307.299868)
			)
		)
		(stroke
			(width 0)
			(type solid)
		)
		(fill yes)
		(layer "In4.Cu")
		(net "P5E_PEX2_STN4_RX_DP<67>")
	)
	(gr_poly
		(pts
			(arc
				(start 312.002932 -305.399948)
				(mid 311.596532 -305.399948)
				(end 312.002932 -305.399948)
			)
		)
		(stroke
			(width 0)
			(type solid)
		)
		(fill yes)
		(layer "In4.Cu")
		(net "P5E_PEX2_STN4_RX_DP<65>")
	)
	(gr_poly
		(pts
			(arc
				(start 312.002932 -288.299906)
				(mid 311.596532 -288.299906)
				(end 312.002932 -288.299906)
			)
		)
		(stroke
			(width 0)
			(type solid)
		)
		(fill yes)
		(layer "In4.Cu")
		(net "P5E_PEX2_STN0_RX_DP<0>")
	)
	(gr_poly
		(pts
			(arc
				(start 312.002932 -286.399732)
				(mid 311.596532 -286.399732)
				(end 312.002932 -286.399732)
			)
		)
		(stroke
			(width 0)
			(type solid)
		)
		(fill yes)
		(layer "In4.Cu")
		(net "P5E_PEX2_STN0_RX_DP<2>")
	)
	(gr_poly
		(pts
			(arc
				(start 312.002932 -284.499812)
				(mid 311.596532 -284.499812)
				(end 312.002932 -284.499812)
			)
		)
		(stroke
			(width 0)
			(type solid)
		)
		(fill yes)
		(layer "In4.Cu")
		(net "P5E_PEX2_STN0_RX_DP<4>")
	)
	(gr_poly
		(pts
			(arc
				(start 312.002932 -282.599892)
				(mid 311.596532 -282.599892)
				(end 312.002932 -282.599892)
			)
		)
		(stroke
			(width 0)
			(type solid)
		)
		(fill yes)
		(layer "In4.Cu")
		(net "P5E_PEX2_STN0_RX_DP<6>")
	)
	(gr_poly
		(pts
			(arc
				(start 312.002932 -280.699718)
				(mid 311.596532 -280.699718)
				(end 312.002932 -280.699718)
			)
		)
		(stroke
			(width 0)
			(type solid)
		)
		(fill yes)
		(layer "In4.Cu")
		(net "P5E_PEX2_STN0_TX_DP<10>")
	)
	(gr_poly
		(pts
			(arc
				(start 312.002932 -279.749758)
				(mid 311.596532 -279.749758)
				(end 312.002932 -279.749758)
			)
		)
		(stroke
			(width 0)
			(type solid)
		)
		(fill yes)
		(layer "In4.Cu")
		(net "P5E_PEX2_STN0_TX_DN<10>")
	)
	(gr_poly
		(pts
			(arc
				(start 312.952638 -274.049744)
				(mid 312.546238 -274.049744)
				(end 312.952638 -274.049744)
			)
		)
		(stroke
			(width 0)
			(type solid)
		)
		(fill yes)
		(layer "In4.Cu")
		(net "P5E_PEX2_STN0_RX_DP<9>")
	)
	(gr_poly
		(pts
			(arc
				(start 312.952638 -273.099784)
				(mid 312.546238 -273.099784)
				(end 312.952638 -273.099784)
			)
		)
		(stroke
			(width 0)
			(type solid)
		)
		(fill yes)
		(layer "In4.Cu")
		(net "P5E_PEX2_STN0_RX_DN<9>")
	)
	(gr_poly
		(pts
			(arc
				(start 312.952892 -318.699896)
				(mid 312.546492 -318.699896)
				(end 312.952892 -318.699896)
			)
		)
		(stroke
			(width 0)
			(type solid)
		)
		(fill yes)
		(layer "In4.Cu")
		(net "P5E_PEX2_STN4_RX_DN<72>")
	)
	(gr_poly
		(pts
			(arc
				(start 312.952892 -317.749936)
				(mid 312.546492 -317.749936)
				(end 312.952892 -317.749936)
			)
		)
		(stroke
			(width 0)
			(type solid)
		)
		(fill yes)
		(layer "In4.Cu")
		(net "P5E_PEX2_STN4_RX_DP<72>")
	)
	(gr_poly
		(pts
			(arc
				(start 312.952892 -313.949842)
				(mid 312.546492 -313.949842)
				(end 312.952892 -313.949842)
			)
		)
		(stroke
			(width 0)
			(type solid)
		)
		(fill yes)
		(layer "In4.Cu")
		(net "P5E_PEX2_STN4_TX_DN<72>")
	)
	(gr_poly
		(pts
			(arc
				(start 312.952892 -312.999882)
				(mid 312.546492 -312.999882)
				(end 312.952892 -312.999882)
			)
		)
		(stroke
			(width 0)
			(type solid)
		)
		(fill yes)
		(layer "In4.Cu")
		(net "P5E_PEX2_STN4_TX_DP<72>")
	)
	(gr_poly
		(pts
			(arc
				(start 312.952892 -309.199788)
				(mid 312.546492 -309.199788)
				(end 312.952892 -309.199788)
			)
		)
		(stroke
			(width 0)
			(type solid)
		)
		(fill yes)
		(layer "In4.Cu")
		(net "P5E_PEX2_STN4_RX_DN<69>")
	)
	(gr_poly
		(pts
			(arc
				(start 312.952892 -307.299868)
				(mid 312.546492 -307.299868)
				(end 312.952892 -307.299868)
			)
		)
		(stroke
			(width 0)
			(type solid)
		)
		(fill yes)
		(layer "In4.Cu")
		(net "P5E_PEX2_STN4_RX_DN<67>")
	)
	(gr_poly
		(pts
			(arc
				(start 312.952892 -305.399948)
				(mid 312.546492 -305.399948)
				(end 312.952892 -305.399948)
			)
		)
		(stroke
			(width 0)
			(type solid)
		)
		(fill yes)
		(layer "In4.Cu")
		(net "P5E_PEX2_STN4_RX_DN<65>")
	)
	(gr_poly
		(pts
			(arc
				(start 312.952892 -288.299906)
				(mid 312.546492 -288.299906)
				(end 312.952892 -288.299906)
			)
		)
		(stroke
			(width 0)
			(type solid)
		)
		(fill yes)
		(layer "In4.Cu")
		(net "P5E_PEX2_STN0_RX_DN<0>")
	)
	(gr_poly
		(pts
			(arc
				(start 312.952892 -286.399732)
				(mid 312.546492 -286.399732)
				(end 312.952892 -286.399732)
			)
		)
		(stroke
			(width 0)
			(type solid)
		)
		(fill yes)
		(layer "In4.Cu")
		(net "P5E_PEX2_STN0_RX_DN<2>")
	)
	(gr_poly
		(pts
			(arc
				(start 312.952892 -284.499812)
				(mid 312.546492 -284.499812)
				(end 312.952892 -284.499812)
			)
		)
		(stroke
			(width 0)
			(type solid)
		)
		(fill yes)
		(layer "In4.Cu")
		(net "P5E_PEX2_STN0_RX_DN<4>")
	)
	(gr_poly
		(pts
			(arc
				(start 312.952892 -282.599892)
				(mid 312.546492 -282.599892)
				(end 312.952892 -282.599892)
			)
		)
		(stroke
			(width 0)
			(type solid)
		)
		(fill yes)
		(layer "In4.Cu")
		(net "P5E_PEX2_STN0_RX_DN<6>")
	)
	(gr_poly
		(pts
			(arc
				(start 312.952892 -278.799798)
				(mid 312.546492 -278.799798)
				(end 312.952892 -278.799798)
			)
		)
		(stroke
			(width 0)
			(type solid)
		)
		(fill yes)
		(layer "In4.Cu")
		(net "P5E_PEX2_STN0_TX_DP<9>")
	)
	(gr_poly
		(pts
			(arc
				(start 312.952892 -277.849838)
				(mid 312.546492 -277.849838)
				(end 312.952892 -277.849838)
			)
		)
		(stroke
			(width 0)
			(type solid)
		)
		(fill yes)
		(layer "In4.Cu")
		(net "P5E_PEX2_STN0_TX_DN<9>")
	)
	(gr_poly
		(pts
			(arc
				(start 313.903106 -316.799722)
				(mid 313.496706 -316.799722)
				(end 313.903106 -316.799722)
			)
		)
		(stroke
			(width 0)
			(type solid)
		)
		(fill yes)
		(layer "In4.Cu")
		(net "P5E_PEX2_STN4_RX_DP<71>")
	)
	(gr_poly
		(pts
			(arc
				(start 313.903106 -314.899802)
				(mid 313.496706 -314.899802)
				(end 313.903106 -314.899802)
			)
		)
		(stroke
			(width 0)
			(type solid)
		)
		(fill yes)
		(layer "In4.Cu")
		(net "P5E_PEX2_STN4_TX_DP<71>")
	)
	(gr_poly
		(pts
			(arc
				(start 313.903106 -312.049922)
				(mid 313.496706 -312.049922)
				(end 313.903106 -312.049922)
			)
		)
		(stroke
			(width 0)
			(type solid)
		)
		(fill yes)
		(layer "In4.Cu")
		(net "P5E_PEX2_STN4_TX_DP<70>")
	)
	(gr_poly
		(pts
			(arc
				(start 313.903106 -310.149748)
				(mid 313.496706 -310.149748)
				(end 313.903106 -310.149748)
			)
		)
		(stroke
			(width 0)
			(type solid)
		)
		(fill yes)
		(layer "In4.Cu")
		(net "P5E_PEX2_STN4_RX_DP<70>")
	)
	(gr_poly
		(pts
			(arc
				(start 313.903106 -308.249828)
				(mid 313.496706 -308.249828)
				(end 313.903106 -308.249828)
			)
		)
		(stroke
			(width 0)
			(type solid)
		)
		(fill yes)
		(layer "In4.Cu")
		(net "P5E_PEX2_STN4_RX_DP<68>")
	)
	(gr_poly
		(pts
			(arc
				(start 313.903106 -306.349908)
				(mid 313.496706 -306.349908)
				(end 313.903106 -306.349908)
			)
		)
		(stroke
			(width 0)
			(type solid)
		)
		(fill yes)
		(layer "In4.Cu")
		(net "P5E_PEX2_STN4_RX_DP<66>")
	)
	(gr_poly
		(pts
			(arc
				(start 313.903106 -304.449734)
				(mid 313.496706 -304.449734)
				(end 313.903106 -304.449734)
			)
		)
		(stroke
			(width 0)
			(type solid)
		)
		(fill yes)
		(layer "In4.Cu")
		(net "P5E_PEX2_STN4_RX_DP<64>")
	)
	(gr_poly
		(pts
			(arc
				(start 313.903106 -287.349946)
				(mid 313.496706 -287.349946)
				(end 313.903106 -287.349946)
			)
		)
		(stroke
			(width 0)
			(type solid)
		)
		(fill yes)
		(layer "In4.Cu")
		(net "P5E_PEX2_STN0_RX_DP<1>")
	)
	(gr_poly
		(pts
			(arc
				(start 313.903106 -285.449772)
				(mid 313.496706 -285.449772)
				(end 313.903106 -285.449772)
			)
		)
		(stroke
			(width 0)
			(type solid)
		)
		(fill yes)
		(layer "In4.Cu")
		(net "P5E_PEX2_STN0_RX_DP<3>")
	)
	(gr_poly
		(pts
			(arc
				(start 313.903106 -283.549852)
				(mid 313.496706 -283.549852)
				(end 313.903106 -283.549852)
			)
		)
		(stroke
			(width 0)
			(type solid)
		)
		(fill yes)
		(layer "In4.Cu")
		(net "P5E_PEX2_STN0_RX_DP<5>")
	)
	(gr_poly
		(pts
			(arc
				(start 313.903106 -281.649932)
				(mid 313.496706 -281.649932)
				(end 313.903106 -281.649932)
			)
		)
		(stroke
			(width 0)
			(type solid)
		)
		(fill yes)
		(layer "In4.Cu")
		(net "P5E_PEX2_STN0_RX_DP<7>")
	)
	(gr_poly
		(pts
			(arc
				(start 313.903106 -279.749758)
				(mid 313.496706 -279.749758)
				(end 313.903106 -279.749758)
			)
		)
		(stroke
			(width 0)
			(type solid)
		)
		(fill yes)
		(layer "In4.Cu")
		(net "P5E_PEX2_STN0_TX_DP<7>")
	)
	(gr_poly
		(pts
			(arc
				(start 313.903106 -276.899878)
				(mid 313.496706 -276.899878)
				(end 313.903106 -276.899878)
			)
		)
		(stroke
			(width 0)
			(type solid)
		)
		(fill yes)
		(layer "In4.Cu")
		(net "P5E_PEX2_STN0_TX_DP<8>")
	)
	(gr_poly
		(pts
			(arc
				(start 313.903106 -274.999704)
				(mid 313.496706 -274.999704)
				(end 313.903106 -274.999704)
			)
		)
		(stroke
			(width 0)
			(type solid)
		)
		(fill yes)
		(layer "In4.Cu")
		(net "P5E_PEX2_STN0_RX_DP<8>")
	)
	(gr_poly
		(pts
			(arc
				(start 314.853066 -316.799722)
				(mid 314.446666 -316.799722)
				(end 314.853066 -316.799722)
			)
		)
		(stroke
			(width 0)
			(type solid)
		)
		(fill yes)
		(layer "In4.Cu")
		(net "P5E_PEX2_STN4_RX_DN<71>")
	)
	(gr_poly
		(pts
			(arc
				(start 314.853066 -314.899802)
				(mid 314.446666 -314.899802)
				(end 314.853066 -314.899802)
			)
		)
		(stroke
			(width 0)
			(type solid)
		)
		(fill yes)
		(layer "In4.Cu")
		(net "P5E_PEX2_STN4_TX_DN<71>")
	)
	(gr_poly
		(pts
			(arc
				(start 314.853066 -312.049922)
				(mid 314.446666 -312.049922)
				(end 314.853066 -312.049922)
			)
		)
		(stroke
			(width 0)
			(type solid)
		)
		(fill yes)
		(layer "In4.Cu")
		(net "P5E_PEX2_STN4_TX_DN<70>")
	)
	(gr_poly
		(pts
			(arc
				(start 314.853066 -310.149748)
				(mid 314.446666 -310.149748)
				(end 314.853066 -310.149748)
			)
		)
		(stroke
			(width 0)
			(type solid)
		)
		(fill yes)
		(layer "In4.Cu")
		(net "P5E_PEX2_STN4_RX_DN<70>")
	)
	(gr_poly
		(pts
			(arc
				(start 314.853066 -308.249828)
				(mid 314.446666 -308.249828)
				(end 314.853066 -308.249828)
			)
		)
		(stroke
			(width 0)
			(type solid)
		)
		(fill yes)
		(layer "In4.Cu")
		(net "P5E_PEX2_STN4_RX_DN<68>")
	)
	(gr_poly
		(pts
			(arc
				(start 314.853066 -306.349908)
				(mid 314.446666 -306.349908)
				(end 314.853066 -306.349908)
			)
		)
		(stroke
			(width 0)
			(type solid)
		)
		(fill yes)
		(layer "In4.Cu")
		(net "P5E_PEX2_STN4_RX_DN<66>")
	)
	(gr_poly
		(pts
			(arc
				(start 314.853066 -304.449734)
				(mid 314.446666 -304.449734)
				(end 314.853066 -304.449734)
			)
		)
		(stroke
			(width 0)
			(type solid)
		)
		(fill yes)
		(layer "In4.Cu")
		(net "P5E_PEX2_STN4_RX_DN<64>")
	)
	(gr_poly
		(pts
			(arc
				(start 314.853066 -287.349946)
				(mid 314.446666 -287.349946)
				(end 314.853066 -287.349946)
			)
		)
		(stroke
			(width 0)
			(type solid)
		)
		(fill yes)
		(layer "In4.Cu")
		(net "P5E_PEX2_STN0_RX_DN<1>")
	)
	(gr_poly
		(pts
			(arc
				(start 314.853066 -285.449772)
				(mid 314.446666 -285.449772)
				(end 314.853066 -285.449772)
			)
		)
		(stroke
			(width 0)
			(type solid)
		)
		(fill yes)
		(layer "In4.Cu")
		(net "P5E_PEX2_STN0_RX_DN<3>")
	)
	(gr_poly
		(pts
			(arc
				(start 314.853066 -283.549852)
				(mid 314.446666 -283.549852)
				(end 314.853066 -283.549852)
			)
		)
		(stroke
			(width 0)
			(type solid)
		)
		(fill yes)
		(layer "In4.Cu")
		(net "P5E_PEX2_STN0_RX_DN<5>")
	)
	(gr_poly
		(pts
			(arc
				(start 314.853066 -281.649932)
				(mid 314.446666 -281.649932)
				(end 314.853066 -281.649932)
			)
		)
		(stroke
			(width 0)
			(type solid)
		)
		(fill yes)
		(layer "In4.Cu")
		(net "P5E_PEX2_STN0_RX_DN<7>")
	)
	(gr_poly
		(pts
			(arc
				(start 314.853066 -279.749758)
				(mid 314.446666 -279.749758)
				(end 314.853066 -279.749758)
			)
		)
		(stroke
			(width 0)
			(type solid)
		)
		(fill yes)
		(layer "In4.Cu")
		(net "P5E_PEX2_STN0_TX_DN<7>")
	)
	(gr_poly
		(pts
			(arc
				(start 314.853066 -276.899878)
				(mid 314.446666 -276.899878)
				(end 314.853066 -276.899878)
			)
		)
		(stroke
			(width 0)
			(type solid)
		)
		(fill yes)
		(layer "In4.Cu")
		(net "P5E_PEX2_STN0_TX_DN<8>")
	)
	(gr_poly
		(pts
			(arc
				(start 314.853066 -274.999704)
				(mid 314.446666 -274.999704)
				(end 314.853066 -274.999704)
			)
		)
		(stroke
			(width 0)
			(type solid)
		)
		(fill yes)
		(layer "In4.Cu")
		(net "P5E_PEX2_STN0_RX_DN<8>")
	)
	(gr_poly
		(pts
			(arc
				(start 385.353052 -316.799722)
				(mid 384.946652 -316.799722)
				(end 385.353052 -316.799722)
			)
		)
		(stroke
			(width 0)
			(type solid)
		)
		(fill yes)
		(layer "In4.Cu")
		(net "P5E_PEX3_STN7_RX_DN<122>")
	)
	(gr_poly
		(pts
			(arc
				(start 385.353052 -314.899802)
				(mid 384.946652 -314.899802)
				(end 385.353052 -314.899802)
			)
		)
		(stroke
			(width 0)
			(type solid)
		)
		(fill yes)
		(layer "In4.Cu")
		(net "P5E_PEX3_STN7_TX_DN<122>")
	)
	(gr_poly
		(pts
			(arc
				(start 385.353052 -312.049922)
				(mid 384.946652 -312.049922)
				(end 385.353052 -312.049922)
			)
		)
		(stroke
			(width 0)
			(type solid)
		)
		(fill yes)
		(layer "In4.Cu")
		(net "P5E_PEX3_STN7_TX_DN<121>")
	)
	(gr_poly
		(pts
			(arc
				(start 385.353052 -310.149748)
				(mid 384.946652 -310.149748)
				(end 385.353052 -310.149748)
			)
		)
		(stroke
			(width 0)
			(type solid)
		)
		(fill yes)
		(layer "In4.Cu")
		(net "P5E_PEX3_STN7_RX_DN<121>")
	)
	(gr_poly
		(pts
			(arc
				(start 385.353052 -308.249828)
				(mid 384.946652 -308.249828)
				(end 385.353052 -308.249828)
			)
		)
		(stroke
			(width 0)
			(type solid)
		)
		(fill yes)
		(layer "In4.Cu")
		(net "P5E_PEX3_STN7_RX_DN<119>")
	)
	(gr_poly
		(pts
			(arc
				(start 385.353052 -306.349908)
				(mid 384.946652 -306.349908)
				(end 385.353052 -306.349908)
			)
		)
		(stroke
			(width 0)
			(type solid)
		)
		(fill yes)
		(layer "In4.Cu")
		(net "P5E_PEX3_STN7_RX_DN<117>")
	)
	(gr_poly
		(pts
			(arc
				(start 385.353052 -304.449734)
				(mid 384.946652 -304.449734)
				(end 385.353052 -304.449734)
			)
		)
		(stroke
			(width 0)
			(type solid)
		)
		(fill yes)
		(layer "In4.Cu")
		(net "P5E_PEX3_STN7_RX_DN<115>")
	)
	(gr_poly
		(pts
			(arc
				(start 385.353052 -302.549814)
				(mid 384.946652 -302.549814)
				(end 385.353052 -302.549814)
			)
		)
		(stroke
			(width 0)
			(type solid)
		)
		(fill yes)
		(layer "In4.Cu")
		(net "P5E_PEX3_STN7_RX_DN<113>")
	)
	(gr_poly
		(pts
			(arc
				(start 386.303012 -316.799722)
				(mid 385.896612 -316.799722)
				(end 386.303012 -316.799722)
			)
		)
		(stroke
			(width 0)
			(type solid)
		)
		(fill yes)
		(layer "In4.Cu")
		(net "P5E_PEX3_STN7_RX_DP<122>")
	)
	(gr_poly
		(pts
			(arc
				(start 386.303012 -314.899802)
				(mid 385.896612 -314.899802)
				(end 386.303012 -314.899802)
			)
		)
		(stroke
			(width 0)
			(type solid)
		)
		(fill yes)
		(layer "In4.Cu")
		(net "P5E_PEX3_STN7_TX_DP<122>")
	)
	(gr_poly
		(pts
			(arc
				(start 386.303012 -312.049922)
				(mid 385.896612 -312.049922)
				(end 386.303012 -312.049922)
			)
		)
		(stroke
			(width 0)
			(type solid)
		)
		(fill yes)
		(layer "In4.Cu")
		(net "P5E_PEX3_STN7_TX_DP<121>")
	)
	(gr_poly
		(pts
			(arc
				(start 386.303012 -310.149748)
				(mid 385.896612 -310.149748)
				(end 386.303012 -310.149748)
			)
		)
		(stroke
			(width 0)
			(type solid)
		)
		(fill yes)
		(layer "In4.Cu")
		(net "P5E_PEX3_STN7_RX_DP<121>")
	)
	(gr_poly
		(pts
			(arc
				(start 386.303012 -308.249828)
				(mid 385.896612 -308.249828)
				(end 386.303012 -308.249828)
			)
		)
		(stroke
			(width 0)
			(type solid)
		)
		(fill yes)
		(layer "In4.Cu")
		(net "P5E_PEX3_STN7_RX_DP<119>")
	)
	(gr_poly
		(pts
			(arc
				(start 386.303012 -306.349908)
				(mid 385.896612 -306.349908)
				(end 386.303012 -306.349908)
			)
		)
		(stroke
			(width 0)
			(type solid)
		)
		(fill yes)
		(layer "In4.Cu")
		(net "P5E_PEX3_STN7_RX_DP<117>")
	)
	(gr_poly
		(pts
			(arc
				(start 386.303012 -304.449734)
				(mid 385.896612 -304.449734)
				(end 386.303012 -304.449734)
			)
		)
		(stroke
			(width 0)
			(type solid)
		)
		(fill yes)
		(layer "In4.Cu")
		(net "P5E_PEX3_STN7_RX_DP<115>")
	)
	(gr_poly
		(pts
			(arc
				(start 386.303012 -302.549814)
				(mid 385.896612 -302.549814)
				(end 386.303012 -302.549814)
			)
		)
		(stroke
			(width 0)
			(type solid)
		)
		(fill yes)
		(layer "In4.Cu")
		(net "P5E_PEX3_STN7_RX_DP<113>")
	)
	(gr_poly
		(pts
			(arc
				(start 387.253226 -318.699896)
				(mid 386.846826 -318.699896)
				(end 387.253226 -318.699896)
			)
		)
		(stroke
			(width 0)
			(type solid)
		)
		(fill yes)
		(layer "In4.Cu")
		(net "P5E_PEX3_STN7_RX_DN<123>")
	)
	(gr_poly
		(pts
			(arc
				(start 387.253226 -317.749936)
				(mid 386.846826 -317.749936)
				(end 387.253226 -317.749936)
			)
		)
		(stroke
			(width 0)
			(type solid)
		)
		(fill yes)
		(layer "In4.Cu")
		(net "P5E_PEX3_STN7_RX_DP<123>")
	)
	(gr_poly
		(pts
			(arc
				(start 387.253226 -313.949842)
				(mid 386.846826 -313.949842)
				(end 387.253226 -313.949842)
			)
		)
		(stroke
			(width 0)
			(type solid)
		)
		(fill yes)
		(layer "In4.Cu")
		(net "P5E_PEX3_STN7_TX_DN<123>")
	)
	(gr_poly
		(pts
			(arc
				(start 387.253226 -312.999882)
				(mid 386.846826 -312.999882)
				(end 387.253226 -312.999882)
			)
		)
		(stroke
			(width 0)
			(type solid)
		)
		(fill yes)
		(layer "In4.Cu")
		(net "P5E_PEX3_STN7_TX_DP<123>")
	)
	(gr_poly
		(pts
			(arc
				(start 387.253226 -309.199788)
				(mid 386.846826 -309.199788)
				(end 387.253226 -309.199788)
			)
		)
		(stroke
			(width 0)
			(type solid)
		)
		(fill yes)
		(layer "In4.Cu")
		(net "P5E_PEX3_STN7_RX_DN<120>")
	)
	(gr_poly
		(pts
			(arc
				(start 387.253226 -307.299868)
				(mid 386.846826 -307.299868)
				(end 387.253226 -307.299868)
			)
		)
		(stroke
			(width 0)
			(type solid)
		)
		(fill yes)
		(layer "In4.Cu")
		(net "P5E_PEX3_STN7_RX_DN<118>")
	)
	(gr_poly
		(pts
			(arc
				(start 387.253226 -305.399948)
				(mid 386.846826 -305.399948)
				(end 387.253226 -305.399948)
			)
		)
		(stroke
			(width 0)
			(type solid)
		)
		(fill yes)
		(layer "In4.Cu")
		(net "P5E_PEX3_STN7_RX_DN<116>")
	)
	(gr_poly
		(pts
			(arc
				(start 387.253226 -303.499774)
				(mid 386.846826 -303.499774)
				(end 387.253226 -303.499774)
			)
		)
		(stroke
			(width 0)
			(type solid)
		)
		(fill yes)
		(layer "In4.Cu")
		(net "P5E_PEX3_STN7_RX_DN<114>")
	)
	(gr_poly
		(pts
			(arc
				(start 387.253226 -301.599854)
				(mid 386.846826 -301.599854)
				(end 387.253226 -301.599854)
			)
		)
		(stroke
			(width 0)
			(type solid)
		)
		(fill yes)
		(layer "In4.Cu")
		(net "P5E_PEX3_STN7_RX_DN<112>")
	)
	(gr_poly
		(pts
			(arc
				(start 388.203186 -316.799722)
				(mid 387.796786 -316.799722)
				(end 388.203186 -316.799722)
			)
		)
		(stroke
			(width 0)
			(type solid)
		)
		(fill yes)
		(layer "In4.Cu")
		(net "P5E_PEX3_STN7_RX_DN<124>")
	)
	(gr_poly
		(pts
			(arc
				(start 388.203186 -315.849762)
				(mid 387.796786 -315.849762)
				(end 388.203186 -315.849762)
			)
		)
		(stroke
			(width 0)
			(type solid)
		)
		(fill yes)
		(layer "In4.Cu")
		(net "P5E_PEX3_STN7_RX_DP<124>")
	)
	(gr_poly
		(pts
			(arc
				(start 388.203186 -312.049922)
				(mid 387.796786 -312.049922)
				(end 388.203186 -312.049922)
			)
		)
		(stroke
			(width 0)
			(type solid)
		)
		(fill yes)
		(layer "In4.Cu")
		(net "P5E_PEX3_STN7_TX_DN<124>")
	)
	(gr_poly
		(pts
			(arc
				(start 388.203186 -311.099962)
				(mid 387.796786 -311.099962)
				(end 388.203186 -311.099962)
			)
		)
		(stroke
			(width 0)
			(type solid)
		)
		(fill yes)
		(layer "In4.Cu")
		(net "P5E_PEX3_STN7_TX_DP<124>")
	)
	(gr_poly
		(pts
			(arc
				(start 388.203186 -309.199788)
				(mid 387.796786 -309.199788)
				(end 388.203186 -309.199788)
			)
		)
		(stroke
			(width 0)
			(type solid)
		)
		(fill yes)
		(layer "In4.Cu")
		(net "P5E_PEX3_STN7_RX_DP<120>")
	)
	(gr_poly
		(pts
			(arc
				(start 388.203186 -307.299868)
				(mid 387.796786 -307.299868)
				(end 388.203186 -307.299868)
			)
		)
		(stroke
			(width 0)
			(type solid)
		)
		(fill yes)
		(layer "In4.Cu")
		(net "P5E_PEX3_STN7_RX_DP<118>")
	)
	(gr_poly
		(pts
			(arc
				(start 388.203186 -305.399948)
				(mid 387.796786 -305.399948)
				(end 388.203186 -305.399948)
			)
		)
		(stroke
			(width 0)
			(type solid)
		)
		(fill yes)
		(layer "In4.Cu")
		(net "P5E_PEX3_STN7_RX_DP<116>")
	)
	(gr_poly
		(pts
			(arc
				(start 388.203186 -303.499774)
				(mid 387.796786 -303.499774)
				(end 388.203186 -303.499774)
			)
		)
		(stroke
			(width 0)
			(type solid)
		)
		(fill yes)
		(layer "In4.Cu")
		(net "P5E_PEX3_STN7_RX_DP<114>")
	)
	(gr_poly
		(pts
			(arc
				(start 388.203186 -301.599854)
				(mid 387.796786 -301.599854)
				(end 388.203186 -301.599854)
			)
		)
		(stroke
			(width 0)
			(type solid)
		)
		(fill yes)
		(layer "In4.Cu")
		(net "P5E_PEX3_STN7_RX_DP<112>")
	)
	(gr_poly
		(pts
			(arc
				(start 389.153146 -318.699896)
				(mid 388.746746 -318.699896)
				(end 389.153146 -318.699896)
			)
		)
		(stroke
			(width 0)
			(type solid)
		)
		(fill yes)
		(layer "In4.Cu")
		(net "P5E_PEX3_STN7_RX_DN<125>")
	)
	(gr_poly
		(pts
			(arc
				(start 389.153146 -317.749936)
				(mid 388.746746 -317.749936)
				(end 389.153146 -317.749936)
			)
		)
		(stroke
			(width 0)
			(type solid)
		)
		(fill yes)
		(layer "In4.Cu")
		(net "P5E_PEX3_STN7_RX_DP<125>")
	)
	(gr_poly
		(pts
			(arc
				(start 389.153146 -313.949842)
				(mid 388.746746 -313.949842)
				(end 389.153146 -313.949842)
			)
		)
		(stroke
			(width 0)
			(type solid)
		)
		(fill yes)
		(layer "In4.Cu")
		(net "P5E_PEX3_STN7_TX_DN<125>")
	)
	(gr_poly
		(pts
			(arc
				(start 389.153146 -312.999882)
				(mid 388.746746 -312.999882)
				(end 389.153146 -312.999882)
			)
		)
		(stroke
			(width 0)
			(type solid)
		)
		(fill yes)
		(layer "In4.Cu")
		(net "P5E_PEX3_STN7_TX_DP<125>")
	)
	(gr_poly
		(pts
			(arc
				(start 390.103106 -316.799722)
				(mid 389.696706 -316.799722)
				(end 390.103106 -316.799722)
			)
		)
		(stroke
			(width 0)
			(type solid)
		)
		(fill yes)
		(layer "In4.Cu")
		(net "P5E_PEX3_STN7_RX_DN<126>")
	)
	(gr_poly
		(pts
			(arc
				(start 390.103106 -315.849762)
				(mid 389.696706 -315.849762)
				(end 390.103106 -315.849762)
			)
		)
		(stroke
			(width 0)
			(type solid)
		)
		(fill yes)
		(layer "In4.Cu")
		(net "P5E_PEX3_STN7_RX_DP<126>")
	)
	(gr_poly
		(pts
			(arc
				(start 390.103106 -312.049922)
				(mid 389.696706 -312.049922)
				(end 390.103106 -312.049922)
			)
		)
		(stroke
			(width 0)
			(type solid)
		)
		(fill yes)
		(layer "In4.Cu")
		(net "P5E_PEX3_STN7_TX_DN<126>")
	)
	(gr_poly
		(pts
			(arc
				(start 390.103106 -311.099962)
				(mid 389.696706 -311.099962)
				(end 390.103106 -311.099962)
			)
		)
		(stroke
			(width 0)
			(type solid)
		)
		(fill yes)
		(layer "In4.Cu")
		(net "P5E_PEX3_STN7_TX_DP<126>")
	)
	(gr_poly
		(pts
			(arc
				(start 390.103106 -309.199788)
				(mid 389.696706 -309.199788)
				(end 390.103106 -309.199788)
			)
		)
		(stroke
			(width 0)
			(type solid)
		)
		(fill yes)
		(layer "In4.Cu")
		(net "P5E_PEX3_STN7_TX_DN<120>")
	)
	(gr_poly
		(pts
			(arc
				(start 390.103106 -307.299868)
				(mid 389.696706 -307.299868)
				(end 390.103106 -307.299868)
			)
		)
		(stroke
			(width 0)
			(type solid)
		)
		(fill yes)
		(layer "In4.Cu")
		(net "P5E_PEX3_STN7_TX_DN<118>")
	)
	(gr_poly
		(pts
			(arc
				(start 390.103106 -305.399948)
				(mid 389.696706 -305.399948)
				(end 390.103106 -305.399948)
			)
		)
		(stroke
			(width 0)
			(type solid)
		)
		(fill yes)
		(layer "In4.Cu")
		(net "P5E_PEX3_STN7_TX_DN<116>")
	)
	(gr_poly
		(pts
			(arc
				(start 390.103106 -303.499774)
				(mid 389.696706 -303.499774)
				(end 390.103106 -303.499774)
			)
		)
		(stroke
			(width 0)
			(type solid)
		)
		(fill yes)
		(layer "In4.Cu")
		(net "P5E_PEX3_STN7_TX_DN<114>")
	)
	(gr_poly
		(pts
			(arc
				(start 390.103106 -301.599854)
				(mid 389.696706 -301.599854)
				(end 390.103106 -301.599854)
			)
		)
		(stroke
			(width 0)
			(type solid)
		)
		(fill yes)
		(layer "In4.Cu")
		(net "P5E_PEX3_STN7_TX_DN<112>")
	)
	(gr_poly
		(pts
			(arc
				(start 391.053066 -318.699896)
				(mid 390.646666 -318.699896)
				(end 391.053066 -318.699896)
			)
		)
		(stroke
			(width 0)
			(type solid)
		)
		(fill yes)
		(layer "In4.Cu")
		(net "P5E_PEX3_STN7_RX_DN<127>")
	)
	(gr_poly
		(pts
			(arc
				(start 391.053066 -317.749936)
				(mid 390.646666 -317.749936)
				(end 391.053066 -317.749936)
			)
		)
		(stroke
			(width 0)
			(type solid)
		)
		(fill yes)
		(layer "In4.Cu")
		(net "P5E_PEX3_STN7_RX_DP<127>")
	)
	(gr_poly
		(pts
			(arc
				(start 391.053066 -313.949842)
				(mid 390.646666 -313.949842)
				(end 391.053066 -313.949842)
			)
		)
		(stroke
			(width 0)
			(type solid)
		)
		(fill yes)
		(layer "In4.Cu")
		(net "P5E_PEX3_STN7_TX_DN<127>")
	)
	(gr_poly
		(pts
			(arc
				(start 391.053066 -312.999882)
				(mid 390.646666 -312.999882)
				(end 391.053066 -312.999882)
			)
		)
		(stroke
			(width 0)
			(type solid)
		)
		(fill yes)
		(layer "In4.Cu")
		(net "P5E_PEX3_STN7_TX_DP<127>")
	)
	(gr_poly
		(pts
			(arc
				(start 391.053066 -309.199788)
				(mid 390.646666 -309.199788)
				(end 391.053066 -309.199788)
			)
		)
		(stroke
			(width 0)
			(type solid)
		)
		(fill yes)
		(layer "In4.Cu")
		(net "P5E_PEX3_STN7_TX_DP<120>")
	)
	(gr_poly
		(pts
			(arc
				(start 391.053066 -307.299868)
				(mid 390.646666 -307.299868)
				(end 391.053066 -307.299868)
			)
		)
		(stroke
			(width 0)
			(type solid)
		)
		(fill yes)
		(layer "In4.Cu")
		(net "P5E_PEX3_STN7_TX_DP<118>")
	)
	(gr_poly
		(pts
			(arc
				(start 391.053066 -305.399948)
				(mid 390.646666 -305.399948)
				(end 391.053066 -305.399948)
			)
		)
		(stroke
			(width 0)
			(type solid)
		)
		(fill yes)
		(layer "In4.Cu")
		(net "P5E_PEX3_STN7_TX_DP<116>")
	)
	(gr_poly
		(pts
			(arc
				(start 391.053066 -303.499774)
				(mid 390.646666 -303.499774)
				(end 391.053066 -303.499774)
			)
		)
		(stroke
			(width 0)
			(type solid)
		)
		(fill yes)
		(layer "In4.Cu")
		(net "P5E_PEX3_STN7_TX_DP<114>")
	)
	(gr_poly
		(pts
			(arc
				(start 391.053066 -301.599854)
				(mid 390.646666 -301.599854)
				(end 391.053066 -301.599854)
			)
		)
		(stroke
			(width 0)
			(type solid)
		)
		(fill yes)
		(layer "In4.Cu")
		(net "P5E_PEX3_STN7_TX_DP<112>")
	)
	(gr_poly
		(pts
			(arc
				(start 392.003026 -316.799722)
				(mid 391.596626 -316.799722)
				(end 392.003026 -316.799722)
			)
		)
		(stroke
			(width 0)
			(type solid)
		)
		(fill yes)
		(layer "In4.Cu")
		(net "P5E_PEX3_STN6_RX_DN<111>")
	)
	(gr_poly
		(pts
			(arc
				(start 392.003026 -315.849762)
				(mid 391.596626 -315.849762)
				(end 392.003026 -315.849762)
			)
		)
		(stroke
			(width 0)
			(type solid)
		)
		(fill yes)
		(layer "In4.Cu")
		(net "P5E_PEX3_STN6_RX_DP<111>")
	)
	(gr_poly
		(pts
			(arc
				(start 392.003026 -312.049922)
				(mid 391.596626 -312.049922)
				(end 392.003026 -312.049922)
			)
		)
		(stroke
			(width 0)
			(type solid)
		)
		(fill yes)
		(layer "In4.Cu")
		(net "P5E_PEX3_STN6_TX_DN<111>")
	)
	(gr_poly
		(pts
			(arc
				(start 392.003026 -311.099962)
				(mid 391.596626 -311.099962)
				(end 392.003026 -311.099962)
			)
		)
		(stroke
			(width 0)
			(type solid)
		)
		(fill yes)
		(layer "In4.Cu")
		(net "P5E_PEX3_STN6_TX_DP<111>")
	)
	(gr_poly
		(pts
			(arc
				(start 392.003026 -308.249828)
				(mid 391.596626 -308.249828)
				(end 392.003026 -308.249828)
			)
		)
		(stroke
			(width 0)
			(type solid)
		)
		(fill yes)
		(layer "In4.Cu")
		(net "P5E_PEX3_STN7_TX_DN<119>")
	)
	(gr_poly
		(pts
			(arc
				(start 392.003026 -306.349908)
				(mid 391.596626 -306.349908)
				(end 392.003026 -306.349908)
			)
		)
		(stroke
			(width 0)
			(type solid)
		)
		(fill yes)
		(layer "In4.Cu")
		(net "P5E_PEX3_STN7_TX_DN<117>")
	)
	(gr_poly
		(pts
			(arc
				(start 392.003026 -304.449734)
				(mid 391.596626 -304.449734)
				(end 392.003026 -304.449734)
			)
		)
		(stroke
			(width 0)
			(type solid)
		)
		(fill yes)
		(layer "In4.Cu")
		(net "P5E_PEX3_STN7_TX_DN<115>")
	)
	(gr_poly
		(pts
			(arc
				(start 392.003026 -302.549814)
				(mid 391.596626 -302.549814)
				(end 392.003026 -302.549814)
			)
		)
		(stroke
			(width 0)
			(type solid)
		)
		(fill yes)
		(layer "In4.Cu")
		(net "P5E_PEX3_STN7_TX_DN<113>")
	)
	(gr_poly
		(pts
			(arc
				(start 392.952986 -318.699896)
				(mid 392.546586 -318.699896)
				(end 392.952986 -318.699896)
			)
		)
		(stroke
			(width 0)
			(type solid)
		)
		(fill yes)
		(layer "In4.Cu")
		(net "P5E_PEX3_STN6_RX_DN<110>")
	)
	(gr_poly
		(pts
			(arc
				(start 392.952986 -317.749936)
				(mid 392.546586 -317.749936)
				(end 392.952986 -317.749936)
			)
		)
		(stroke
			(width 0)
			(type solid)
		)
		(fill yes)
		(layer "In4.Cu")
		(net "P5E_PEX3_STN6_RX_DP<110>")
	)
	(gr_poly
		(pts
			(arc
				(start 392.952986 -313.949842)
				(mid 392.546586 -313.949842)
				(end 392.952986 -313.949842)
			)
		)
		(stroke
			(width 0)
			(type solid)
		)
		(fill yes)
		(layer "In4.Cu")
		(net "P5E_PEX3_STN6_TX_DN<110>")
	)
	(gr_poly
		(pts
			(arc
				(start 392.952986 -312.999882)
				(mid 392.546586 -312.999882)
				(end 392.952986 -312.999882)
			)
		)
		(stroke
			(width 0)
			(type solid)
		)
		(fill yes)
		(layer "In4.Cu")
		(net "P5E_PEX3_STN6_TX_DP<110>")
	)
	(gr_poly
		(pts
			(arc
				(start 392.952986 -308.249828)
				(mid 392.546586 -308.249828)
				(end 392.952986 -308.249828)
			)
		)
		(stroke
			(width 0)
			(type solid)
		)
		(fill yes)
		(layer "In4.Cu")
		(net "P5E_PEX3_STN7_TX_DP<119>")
	)
	(gr_poly
		(pts
			(arc
				(start 392.952986 -306.349908)
				(mid 392.546586 -306.349908)
				(end 392.952986 -306.349908)
			)
		)
		(stroke
			(width 0)
			(type solid)
		)
		(fill yes)
		(layer "In4.Cu")
		(net "P5E_PEX3_STN7_TX_DP<117>")
	)
	(gr_poly
		(pts
			(arc
				(start 392.952986 -304.449734)
				(mid 392.546586 -304.449734)
				(end 392.952986 -304.449734)
			)
		)
		(stroke
			(width 0)
			(type solid)
		)
		(fill yes)
		(layer "In4.Cu")
		(net "P5E_PEX3_STN7_TX_DP<115>")
	)
	(gr_poly
		(pts
			(arc
				(start 392.952986 -302.549814)
				(mid 392.546586 -302.549814)
				(end 392.952986 -302.549814)
			)
		)
		(stroke
			(width 0)
			(type solid)
		)
		(fill yes)
		(layer "In4.Cu")
		(net "P5E_PEX3_STN7_TX_DP<113>")
	)
	(gr_poly
		(pts
			(arc
				(start 392.952986 -278.799798)
				(mid 392.546586 -278.799798)
				(end 392.952986 -278.799798)
			)
		)
		(stroke
			(width 0)
			(type solid)
		)
		(fill yes)
		(layer "In4.Cu")
		(net "P5E_PEX3_STN2_TX_DP<47>")
	)
	(gr_poly
		(pts
			(arc
				(start 392.952986 -277.849838)
				(mid 392.546586 -277.849838)
				(end 392.952986 -277.849838)
			)
		)
		(stroke
			(width 0)
			(type solid)
		)
		(fill yes)
		(layer "In4.Cu")
		(net "P5E_PEX3_STN2_TX_DN<47>")
	)
	(gr_poly
		(pts
			(arc
				(start 392.952986 -274.049744)
				(mid 392.546586 -274.049744)
				(end 392.952986 -274.049744)
			)
		)
		(stroke
			(width 0)
			(type solid)
		)
		(fill yes)
		(layer "In4.Cu")
		(net "P5E_PEX3_STN2_RX_DP<47>")
	)
	(gr_poly
		(pts
			(arc
				(start 392.952986 -273.099784)
				(mid 392.546586 -273.099784)
				(end 392.952986 -273.099784)
			)
		)
		(stroke
			(width 0)
			(type solid)
		)
		(fill yes)
		(layer "In4.Cu")
		(net "P5E_PEX3_STN2_RX_DN<47>")
	)
	(gr_poly
		(pts
			(arc
				(start 393.9032 -316.799722)
				(mid 393.4968 -316.799722)
				(end 393.9032 -316.799722)
			)
		)
		(stroke
			(width 0)
			(type solid)
		)
		(fill yes)
		(layer "In4.Cu")
		(net "P5E_PEX3_STN6_RX_DN<109>")
	)
	(gr_poly
		(pts
			(arc
				(start 393.9032 -315.849762)
				(mid 393.4968 -315.849762)
				(end 393.9032 -315.849762)
			)
		)
		(stroke
			(width 0)
			(type solid)
		)
		(fill yes)
		(layer "In4.Cu")
		(net "P5E_PEX3_STN6_RX_DP<109>")
	)
	(gr_poly
		(pts
			(arc
				(start 393.9032 -312.049922)
				(mid 393.4968 -312.049922)
				(end 393.9032 -312.049922)
			)
		)
		(stroke
			(width 0)
			(type solid)
		)
		(fill yes)
		(layer "In4.Cu")
		(net "P5E_PEX3_STN6_TX_DN<109>")
	)
	(gr_poly
		(pts
			(arc
				(start 393.9032 -311.099962)
				(mid 393.4968 -311.099962)
				(end 393.9032 -311.099962)
			)
		)
		(stroke
			(width 0)
			(type solid)
		)
		(fill yes)
		(layer "In4.Cu")
		(net "P5E_PEX3_STN6_TX_DP<109>")
	)
	(gr_poly
		(pts
			(arc
				(start 393.9032 -280.699464)
				(mid 393.4968 -280.699464)
				(end 393.9032 -280.699464)
			)
		)
		(stroke
			(width 0)
			(type solid)
		)
		(fill yes)
		(layer "In4.Cu")
		(net "P5E_PEX3_STN2_TX_DP<46>")
	)
	(gr_poly
		(pts
			(arc
				(start 393.9032 -279.749504)
				(mid 393.4968 -279.749504)
				(end 393.9032 -279.749504)
			)
		)
		(stroke
			(width 0)
			(type solid)
		)
		(fill yes)
		(layer "In4.Cu")
		(net "P5E_PEX3_STN2_TX_DN<46>")
	)
	(gr_poly
		(pts
			(arc
				(start 393.9032 -275.949918)
				(mid 393.4968 -275.949918)
				(end 393.9032 -275.949918)
			)
		)
		(stroke
			(width 0)
			(type solid)
		)
		(fill yes)
		(layer "In4.Cu")
		(net "P5E_PEX3_STN2_RX_DP<46>")
	)
	(gr_poly
		(pts
			(arc
				(start 393.9032 -274.999958)
				(mid 393.4968 -274.999958)
				(end 393.9032 -274.999958)
			)
		)
		(stroke
			(width 0)
			(type solid)
		)
		(fill yes)
		(layer "In4.Cu")
		(net "P5E_PEX3_STN2_RX_DN<46>")
	)
	(gr_poly
		(pts
			(arc
				(start 394.85316 -318.699896)
				(mid 394.44676 -318.699896)
				(end 394.85316 -318.699896)
			)
		)
		(stroke
			(width 0)
			(type solid)
		)
		(fill yes)
		(layer "In4.Cu")
		(net "P5E_PEX3_STN6_RX_DN<108>")
	)
	(gr_poly
		(pts
			(arc
				(start 394.85316 -317.749936)
				(mid 394.44676 -317.749936)
				(end 394.85316 -317.749936)
			)
		)
		(stroke
			(width 0)
			(type solid)
		)
		(fill yes)
		(layer "In4.Cu")
		(net "P5E_PEX3_STN6_RX_DP<108>")
	)
	(gr_poly
		(pts
			(arc
				(start 394.85316 -313.949842)
				(mid 394.44676 -313.949842)
				(end 394.85316 -313.949842)
			)
		)
		(stroke
			(width 0)
			(type solid)
		)
		(fill yes)
		(layer "In4.Cu")
		(net "P5E_PEX3_STN6_TX_DN<108>")
	)
	(gr_poly
		(pts
			(arc
				(start 394.85316 -312.999882)
				(mid 394.44676 -312.999882)
				(end 394.85316 -312.999882)
			)
		)
		(stroke
			(width 0)
			(type solid)
		)
		(fill yes)
		(layer "In4.Cu")
		(net "P5E_PEX3_STN6_TX_DP<108>")
	)
	(gr_poly
		(pts
			(arc
				(start 394.85316 -278.799798)
				(mid 394.44676 -278.799798)
				(end 394.85316 -278.799798)
			)
		)
		(stroke
			(width 0)
			(type solid)
		)
		(fill yes)
		(layer "In4.Cu")
		(net "P5E_PEX3_STN2_TX_DP<45>")
	)
	(gr_poly
		(pts
			(arc
				(start 394.85316 -277.849838)
				(mid 394.44676 -277.849838)
				(end 394.85316 -277.849838)
			)
		)
		(stroke
			(width 0)
			(type solid)
		)
		(fill yes)
		(layer "In4.Cu")
		(net "P5E_PEX3_STN2_TX_DN<45>")
	)
	(gr_poly
		(pts
			(arc
				(start 394.85316 -274.049744)
				(mid 394.44676 -274.049744)
				(end 394.85316 -274.049744)
			)
		)
		(stroke
			(width 0)
			(type solid)
		)
		(fill yes)
		(layer "In4.Cu")
		(net "P5E_PEX3_STN2_RX_DP<45>")
	)
	(gr_poly
		(pts
			(arc
				(start 394.85316 -273.099784)
				(mid 394.44676 -273.099784)
				(end 394.85316 -273.099784)
			)
		)
		(stroke
			(width 0)
			(type solid)
		)
		(fill yes)
		(layer "In4.Cu")
		(net "P5E_PEX3_STN2_RX_DN<45>")
	)
	(gr_poly
		(pts
			(arc
				(start 395.80312 -316.799722)
				(mid 395.39672 -316.799722)
				(end 395.80312 -316.799722)
			)
		)
		(stroke
			(width 0)
			(type solid)
		)
		(fill yes)
		(layer "In4.Cu")
		(net "P5E_PEX3_STN6_RX_DN<107>")
	)
	(gr_poly
		(pts
			(arc
				(start 395.80312 -315.849762)
				(mid 395.39672 -315.849762)
				(end 395.80312 -315.849762)
			)
		)
		(stroke
			(width 0)
			(type solid)
		)
		(fill yes)
		(layer "In4.Cu")
		(net "P5E_PEX3_STN6_RX_DP<107>")
	)
	(gr_poly
		(pts
			(arc
				(start 395.80312 -312.049922)
				(mid 395.39672 -312.049922)
				(end 395.80312 -312.049922)
			)
		)
		(stroke
			(width 0)
			(type solid)
		)
		(fill yes)
		(layer "In4.Cu")
		(net "P5E_PEX3_STN6_TX_DN<107>")
	)
	(gr_poly
		(pts
			(arc
				(start 395.80312 -311.099962)
				(mid 395.39672 -311.099962)
				(end 395.80312 -311.099962)
			)
		)
		(stroke
			(width 0)
			(type solid)
		)
		(fill yes)
		(layer "In4.Cu")
		(net "P5E_PEX3_STN6_TX_DP<107>")
	)
	(gr_poly
		(pts
			(arc
				(start 395.80312 -280.699464)
				(mid 395.39672 -280.699464)
				(end 395.80312 -280.699464)
			)
		)
		(stroke
			(width 0)
			(type solid)
		)
		(fill yes)
		(layer "In4.Cu")
		(net "P5E_PEX3_STN2_TX_DP<44>")
	)
	(gr_poly
		(pts
			(arc
				(start 395.80312 -279.749504)
				(mid 395.39672 -279.749504)
				(end 395.80312 -279.749504)
			)
		)
		(stroke
			(width 0)
			(type solid)
		)
		(fill yes)
		(layer "In4.Cu")
		(net "P5E_PEX3_STN2_TX_DN<44>")
	)
	(gr_poly
		(pts
			(arc
				(start 395.80312 -275.949918)
				(mid 395.39672 -275.949918)
				(end 395.80312 -275.949918)
			)
		)
		(stroke
			(width 0)
			(type solid)
		)
		(fill yes)
		(layer "In4.Cu")
		(net "P5E_PEX3_STN2_RX_DP<44>")
	)
	(gr_poly
		(pts
			(arc
				(start 395.80312 -274.999958)
				(mid 395.39672 -274.999958)
				(end 395.80312 -274.999958)
			)
		)
		(stroke
			(width 0)
			(type solid)
		)
		(fill yes)
		(layer "In4.Cu")
		(net "P5E_PEX3_STN2_RX_DN<44>")
	)
	(gr_poly
		(pts
			(arc
				(start 396.75308 -318.699896)
				(mid 396.34668 -318.699896)
				(end 396.75308 -318.699896)
			)
		)
		(stroke
			(width 0)
			(type solid)
		)
		(fill yes)
		(layer "In4.Cu")
		(net "P5E_PEX3_STN6_RX_DN<106>")
	)
	(gr_poly
		(pts
			(arc
				(start 396.75308 -317.749936)
				(mid 396.34668 -317.749936)
				(end 396.75308 -317.749936)
			)
		)
		(stroke
			(width 0)
			(type solid)
		)
		(fill yes)
		(layer "In4.Cu")
		(net "P5E_PEX3_STN6_RX_DP<106>")
	)
	(gr_poly
		(pts
			(arc
				(start 396.75308 -313.949842)
				(mid 396.34668 -313.949842)
				(end 396.75308 -313.949842)
			)
		)
		(stroke
			(width 0)
			(type solid)
		)
		(fill yes)
		(layer "In4.Cu")
		(net "P5E_PEX3_STN6_TX_DN<106>")
	)
	(gr_poly
		(pts
			(arc
				(start 396.75308 -312.999882)
				(mid 396.34668 -312.999882)
				(end 396.75308 -312.999882)
			)
		)
		(stroke
			(width 0)
			(type solid)
		)
		(fill yes)
		(layer "In4.Cu")
		(net "P5E_PEX3_STN6_TX_DP<106>")
	)
	(gr_poly
		(pts
			(arc
				(start 396.75308 -278.799798)
				(mid 396.34668 -278.799798)
				(end 396.75308 -278.799798)
			)
		)
		(stroke
			(width 0)
			(type solid)
		)
		(fill yes)
		(layer "In4.Cu")
		(net "P5E_PEX3_STN2_TX_DP<43>")
	)
	(gr_poly
		(pts
			(arc
				(start 396.75308 -277.849838)
				(mid 396.34668 -277.849838)
				(end 396.75308 -277.849838)
			)
		)
		(stroke
			(width 0)
			(type solid)
		)
		(fill yes)
		(layer "In4.Cu")
		(net "P5E_PEX3_STN2_TX_DN<43>")
	)
	(gr_poly
		(pts
			(arc
				(start 396.75308 -274.049744)
				(mid 396.34668 -274.049744)
				(end 396.75308 -274.049744)
			)
		)
		(stroke
			(width 0)
			(type solid)
		)
		(fill yes)
		(layer "In4.Cu")
		(net "P5E_PEX3_STN2_RX_DP<43>")
	)
	(gr_poly
		(pts
			(arc
				(start 396.75308 -273.099784)
				(mid 396.34668 -273.099784)
				(end 396.75308 -273.099784)
			)
		)
		(stroke
			(width 0)
			(type solid)
		)
		(fill yes)
		(layer "In4.Cu")
		(net "P5E_PEX3_STN2_RX_DN<43>")
	)
	(gr_poly
		(pts
			(arc
				(start 397.70304 -316.799722)
				(mid 397.29664 -316.799722)
				(end 397.70304 -316.799722)
			)
		)
		(stroke
			(width 0)
			(type solid)
		)
		(fill yes)
		(layer "In4.Cu")
		(net "P5E_PEX3_STN6_RX_DN<105>")
	)
	(gr_poly
		(pts
			(arc
				(start 397.70304 -315.849762)
				(mid 397.29664 -315.849762)
				(end 397.70304 -315.849762)
			)
		)
		(stroke
			(width 0)
			(type solid)
		)
		(fill yes)
		(layer "In4.Cu")
		(net "P5E_PEX3_STN6_RX_DP<105>")
	)
	(gr_poly
		(pts
			(arc
				(start 397.70304 -312.049922)
				(mid 397.29664 -312.049922)
				(end 397.70304 -312.049922)
			)
		)
		(stroke
			(width 0)
			(type solid)
		)
		(fill yes)
		(layer "In4.Cu")
		(net "P5E_PEX3_STN6_TX_DN<105>")
	)
	(gr_poly
		(pts
			(arc
				(start 397.70304 -311.099962)
				(mid 397.29664 -311.099962)
				(end 397.70304 -311.099962)
			)
		)
		(stroke
			(width 0)
			(type solid)
		)
		(fill yes)
		(layer "In4.Cu")
		(net "P5E_PEX3_STN6_TX_DP<105>")
	)
	(gr_poly
		(pts
			(arc
				(start 397.70304 -280.699464)
				(mid 397.29664 -280.699464)
				(end 397.70304 -280.699464)
			)
		)
		(stroke
			(width 0)
			(type solid)
		)
		(fill yes)
		(layer "In4.Cu")
		(net "P5E_PEX3_STN2_TX_DP<42>")
	)
	(gr_poly
		(pts
			(arc
				(start 397.70304 -279.749504)
				(mid 397.29664 -279.749504)
				(end 397.70304 -279.749504)
			)
		)
		(stroke
			(width 0)
			(type solid)
		)
		(fill yes)
		(layer "In4.Cu")
		(net "P5E_PEX3_STN2_TX_DN<42>")
	)
	(gr_poly
		(pts
			(arc
				(start 397.70304 -275.949918)
				(mid 397.29664 -275.949918)
				(end 397.70304 -275.949918)
			)
		)
		(stroke
			(width 0)
			(type solid)
		)
		(fill yes)
		(layer "In4.Cu")
		(net "P5E_PEX3_STN2_RX_DP<42>")
	)
	(gr_poly
		(pts
			(arc
				(start 397.70304 -274.999958)
				(mid 397.29664 -274.999958)
				(end 397.70304 -274.999958)
			)
		)
		(stroke
			(width 0)
			(type solid)
		)
		(fill yes)
		(layer "In4.Cu")
		(net "P5E_PEX3_STN2_RX_DN<42>")
	)
	(gr_poly
		(pts
			(arc
				(start 398.653 -318.699896)
				(mid 398.2466 -318.699896)
				(end 398.653 -318.699896)
			)
		)
		(stroke
			(width 0)
			(type solid)
		)
		(fill yes)
		(layer "In4.Cu")
		(net "P5E_PEX3_STN6_RX_DN<104>")
	)
	(gr_poly
		(pts
			(arc
				(start 398.653 -317.749936)
				(mid 398.2466 -317.749936)
				(end 398.653 -317.749936)
			)
		)
		(stroke
			(width 0)
			(type solid)
		)
		(fill yes)
		(layer "In4.Cu")
		(net "P5E_PEX3_STN6_RX_DP<104>")
	)
	(gr_poly
		(pts
			(arc
				(start 398.653 -313.949842)
				(mid 398.2466 -313.949842)
				(end 398.653 -313.949842)
			)
		)
		(stroke
			(width 0)
			(type solid)
		)
		(fill yes)
		(layer "In4.Cu")
		(net "P5E_PEX3_STN6_TX_DN<104>")
	)
	(gr_poly
		(pts
			(arc
				(start 398.653 -312.999882)
				(mid 398.2466 -312.999882)
				(end 398.653 -312.999882)
			)
		)
		(stroke
			(width 0)
			(type solid)
		)
		(fill yes)
		(layer "In4.Cu")
		(net "P5E_PEX3_STN6_TX_DP<104>")
	)
	(gr_poly
		(pts
			(arc
				(start 398.653 -278.799798)
				(mid 398.2466 -278.799798)
				(end 398.653 -278.799798)
			)
		)
		(stroke
			(width 0)
			(type solid)
		)
		(fill yes)
		(layer "In4.Cu")
		(net "P5E_PEX3_STN2_TX_DP<41>")
	)
	(gr_poly
		(pts
			(arc
				(start 398.653 -277.849838)
				(mid 398.2466 -277.849838)
				(end 398.653 -277.849838)
			)
		)
		(stroke
			(width 0)
			(type solid)
		)
		(fill yes)
		(layer "In4.Cu")
		(net "P5E_PEX3_STN2_TX_DN<41>")
	)
	(gr_poly
		(pts
			(arc
				(start 398.653 -274.049744)
				(mid 398.2466 -274.049744)
				(end 398.653 -274.049744)
			)
		)
		(stroke
			(width 0)
			(type solid)
		)
		(fill yes)
		(layer "In4.Cu")
		(net "P5E_PEX3_STN2_RX_DP<41>")
	)
	(gr_poly
		(pts
			(arc
				(start 398.653 -273.099784)
				(mid 398.2466 -273.099784)
				(end 398.653 -273.099784)
			)
		)
		(stroke
			(width 0)
			(type solid)
		)
		(fill yes)
		(layer "In4.Cu")
		(net "P5E_PEX3_STN2_RX_DN<41>")
	)
	(gr_poly
		(pts
			(arc
				(start 399.603214 -316.799722)
				(mid 399.196814 -316.799722)
				(end 399.603214 -316.799722)
			)
		)
		(stroke
			(width 0)
			(type solid)
		)
		(fill yes)
		(layer "In4.Cu")
		(net "P5E_PEX3_STN6_RX_DN<103>")
	)
	(gr_poly
		(pts
			(arc
				(start 399.603214 -315.849762)
				(mid 399.196814 -315.849762)
				(end 399.603214 -315.849762)
			)
		)
		(stroke
			(width 0)
			(type solid)
		)
		(fill yes)
		(layer "In4.Cu")
		(net "P5E_PEX3_STN6_RX_DP<103>")
	)
	(gr_poly
		(pts
			(arc
				(start 399.603214 -312.049922)
				(mid 399.196814 -312.049922)
				(end 399.603214 -312.049922)
			)
		)
		(stroke
			(width 0)
			(type solid)
		)
		(fill yes)
		(layer "In4.Cu")
		(net "P5E_PEX3_STN6_TX_DN<103>")
	)
	(gr_poly
		(pts
			(arc
				(start 399.603214 -311.099962)
				(mid 399.196814 -311.099962)
				(end 399.603214 -311.099962)
			)
		)
		(stroke
			(width 0)
			(type solid)
		)
		(fill yes)
		(layer "In4.Cu")
		(net "P5E_PEX3_STN6_TX_DP<103>")
	)
	(gr_poly
		(pts
			(arc
				(start 399.603214 -280.699464)
				(mid 399.196814 -280.699464)
				(end 399.603214 -280.699464)
			)
		)
		(stroke
			(width 0)
			(type solid)
		)
		(fill yes)
		(layer "In4.Cu")
		(net "P5E_PEX3_STN2_TX_DP<40>")
	)
	(gr_poly
		(pts
			(arc
				(start 399.603214 -279.749504)
				(mid 399.196814 -279.749504)
				(end 399.603214 -279.749504)
			)
		)
		(stroke
			(width 0)
			(type solid)
		)
		(fill yes)
		(layer "In4.Cu")
		(net "P5E_PEX3_STN2_TX_DN<40>")
	)
	(gr_poly
		(pts
			(arc
				(start 399.603214 -275.949918)
				(mid 399.196814 -275.949918)
				(end 399.603214 -275.949918)
			)
		)
		(stroke
			(width 0)
			(type solid)
		)
		(fill yes)
		(layer "In4.Cu")
		(net "P5E_PEX3_STN2_RX_DP<40>")
	)
	(gr_poly
		(pts
			(arc
				(start 399.603214 -274.999958)
				(mid 399.196814 -274.999958)
				(end 399.603214 -274.999958)
			)
		)
		(stroke
			(width 0)
			(type solid)
		)
		(fill yes)
		(layer "In4.Cu")
		(net "P5E_PEX3_STN2_RX_DN<40>")
	)
	(gr_poly
		(pts
			(arc
				(start 400.553174 -318.699896)
				(mid 400.146774 -318.699896)
				(end 400.553174 -318.699896)
			)
		)
		(stroke
			(width 0)
			(type solid)
		)
		(fill yes)
		(layer "In4.Cu")
		(net "P5E_PEX3_STN6_RX_DN<102>")
	)
	(gr_poly
		(pts
			(arc
				(start 400.553174 -317.749936)
				(mid 400.146774 -317.749936)
				(end 400.553174 -317.749936)
			)
		)
		(stroke
			(width 0)
			(type solid)
		)
		(fill yes)
		(layer "In4.Cu")
		(net "P5E_PEX3_STN6_RX_DP<102>")
	)
	(gr_poly
		(pts
			(arc
				(start 400.553174 -313.949842)
				(mid 400.146774 -313.949842)
				(end 400.553174 -313.949842)
			)
		)
		(stroke
			(width 0)
			(type solid)
		)
		(fill yes)
		(layer "In4.Cu")
		(net "P5E_PEX3_STN6_TX_DN<102>")
	)
	(gr_poly
		(pts
			(arc
				(start 400.553174 -312.999882)
				(mid 400.146774 -312.999882)
				(end 400.553174 -312.999882)
			)
		)
		(stroke
			(width 0)
			(type solid)
		)
		(fill yes)
		(layer "In4.Cu")
		(net "P5E_PEX3_STN6_TX_DP<102>")
	)
	(gr_poly
		(pts
			(arc
				(start 400.553174 -278.799798)
				(mid 400.146774 -278.799798)
				(end 400.553174 -278.799798)
			)
		)
		(stroke
			(width 0)
			(type solid)
		)
		(fill yes)
		(layer "In4.Cu")
		(net "P5E_PEX3_STN2_TX_DP<39>")
	)
	(gr_poly
		(pts
			(arc
				(start 400.553174 -277.849838)
				(mid 400.146774 -277.849838)
				(end 400.553174 -277.849838)
			)
		)
		(stroke
			(width 0)
			(type solid)
		)
		(fill yes)
		(layer "In4.Cu")
		(net "P5E_PEX3_STN2_TX_DN<39>")
	)
	(gr_poly
		(pts
			(arc
				(start 400.553174 -274.049744)
				(mid 400.146774 -274.049744)
				(end 400.553174 -274.049744)
			)
		)
		(stroke
			(width 0)
			(type solid)
		)
		(fill yes)
		(layer "In4.Cu")
		(net "P5E_PEX3_STN2_RX_DP<39>")
	)
	(gr_poly
		(pts
			(arc
				(start 400.553174 -273.099784)
				(mid 400.146774 -273.099784)
				(end 400.553174 -273.099784)
			)
		)
		(stroke
			(width 0)
			(type solid)
		)
		(fill yes)
		(layer "In4.Cu")
		(net "P5E_PEX3_STN2_RX_DN<39>")
	)
	(gr_poly
		(pts
			(arc
				(start 401.503134 -316.799722)
				(mid 401.096734 -316.799722)
				(end 401.503134 -316.799722)
			)
		)
		(stroke
			(width 0)
			(type solid)
		)
		(fill yes)
		(layer "In4.Cu")
		(net "P5E_PEX3_STN6_RX_DN<101>")
	)
	(gr_poly
		(pts
			(arc
				(start 401.503134 -315.849762)
				(mid 401.096734 -315.849762)
				(end 401.503134 -315.849762)
			)
		)
		(stroke
			(width 0)
			(type solid)
		)
		(fill yes)
		(layer "In4.Cu")
		(net "P5E_PEX3_STN6_RX_DP<101>")
	)
	(gr_poly
		(pts
			(arc
				(start 401.503134 -312.049922)
				(mid 401.096734 -312.049922)
				(end 401.503134 -312.049922)
			)
		)
		(stroke
			(width 0)
			(type solid)
		)
		(fill yes)
		(layer "In4.Cu")
		(net "P5E_PEX3_STN6_TX_DN<101>")
	)
	(gr_poly
		(pts
			(arc
				(start 401.503134 -311.099962)
				(mid 401.096734 -311.099962)
				(end 401.503134 -311.099962)
			)
		)
		(stroke
			(width 0)
			(type solid)
		)
		(fill yes)
		(layer "In4.Cu")
		(net "P5E_PEX3_STN6_TX_DP<101>")
	)
	(gr_poly
		(pts
			(arc
				(start 401.503134 -280.699464)
				(mid 401.096734 -280.699464)
				(end 401.503134 -280.699464)
			)
		)
		(stroke
			(width 0)
			(type solid)
		)
		(fill yes)
		(layer "In4.Cu")
		(net "P5E_PEX3_STN2_TX_DP<38>")
	)
	(gr_poly
		(pts
			(arc
				(start 401.503134 -279.749504)
				(mid 401.096734 -279.749504)
				(end 401.503134 -279.749504)
			)
		)
		(stroke
			(width 0)
			(type solid)
		)
		(fill yes)
		(layer "In4.Cu")
		(net "P5E_PEX3_STN2_TX_DN<38>")
	)
	(gr_poly
		(pts
			(arc
				(start 401.503134 -275.949918)
				(mid 401.096734 -275.949918)
				(end 401.503134 -275.949918)
			)
		)
		(stroke
			(width 0)
			(type solid)
		)
		(fill yes)
		(layer "In4.Cu")
		(net "P5E_PEX3_STN2_RX_DP<38>")
	)
	(gr_poly
		(pts
			(arc
				(start 401.503134 -274.999958)
				(mid 401.096734 -274.999958)
				(end 401.503134 -274.999958)
			)
		)
		(stroke
			(width 0)
			(type solid)
		)
		(fill yes)
		(layer "In4.Cu")
		(net "P5E_PEX3_STN2_RX_DN<38>")
	)
	(gr_poly
		(pts
			(arc
				(start 402.453094 -318.699896)
				(mid 402.046694 -318.699896)
				(end 402.453094 -318.699896)
			)
		)
		(stroke
			(width 0)
			(type solid)
		)
		(fill yes)
		(layer "In4.Cu")
		(net "P5E_PEX3_STN6_RX_DN<100>")
	)
	(gr_poly
		(pts
			(arc
				(start 402.453094 -317.749936)
				(mid 402.046694 -317.749936)
				(end 402.453094 -317.749936)
			)
		)
		(stroke
			(width 0)
			(type solid)
		)
		(fill yes)
		(layer "In4.Cu")
		(net "P5E_PEX3_STN6_RX_DP<100>")
	)
	(gr_poly
		(pts
			(arc
				(start 402.453094 -313.949842)
				(mid 402.046694 -313.949842)
				(end 402.453094 -313.949842)
			)
		)
		(stroke
			(width 0)
			(type solid)
		)
		(fill yes)
		(layer "In4.Cu")
		(net "P5E_PEX3_STN6_TX_DN<100>")
	)
	(gr_poly
		(pts
			(arc
				(start 402.453094 -312.999882)
				(mid 402.046694 -312.999882)
				(end 402.453094 -312.999882)
			)
		)
		(stroke
			(width 0)
			(type solid)
		)
		(fill yes)
		(layer "In4.Cu")
		(net "P5E_PEX3_STN6_TX_DP<100>")
	)
	(gr_poly
		(pts
			(arc
				(start 402.453094 -278.799798)
				(mid 402.046694 -278.799798)
				(end 402.453094 -278.799798)
			)
		)
		(stroke
			(width 0)
			(type solid)
		)
		(fill yes)
		(layer "In4.Cu")
		(net "P5E_PEX3_STN2_TX_DP<37>")
	)
	(gr_poly
		(pts
			(arc
				(start 402.453094 -277.849838)
				(mid 402.046694 -277.849838)
				(end 402.453094 -277.849838)
			)
		)
		(stroke
			(width 0)
			(type solid)
		)
		(fill yes)
		(layer "In4.Cu")
		(net "P5E_PEX3_STN2_TX_DN<37>")
	)
	(gr_poly
		(pts
			(arc
				(start 402.453094 -274.049744)
				(mid 402.046694 -274.049744)
				(end 402.453094 -274.049744)
			)
		)
		(stroke
			(width 0)
			(type solid)
		)
		(fill yes)
		(layer "In4.Cu")
		(net "P5E_PEX3_STN2_RX_DP<37>")
	)
	(gr_poly
		(pts
			(arc
				(start 402.453094 -273.099784)
				(mid 402.046694 -273.099784)
				(end 402.453094 -273.099784)
			)
		)
		(stroke
			(width 0)
			(type solid)
		)
		(fill yes)
		(layer "In4.Cu")
		(net "P5E_PEX3_STN2_RX_DN<37>")
	)
	(gr_poly
		(pts
			(arc
				(start 403.403054 -316.799722)
				(mid 402.996654 -316.799722)
				(end 403.403054 -316.799722)
			)
		)
		(stroke
			(width 0)
			(type solid)
		)
		(fill yes)
		(layer "In4.Cu")
		(net "P5E_PEX3_STN6_RX_DN<99>")
	)
	(gr_poly
		(pts
			(arc
				(start 403.403054 -315.849762)
				(mid 402.996654 -315.849762)
				(end 403.403054 -315.849762)
			)
		)
		(stroke
			(width 0)
			(type solid)
		)
		(fill yes)
		(layer "In4.Cu")
		(net "P5E_PEX3_STN6_RX_DP<99>")
	)
	(gr_poly
		(pts
			(arc
				(start 403.403054 -312.049922)
				(mid 402.996654 -312.049922)
				(end 403.403054 -312.049922)
			)
		)
		(stroke
			(width 0)
			(type solid)
		)
		(fill yes)
		(layer "In4.Cu")
		(net "P5E_PEX3_STN6_TX_DN<99>")
	)
	(gr_poly
		(pts
			(arc
				(start 403.403054 -311.099962)
				(mid 402.996654 -311.099962)
				(end 403.403054 -311.099962)
			)
		)
		(stroke
			(width 0)
			(type solid)
		)
		(fill yes)
		(layer "In4.Cu")
		(net "P5E_PEX3_STN6_TX_DP<99>")
	)
	(gr_poly
		(pts
			(arc
				(start 403.403054 -280.699464)
				(mid 402.996654 -280.699464)
				(end 403.403054 -280.699464)
			)
		)
		(stroke
			(width 0)
			(type solid)
		)
		(fill yes)
		(layer "In4.Cu")
		(net "P5E_PEX3_STN2_TX_DP<36>")
	)
	(gr_poly
		(pts
			(arc
				(start 403.403054 -279.749504)
				(mid 402.996654 -279.749504)
				(end 403.403054 -279.749504)
			)
		)
		(stroke
			(width 0)
			(type solid)
		)
		(fill yes)
		(layer "In4.Cu")
		(net "P5E_PEX3_STN2_TX_DN<36>")
	)
	(gr_poly
		(pts
			(arc
				(start 403.403054 -275.949918)
				(mid 402.996654 -275.949918)
				(end 403.403054 -275.949918)
			)
		)
		(stroke
			(width 0)
			(type solid)
		)
		(fill yes)
		(layer "In4.Cu")
		(net "P5E_PEX3_STN2_RX_DP<36>")
	)
	(gr_poly
		(pts
			(arc
				(start 403.403054 -274.999958)
				(mid 402.996654 -274.999958)
				(end 403.403054 -274.999958)
			)
		)
		(stroke
			(width 0)
			(type solid)
		)
		(fill yes)
		(layer "In4.Cu")
		(net "P5E_PEX3_STN2_RX_DN<36>")
	)
	(gr_poly
		(pts
			(arc
				(start 404.353014 -318.699896)
				(mid 403.946614 -318.699896)
				(end 404.353014 -318.699896)
			)
		)
		(stroke
			(width 0)
			(type solid)
		)
		(fill yes)
		(layer "In4.Cu")
		(net "P5E_PEX3_STN6_RX_DN<98>")
	)
	(gr_poly
		(pts
			(arc
				(start 404.353014 -317.749936)
				(mid 403.946614 -317.749936)
				(end 404.353014 -317.749936)
			)
		)
		(stroke
			(width 0)
			(type solid)
		)
		(fill yes)
		(layer "In4.Cu")
		(net "P5E_PEX3_STN6_RX_DP<98>")
	)
	(gr_poly
		(pts
			(arc
				(start 404.353014 -313.949842)
				(mid 403.946614 -313.949842)
				(end 404.353014 -313.949842)
			)
		)
		(stroke
			(width 0)
			(type solid)
		)
		(fill yes)
		(layer "In4.Cu")
		(net "P5E_PEX3_STN6_TX_DN<98>")
	)
	(gr_poly
		(pts
			(arc
				(start 404.353014 -312.999882)
				(mid 403.946614 -312.999882)
				(end 404.353014 -312.999882)
			)
		)
		(stroke
			(width 0)
			(type solid)
		)
		(fill yes)
		(layer "In4.Cu")
		(net "P5E_PEX3_STN6_TX_DP<98>")
	)
	(gr_poly
		(pts
			(arc
				(start 404.353014 -278.799798)
				(mid 403.946614 -278.799798)
				(end 404.353014 -278.799798)
			)
		)
		(stroke
			(width 0)
			(type solid)
		)
		(fill yes)
		(layer "In4.Cu")
		(net "P5E_PEX3_STN2_TX_DP<35>")
	)
	(gr_poly
		(pts
			(arc
				(start 404.353014 -277.849838)
				(mid 403.946614 -277.849838)
				(end 404.353014 -277.849838)
			)
		)
		(stroke
			(width 0)
			(type solid)
		)
		(fill yes)
		(layer "In4.Cu")
		(net "P5E_PEX3_STN2_TX_DN<35>")
	)
	(gr_poly
		(pts
			(arc
				(start 404.353014 -274.049744)
				(mid 403.946614 -274.049744)
				(end 404.353014 -274.049744)
			)
		)
		(stroke
			(width 0)
			(type solid)
		)
		(fill yes)
		(layer "In4.Cu")
		(net "P5E_PEX3_STN2_RX_DP<35>")
	)
	(gr_poly
		(pts
			(arc
				(start 404.353014 -273.099784)
				(mid 403.946614 -273.099784)
				(end 404.353014 -273.099784)
			)
		)
		(stroke
			(width 0)
			(type solid)
		)
		(fill yes)
		(layer "In4.Cu")
		(net "P5E_PEX3_STN2_RX_DN<35>")
	)
	(gr_poly
		(pts
			(arc
				(start 405.302974 -280.699464)
				(mid 404.896574 -280.699464)
				(end 405.302974 -280.699464)
			)
		)
		(stroke
			(width 0)
			(type solid)
		)
		(fill yes)
		(layer "In4.Cu")
		(net "P5E_PEX3_STN2_TX_DP<34>")
	)
	(gr_poly
		(pts
			(arc
				(start 405.302974 -279.749504)
				(mid 404.896574 -279.749504)
				(end 405.302974 -279.749504)
			)
		)
		(stroke
			(width 0)
			(type solid)
		)
		(fill yes)
		(layer "In4.Cu")
		(net "P5E_PEX3_STN2_TX_DN<34>")
	)
	(gr_poly
		(pts
			(arc
				(start 405.303228 -316.799722)
				(mid 404.896828 -316.799722)
				(end 405.303228 -316.799722)
			)
		)
		(stroke
			(width 0)
			(type solid)
		)
		(fill yes)
		(layer "In4.Cu")
		(net "P5E_PEX3_STN6_RX_DN<97>")
	)
	(gr_poly
		(pts
			(arc
				(start 405.303228 -315.849762)
				(mid 404.896828 -315.849762)
				(end 405.303228 -315.849762)
			)
		)
		(stroke
			(width 0)
			(type solid)
		)
		(fill yes)
		(layer "In4.Cu")
		(net "P5E_PEX3_STN6_RX_DP<97>")
	)
	(gr_poly
		(pts
			(arc
				(start 405.303228 -312.049922)
				(mid 404.896828 -312.049922)
				(end 405.303228 -312.049922)
			)
		)
		(stroke
			(width 0)
			(type solid)
		)
		(fill yes)
		(layer "In4.Cu")
		(net "P5E_PEX3_STN6_TX_DN<97>")
	)
	(gr_poly
		(pts
			(arc
				(start 405.303228 -311.099962)
				(mid 404.896828 -311.099962)
				(end 405.303228 -311.099962)
			)
		)
		(stroke
			(width 0)
			(type solid)
		)
		(fill yes)
		(layer "In4.Cu")
		(net "P5E_PEX3_STN6_TX_DP<97>")
	)
	(gr_poly
		(pts
			(arc
				(start 405.303228 -275.949918)
				(mid 404.896828 -275.949918)
				(end 405.303228 -275.949918)
			)
		)
		(stroke
			(width 0)
			(type solid)
		)
		(fill yes)
		(layer "In4.Cu")
		(net "P5E_PEX3_STN2_RX_DP<34>")
	)
	(gr_poly
		(pts
			(arc
				(start 405.303228 -274.999958)
				(mid 404.896828 -274.999958)
				(end 405.303228 -274.999958)
			)
		)
		(stroke
			(width 0)
			(type solid)
		)
		(fill yes)
		(layer "In4.Cu")
		(net "P5E_PEX3_STN2_RX_DN<34>")
	)
	(gr_poly
		(pts
			(arc
				(start 406.253188 -318.699896)
				(mid 405.846788 -318.699896)
				(end 406.253188 -318.699896)
			)
		)
		(stroke
			(width 0)
			(type solid)
		)
		(fill yes)
		(layer "In4.Cu")
		(net "P5E_PEX3_STN6_RX_DN<96>")
	)
	(gr_poly
		(pts
			(arc
				(start 406.253188 -317.749936)
				(mid 405.846788 -317.749936)
				(end 406.253188 -317.749936)
			)
		)
		(stroke
			(width 0)
			(type solid)
		)
		(fill yes)
		(layer "In4.Cu")
		(net "P5E_PEX3_STN6_RX_DP<96>")
	)
	(gr_poly
		(pts
			(arc
				(start 406.253188 -313.949842)
				(mid 405.846788 -313.949842)
				(end 406.253188 -313.949842)
			)
		)
		(stroke
			(width 0)
			(type solid)
		)
		(fill yes)
		(layer "In4.Cu")
		(net "P5E_PEX3_STN6_TX_DN<96>")
	)
	(gr_poly
		(pts
			(arc
				(start 406.253188 -312.999882)
				(mid 405.846788 -312.999882)
				(end 406.253188 -312.999882)
			)
		)
		(stroke
			(width 0)
			(type solid)
		)
		(fill yes)
		(layer "In4.Cu")
		(net "P5E_PEX3_STN6_TX_DP<96>")
	)
	(gr_poly
		(pts
			(arc
				(start 406.253188 -278.799798)
				(mid 405.846788 -278.799798)
				(end 406.253188 -278.799798)
			)
		)
		(stroke
			(width 0)
			(type solid)
		)
		(fill yes)
		(layer "In4.Cu")
		(net "P5E_PEX3_STN2_TX_DP<33>")
	)
	(gr_poly
		(pts
			(arc
				(start 406.253188 -277.849838)
				(mid 405.846788 -277.849838)
				(end 406.253188 -277.849838)
			)
		)
		(stroke
			(width 0)
			(type solid)
		)
		(fill yes)
		(layer "In4.Cu")
		(net "P5E_PEX3_STN2_TX_DN<33>")
	)
	(gr_poly
		(pts
			(arc
				(start 406.253188 -274.049744)
				(mid 405.846788 -274.049744)
				(end 406.253188 -274.049744)
			)
		)
		(stroke
			(width 0)
			(type solid)
		)
		(fill yes)
		(layer "In4.Cu")
		(net "P5E_PEX3_STN2_RX_DP<33>")
	)
	(gr_poly
		(pts
			(arc
				(start 406.253188 -273.099784)
				(mid 405.846788 -273.099784)
				(end 406.253188 -273.099784)
			)
		)
		(stroke
			(width 0)
			(type solid)
		)
		(fill yes)
		(layer "In4.Cu")
		(net "P5E_PEX3_STN2_RX_DN<33>")
	)
	(gr_poly
		(pts
			(arc
				(start 407.203148 -316.799722)
				(mid 406.796748 -316.799722)
				(end 407.203148 -316.799722)
			)
		)
		(stroke
			(width 0)
			(type solid)
		)
		(fill yes)
		(layer "In4.Cu")
		(net "P5E_PEX3_STN5_RX_DN<80>")
	)
	(gr_poly
		(pts
			(arc
				(start 407.203148 -315.849762)
				(mid 406.796748 -315.849762)
				(end 407.203148 -315.849762)
			)
		)
		(stroke
			(width 0)
			(type solid)
		)
		(fill yes)
		(layer "In4.Cu")
		(net "P5E_PEX3_STN5_RX_DP<80>")
	)
	(gr_poly
		(pts
			(arc
				(start 407.203148 -312.049922)
				(mid 406.796748 -312.049922)
				(end 407.203148 -312.049922)
			)
		)
		(stroke
			(width 0)
			(type solid)
		)
		(fill yes)
		(layer "In4.Cu")
		(net "P5E_PEX3_STN5_TX_DN<80>")
	)
	(gr_poly
		(pts
			(arc
				(start 407.203148 -311.099962)
				(mid 406.796748 -311.099962)
				(end 407.203148 -311.099962)
			)
		)
		(stroke
			(width 0)
			(type solid)
		)
		(fill yes)
		(layer "In4.Cu")
		(net "P5E_PEX3_STN5_TX_DP<80>")
	)
	(gr_poly
		(pts
			(arc
				(start 407.203148 -280.699464)
				(mid 406.796748 -280.699464)
				(end 407.203148 -280.699464)
			)
		)
		(stroke
			(width 0)
			(type solid)
		)
		(fill yes)
		(layer "In4.Cu")
		(net "P5E_PEX3_STN2_TX_DP<32>")
	)
	(gr_poly
		(pts
			(arc
				(start 407.203148 -279.749504)
				(mid 406.796748 -279.749504)
				(end 407.203148 -279.749504)
			)
		)
		(stroke
			(width 0)
			(type solid)
		)
		(fill yes)
		(layer "In4.Cu")
		(net "P5E_PEX3_STN2_TX_DN<32>")
	)
	(gr_poly
		(pts
			(arc
				(start 407.203148 -275.949918)
				(mid 406.796748 -275.949918)
				(end 407.203148 -275.949918)
			)
		)
		(stroke
			(width 0)
			(type solid)
		)
		(fill yes)
		(layer "In4.Cu")
		(net "P5E_PEX3_STN2_RX_DP<32>")
	)
	(gr_poly
		(pts
			(arc
				(start 407.203148 -274.999958)
				(mid 406.796748 -274.999958)
				(end 407.203148 -274.999958)
			)
		)
		(stroke
			(width 0)
			(type solid)
		)
		(fill yes)
		(layer "In4.Cu")
		(net "P5E_PEX3_STN2_RX_DN<32>")
	)
	(gr_poly
		(pts
			(arc
				(start 408.152854 -278.799798)
				(mid 407.746454 -278.799798)
				(end 408.152854 -278.799798)
			)
		)
		(stroke
			(width 0)
			(type solid)
		)
		(fill yes)
		(layer "In4.Cu")
		(net "P5E_PEX3_STN1_TX_DP<16>")
	)
	(gr_poly
		(pts
			(arc
				(start 408.152854 -277.849838)
				(mid 407.746454 -277.849838)
				(end 408.152854 -277.849838)
			)
		)
		(stroke
			(width 0)
			(type solid)
		)
		(fill yes)
		(layer "In4.Cu")
		(net "P5E_PEX3_STN1_TX_DN<16>")
	)
	(gr_poly
		(pts
			(arc
				(start 408.152854 -274.04949)
				(mid 407.746454 -274.04949)
				(end 408.152854 -274.04949)
			)
		)
		(stroke
			(width 0)
			(type solid)
		)
		(fill yes)
		(layer "In4.Cu")
		(net "P5E_PEX3_STN1_RX_DP<16>")
	)
	(gr_poly
		(pts
			(arc
				(start 408.152854 -273.09953)
				(mid 407.746454 -273.09953)
				(end 408.152854 -273.09953)
			)
		)
		(stroke
			(width 0)
			(type solid)
		)
		(fill yes)
		(layer "In4.Cu")
		(net "P5E_PEX3_STN1_RX_DN<16>")
	)
	(gr_poly
		(pts
			(arc
				(start 408.153108 -318.699896)
				(mid 407.746708 -318.699896)
				(end 408.153108 -318.699896)
			)
		)
		(stroke
			(width 0)
			(type solid)
		)
		(fill yes)
		(layer "In4.Cu")
		(net "P5E_PEX3_STN5_RX_DN<81>")
	)
	(gr_poly
		(pts
			(arc
				(start 408.153108 -317.749936)
				(mid 407.746708 -317.749936)
				(end 408.153108 -317.749936)
			)
		)
		(stroke
			(width 0)
			(type solid)
		)
		(fill yes)
		(layer "In4.Cu")
		(net "P5E_PEX3_STN5_RX_DP<81>")
	)
	(gr_poly
		(pts
			(arc
				(start 408.153108 -313.949842)
				(mid 407.746708 -313.949842)
				(end 408.153108 -313.949842)
			)
		)
		(stroke
			(width 0)
			(type solid)
		)
		(fill yes)
		(layer "In4.Cu")
		(net "P5E_PEX3_STN5_TX_DN<81>")
	)
	(gr_poly
		(pts
			(arc
				(start 408.153108 -312.999882)
				(mid 407.746708 -312.999882)
				(end 408.153108 -312.999882)
			)
		)
		(stroke
			(width 0)
			(type solid)
		)
		(fill yes)
		(layer "In4.Cu")
		(net "P5E_PEX3_STN5_TX_DP<81>")
	)
	(gr_poly
		(pts
			(arc
				(start 409.102814 -275.949664)
				(mid 408.696414 -275.949664)
				(end 409.102814 -275.949664)
			)
		)
		(stroke
			(width 0)
			(type solid)
		)
		(fill yes)
		(layer "In4.Cu")
		(net "P5E_PEX3_STN1_RX_DP<17>")
	)
	(gr_poly
		(pts
			(arc
				(start 409.102814 -274.999704)
				(mid 408.696414 -274.999704)
				(end 409.102814 -274.999704)
			)
		)
		(stroke
			(width 0)
			(type solid)
		)
		(fill yes)
		(layer "In4.Cu")
		(net "P5E_PEX3_STN1_RX_DN<17>")
	)
	(gr_poly
		(pts
			(arc
				(start 409.103068 -316.799722)
				(mid 408.696668 -316.799722)
				(end 409.103068 -316.799722)
			)
		)
		(stroke
			(width 0)
			(type solid)
		)
		(fill yes)
		(layer "In4.Cu")
		(net "P5E_PEX3_STN5_RX_DN<82>")
	)
	(gr_poly
		(pts
			(arc
				(start 409.103068 -315.849762)
				(mid 408.696668 -315.849762)
				(end 409.103068 -315.849762)
			)
		)
		(stroke
			(width 0)
			(type solid)
		)
		(fill yes)
		(layer "In4.Cu")
		(net "P5E_PEX3_STN5_RX_DP<82>")
	)
	(gr_poly
		(pts
			(arc
				(start 409.103068 -312.049922)
				(mid 408.696668 -312.049922)
				(end 409.103068 -312.049922)
			)
		)
		(stroke
			(width 0)
			(type solid)
		)
		(fill yes)
		(layer "In4.Cu")
		(net "P5E_PEX3_STN5_TX_DN<82>")
	)
	(gr_poly
		(pts
			(arc
				(start 409.103068 -311.099962)
				(mid 408.696668 -311.099962)
				(end 409.103068 -311.099962)
			)
		)
		(stroke
			(width 0)
			(type solid)
		)
		(fill yes)
		(layer "In4.Cu")
		(net "P5E_PEX3_STN5_TX_DP<82>")
	)
	(gr_poly
		(pts
			(arc
				(start 409.103068 -280.699464)
				(mid 408.696668 -280.699464)
				(end 409.103068 -280.699464)
			)
		)
		(stroke
			(width 0)
			(type solid)
		)
		(fill yes)
		(layer "In4.Cu")
		(net "P5E_PEX3_STN1_TX_DN<17>")
	)
	(gr_poly
		(pts
			(arc
				(start 409.103068 -279.749504)
				(mid 408.696668 -279.749504)
				(end 409.103068 -279.749504)
			)
		)
		(stroke
			(width 0)
			(type solid)
		)
		(fill yes)
		(layer "In4.Cu")
		(net "P5E_PEX3_STN1_TX_DP<17>")
	)
	(gr_poly
		(pts
			(arc
				(start 410.052774 -278.799798)
				(mid 409.646374 -278.799798)
				(end 410.052774 -278.799798)
			)
		)
		(stroke
			(width 0)
			(type solid)
		)
		(fill yes)
		(layer "In4.Cu")
		(net "P5E_PEX3_STN1_TX_DP<18>")
	)
	(gr_poly
		(pts
			(arc
				(start 410.052774 -277.849838)
				(mid 409.646374 -277.849838)
				(end 410.052774 -277.849838)
			)
		)
		(stroke
			(width 0)
			(type solid)
		)
		(fill yes)
		(layer "In4.Cu")
		(net "P5E_PEX3_STN1_TX_DN<18>")
	)
	(gr_poly
		(pts
			(arc
				(start 410.052774 -274.049744)
				(mid 409.646374 -274.049744)
				(end 410.052774 -274.049744)
			)
		)
		(stroke
			(width 0)
			(type solid)
		)
		(fill yes)
		(layer "In4.Cu")
		(net "P5E_PEX3_STN1_RX_DP<18>")
	)
	(gr_poly
		(pts
			(arc
				(start 410.052774 -273.099784)
				(mid 409.646374 -273.099784)
				(end 410.052774 -273.099784)
			)
		)
		(stroke
			(width 0)
			(type solid)
		)
		(fill yes)
		(layer "In4.Cu")
		(net "P5E_PEX3_STN1_RX_DN<18>")
	)
	(gr_poly
		(pts
			(arc
				(start 410.053028 -318.699896)
				(mid 409.646628 -318.699896)
				(end 410.053028 -318.699896)
			)
		)
		(stroke
			(width 0)
			(type solid)
		)
		(fill yes)
		(layer "In4.Cu")
		(net "P5E_PEX3_STN5_RX_DN<83>")
	)
	(gr_poly
		(pts
			(arc
				(start 410.053028 -317.749936)
				(mid 409.646628 -317.749936)
				(end 410.053028 -317.749936)
			)
		)
		(stroke
			(width 0)
			(type solid)
		)
		(fill yes)
		(layer "In4.Cu")
		(net "P5E_PEX3_STN5_RX_DP<83>")
	)
	(gr_poly
		(pts
			(arc
				(start 410.053028 -313.949842)
				(mid 409.646628 -313.949842)
				(end 410.053028 -313.949842)
			)
		)
		(stroke
			(width 0)
			(type solid)
		)
		(fill yes)
		(layer "In4.Cu")
		(net "P5E_PEX3_STN5_TX_DN<83>")
	)
	(gr_poly
		(pts
			(arc
				(start 410.053028 -312.999882)
				(mid 409.646628 -312.999882)
				(end 410.053028 -312.999882)
			)
		)
		(stroke
			(width 0)
			(type solid)
		)
		(fill yes)
		(layer "In4.Cu")
		(net "P5E_PEX3_STN5_TX_DP<83>")
	)
	(gr_poly
		(pts
			(arc
				(start 411.002734 -275.949918)
				(mid 410.596334 -275.949918)
				(end 411.002734 -275.949918)
			)
		)
		(stroke
			(width 0)
			(type solid)
		)
		(fill yes)
		(layer "In4.Cu")
		(net "P5E_PEX3_STN1_RX_DP<19>")
	)
	(gr_poly
		(pts
			(arc
				(start 411.002734 -274.999958)
				(mid 410.596334 -274.999958)
				(end 411.002734 -274.999958)
			)
		)
		(stroke
			(width 0)
			(type solid)
		)
		(fill yes)
		(layer "In4.Cu")
		(net "P5E_PEX3_STN1_RX_DN<19>")
	)
	(gr_poly
		(pts
			(arc
				(start 411.002988 -316.799722)
				(mid 410.596588 -316.799722)
				(end 411.002988 -316.799722)
			)
		)
		(stroke
			(width 0)
			(type solid)
		)
		(fill yes)
		(layer "In4.Cu")
		(net "P5E_PEX3_STN5_RX_DN<84>")
	)
	(gr_poly
		(pts
			(arc
				(start 411.002988 -315.849762)
				(mid 410.596588 -315.849762)
				(end 411.002988 -315.849762)
			)
		)
		(stroke
			(width 0)
			(type solid)
		)
		(fill yes)
		(layer "In4.Cu")
		(net "P5E_PEX3_STN5_RX_DP<84>")
	)
	(gr_poly
		(pts
			(arc
				(start 411.002988 -312.049922)
				(mid 410.596588 -312.049922)
				(end 411.002988 -312.049922)
			)
		)
		(stroke
			(width 0)
			(type solid)
		)
		(fill yes)
		(layer "In4.Cu")
		(net "P5E_PEX3_STN5_TX_DN<84>")
	)
	(gr_poly
		(pts
			(arc
				(start 411.002988 -311.099962)
				(mid 410.596588 -311.099962)
				(end 411.002988 -311.099962)
			)
		)
		(stroke
			(width 0)
			(type solid)
		)
		(fill yes)
		(layer "In4.Cu")
		(net "P5E_PEX3_STN5_TX_DP<84>")
	)
	(gr_poly
		(pts
			(arc
				(start 411.002988 -280.699464)
				(mid 410.596588 -280.699464)
				(end 411.002988 -280.699464)
			)
		)
		(stroke
			(width 0)
			(type solid)
		)
		(fill yes)
		(layer "In4.Cu")
		(net "P5E_PEX3_STN1_TX_DN<19>")
	)
	(gr_poly
		(pts
			(arc
				(start 411.002988 -279.749504)
				(mid 410.596588 -279.749504)
				(end 411.002988 -279.749504)
			)
		)
		(stroke
			(width 0)
			(type solid)
		)
		(fill yes)
		(layer "In4.Cu")
		(net "P5E_PEX3_STN1_TX_DP<19>")
	)
	(gr_poly
		(pts
			(arc
				(start 411.952948 -278.799798)
				(mid 411.546548 -278.799798)
				(end 411.952948 -278.799798)
			)
		)
		(stroke
			(width 0)
			(type solid)
		)
		(fill yes)
		(layer "In4.Cu")
		(net "P5E_PEX3_STN1_TX_DP<20>")
	)
	(gr_poly
		(pts
			(arc
				(start 411.952948 -277.849838)
				(mid 411.546548 -277.849838)
				(end 411.952948 -277.849838)
			)
		)
		(stroke
			(width 0)
			(type solid)
		)
		(fill yes)
		(layer "In4.Cu")
		(net "P5E_PEX3_STN1_TX_DN<20>")
	)
	(gr_poly
		(pts
			(arc
				(start 411.952948 -274.049744)
				(mid 411.546548 -274.049744)
				(end 411.952948 -274.049744)
			)
		)
		(stroke
			(width 0)
			(type solid)
		)
		(fill yes)
		(layer "In4.Cu")
		(net "P5E_PEX3_STN1_RX_DP<20>")
	)
	(gr_poly
		(pts
			(arc
				(start 411.952948 -273.099784)
				(mid 411.546548 -273.099784)
				(end 411.952948 -273.099784)
			)
		)
		(stroke
			(width 0)
			(type solid)
		)
		(fill yes)
		(layer "In4.Cu")
		(net "P5E_PEX3_STN1_RX_DN<20>")
	)
	(gr_poly
		(pts
			(arc
				(start 411.953202 -318.699896)
				(mid 411.546802 -318.699896)
				(end 411.953202 -318.699896)
			)
		)
		(stroke
			(width 0)
			(type solid)
		)
		(fill yes)
		(layer "In4.Cu")
		(net "P5E_PEX3_STN5_RX_DN<85>")
	)
	(gr_poly
		(pts
			(arc
				(start 411.953202 -317.749936)
				(mid 411.546802 -317.749936)
				(end 411.953202 -317.749936)
			)
		)
		(stroke
			(width 0)
			(type solid)
		)
		(fill yes)
		(layer "In4.Cu")
		(net "P5E_PEX3_STN5_RX_DP<85>")
	)
	(gr_poly
		(pts
			(arc
				(start 411.953202 -313.949842)
				(mid 411.546802 -313.949842)
				(end 411.953202 -313.949842)
			)
		)
		(stroke
			(width 0)
			(type solid)
		)
		(fill yes)
		(layer "In4.Cu")
		(net "P5E_PEX3_STN5_TX_DN<85>")
	)
	(gr_poly
		(pts
			(arc
				(start 411.953202 -312.999882)
				(mid 411.546802 -312.999882)
				(end 411.953202 -312.999882)
			)
		)
		(stroke
			(width 0)
			(type solid)
		)
		(fill yes)
		(layer "In4.Cu")
		(net "P5E_PEX3_STN5_TX_DP<85>")
	)
	(gr_poly
		(pts
			(arc
				(start 412.902908 -275.949664)
				(mid 412.496508 -275.949664)
				(end 412.902908 -275.949664)
			)
		)
		(stroke
			(width 0)
			(type solid)
		)
		(fill yes)
		(layer "In4.Cu")
		(net "P5E_PEX3_STN1_RX_DP<21>")
	)
	(gr_poly
		(pts
			(arc
				(start 412.902908 -274.999704)
				(mid 412.496508 -274.999704)
				(end 412.902908 -274.999704)
			)
		)
		(stroke
			(width 0)
			(type solid)
		)
		(fill yes)
		(layer "In4.Cu")
		(net "P5E_PEX3_STN1_RX_DN<21>")
	)
	(gr_poly
		(pts
			(arc
				(start 412.903162 -316.799722)
				(mid 412.496762 -316.799722)
				(end 412.903162 -316.799722)
			)
		)
		(stroke
			(width 0)
			(type solid)
		)
		(fill yes)
		(layer "In4.Cu")
		(net "P5E_PEX3_STN5_RX_DN<86>")
	)
	(gr_poly
		(pts
			(arc
				(start 412.903162 -315.849762)
				(mid 412.496762 -315.849762)
				(end 412.903162 -315.849762)
			)
		)
		(stroke
			(width 0)
			(type solid)
		)
		(fill yes)
		(layer "In4.Cu")
		(net "P5E_PEX3_STN5_RX_DP<86>")
	)
	(gr_poly
		(pts
			(arc
				(start 412.903162 -312.049922)
				(mid 412.496762 -312.049922)
				(end 412.903162 -312.049922)
			)
		)
		(stroke
			(width 0)
			(type solid)
		)
		(fill yes)
		(layer "In4.Cu")
		(net "P5E_PEX3_STN5_TX_DN<86>")
	)
	(gr_poly
		(pts
			(arc
				(start 412.903162 -311.099962)
				(mid 412.496762 -311.099962)
				(end 412.903162 -311.099962)
			)
		)
		(stroke
			(width 0)
			(type solid)
		)
		(fill yes)
		(layer "In4.Cu")
		(net "P5E_PEX3_STN5_TX_DP<86>")
	)
	(gr_poly
		(pts
			(arc
				(start 412.903162 -280.699464)
				(mid 412.496762 -280.699464)
				(end 412.903162 -280.699464)
			)
		)
		(stroke
			(width 0)
			(type solid)
		)
		(fill yes)
		(layer "In4.Cu")
		(net "P5E_PEX3_STN1_TX_DN<21>")
	)
	(gr_poly
		(pts
			(arc
				(start 412.903162 -279.749504)
				(mid 412.496762 -279.749504)
				(end 412.903162 -279.749504)
			)
		)
		(stroke
			(width 0)
			(type solid)
		)
		(fill yes)
		(layer "In4.Cu")
		(net "P5E_PEX3_STN1_TX_DP<21>")
	)
	(gr_poly
		(pts
			(arc
				(start 413.852868 -278.799798)
				(mid 413.446468 -278.799798)
				(end 413.852868 -278.799798)
			)
		)
		(stroke
			(width 0)
			(type solid)
		)
		(fill yes)
		(layer "In4.Cu")
		(net "P5E_PEX3_STN1_TX_DP<22>")
	)
	(gr_poly
		(pts
			(arc
				(start 413.852868 -277.849838)
				(mid 413.446468 -277.849838)
				(end 413.852868 -277.849838)
			)
		)
		(stroke
			(width 0)
			(type solid)
		)
		(fill yes)
		(layer "In4.Cu")
		(net "P5E_PEX3_STN1_TX_DN<22>")
	)
	(gr_poly
		(pts
			(arc
				(start 413.852868 -274.049744)
				(mid 413.446468 -274.049744)
				(end 413.852868 -274.049744)
			)
		)
		(stroke
			(width 0)
			(type solid)
		)
		(fill yes)
		(layer "In4.Cu")
		(net "P5E_PEX3_STN1_RX_DP<22>")
	)
	(gr_poly
		(pts
			(arc
				(start 413.852868 -273.099784)
				(mid 413.446468 -273.099784)
				(end 413.852868 -273.099784)
			)
		)
		(stroke
			(width 0)
			(type solid)
		)
		(fill yes)
		(layer "In4.Cu")
		(net "P5E_PEX3_STN1_RX_DN<22>")
	)
	(gr_poly
		(pts
			(arc
				(start 413.853122 -318.699896)
				(mid 413.446722 -318.699896)
				(end 413.853122 -318.699896)
			)
		)
		(stroke
			(width 0)
			(type solid)
		)
		(fill yes)
		(layer "In4.Cu")
		(net "P5E_PEX3_STN5_RX_DN<87>")
	)
	(gr_poly
		(pts
			(arc
				(start 413.853122 -317.749936)
				(mid 413.446722 -317.749936)
				(end 413.853122 -317.749936)
			)
		)
		(stroke
			(width 0)
			(type solid)
		)
		(fill yes)
		(layer "In4.Cu")
		(net "P5E_PEX3_STN5_RX_DP<87>")
	)
	(gr_poly
		(pts
			(arc
				(start 413.853122 -313.949842)
				(mid 413.446722 -313.949842)
				(end 413.853122 -313.949842)
			)
		)
		(stroke
			(width 0)
			(type solid)
		)
		(fill yes)
		(layer "In4.Cu")
		(net "P5E_PEX3_STN5_TX_DN<87>")
	)
	(gr_poly
		(pts
			(arc
				(start 413.853122 -312.999882)
				(mid 413.446722 -312.999882)
				(end 413.853122 -312.999882)
			)
		)
		(stroke
			(width 0)
			(type solid)
		)
		(fill yes)
		(layer "In4.Cu")
		(net "P5E_PEX3_STN5_TX_DP<87>")
	)
	(gr_poly
		(pts
			(arc
				(start 414.802828 -275.949918)
				(mid 414.396428 -275.949918)
				(end 414.802828 -275.949918)
			)
		)
		(stroke
			(width 0)
			(type solid)
		)
		(fill yes)
		(layer "In4.Cu")
		(net "P5E_PEX3_STN1_RX_DP<23>")
	)
	(gr_poly
		(pts
			(arc
				(start 414.802828 -274.999958)
				(mid 414.396428 -274.999958)
				(end 414.802828 -274.999958)
			)
		)
		(stroke
			(width 0)
			(type solid)
		)
		(fill yes)
		(layer "In4.Cu")
		(net "P5E_PEX3_STN1_RX_DN<23>")
	)
	(gr_poly
		(pts
			(arc
				(start 414.803082 -316.799722)
				(mid 414.396682 -316.799722)
				(end 414.803082 -316.799722)
			)
		)
		(stroke
			(width 0)
			(type solid)
		)
		(fill yes)
		(layer "In4.Cu")
		(net "P5E_PEX3_STN5_RX_DN<88>")
	)
	(gr_poly
		(pts
			(arc
				(start 414.803082 -315.849762)
				(mid 414.396682 -315.849762)
				(end 414.803082 -315.849762)
			)
		)
		(stroke
			(width 0)
			(type solid)
		)
		(fill yes)
		(layer "In4.Cu")
		(net "P5E_PEX3_STN5_RX_DP<88>")
	)
	(gr_poly
		(pts
			(arc
				(start 414.803082 -312.049922)
				(mid 414.396682 -312.049922)
				(end 414.803082 -312.049922)
			)
		)
		(stroke
			(width 0)
			(type solid)
		)
		(fill yes)
		(layer "In4.Cu")
		(net "P5E_PEX3_STN5_TX_DN<88>")
	)
	(gr_poly
		(pts
			(arc
				(start 414.803082 -311.099962)
				(mid 414.396682 -311.099962)
				(end 414.803082 -311.099962)
			)
		)
		(stroke
			(width 0)
			(type solid)
		)
		(fill yes)
		(layer "In4.Cu")
		(net "P5E_PEX3_STN5_TX_DP<88>")
	)
	(gr_poly
		(pts
			(arc
				(start 414.803082 -280.699464)
				(mid 414.396682 -280.699464)
				(end 414.803082 -280.699464)
			)
		)
		(stroke
			(width 0)
			(type solid)
		)
		(fill yes)
		(layer "In4.Cu")
		(net "P5E_PEX3_STN1_TX_DN<23>")
	)
	(gr_poly
		(pts
			(arc
				(start 414.803082 -279.749504)
				(mid 414.396682 -279.749504)
				(end 414.803082 -279.749504)
			)
		)
		(stroke
			(width 0)
			(type solid)
		)
		(fill yes)
		(layer "In4.Cu")
		(net "P5E_PEX3_STN1_TX_DP<23>")
	)
	(gr_poly
		(pts
			(arc
				(start 415.752788 -278.799798)
				(mid 415.346388 -278.799798)
				(end 415.752788 -278.799798)
			)
		)
		(stroke
			(width 0)
			(type solid)
		)
		(fill yes)
		(layer "In4.Cu")
		(net "P5E_PEX3_STN1_TX_DP<24>")
	)
	(gr_poly
		(pts
			(arc
				(start 415.752788 -277.849838)
				(mid 415.346388 -277.849838)
				(end 415.752788 -277.849838)
			)
		)
		(stroke
			(width 0)
			(type solid)
		)
		(fill yes)
		(layer "In4.Cu")
		(net "P5E_PEX3_STN1_TX_DN<24>")
	)
	(gr_poly
		(pts
			(arc
				(start 415.752788 -274.049744)
				(mid 415.346388 -274.049744)
				(end 415.752788 -274.049744)
			)
		)
		(stroke
			(width 0)
			(type solid)
		)
		(fill yes)
		(layer "In4.Cu")
		(net "P5E_PEX3_STN1_RX_DP<24>")
	)
	(gr_poly
		(pts
			(arc
				(start 415.752788 -273.099784)
				(mid 415.346388 -273.099784)
				(end 415.752788 -273.099784)
			)
		)
		(stroke
			(width 0)
			(type solid)
		)
		(fill yes)
		(layer "In4.Cu")
		(net "P5E_PEX3_STN1_RX_DN<24>")
	)
	(gr_poly
		(pts
			(arc
				(start 415.753042 -318.699896)
				(mid 415.346642 -318.699896)
				(end 415.753042 -318.699896)
			)
		)
		(stroke
			(width 0)
			(type solid)
		)
		(fill yes)
		(layer "In4.Cu")
		(net "P5E_PEX3_STN5_RX_DN<89>")
	)
	(gr_poly
		(pts
			(arc
				(start 415.753042 -317.749936)
				(mid 415.346642 -317.749936)
				(end 415.753042 -317.749936)
			)
		)
		(stroke
			(width 0)
			(type solid)
		)
		(fill yes)
		(layer "In4.Cu")
		(net "P5E_PEX3_STN5_RX_DP<89>")
	)
	(gr_poly
		(pts
			(arc
				(start 415.753042 -313.949842)
				(mid 415.346642 -313.949842)
				(end 415.753042 -313.949842)
			)
		)
		(stroke
			(width 0)
			(type solid)
		)
		(fill yes)
		(layer "In4.Cu")
		(net "P5E_PEX3_STN5_TX_DN<89>")
	)
	(gr_poly
		(pts
			(arc
				(start 415.753042 -312.999882)
				(mid 415.346642 -312.999882)
				(end 415.753042 -312.999882)
			)
		)
		(stroke
			(width 0)
			(type solid)
		)
		(fill yes)
		(layer "In4.Cu")
		(net "P5E_PEX3_STN5_TX_DP<89>")
	)
	(gr_poly
		(pts
			(arc
				(start 416.702748 -275.949664)
				(mid 416.296348 -275.949664)
				(end 416.702748 -275.949664)
			)
		)
		(stroke
			(width 0)
			(type solid)
		)
		(fill yes)
		(layer "In4.Cu")
		(net "P5E_PEX3_STN1_RX_DP<25>")
	)
	(gr_poly
		(pts
			(arc
				(start 416.702748 -274.999704)
				(mid 416.296348 -274.999704)
				(end 416.702748 -274.999704)
			)
		)
		(stroke
			(width 0)
			(type solid)
		)
		(fill yes)
		(layer "In4.Cu")
		(net "P5E_PEX3_STN1_RX_DN<25>")
	)
	(gr_poly
		(pts
			(arc
				(start 416.703002 -316.799722)
				(mid 416.296602 -316.799722)
				(end 416.703002 -316.799722)
			)
		)
		(stroke
			(width 0)
			(type solid)
		)
		(fill yes)
		(layer "In4.Cu")
		(net "P5E_PEX3_STN5_RX_DN<90>")
	)
	(gr_poly
		(pts
			(arc
				(start 416.703002 -315.849762)
				(mid 416.296602 -315.849762)
				(end 416.703002 -315.849762)
			)
		)
		(stroke
			(width 0)
			(type solid)
		)
		(fill yes)
		(layer "In4.Cu")
		(net "P5E_PEX3_STN5_RX_DP<90>")
	)
	(gr_poly
		(pts
			(arc
				(start 416.703002 -312.049922)
				(mid 416.296602 -312.049922)
				(end 416.703002 -312.049922)
			)
		)
		(stroke
			(width 0)
			(type solid)
		)
		(fill yes)
		(layer "In4.Cu")
		(net "P5E_PEX3_STN5_TX_DN<90>")
	)
	(gr_poly
		(pts
			(arc
				(start 416.703002 -311.099962)
				(mid 416.296602 -311.099962)
				(end 416.703002 -311.099962)
			)
		)
		(stroke
			(width 0)
			(type solid)
		)
		(fill yes)
		(layer "In4.Cu")
		(net "P5E_PEX3_STN5_TX_DP<90>")
	)
	(gr_poly
		(pts
			(arc
				(start 416.703002 -280.699464)
				(mid 416.296602 -280.699464)
				(end 416.703002 -280.699464)
			)
		)
		(stroke
			(width 0)
			(type solid)
		)
		(fill yes)
		(layer "In4.Cu")
		(net "P5E_PEX3_STN1_TX_DN<25>")
	)
	(gr_poly
		(pts
			(arc
				(start 416.703002 -279.749504)
				(mid 416.296602 -279.749504)
				(end 416.703002 -279.749504)
			)
		)
		(stroke
			(width 0)
			(type solid)
		)
		(fill yes)
		(layer "In4.Cu")
		(net "P5E_PEX3_STN1_TX_DP<25>")
	)
	(gr_poly
		(pts
			(arc
				(start 417.652962 -278.799798)
				(mid 417.246562 -278.799798)
				(end 417.652962 -278.799798)
			)
		)
		(stroke
			(width 0)
			(type solid)
		)
		(fill yes)
		(layer "In4.Cu")
		(net "P5E_PEX3_STN1_TX_DP<26>")
	)
	(gr_poly
		(pts
			(arc
				(start 417.652962 -277.849838)
				(mid 417.246562 -277.849838)
				(end 417.652962 -277.849838)
			)
		)
		(stroke
			(width 0)
			(type solid)
		)
		(fill yes)
		(layer "In4.Cu")
		(net "P5E_PEX3_STN1_TX_DN<26>")
	)
	(gr_poly
		(pts
			(arc
				(start 417.652962 -274.049744)
				(mid 417.246562 -274.049744)
				(end 417.652962 -274.049744)
			)
		)
		(stroke
			(width 0)
			(type solid)
		)
		(fill yes)
		(layer "In4.Cu")
		(net "P5E_PEX3_STN1_RX_DP<26>")
	)
	(gr_poly
		(pts
			(arc
				(start 417.652962 -273.099784)
				(mid 417.246562 -273.099784)
				(end 417.652962 -273.099784)
			)
		)
		(stroke
			(width 0)
			(type solid)
		)
		(fill yes)
		(layer "In4.Cu")
		(net "P5E_PEX3_STN1_RX_DN<26>")
	)
	(gr_poly
		(pts
			(arc
				(start 417.653216 -318.699896)
				(mid 417.246816 -318.699896)
				(end 417.653216 -318.699896)
			)
		)
		(stroke
			(width 0)
			(type solid)
		)
		(fill yes)
		(layer "In4.Cu")
		(net "P5E_PEX3_STN5_RX_DN<91>")
	)
	(gr_poly
		(pts
			(arc
				(start 417.653216 -317.749936)
				(mid 417.246816 -317.749936)
				(end 417.653216 -317.749936)
			)
		)
		(stroke
			(width 0)
			(type solid)
		)
		(fill yes)
		(layer "In4.Cu")
		(net "P5E_PEX3_STN5_RX_DP<91>")
	)
	(gr_poly
		(pts
			(arc
				(start 417.653216 -313.949842)
				(mid 417.246816 -313.949842)
				(end 417.653216 -313.949842)
			)
		)
		(stroke
			(width 0)
			(type solid)
		)
		(fill yes)
		(layer "In4.Cu")
		(net "P5E_PEX3_STN5_TX_DN<91>")
	)
	(gr_poly
		(pts
			(arc
				(start 417.653216 -312.999882)
				(mid 417.246816 -312.999882)
				(end 417.653216 -312.999882)
			)
		)
		(stroke
			(width 0)
			(type solid)
		)
		(fill yes)
		(layer "In4.Cu")
		(net "P5E_PEX3_STN5_TX_DP<91>")
	)
	(gr_poly
		(pts
			(arc
				(start 418.602668 -275.949918)
				(mid 418.196268 -275.949918)
				(end 418.602668 -275.949918)
			)
		)
		(stroke
			(width 0)
			(type solid)
		)
		(fill yes)
		(layer "In4.Cu")
		(net "P5E_PEX3_STN1_RX_DP<27>")
	)
	(gr_poly
		(pts
			(arc
				(start 418.602668 -274.999958)
				(mid 418.196268 -274.999958)
				(end 418.602668 -274.999958)
			)
		)
		(stroke
			(width 0)
			(type solid)
		)
		(fill yes)
		(layer "In4.Cu")
		(net "P5E_PEX3_STN1_RX_DN<27>")
	)
	(gr_poly
		(pts
			(arc
				(start 418.603176 -316.799722)
				(mid 418.196776 -316.799722)
				(end 418.603176 -316.799722)
			)
		)
		(stroke
			(width 0)
			(type solid)
		)
		(fill yes)
		(layer "In4.Cu")
		(net "P5E_PEX3_STN5_RX_DN<92>")
	)
	(gr_poly
		(pts
			(arc
				(start 418.603176 -315.849762)
				(mid 418.196776 -315.849762)
				(end 418.603176 -315.849762)
			)
		)
		(stroke
			(width 0)
			(type solid)
		)
		(fill yes)
		(layer "In4.Cu")
		(net "P5E_PEX3_STN5_RX_DP<92>")
	)
	(gr_poly
		(pts
			(arc
				(start 418.603176 -312.049922)
				(mid 418.196776 -312.049922)
				(end 418.603176 -312.049922)
			)
		)
		(stroke
			(width 0)
			(type solid)
		)
		(fill yes)
		(layer "In4.Cu")
		(net "P5E_PEX3_STN5_TX_DN<92>")
	)
	(gr_poly
		(pts
			(arc
				(start 418.603176 -311.099962)
				(mid 418.196776 -311.099962)
				(end 418.603176 -311.099962)
			)
		)
		(stroke
			(width 0)
			(type solid)
		)
		(fill yes)
		(layer "In4.Cu")
		(net "P5E_PEX3_STN5_TX_DP<92>")
	)
	(gr_poly
		(pts
			(arc
				(start 418.603176 -280.699464)
				(mid 418.196776 -280.699464)
				(end 418.603176 -280.699464)
			)
		)
		(stroke
			(width 0)
			(type solid)
		)
		(fill yes)
		(layer "In4.Cu")
		(net "P5E_PEX3_STN1_TX_DN<27>")
	)
	(gr_poly
		(pts
			(arc
				(start 418.603176 -279.749504)
				(mid 418.196776 -279.749504)
				(end 418.603176 -279.749504)
			)
		)
		(stroke
			(width 0)
			(type solid)
		)
		(fill yes)
		(layer "In4.Cu")
		(net "P5E_PEX3_STN1_TX_DP<27>")
	)
	(gr_poly
		(pts
			(arc
				(start 419.552882 -278.799798)
				(mid 419.146482 -278.799798)
				(end 419.552882 -278.799798)
			)
		)
		(stroke
			(width 0)
			(type solid)
		)
		(fill yes)
		(layer "In4.Cu")
		(net "P5E_PEX3_STN1_TX_DP<28>")
	)
	(gr_poly
		(pts
			(arc
				(start 419.552882 -277.849838)
				(mid 419.146482 -277.849838)
				(end 419.552882 -277.849838)
			)
		)
		(stroke
			(width 0)
			(type solid)
		)
		(fill yes)
		(layer "In4.Cu")
		(net "P5E_PEX3_STN1_TX_DN<28>")
	)
	(gr_poly
		(pts
			(arc
				(start 419.552882 -274.049744)
				(mid 419.146482 -274.049744)
				(end 419.552882 -274.049744)
			)
		)
		(stroke
			(width 0)
			(type solid)
		)
		(fill yes)
		(layer "In4.Cu")
		(net "P5E_PEX3_STN1_RX_DP<28>")
	)
	(gr_poly
		(pts
			(arc
				(start 419.552882 -273.099784)
				(mid 419.146482 -273.099784)
				(end 419.552882 -273.099784)
			)
		)
		(stroke
			(width 0)
			(type solid)
		)
		(fill yes)
		(layer "In4.Cu")
		(net "P5E_PEX3_STN1_RX_DN<28>")
	)
	(gr_poly
		(pts
			(arc
				(start 419.553136 -318.699896)
				(mid 419.146736 -318.699896)
				(end 419.553136 -318.699896)
			)
		)
		(stroke
			(width 0)
			(type solid)
		)
		(fill yes)
		(layer "In4.Cu")
		(net "P5E_PEX3_STN5_RX_DN<93>")
	)
	(gr_poly
		(pts
			(arc
				(start 419.553136 -317.749936)
				(mid 419.146736 -317.749936)
				(end 419.553136 -317.749936)
			)
		)
		(stroke
			(width 0)
			(type solid)
		)
		(fill yes)
		(layer "In4.Cu")
		(net "P5E_PEX3_STN5_RX_DP<93>")
	)
	(gr_poly
		(pts
			(arc
				(start 419.553136 -313.949842)
				(mid 419.146736 -313.949842)
				(end 419.553136 -313.949842)
			)
		)
		(stroke
			(width 0)
			(type solid)
		)
		(fill yes)
		(layer "In4.Cu")
		(net "P5E_PEX3_STN5_TX_DN<93>")
	)
	(gr_poly
		(pts
			(arc
				(start 419.553136 -312.999882)
				(mid 419.146736 -312.999882)
				(end 419.553136 -312.999882)
			)
		)
		(stroke
			(width 0)
			(type solid)
		)
		(fill yes)
		(layer "In4.Cu")
		(net "P5E_PEX3_STN5_TX_DP<93>")
	)
	(gr_poly
		(pts
			(arc
				(start 420.502842 -275.949664)
				(mid 420.096442 -275.949664)
				(end 420.502842 -275.949664)
			)
		)
		(stroke
			(width 0)
			(type solid)
		)
		(fill yes)
		(layer "In4.Cu")
		(net "P5E_PEX3_STN1_RX_DP<29>")
	)
	(gr_poly
		(pts
			(arc
				(start 420.502842 -274.999704)
				(mid 420.096442 -274.999704)
				(end 420.502842 -274.999704)
			)
		)
		(stroke
			(width 0)
			(type solid)
		)
		(fill yes)
		(layer "In4.Cu")
		(net "P5E_PEX3_STN1_RX_DN<29>")
	)
	(gr_poly
		(pts
			(arc
				(start 420.503096 -316.799722)
				(mid 420.096696 -316.799722)
				(end 420.503096 -316.799722)
			)
		)
		(stroke
			(width 0)
			(type solid)
		)
		(fill yes)
		(layer "In4.Cu")
		(net "P5E_PEX3_STN5_RX_DN<94>")
	)
	(gr_poly
		(pts
			(arc
				(start 420.503096 -315.849762)
				(mid 420.096696 -315.849762)
				(end 420.503096 -315.849762)
			)
		)
		(stroke
			(width 0)
			(type solid)
		)
		(fill yes)
		(layer "In4.Cu")
		(net "P5E_PEX3_STN5_RX_DP<94>")
	)
	(gr_poly
		(pts
			(arc
				(start 420.503096 -312.049922)
				(mid 420.096696 -312.049922)
				(end 420.503096 -312.049922)
			)
		)
		(stroke
			(width 0)
			(type solid)
		)
		(fill yes)
		(layer "In4.Cu")
		(net "P5E_PEX3_STN5_TX_DN<94>")
	)
	(gr_poly
		(pts
			(arc
				(start 420.503096 -311.099962)
				(mid 420.096696 -311.099962)
				(end 420.503096 -311.099962)
			)
		)
		(stroke
			(width 0)
			(type solid)
		)
		(fill yes)
		(layer "In4.Cu")
		(net "P5E_PEX3_STN5_TX_DP<94>")
	)
	(gr_poly
		(pts
			(arc
				(start 420.503096 -280.699464)
				(mid 420.096696 -280.699464)
				(end 420.503096 -280.699464)
			)
		)
		(stroke
			(width 0)
			(type solid)
		)
		(fill yes)
		(layer "In4.Cu")
		(net "P5E_PEX3_STN1_TX_DN<29>")
	)
	(gr_poly
		(pts
			(arc
				(start 420.503096 -279.749504)
				(mid 420.096696 -279.749504)
				(end 420.503096 -279.749504)
			)
		)
		(stroke
			(width 0)
			(type solid)
		)
		(fill yes)
		(layer "In4.Cu")
		(net "P5E_PEX3_STN1_TX_DP<29>")
	)
	(gr_poly
		(pts
			(arc
				(start 421.452802 -278.799798)
				(mid 421.046402 -278.799798)
				(end 421.452802 -278.799798)
			)
		)
		(stroke
			(width 0)
			(type solid)
		)
		(fill yes)
		(layer "In4.Cu")
		(net "P5E_PEX3_STN1_TX_DP<30>")
	)
	(gr_poly
		(pts
			(arc
				(start 421.452802 -277.849838)
				(mid 421.046402 -277.849838)
				(end 421.452802 -277.849838)
			)
		)
		(stroke
			(width 0)
			(type solid)
		)
		(fill yes)
		(layer "In4.Cu")
		(net "P5E_PEX3_STN1_TX_DN<30>")
	)
	(gr_poly
		(pts
			(arc
				(start 421.452802 -274.049744)
				(mid 421.046402 -274.049744)
				(end 421.452802 -274.049744)
			)
		)
		(stroke
			(width 0)
			(type solid)
		)
		(fill yes)
		(layer "In4.Cu")
		(net "P5E_PEX3_STN1_RX_DP<30>")
	)
	(gr_poly
		(pts
			(arc
				(start 421.452802 -273.099784)
				(mid 421.046402 -273.099784)
				(end 421.452802 -273.099784)
			)
		)
		(stroke
			(width 0)
			(type solid)
		)
		(fill yes)
		(layer "In4.Cu")
		(net "P5E_PEX3_STN1_RX_DN<30>")
	)
	(gr_poly
		(pts
			(arc
				(start 421.453056 -318.699896)
				(mid 421.046656 -318.699896)
				(end 421.453056 -318.699896)
			)
		)
		(stroke
			(width 0)
			(type solid)
		)
		(fill yes)
		(layer "In4.Cu")
		(net "P5E_PEX3_STN5_RX_DN<95>")
	)
	(gr_poly
		(pts
			(arc
				(start 421.453056 -317.749936)
				(mid 421.046656 -317.749936)
				(end 421.453056 -317.749936)
			)
		)
		(stroke
			(width 0)
			(type solid)
		)
		(fill yes)
		(layer "In4.Cu")
		(net "P5E_PEX3_STN5_RX_DP<95>")
	)
	(gr_poly
		(pts
			(arc
				(start 421.453056 -313.949842)
				(mid 421.046656 -313.949842)
				(end 421.453056 -313.949842)
			)
		)
		(stroke
			(width 0)
			(type solid)
		)
		(fill yes)
		(layer "In4.Cu")
		(net "P5E_PEX3_STN5_TX_DN<95>")
	)
	(gr_poly
		(pts
			(arc
				(start 421.453056 -312.999882)
				(mid 421.046656 -312.999882)
				(end 421.453056 -312.999882)
			)
		)
		(stroke
			(width 0)
			(type solid)
		)
		(fill yes)
		(layer "In4.Cu")
		(net "P5E_PEX3_STN5_TX_DP<95>")
	)
	(gr_poly
		(pts
			(arc
				(start 422.402762 -275.949918)
				(mid 421.996362 -275.949918)
				(end 422.402762 -275.949918)
			)
		)
		(stroke
			(width 0)
			(type solid)
		)
		(fill yes)
		(layer "In4.Cu")
		(net "P5E_PEX3_STN1_RX_DP<31>")
	)
	(gr_poly
		(pts
			(arc
				(start 422.402762 -274.999958)
				(mid 421.996362 -274.999958)
				(end 422.402762 -274.999958)
			)
		)
		(stroke
			(width 0)
			(type solid)
		)
		(fill yes)
		(layer "In4.Cu")
		(net "P5E_PEX3_STN1_RX_DN<31>")
	)
	(gr_poly
		(pts
			(arc
				(start 422.403016 -316.799722)
				(mid 421.996616 -316.799722)
				(end 422.403016 -316.799722)
			)
		)
		(stroke
			(width 0)
			(type solid)
		)
		(fill yes)
		(layer "In4.Cu")
		(net "P5E_PEX3_STN4_RX_DN<79>")
	)
	(gr_poly
		(pts
			(arc
				(start 422.403016 -315.849762)
				(mid 421.996616 -315.849762)
				(end 422.403016 -315.849762)
			)
		)
		(stroke
			(width 0)
			(type solid)
		)
		(fill yes)
		(layer "In4.Cu")
		(net "P5E_PEX3_STN4_RX_DP<79>")
	)
	(gr_poly
		(pts
			(arc
				(start 422.403016 -312.049922)
				(mid 421.996616 -312.049922)
				(end 422.403016 -312.049922)
			)
		)
		(stroke
			(width 0)
			(type solid)
		)
		(fill yes)
		(layer "In4.Cu")
		(net "P5E_PEX3_STN4_TX_DN<79>")
	)
	(gr_poly
		(pts
			(arc
				(start 422.403016 -311.099962)
				(mid 421.996616 -311.099962)
				(end 422.403016 -311.099962)
			)
		)
		(stroke
			(width 0)
			(type solid)
		)
		(fill yes)
		(layer "In4.Cu")
		(net "P5E_PEX3_STN4_TX_DP<79>")
	)
	(gr_poly
		(pts
			(arc
				(start 422.403016 -280.699464)
				(mid 421.996616 -280.699464)
				(end 422.403016 -280.699464)
			)
		)
		(stroke
			(width 0)
			(type solid)
		)
		(fill yes)
		(layer "In4.Cu")
		(net "P5E_PEX3_STN1_TX_DN<31>")
	)
	(gr_poly
		(pts
			(arc
				(start 422.403016 -279.749504)
				(mid 421.996616 -279.749504)
				(end 422.403016 -279.749504)
			)
		)
		(stroke
			(width 0)
			(type solid)
		)
		(fill yes)
		(layer "In4.Cu")
		(net "P5E_PEX3_STN1_TX_DP<31>")
	)
	(gr_poly
		(pts
			(arc
				(start 423.352976 -278.799798)
				(mid 422.946576 -278.799798)
				(end 423.352976 -278.799798)
			)
		)
		(stroke
			(width 0)
			(type solid)
		)
		(fill yes)
		(layer "In4.Cu")
		(net "P5E_PEX3_STN0_TX_DP<15>")
	)
	(gr_poly
		(pts
			(arc
				(start 423.352976 -277.849838)
				(mid 422.946576 -277.849838)
				(end 423.352976 -277.849838)
			)
		)
		(stroke
			(width 0)
			(type solid)
		)
		(fill yes)
		(layer "In4.Cu")
		(net "P5E_PEX3_STN0_TX_DN<15>")
	)
	(gr_poly
		(pts
			(arc
				(start 423.352976 -274.049744)
				(mid 422.946576 -274.049744)
				(end 423.352976 -274.049744)
			)
		)
		(stroke
			(width 0)
			(type solid)
		)
		(fill yes)
		(layer "In4.Cu")
		(net "P5E_PEX3_STN0_RX_DP<15>")
	)
	(gr_poly
		(pts
			(arc
				(start 423.352976 -273.099784)
				(mid 422.946576 -273.099784)
				(end 423.352976 -273.099784)
			)
		)
		(stroke
			(width 0)
			(type solid)
		)
		(fill yes)
		(layer "In4.Cu")
		(net "P5E_PEX3_STN0_RX_DN<15>")
	)
	(gr_poly
		(pts
			(arc
				(start 423.35323 -318.699896)
				(mid 422.94683 -318.699896)
				(end 423.35323 -318.699896)
			)
		)
		(stroke
			(width 0)
			(type solid)
		)
		(fill yes)
		(layer "In4.Cu")
		(net "P5E_PEX3_STN4_RX_DN<78>")
	)
	(gr_poly
		(pts
			(arc
				(start 423.35323 -317.749936)
				(mid 422.94683 -317.749936)
				(end 423.35323 -317.749936)
			)
		)
		(stroke
			(width 0)
			(type solid)
		)
		(fill yes)
		(layer "In4.Cu")
		(net "P5E_PEX3_STN4_RX_DP<78>")
	)
	(gr_poly
		(pts
			(arc
				(start 423.35323 -313.949842)
				(mid 422.94683 -313.949842)
				(end 423.35323 -313.949842)
			)
		)
		(stroke
			(width 0)
			(type solid)
		)
		(fill yes)
		(layer "In4.Cu")
		(net "P5E_PEX3_STN4_TX_DN<78>")
	)
	(gr_poly
		(pts
			(arc
				(start 423.35323 -312.999882)
				(mid 422.94683 -312.999882)
				(end 423.35323 -312.999882)
			)
		)
		(stroke
			(width 0)
			(type solid)
		)
		(fill yes)
		(layer "In4.Cu")
		(net "P5E_PEX3_STN4_TX_DP<78>")
	)
	(gr_poly
		(pts
			(arc
				(start 423.35323 -308.249828)
				(mid 422.94683 -308.249828)
				(end 423.35323 -308.249828)
			)
		)
		(stroke
			(width 0)
			(type solid)
		)
		(fill yes)
		(layer "In4.Cu")
		(net "P5E_PEX3_STN4_TX_DP<68>")
	)
	(gr_poly
		(pts
			(arc
				(start 423.35323 -306.349908)
				(mid 422.94683 -306.349908)
				(end 423.35323 -306.349908)
			)
		)
		(stroke
			(width 0)
			(type solid)
		)
		(fill yes)
		(layer "In4.Cu")
		(net "P5E_PEX3_STN4_TX_DP<66>")
	)
	(gr_poly
		(pts
			(arc
				(start 423.35323 -304.449734)
				(mid 422.94683 -304.449734)
				(end 423.35323 -304.449734)
			)
		)
		(stroke
			(width 0)
			(type solid)
		)
		(fill yes)
		(layer "In4.Cu")
		(net "P5E_PEX3_STN4_TX_DP<64>")
	)
	(gr_poly
		(pts
			(arc
				(start 423.35323 -287.349946)
				(mid 422.94683 -287.349946)
				(end 423.35323 -287.349946)
			)
		)
		(stroke
			(width 0)
			(type solid)
		)
		(fill yes)
		(layer "In4.Cu")
		(net "P5E_PEX3_STN0_TX_DP<1>")
	)
	(gr_poly
		(pts
			(arc
				(start 423.35323 -285.449772)
				(mid 422.94683 -285.449772)
				(end 423.35323 -285.449772)
			)
		)
		(stroke
			(width 0)
			(type solid)
		)
		(fill yes)
		(layer "In4.Cu")
		(net "P5E_PEX3_STN0_TX_DP<3>")
	)
	(gr_poly
		(pts
			(arc
				(start 423.35323 -283.549852)
				(mid 422.94683 -283.549852)
				(end 423.35323 -283.549852)
			)
		)
		(stroke
			(width 0)
			(type solid)
		)
		(fill yes)
		(layer "In4.Cu")
		(net "P5E_PEX3_STN0_TX_DP<5>")
	)
	(gr_poly
		(pts
			(arc
				(start 424.302936 -275.949664)
				(mid 423.896536 -275.949664)
				(end 424.302936 -275.949664)
			)
		)
		(stroke
			(width 0)
			(type solid)
		)
		(fill yes)
		(layer "In4.Cu")
		(net "P5E_PEX3_STN0_RX_DP<14>")
	)
	(gr_poly
		(pts
			(arc
				(start 424.302936 -274.999704)
				(mid 423.896536 -274.999704)
				(end 424.302936 -274.999704)
			)
		)
		(stroke
			(width 0)
			(type solid)
		)
		(fill yes)
		(layer "In4.Cu")
		(net "P5E_PEX3_STN0_RX_DN<14>")
	)
	(gr_poly
		(pts
			(arc
				(start 424.30319 -316.799722)
				(mid 423.89679 -316.799722)
				(end 424.30319 -316.799722)
			)
		)
		(stroke
			(width 0)
			(type solid)
		)
		(fill yes)
		(layer "In4.Cu")
		(net "P5E_PEX3_STN4_RX_DN<77>")
	)
	(gr_poly
		(pts
			(arc
				(start 424.30319 -315.849762)
				(mid 423.89679 -315.849762)
				(end 424.30319 -315.849762)
			)
		)
		(stroke
			(width 0)
			(type solid)
		)
		(fill yes)
		(layer "In4.Cu")
		(net "P5E_PEX3_STN4_RX_DP<77>")
	)
	(gr_poly
		(pts
			(arc
				(start 424.30319 -312.049922)
				(mid 423.89679 -312.049922)
				(end 424.30319 -312.049922)
			)
		)
		(stroke
			(width 0)
			(type solid)
		)
		(fill yes)
		(layer "In4.Cu")
		(net "P5E_PEX3_STN4_TX_DN<77>")
	)
	(gr_poly
		(pts
			(arc
				(start 424.30319 -311.099962)
				(mid 423.89679 -311.099962)
				(end 424.30319 -311.099962)
			)
		)
		(stroke
			(width 0)
			(type solid)
		)
		(fill yes)
		(layer "In4.Cu")
		(net "P5E_PEX3_STN4_TX_DP<77>")
	)
	(gr_poly
		(pts
			(arc
				(start 424.30319 -308.249828)
				(mid 423.89679 -308.249828)
				(end 424.30319 -308.249828)
			)
		)
		(stroke
			(width 0)
			(type solid)
		)
		(fill yes)
		(layer "In4.Cu")
		(net "P5E_PEX3_STN4_TX_DN<68>")
	)
	(gr_poly
		(pts
			(arc
				(start 424.30319 -306.349908)
				(mid 423.89679 -306.349908)
				(end 424.30319 -306.349908)
			)
		)
		(stroke
			(width 0)
			(type solid)
		)
		(fill yes)
		(layer "In4.Cu")
		(net "P5E_PEX3_STN4_TX_DN<66>")
	)
	(gr_poly
		(pts
			(arc
				(start 424.30319 -304.449734)
				(mid 423.89679 -304.449734)
				(end 424.30319 -304.449734)
			)
		)
		(stroke
			(width 0)
			(type solid)
		)
		(fill yes)
		(layer "In4.Cu")
		(net "P5E_PEX3_STN4_TX_DN<64>")
	)
	(gr_poly
		(pts
			(arc
				(start 424.30319 -287.349946)
				(mid 423.89679 -287.349946)
				(end 424.30319 -287.349946)
			)
		)
		(stroke
			(width 0)
			(type solid)
		)
		(fill yes)
		(layer "In4.Cu")
		(net "P5E_PEX3_STN0_TX_DN<1>")
	)
	(gr_poly
		(pts
			(arc
				(start 424.30319 -285.449772)
				(mid 423.89679 -285.449772)
				(end 424.30319 -285.449772)
			)
		)
		(stroke
			(width 0)
			(type solid)
		)
		(fill yes)
		(layer "In4.Cu")
		(net "P5E_PEX3_STN0_TX_DN<3>")
	)
	(gr_poly
		(pts
			(arc
				(start 424.30319 -283.549852)
				(mid 423.89679 -283.549852)
				(end 424.30319 -283.549852)
			)
		)
		(stroke
			(width 0)
			(type solid)
		)
		(fill yes)
		(layer "In4.Cu")
		(net "P5E_PEX3_STN0_TX_DN<5>")
	)
	(gr_poly
		(pts
			(arc
				(start 424.30319 -280.699464)
				(mid 423.89679 -280.699464)
				(end 424.30319 -280.699464)
			)
		)
		(stroke
			(width 0)
			(type solid)
		)
		(fill yes)
		(layer "In4.Cu")
		(net "P5E_PEX3_STN0_TX_DN<14>")
	)
	(gr_poly
		(pts
			(arc
				(start 424.30319 -279.749504)
				(mid 423.89679 -279.749504)
				(end 424.30319 -279.749504)
			)
		)
		(stroke
			(width 0)
			(type solid)
		)
		(fill yes)
		(layer "In4.Cu")
		(net "P5E_PEX3_STN0_TX_DP<14>")
	)
	(gr_poly
		(pts
			(arc
				(start 425.252896 -278.799798)
				(mid 424.846496 -278.799798)
				(end 425.252896 -278.799798)
			)
		)
		(stroke
			(width 0)
			(type solid)
		)
		(fill yes)
		(layer "In4.Cu")
		(net "P5E_PEX3_STN0_TX_DP<13>")
	)
	(gr_poly
		(pts
			(arc
				(start 425.252896 -277.849838)
				(mid 424.846496 -277.849838)
				(end 425.252896 -277.849838)
			)
		)
		(stroke
			(width 0)
			(type solid)
		)
		(fill yes)
		(layer "In4.Cu")
		(net "P5E_PEX3_STN0_TX_DN<13>")
	)
	(gr_poly
		(pts
			(arc
				(start 425.252896 -274.049744)
				(mid 424.846496 -274.049744)
				(end 425.252896 -274.049744)
			)
		)
		(stroke
			(width 0)
			(type solid)
		)
		(fill yes)
		(layer "In4.Cu")
		(net "P5E_PEX3_STN0_RX_DP<13>")
	)
	(gr_poly
		(pts
			(arc
				(start 425.252896 -273.099784)
				(mid 424.846496 -273.099784)
				(end 425.252896 -273.099784)
			)
		)
		(stroke
			(width 0)
			(type solid)
		)
		(fill yes)
		(layer "In4.Cu")
		(net "P5E_PEX3_STN0_RX_DN<13>")
	)
	(gr_poly
		(pts
			(arc
				(start 425.25315 -318.699896)
				(mid 424.84675 -318.699896)
				(end 425.25315 -318.699896)
			)
		)
		(stroke
			(width 0)
			(type solid)
		)
		(fill yes)
		(layer "In4.Cu")
		(net "P5E_PEX3_STN4_RX_DN<76>")
	)
	(gr_poly
		(pts
			(arc
				(start 425.25315 -317.749936)
				(mid 424.84675 -317.749936)
				(end 425.25315 -317.749936)
			)
		)
		(stroke
			(width 0)
			(type solid)
		)
		(fill yes)
		(layer "In4.Cu")
		(net "P5E_PEX3_STN4_RX_DP<76>")
	)
	(gr_poly
		(pts
			(arc
				(start 425.25315 -313.949842)
				(mid 424.84675 -313.949842)
				(end 425.25315 -313.949842)
			)
		)
		(stroke
			(width 0)
			(type solid)
		)
		(fill yes)
		(layer "In4.Cu")
		(net "P5E_PEX3_STN4_TX_DN<76>")
	)
	(gr_poly
		(pts
			(arc
				(start 425.25315 -312.999882)
				(mid 424.84675 -312.999882)
				(end 425.25315 -312.999882)
			)
		)
		(stroke
			(width 0)
			(type solid)
		)
		(fill yes)
		(layer "In4.Cu")
		(net "P5E_PEX3_STN4_TX_DP<76>")
	)
	(gr_poly
		(pts
			(arc
				(start 425.25315 -309.199788)
				(mid 424.84675 -309.199788)
				(end 425.25315 -309.199788)
			)
		)
		(stroke
			(width 0)
			(type solid)
		)
		(fill yes)
		(layer "In4.Cu")
		(net "P5E_PEX3_STN4_TX_DP<69>")
	)
	(gr_poly
		(pts
			(arc
				(start 425.25315 -307.299868)
				(mid 424.84675 -307.299868)
				(end 425.25315 -307.299868)
			)
		)
		(stroke
			(width 0)
			(type solid)
		)
		(fill yes)
		(layer "In4.Cu")
		(net "P5E_PEX3_STN4_TX_DP<67>")
	)
	(gr_poly
		(pts
			(arc
				(start 425.25315 -305.399948)
				(mid 424.84675 -305.399948)
				(end 425.25315 -305.399948)
			)
		)
		(stroke
			(width 0)
			(type solid)
		)
		(fill yes)
		(layer "In4.Cu")
		(net "P5E_PEX3_STN4_TX_DP<65>")
	)
	(gr_poly
		(pts
			(arc
				(start 425.25315 -288.299906)
				(mid 424.84675 -288.299906)
				(end 425.25315 -288.299906)
			)
		)
		(stroke
			(width 0)
			(type solid)
		)
		(fill yes)
		(layer "In4.Cu")
		(net "P5E_PEX3_STN0_TX_DP<0>")
	)
	(gr_poly
		(pts
			(arc
				(start 425.25315 -286.399986)
				(mid 424.84675 -286.399986)
				(end 425.25315 -286.399986)
			)
		)
		(stroke
			(width 0)
			(type solid)
		)
		(fill yes)
		(layer "In4.Cu")
		(net "P5E_PEX3_STN0_TX_DP<2>")
	)
	(gr_poly
		(pts
			(arc
				(start 425.25315 -284.499812)
				(mid 424.84675 -284.499812)
				(end 425.25315 -284.499812)
			)
		)
		(stroke
			(width 0)
			(type solid)
		)
		(fill yes)
		(layer "In4.Cu")
		(net "P5E_PEX3_STN0_TX_DP<4>")
	)
	(gr_poly
		(pts
			(arc
				(start 425.25315 -282.599892)
				(mid 424.84675 -282.599892)
				(end 425.25315 -282.599892)
			)
		)
		(stroke
			(width 0)
			(type solid)
		)
		(fill yes)
		(layer "In4.Cu")
		(net "P5E_PEX3_STN0_TX_DP<6>")
	)
	(gr_poly
		(pts
			(arc
				(start 426.202856 -275.949918)
				(mid 425.796456 -275.949918)
				(end 426.202856 -275.949918)
			)
		)
		(stroke
			(width 0)
			(type solid)
		)
		(fill yes)
		(layer "In4.Cu")
		(net "P5E_PEX3_STN0_RX_DP<12>")
	)
	(gr_poly
		(pts
			(arc
				(start 426.202856 -274.999958)
				(mid 425.796456 -274.999958)
				(end 426.202856 -274.999958)
			)
		)
		(stroke
			(width 0)
			(type solid)
		)
		(fill yes)
		(layer "In4.Cu")
		(net "P5E_PEX3_STN0_RX_DN<12>")
	)
	(gr_poly
		(pts
			(arc
				(start 426.20311 -316.799722)
				(mid 425.79671 -316.799722)
				(end 426.20311 -316.799722)
			)
		)
		(stroke
			(width 0)
			(type solid)
		)
		(fill yes)
		(layer "In4.Cu")
		(net "P5E_PEX3_STN4_RX_DN<75>")
	)
	(gr_poly
		(pts
			(arc
				(start 426.20311 -315.849762)
				(mid 425.79671 -315.849762)
				(end 426.20311 -315.849762)
			)
		)
		(stroke
			(width 0)
			(type solid)
		)
		(fill yes)
		(layer "In4.Cu")
		(net "P5E_PEX3_STN4_RX_DP<75>")
	)
	(gr_poly
		(pts
			(arc
				(start 426.20311 -312.049922)
				(mid 425.79671 -312.049922)
				(end 426.20311 -312.049922)
			)
		)
		(stroke
			(width 0)
			(type solid)
		)
		(fill yes)
		(layer "In4.Cu")
		(net "P5E_PEX3_STN4_TX_DN<75>")
	)
	(gr_poly
		(pts
			(arc
				(start 426.20311 -311.099962)
				(mid 425.79671 -311.099962)
				(end 426.20311 -311.099962)
			)
		)
		(stroke
			(width 0)
			(type solid)
		)
		(fill yes)
		(layer "In4.Cu")
		(net "P5E_PEX3_STN4_TX_DP<75>")
	)
	(gr_poly
		(pts
			(arc
				(start 426.20311 -309.199788)
				(mid 425.79671 -309.199788)
				(end 426.20311 -309.199788)
			)
		)
		(stroke
			(width 0)
			(type solid)
		)
		(fill yes)
		(layer "In4.Cu")
		(net "P5E_PEX3_STN4_TX_DN<69>")
	)
	(gr_poly
		(pts
			(arc
				(start 426.20311 -307.299868)
				(mid 425.79671 -307.299868)
				(end 426.20311 -307.299868)
			)
		)
		(stroke
			(width 0)
			(type solid)
		)
		(fill yes)
		(layer "In4.Cu")
		(net "P5E_PEX3_STN4_TX_DN<67>")
	)
	(gr_poly
		(pts
			(arc
				(start 426.20311 -305.399948)
				(mid 425.79671 -305.399948)
				(end 426.20311 -305.399948)
			)
		)
		(stroke
			(width 0)
			(type solid)
		)
		(fill yes)
		(layer "In4.Cu")
		(net "P5E_PEX3_STN4_TX_DN<65>")
	)
	(gr_poly
		(pts
			(arc
				(start 426.20311 -288.299906)
				(mid 425.79671 -288.299906)
				(end 426.20311 -288.299906)
			)
		)
		(stroke
			(width 0)
			(type solid)
		)
		(fill yes)
		(layer "In4.Cu")
		(net "P5E_PEX3_STN0_TX_DN<0>")
	)
	(gr_poly
		(pts
			(arc
				(start 426.20311 -286.399986)
				(mid 425.79671 -286.399986)
				(end 426.20311 -286.399986)
			)
		)
		(stroke
			(width 0)
			(type solid)
		)
		(fill yes)
		(layer "In4.Cu")
		(net "P5E_PEX3_STN0_TX_DN<2>")
	)
	(gr_poly
		(pts
			(arc
				(start 426.20311 -284.499812)
				(mid 425.79671 -284.499812)
				(end 426.20311 -284.499812)
			)
		)
		(stroke
			(width 0)
			(type solid)
		)
		(fill yes)
		(layer "In4.Cu")
		(net "P5E_PEX3_STN0_TX_DN<4>")
	)
	(gr_poly
		(pts
			(arc
				(start 426.20311 -282.599892)
				(mid 425.79671 -282.599892)
				(end 426.20311 -282.599892)
			)
		)
		(stroke
			(width 0)
			(type solid)
		)
		(fill yes)
		(layer "In4.Cu")
		(net "P5E_PEX3_STN0_TX_DN<6>")
	)
	(gr_poly
		(pts
			(arc
				(start 426.20311 -280.699464)
				(mid 425.79671 -280.699464)
				(end 426.20311 -280.699464)
			)
		)
		(stroke
			(width 0)
			(type solid)
		)
		(fill yes)
		(layer "In4.Cu")
		(net "P5E_PEX3_STN0_TX_DN<12>")
	)
	(gr_poly
		(pts
			(arc
				(start 426.20311 -279.749504)
				(mid 425.79671 -279.749504)
				(end 426.20311 -279.749504)
			)
		)
		(stroke
			(width 0)
			(type solid)
		)
		(fill yes)
		(layer "In4.Cu")
		(net "P5E_PEX3_STN0_TX_DP<12>")
	)
	(gr_poly
		(pts
			(arc
				(start 427.152816 -278.799798)
				(mid 426.746416 -278.799798)
				(end 427.152816 -278.799798)
			)
		)
		(stroke
			(width 0)
			(type solid)
		)
		(fill yes)
		(layer "In4.Cu")
		(net "P5E_PEX3_STN0_TX_DP<11>")
	)
	(gr_poly
		(pts
			(arc
				(start 427.152816 -277.849838)
				(mid 426.746416 -277.849838)
				(end 427.152816 -277.849838)
			)
		)
		(stroke
			(width 0)
			(type solid)
		)
		(fill yes)
		(layer "In4.Cu")
		(net "P5E_PEX3_STN0_TX_DN<11>")
	)
	(gr_poly
		(pts
			(arc
				(start 427.152816 -274.049744)
				(mid 426.746416 -274.049744)
				(end 427.152816 -274.049744)
			)
		)
		(stroke
			(width 0)
			(type solid)
		)
		(fill yes)
		(layer "In4.Cu")
		(net "P5E_PEX3_STN0_RX_DP<11>")
	)
	(gr_poly
		(pts
			(arc
				(start 427.152816 -273.099784)
				(mid 426.746416 -273.099784)
				(end 427.152816 -273.099784)
			)
		)
		(stroke
			(width 0)
			(type solid)
		)
		(fill yes)
		(layer "In4.Cu")
		(net "P5E_PEX3_STN0_RX_DN<11>")
	)
	(gr_poly
		(pts
			(arc
				(start 427.15307 -318.699896)
				(mid 426.74667 -318.699896)
				(end 427.15307 -318.699896)
			)
		)
		(stroke
			(width 0)
			(type solid)
		)
		(fill yes)
		(layer "In4.Cu")
		(net "P5E_PEX3_STN4_RX_DN<74>")
	)
	(gr_poly
		(pts
			(arc
				(start 427.15307 -317.749936)
				(mid 426.74667 -317.749936)
				(end 427.15307 -317.749936)
			)
		)
		(stroke
			(width 0)
			(type solid)
		)
		(fill yes)
		(layer "In4.Cu")
		(net "P5E_PEX3_STN4_RX_DP<74>")
	)
	(gr_poly
		(pts
			(arc
				(start 427.15307 -313.949842)
				(mid 426.74667 -313.949842)
				(end 427.15307 -313.949842)
			)
		)
		(stroke
			(width 0)
			(type solid)
		)
		(fill yes)
		(layer "In4.Cu")
		(net "P5E_PEX3_STN4_TX_DN<74>")
	)
	(gr_poly
		(pts
			(arc
				(start 427.15307 -312.999882)
				(mid 426.74667 -312.999882)
				(end 427.15307 -312.999882)
			)
		)
		(stroke
			(width 0)
			(type solid)
		)
		(fill yes)
		(layer "In4.Cu")
		(net "P5E_PEX3_STN4_TX_DP<74>")
	)
	(gr_poly
		(pts
			(arc
				(start 428.102776 -275.949918)
				(mid 427.696376 -275.949918)
				(end 428.102776 -275.949918)
			)
		)
		(stroke
			(width 0)
			(type solid)
		)
		(fill yes)
		(layer "In4.Cu")
		(net "P5E_PEX3_STN0_RX_DP<10>")
	)
	(gr_poly
		(pts
			(arc
				(start 428.102776 -274.999958)
				(mid 427.696376 -274.999958)
				(end 428.102776 -274.999958)
			)
		)
		(stroke
			(width 0)
			(type solid)
		)
		(fill yes)
		(layer "In4.Cu")
		(net "P5E_PEX3_STN0_RX_DN<10>")
	)
	(gr_poly
		(pts
			(arc
				(start 428.10303 -316.799722)
				(mid 427.69663 -316.799722)
				(end 428.10303 -316.799722)
			)
		)
		(stroke
			(width 0)
			(type solid)
		)
		(fill yes)
		(layer "In4.Cu")
		(net "P5E_PEX3_STN4_RX_DN<73>")
	)
	(gr_poly
		(pts
			(arc
				(start 428.10303 -315.849762)
				(mid 427.69663 -315.849762)
				(end 428.10303 -315.849762)
			)
		)
		(stroke
			(width 0)
			(type solid)
		)
		(fill yes)
		(layer "In4.Cu")
		(net "P5E_PEX3_STN4_RX_DP<73>")
	)
	(gr_poly
		(pts
			(arc
				(start 428.10303 -312.049922)
				(mid 427.69663 -312.049922)
				(end 428.10303 -312.049922)
			)
		)
		(stroke
			(width 0)
			(type solid)
		)
		(fill yes)
		(layer "In4.Cu")
		(net "P5E_PEX3_STN4_TX_DN<73>")
	)
	(gr_poly
		(pts
			(arc
				(start 428.10303 -311.099962)
				(mid 427.69663 -311.099962)
				(end 428.10303 -311.099962)
			)
		)
		(stroke
			(width 0)
			(type solid)
		)
		(fill yes)
		(layer "In4.Cu")
		(net "P5E_PEX3_STN4_TX_DP<73>")
	)
	(gr_poly
		(pts
			(arc
				(start 428.10303 -309.199788)
				(mid 427.69663 -309.199788)
				(end 428.10303 -309.199788)
			)
		)
		(stroke
			(width 0)
			(type solid)
		)
		(fill yes)
		(layer "In4.Cu")
		(net "P5E_PEX3_STN4_RX_DP<69>")
	)
	(gr_poly
		(pts
			(arc
				(start 428.10303 -307.299868)
				(mid 427.69663 -307.299868)
				(end 428.10303 -307.299868)
			)
		)
		(stroke
			(width 0)
			(type solid)
		)
		(fill yes)
		(layer "In4.Cu")
		(net "P5E_PEX3_STN4_RX_DP<67>")
	)
	(gr_poly
		(pts
			(arc
				(start 428.10303 -305.399948)
				(mid 427.69663 -305.399948)
				(end 428.10303 -305.399948)
			)
		)
		(stroke
			(width 0)
			(type solid)
		)
		(fill yes)
		(layer "In4.Cu")
		(net "P5E_PEX3_STN4_RX_DP<65>")
	)
	(gr_poly
		(pts
			(arc
				(start 428.10303 -288.299906)
				(mid 427.69663 -288.299906)
				(end 428.10303 -288.299906)
			)
		)
		(stroke
			(width 0)
			(type solid)
		)
		(fill yes)
		(layer "In4.Cu")
		(net "P5E_PEX3_STN0_RX_DP<0>")
	)
	(gr_poly
		(pts
			(arc
				(start 428.10303 -286.399732)
				(mid 427.69663 -286.399732)
				(end 428.10303 -286.399732)
			)
		)
		(stroke
			(width 0)
			(type solid)
		)
		(fill yes)
		(layer "In4.Cu")
		(net "P5E_PEX3_STN0_RX_DP<2>")
	)
	(gr_poly
		(pts
			(arc
				(start 428.10303 -284.499812)
				(mid 427.69663 -284.499812)
				(end 428.10303 -284.499812)
			)
		)
		(stroke
			(width 0)
			(type solid)
		)
		(fill yes)
		(layer "In4.Cu")
		(net "P5E_PEX3_STN0_RX_DP<4>")
	)
	(gr_poly
		(pts
			(arc
				(start 428.10303 -282.599892)
				(mid 427.69663 -282.599892)
				(end 428.10303 -282.599892)
			)
		)
		(stroke
			(width 0)
			(type solid)
		)
		(fill yes)
		(layer "In4.Cu")
		(net "P5E_PEX3_STN0_RX_DP<6>")
	)
	(gr_poly
		(pts
			(arc
				(start 428.10303 -280.699718)
				(mid 427.69663 -280.699718)
				(end 428.10303 -280.699718)
			)
		)
		(stroke
			(width 0)
			(type solid)
		)
		(fill yes)
		(layer "In4.Cu")
		(net "P5E_PEX3_STN0_TX_DP<10>")
	)
	(gr_poly
		(pts
			(arc
				(start 428.10303 -279.749758)
				(mid 427.69663 -279.749758)
				(end 428.10303 -279.749758)
			)
		)
		(stroke
			(width 0)
			(type solid)
		)
		(fill yes)
		(layer "In4.Cu")
		(net "P5E_PEX3_STN0_TX_DN<10>")
	)
	(gr_poly
		(pts
			(arc
				(start 429.052736 -274.049744)
				(mid 428.646336 -274.049744)
				(end 429.052736 -274.049744)
			)
		)
		(stroke
			(width 0)
			(type solid)
		)
		(fill yes)
		(layer "In4.Cu")
		(net "P5E_PEX3_STN0_RX_DP<9>")
	)
	(gr_poly
		(pts
			(arc
				(start 429.052736 -273.099784)
				(mid 428.646336 -273.099784)
				(end 429.052736 -273.099784)
			)
		)
		(stroke
			(width 0)
			(type solid)
		)
		(fill yes)
		(layer "In4.Cu")
		(net "P5E_PEX3_STN0_RX_DN<9>")
	)
	(gr_poly
		(pts
			(arc
				(start 429.05299 -318.699896)
				(mid 428.64659 -318.699896)
				(end 429.05299 -318.699896)
			)
		)
		(stroke
			(width 0)
			(type solid)
		)
		(fill yes)
		(layer "In4.Cu")
		(net "P5E_PEX3_STN4_RX_DN<72>")
	)
	(gr_poly
		(pts
			(arc
				(start 429.05299 -317.749936)
				(mid 428.64659 -317.749936)
				(end 429.05299 -317.749936)
			)
		)
		(stroke
			(width 0)
			(type solid)
		)
		(fill yes)
		(layer "In4.Cu")
		(net "P5E_PEX3_STN4_RX_DP<72>")
	)
	(gr_poly
		(pts
			(arc
				(start 429.05299 -313.949842)
				(mid 428.64659 -313.949842)
				(end 429.05299 -313.949842)
			)
		)
		(stroke
			(width 0)
			(type solid)
		)
		(fill yes)
		(layer "In4.Cu")
		(net "P5E_PEX3_STN4_TX_DN<72>")
	)
	(gr_poly
		(pts
			(arc
				(start 429.05299 -312.999882)
				(mid 428.64659 -312.999882)
				(end 429.05299 -312.999882)
			)
		)
		(stroke
			(width 0)
			(type solid)
		)
		(fill yes)
		(layer "In4.Cu")
		(net "P5E_PEX3_STN4_TX_DP<72>")
	)
	(gr_poly
		(pts
			(arc
				(start 429.05299 -309.199788)
				(mid 428.64659 -309.199788)
				(end 429.05299 -309.199788)
			)
		)
		(stroke
			(width 0)
			(type solid)
		)
		(fill yes)
		(layer "In4.Cu")
		(net "P5E_PEX3_STN4_RX_DN<69>")
	)
	(gr_poly
		(pts
			(arc
				(start 429.05299 -307.299868)
				(mid 428.64659 -307.299868)
				(end 429.05299 -307.299868)
			)
		)
		(stroke
			(width 0)
			(type solid)
		)
		(fill yes)
		(layer "In4.Cu")
		(net "P5E_PEX3_STN4_RX_DN<67>")
	)
	(gr_poly
		(pts
			(arc
				(start 429.05299 -305.399948)
				(mid 428.64659 -305.399948)
				(end 429.05299 -305.399948)
			)
		)
		(stroke
			(width 0)
			(type solid)
		)
		(fill yes)
		(layer "In4.Cu")
		(net "P5E_PEX3_STN4_RX_DN<65>")
	)
	(gr_poly
		(pts
			(arc
				(start 429.05299 -288.299906)
				(mid 428.64659 -288.299906)
				(end 429.05299 -288.299906)
			)
		)
		(stroke
			(width 0)
			(type solid)
		)
		(fill yes)
		(layer "In4.Cu")
		(net "P5E_PEX3_STN0_RX_DN<0>")
	)
	(gr_poly
		(pts
			(arc
				(start 429.05299 -286.399732)
				(mid 428.64659 -286.399732)
				(end 429.05299 -286.399732)
			)
		)
		(stroke
			(width 0)
			(type solid)
		)
		(fill yes)
		(layer "In4.Cu")
		(net "P5E_PEX3_STN0_RX_DN<2>")
	)
	(gr_poly
		(pts
			(arc
				(start 429.05299 -284.499812)
				(mid 428.64659 -284.499812)
				(end 429.05299 -284.499812)
			)
		)
		(stroke
			(width 0)
			(type solid)
		)
		(fill yes)
		(layer "In4.Cu")
		(net "P5E_PEX3_STN0_RX_DN<4>")
	)
	(gr_poly
		(pts
			(arc
				(start 429.05299 -282.599892)
				(mid 428.64659 -282.599892)
				(end 429.05299 -282.599892)
			)
		)
		(stroke
			(width 0)
			(type solid)
		)
		(fill yes)
		(layer "In4.Cu")
		(net "P5E_PEX3_STN0_RX_DN<6>")
	)
	(gr_poly
		(pts
			(arc
				(start 429.05299 -278.799798)
				(mid 428.64659 -278.799798)
				(end 429.05299 -278.799798)
			)
		)
		(stroke
			(width 0)
			(type solid)
		)
		(fill yes)
		(layer "In4.Cu")
		(net "P5E_PEX3_STN0_TX_DP<9>")
	)
	(gr_poly
		(pts
			(arc
				(start 429.05299 -277.849838)
				(mid 428.64659 -277.849838)
				(end 429.05299 -277.849838)
			)
		)
		(stroke
			(width 0)
			(type solid)
		)
		(fill yes)
		(layer "In4.Cu")
		(net "P5E_PEX3_STN0_TX_DN<9>")
	)
	(gr_poly
		(pts
			(arc
				(start 430.003204 -316.799722)
				(mid 429.596804 -316.799722)
				(end 430.003204 -316.799722)
			)
		)
		(stroke
			(width 0)
			(type solid)
		)
		(fill yes)
		(layer "In4.Cu")
		(net "P5E_PEX3_STN4_RX_DP<71>")
	)
	(gr_poly
		(pts
			(arc
				(start 430.003204 -314.899802)
				(mid 429.596804 -314.899802)
				(end 430.003204 -314.899802)
			)
		)
		(stroke
			(width 0)
			(type solid)
		)
		(fill yes)
		(layer "In4.Cu")
		(net "P5E_PEX3_STN4_TX_DP<71>")
	)
	(gr_poly
		(pts
			(arc
				(start 430.003204 -312.049922)
				(mid 429.596804 -312.049922)
				(end 430.003204 -312.049922)
			)
		)
		(stroke
			(width 0)
			(type solid)
		)
		(fill yes)
		(layer "In4.Cu")
		(net "P5E_PEX3_STN4_TX_DP<70>")
	)
	(gr_poly
		(pts
			(arc
				(start 430.003204 -310.149748)
				(mid 429.596804 -310.149748)
				(end 430.003204 -310.149748)
			)
		)
		(stroke
			(width 0)
			(type solid)
		)
		(fill yes)
		(layer "In4.Cu")
		(net "P5E_PEX3_STN4_RX_DP<70>")
	)
	(gr_poly
		(pts
			(arc
				(start 430.003204 -308.249828)
				(mid 429.596804 -308.249828)
				(end 430.003204 -308.249828)
			)
		)
		(stroke
			(width 0)
			(type solid)
		)
		(fill yes)
		(layer "In4.Cu")
		(net "P5E_PEX3_STN4_RX_DP<68>")
	)
	(gr_poly
		(pts
			(arc
				(start 430.003204 -306.349908)
				(mid 429.596804 -306.349908)
				(end 430.003204 -306.349908)
			)
		)
		(stroke
			(width 0)
			(type solid)
		)
		(fill yes)
		(layer "In4.Cu")
		(net "P5E_PEX3_STN4_RX_DP<66>")
	)
	(gr_poly
		(pts
			(arc
				(start 430.003204 -304.449734)
				(mid 429.596804 -304.449734)
				(end 430.003204 -304.449734)
			)
		)
		(stroke
			(width 0)
			(type solid)
		)
		(fill yes)
		(layer "In4.Cu")
		(net "P5E_PEX3_STN4_RX_DP<64>")
	)
	(gr_poly
		(pts
			(arc
				(start 430.003204 -287.349946)
				(mid 429.596804 -287.349946)
				(end 430.003204 -287.349946)
			)
		)
		(stroke
			(width 0)
			(type solid)
		)
		(fill yes)
		(layer "In4.Cu")
		(net "P5E_PEX3_STN0_RX_DP<1>")
	)
	(gr_poly
		(pts
			(arc
				(start 430.003204 -285.449772)
				(mid 429.596804 -285.449772)
				(end 430.003204 -285.449772)
			)
		)
		(stroke
			(width 0)
			(type solid)
		)
		(fill yes)
		(layer "In4.Cu")
		(net "P5E_PEX3_STN0_RX_DP<3>")
	)
	(gr_poly
		(pts
			(arc
				(start 430.003204 -283.549852)
				(mid 429.596804 -283.549852)
				(end 430.003204 -283.549852)
			)
		)
		(stroke
			(width 0)
			(type solid)
		)
		(fill yes)
		(layer "In4.Cu")
		(net "P5E_PEX3_STN0_RX_DP<5>")
	)
	(gr_poly
		(pts
			(arc
				(start 430.003204 -281.649932)
				(mid 429.596804 -281.649932)
				(end 430.003204 -281.649932)
			)
		)
		(stroke
			(width 0)
			(type solid)
		)
		(fill yes)
		(layer "In4.Cu")
		(net "P5E_PEX3_STN0_RX_DP<7>")
	)
	(gr_poly
		(pts
			(arc
				(start 430.003204 -279.749758)
				(mid 429.596804 -279.749758)
				(end 430.003204 -279.749758)
			)
		)
		(stroke
			(width 0)
			(type solid)
		)
		(fill yes)
		(layer "In4.Cu")
		(net "P5E_PEX3_STN0_TX_DP<7>")
	)
	(gr_poly
		(pts
			(arc
				(start 430.003204 -276.899878)
				(mid 429.596804 -276.899878)
				(end 430.003204 -276.899878)
			)
		)
		(stroke
			(width 0)
			(type solid)
		)
		(fill yes)
		(layer "In4.Cu")
		(net "P5E_PEX3_STN0_TX_DP<8>")
	)
	(gr_poly
		(pts
			(arc
				(start 430.003204 -274.999704)
				(mid 429.596804 -274.999704)
				(end 430.003204 -274.999704)
			)
		)
		(stroke
			(width 0)
			(type solid)
		)
		(fill yes)
		(layer "In4.Cu")
		(net "P5E_PEX3_STN0_RX_DP<8>")
	)
	(gr_poly
		(pts
			(arc
				(start 430.953164 -316.799722)
				(mid 430.546764 -316.799722)
				(end 430.953164 -316.799722)
			)
		)
		(stroke
			(width 0)
			(type solid)
		)
		(fill yes)
		(layer "In4.Cu")
		(net "P5E_PEX3_STN4_RX_DN<71>")
	)
	(gr_poly
		(pts
			(arc
				(start 430.953164 -314.899802)
				(mid 430.546764 -314.899802)
				(end 430.953164 -314.899802)
			)
		)
		(stroke
			(width 0)
			(type solid)
		)
		(fill yes)
		(layer "In4.Cu")
		(net "P5E_PEX3_STN4_TX_DN<71>")
	)
	(gr_poly
		(pts
			(arc
				(start 430.953164 -312.049922)
				(mid 430.546764 -312.049922)
				(end 430.953164 -312.049922)
			)
		)
		(stroke
			(width 0)
			(type solid)
		)
		(fill yes)
		(layer "In4.Cu")
		(net "P5E_PEX3_STN4_TX_DN<70>")
	)
	(gr_poly
		(pts
			(arc
				(start 430.953164 -310.149748)
				(mid 430.546764 -310.149748)
				(end 430.953164 -310.149748)
			)
		)
		(stroke
			(width 0)
			(type solid)
		)
		(fill yes)
		(layer "In4.Cu")
		(net "P5E_PEX3_STN4_RX_DN<70>")
	)
	(gr_poly
		(pts
			(arc
				(start 430.953164 -308.249828)
				(mid 430.546764 -308.249828)
				(end 430.953164 -308.249828)
			)
		)
		(stroke
			(width 0)
			(type solid)
		)
		(fill yes)
		(layer "In4.Cu")
		(net "P5E_PEX3_STN4_RX_DN<68>")
	)
	(gr_poly
		(pts
			(arc
				(start 430.953164 -306.349908)
				(mid 430.546764 -306.349908)
				(end 430.953164 -306.349908)
			)
		)
		(stroke
			(width 0)
			(type solid)
		)
		(fill yes)
		(layer "In4.Cu")
		(net "P5E_PEX3_STN4_RX_DN<66>")
	)
	(gr_poly
		(pts
			(arc
				(start 430.953164 -304.449734)
				(mid 430.546764 -304.449734)
				(end 430.953164 -304.449734)
			)
		)
		(stroke
			(width 0)
			(type solid)
		)
		(fill yes)
		(layer "In4.Cu")
		(net "P5E_PEX3_STN4_RX_DN<64>")
	)
	(gr_poly
		(pts
			(arc
				(start 430.953164 -287.349946)
				(mid 430.546764 -287.349946)
				(end 430.953164 -287.349946)
			)
		)
		(stroke
			(width 0)
			(type solid)
		)
		(fill yes)
		(layer "In4.Cu")
		(net "P5E_PEX3_STN0_RX_DN<1>")
	)
	(gr_poly
		(pts
			(arc
				(start 430.953164 -285.449772)
				(mid 430.546764 -285.449772)
				(end 430.953164 -285.449772)
			)
		)
		(stroke
			(width 0)
			(type solid)
		)
		(fill yes)
		(layer "In4.Cu")
		(net "P5E_PEX3_STN0_RX_DN<3>")
	)
	(gr_poly
		(pts
			(arc
				(start 430.953164 -283.549852)
				(mid 430.546764 -283.549852)
				(end 430.953164 -283.549852)
			)
		)
		(stroke
			(width 0)
			(type solid)
		)
		(fill yes)
		(layer "In4.Cu")
		(net "P5E_PEX3_STN0_RX_DN<5>")
	)
	(gr_poly
		(pts
			(arc
				(start 430.953164 -281.649932)
				(mid 430.546764 -281.649932)
				(end 430.953164 -281.649932)
			)
		)
		(stroke
			(width 0)
			(type solid)
		)
		(fill yes)
		(layer "In4.Cu")
		(net "P5E_PEX3_STN0_RX_DN<7>")
	)
	(gr_poly
		(pts
			(arc
				(start 430.953164 -279.749758)
				(mid 430.546764 -279.749758)
				(end 430.953164 -279.749758)
			)
		)
		(stroke
			(width 0)
			(type solid)
		)
		(fill yes)
		(layer "In4.Cu")
		(net "P5E_PEX3_STN0_TX_DN<7>")
	)
	(gr_poly
		(pts
			(arc
				(start 430.953164 -276.899878)
				(mid 430.546764 -276.899878)
				(end 430.953164 -276.899878)
			)
		)
		(stroke
			(width 0)
			(type solid)
		)
		(fill yes)
		(layer "In4.Cu")
		(net "P5E_PEX3_STN0_TX_DN<8>")
	)
	(gr_poly
		(pts
			(arc
				(start 430.953164 -274.999704)
				(mid 430.546764 -274.999704)
				(end 430.953164 -274.999704)
			)
		)
		(stroke
			(width 0)
			(type solid)
		)
		(fill yes)
		(layer "In4.Cu")
		(net "P5E_PEX3_STN0_RX_DN<8>")
	)
	(gr_poly
		(pts
			(arc
				(start 241.741198 -376.399806)
				(mid 241.763367 -376.39459)
				(end 241.781076 -376.380248)
			)
			(arc
				(start 241.781076 -376.380248)
				(mid 241.793461 -376.365378)
				(end 241.80673 -376.351292)
			)
			(xy 242.08994 -376.068082)
			(arc
				(start 242.09502 -376.063002)
				(mid 242.106647 -376.046325)
				(end 242.110768 -376.026426)
			)
			(arc
				(start 242.110768 -368.666268)
				(mid 242.106867 -368.646745)
				(end 242.095782 -368.6302)
			)
			(arc
				(start 241.977672 -368.51209)
				(mid 241.961138 -368.500979)
				(end 241.941604 -368.497104)
			)
			(arc
				(start 236.370368 -368.497104)
				(mid 236.350845 -368.501005)
				(end 236.3343 -368.51209)
			)
			(arc
				(start 236.123734 -368.722656)
				(mid 236.112623 -368.73919)
				(end 236.108748 -368.758724)
			)
			(arc
				(start 236.108748 -376.146314)
				(mid 236.112649 -376.165837)
				(end 236.123734 -376.182382)
			)
			(arc
				(start 236.326172 -376.38482)
				(mid 236.342706 -376.395931)
				(end 236.36224 -376.399806)
			)
		)
		(stroke
			(width 0)
			(type solid)
		)
		(fill yes)
		(layer "In4.Cu")
		(net "P12V_STBY_R1")
	)
	(gr_poly
		(pts
			(arc
				(start 235.60151 -413.087058)
				(mid 235.621033 -413.083157)
				(end 235.637578 -413.072072)
			)
			(arc
				(start 236.756956 -411.952694)
				(mid 236.768067 -411.93616)
				(end 236.771942 -411.916626)
			)
			(arc
				(start 236.771942 -402.84527)
				(mid 236.796095 -402.723754)
				(end 236.864906 -402.620734)
			)
			(arc
				(start 238.766604 -400.719036)
				(mid 238.869636 -400.650255)
				(end 238.99114 -400.626072)
			)
			(arc
				(start 242.910868 -400.626072)
				(mid 242.930391 -400.622171)
				(end 242.946936 -400.611086)
			)
			(arc
				(start 243.79682 -399.761202)
				(mid 243.807931 -399.744668)
				(end 243.811806 -399.725134)
			)
			(arc
				(start 243.811806 -392.09472)
				(mid 243.835959 -391.973204)
				(end 243.90477 -391.870184)
			)
			(arc
				(start 244.93093 -390.844024)
				(mid 245.033962 -390.775243)
				(end 245.155466 -390.75106)
			)
			(arc
				(start 259.056124 -390.75106)
				(mid 259.075647 -390.747159)
				(end 259.092192 -390.736074)
			)
			(arc
				(start 262.00481 -387.823456)
				(mid 262.015921 -387.806922)
				(end 262.019796 -387.787388)
			)
			(arc
				(start 262.019796 -379.197616)
				(mid 262.015895 -379.178093)
				(end 262.00481 -379.161548)
			)
			(arc
				(start 261.967472 -379.12421)
				(mid 261.950938 -379.113099)
				(end 261.931404 -379.109224)
			)
			(arc
				(start 240.584482 -379.109224)
				(mid 240.564959 -379.113125)
				(end 240.548414 -379.12421)
			)
			(arc
				(start 239.998504 -379.67412)
				(mid 239.895472 -379.742901)
				(end 239.773968 -379.767084)
			)
			(arc
				(start 237.129066 -379.767084)
				(mid 237.00755 -379.742931)
				(end 236.90453 -379.67412)
			)
			(arc
				(start 232.953814 -375.723404)
				(mid 232.885033 -375.620372)
				(end 232.86085 -375.498868)
			)
			(arc
				(start 232.86085 -372.11508)
				(mid 232.856949 -372.095557)
				(end 232.845864 -372.079012)
			)
			(arc
				(start 232.203752 -371.4369)
				(mid 232.134971 -371.333868)
				(end 232.110788 -371.212364)
			)
			(arc
				(start 232.110788 -371.075712)
				(mid 232.106887 -371.056189)
				(end 232.095802 -371.039644)
			)
			(arc
				(start 232.035858 -370.9797)
				(mid 231.967077 -370.876668)
				(end 231.942894 -370.755164)
			)
			(arc
				(start 231.942894 -367.397792)
				(mid 231.938993 -367.378269)
				(end 231.927908 -367.361724)
			)
			(arc
				(start 231.89057 -367.324386)
				(mid 231.874036 -367.313275)
				(end 231.854502 -367.3094)
			)
			(arc
				(start 228.741986 -367.3094)
				(mid 228.722463 -367.313301)
				(end 228.705918 -367.324386)
			)
			(arc
				(start 228.66858 -367.361724)
				(mid 228.657469 -367.378258)
				(end 228.653594 -367.397792)
			)
			(arc
				(start 228.653594 -370.74856)
				(mid 228.629441 -370.870076)
				(end 228.56063 -370.973096)
			)
			(arc
				(start 228.481128 -371.052598)
				(mid 228.470017 -371.069132)
				(end 228.466142 -371.088666)
			)
			(arc
				(start 228.466142 -371.354096)
				(mid 228.441989 -371.475612)
				(end 228.373178 -371.578632)
			)
			(arc
				(start 227.178362 -372.773448)
				(mid 227.167251 -372.789982)
				(end 227.163376 -372.809516)
			)
			(arc
				(start 227.163376 -374.166384)
				(mid 227.139223 -374.2879)
				(end 227.070412 -374.39092)
			)
			(arc
				(start 225.794062 -375.66727)
				(mid 225.69103 -375.736051)
				(end 225.569526 -375.760234)
			)
			(arc
				(start 223.648016 -375.760234)
				(mid 223.5265 -375.736081)
				(end 223.42348 -375.66727)
			)
			(arc
				(start 221.55531 -373.7991)
				(mid 221.486529 -373.696068)
				(end 221.462346 -373.574564)
			)
			(arc
				(start 221.462346 -371.091714)
				(mid 221.458445 -371.072191)
				(end 221.44736 -371.055646)
			)
			(arc
				(start 221.361508 -370.969794)
				(mid 221.292727 -370.866762)
				(end 221.268544 -370.745258)
			)
			(arc
				(start 221.268544 -367.391442)
				(mid 221.264643 -367.371919)
				(end 221.253558 -367.355374)
			)
			(arc
				(start 221.225872 -367.327688)
				(mid 221.209338 -367.316577)
				(end 221.189804 -367.312702)
			)
			(arc
				(start 218.110308 -367.312702)
				(mid 218.090785 -367.316603)
				(end 218.07424 -367.327688)
			)
			(arc
				(start 217.967306 -367.434622)
				(mid 217.956195 -367.451156)
				(end 217.95232 -367.47069)
			)
			(arc
				(start 217.95232 -370.719096)
				(mid 217.928167 -370.840612)
				(end 217.859356 -370.943632)
			)
			(arc
				(start 216.82964 -371.973348)
				(mid 216.726608 -372.042129)
				(end 216.605104 -372.066312)
			)
			(arc
				(start 210.424014 -372.066312)
				(mid 210.302498 -372.042159)
				(end 210.199478 -371.973348)
			)
			(arc
				(start 210.067906 -371.841776)
				(mid 209.999125 -371.738744)
				(end 209.974942 -371.61724)
			)
			(arc
				(start 209.974942 -371.309138)
				(mid 209.971041 -371.289615)
				(end 209.959956 -371.27307)
			)
			(arc
				(start 209.949034 -371.262148)
				(mid 209.9325 -371.251037)
				(end 209.912966 -371.247162)
			)
			(arc
				(start 209.559144 -371.247162)
				(mid 209.437628 -371.223009)
				(end 209.334608 -371.154198)
			)
			(arc
				(start 208.669382 -370.488972)
				(mid 208.652848 -370.477861)
				(end 208.633314 -370.473986)
			)
			(arc
				(start 208.394554 -370.473986)
				(mid 208.273038 -370.449833)
				(end 208.170018 -370.381022)
			)
			(arc
				(start 208.11744 -370.328444)
				(mid 208.048659 -370.225412)
				(end 208.024476 -370.103908)
			)
			(arc
				(start 208.024476 -367.401348)
				(mid 208.020575 -367.381825)
				(end 208.00949 -367.36528)
			)
			(arc
				(start 207.981804 -367.337594)
				(mid 207.96527 -367.326483)
				(end 207.945736 -367.322608)
			)
			(arc
				(start 204.823822 -367.322608)
				(mid 204.804299 -367.326509)
				(end 204.787754 -367.337594)
			)
			(arc
				(start 204.740002 -367.385346)
				(mid 204.728891 -367.40188)
				(end 204.725016 -367.421414)
			)
			(arc
				(start 204.725016 -370.796312)
				(mid 204.728917 -370.815835)
				(end 204.740002 -370.83238)
			)
			(arc
				(start 204.77353 -370.865908)
				(mid 204.842311 -370.96894)
				(end 204.866494 -371.090444)
			)
			(arc
				(start 204.866494 -374.47474)
				(mid 204.870058 -374.493432)
				(end 204.88021 -374.509538)
			)
			(arc
				(start 204.88021 -374.509538)
				(mid 204.94326 -374.609679)
				(end 204.9653 -374.725946)
			)
			(arc
				(start 204.9653 -387.02361)
				(mid 204.969201 -387.043133)
				(end 204.980286 -387.059678)
			)
			(arc
				(start 207.47482 -389.554212)
				(mid 207.543601 -389.657244)
				(end 207.567784 -389.778748)
			)
			(arc
				(start 207.567784 -411.696662)
				(mid 207.571685 -411.716185)
				(end 207.58277 -411.73273)
			)
			(arc
				(start 208.922112 -413.072072)
				(mid 208.938646 -413.083183)
				(end 208.95818 -413.087058)
			)
		)
		(stroke
			(width 0)
			(type solid)
		)
		(fill yes)
		(layer "In4.Cu")
		(net "P12V_STBY")
	)
	(gr_poly
		(pts
			(xy 465.600034 -461.99552) (xy 465.655841 -461.994997) (xy 465.767141 -461.986654) (xy 465.877508 -461.970017)
			(xy 465.986322 -461.945179) (xy 466.092976 -461.912278) (xy 466.196873 -461.8715) (xy 466.297432 -461.823072)
			(xy 466.394091 -461.767264) (xy 466.48631 -461.70439) (xy 466.573572 -461.6348) (xy 466.65539 -461.558883)
			(xy 466.731306 -461.477065) (xy 466.800896 -461.389802) (xy 466.86377 -461.297583) (xy 466.919577 -461.200923)
			(xy 466.968004 -461.100364) (xy 467.008782 -460.996466) (xy 467.041681 -460.889812) (xy 467.066519 -460.780998)
			(xy 467.083155 -460.670631) (xy 467.091497 -460.559331) (xy 467.09203 -460.503524) (xy 467.09203 -422.58996)
			(xy 467.091507 -422.534153) (xy 467.083163 -422.422853) (xy 467.066526 -422.312487) (xy 467.041687 -422.203672)
			(xy 467.008787 -422.097019) (xy 466.968009 -421.993121) (xy 466.91958 -421.892562) (xy 466.863773 -421.795903)
			(xy 466.800898 -421.703684) (xy 466.731308 -421.616422) (xy 466.655392 -421.534604) (xy 466.573573 -421.458688)
			(xy 466.486311 -421.389098) (xy 466.394092 -421.326224) (xy 466.297433 -421.270417) (xy 466.196873 -421.221989)
			(xy 466.092976 -421.181211) (xy 465.986322 -421.148311) (xy 465.877508 -421.123473) (xy 465.767141 -421.106836)
			(xy 465.655841 -421.098493) (xy 465.600034 -421.097964) (xy 447.939922 -421.097964) (xy 447.884114 -421.098485)
			(xy 447.77281 -421.106824) (xy 447.66244 -421.123458) (xy 447.553622 -421.148293) (xy 447.446964 -421.181191)
			(xy 447.343062 -421.221967) (xy 447.242499 -421.270394) (xy 447.145835 -421.3262) (xy 447.053613 -421.389074)
			(xy 446.966346 -421.458664) (xy 446.884524 -421.53458) (xy 446.808604 -421.616399) (xy 446.739011 -421.703663)
			(xy 446.676133 -421.795883) (xy 446.620323 -421.892544) (xy 446.571892 -421.993106) (xy 446.531111 -422.097005)
			(xy 446.498209 -422.203662) (xy 446.47337 -422.312479) (xy 446.456731 -422.422848) (xy 446.448387 -422.534152)
			(xy 446.447926 -422.58996) (xy 446.447926 -429.090074) (xy 446.447433 -429.160429) (xy 446.439545 -429.300916)
			(xy 446.423792 -429.440741) (xy 446.400224 -429.579462) (xy 446.368915 -429.716643) (xy 446.329963 -429.851854)
			(xy 446.283491 -429.984667) (xy 446.229646 -430.114666) (xy 446.168596 -430.241441) (xy 446.100533 -430.364593)
			(xy 446.025673 -430.483736) (xy 445.94425 -430.598494) (xy 445.856521 -430.708505) (xy 445.762761 -430.813425)
			(xy 445.663266 -430.912922) (xy 445.558348 -431.006684) (xy 445.448338 -431.094416) (xy 445.333582 -431.175842)
			(xy 445.214442 -431.250705) (xy 445.091291 -431.31877) (xy 444.964517 -431.379823) (xy 444.834519 -431.433671)
			(xy 444.701707 -431.480146) (xy 444.566498 -431.519101) (xy 444.429317 -431.550413) (xy 444.290596 -431.573985)
			(xy 444.150772 -431.589741) (xy 444.010285 -431.597632) (xy 443.93993 -431.59807) (xy 371.24005 -431.59807)
			(xy 371.169695 -431.597587) (xy 371.029207 -431.5897) (xy 370.889383 -431.573948) (xy 370.750661 -431.550381)
			(xy 370.613479 -431.519072) (xy 370.478269 -431.480121) (xy 370.345455 -431.433649) (xy 370.215456 -431.379804)
			(xy 370.088681 -431.318754) (xy 369.965528 -431.250691) (xy 369.846385 -431.175831) (xy 369.731628 -431.094407)
			(xy 369.621616 -431.006677) (xy 369.516697 -430.912917) (xy 369.4172 -430.813421) (xy 369.323438 -430.708502)
			(xy 369.235707 -430.598492) (xy 369.154283 -430.483735) (xy 369.079421 -430.364593) (xy 369.011357 -430.241441)
			(xy 368.950306 -430.114666) (xy 368.896459 -429.984667) (xy 368.849986 -429.851854) (xy 368.811034 -429.716644)
			(xy 368.779724 -429.579463) (xy 368.756155 -429.440741) (xy 368.740402 -429.300917) (xy 368.732514 -429.160429)
			(xy 368.732054 -429.090074) (xy 368.732054 -422.58996) (xy 368.731543 -422.534154) (xy 368.7232 -422.422854)
			(xy 368.706562 -422.31249) (xy 368.681723 -422.203677) (xy 368.648822 -422.097024) (xy 368.608042 -421.993129)
			(xy 368.559613 -421.892571) (xy 368.503804 -421.795914) (xy 368.440929 -421.703697) (xy 368.371337 -421.616438)
			(xy 368.29542 -421.534622) (xy 368.2136 -421.458709) (xy 368.126337 -421.389123) (xy 368.034117 -421.326252)
			(xy 367.937456 -421.270449) (xy 367.836896 -421.222025) (xy 367.732998 -421.181251) (xy 367.626344 -421.148356)
			(xy 367.51753 -421.123523) (xy 367.407164 -421.106891) (xy 367.295864 -421.098554) (xy 367.240058 -421.097964)
			(xy 359.940098 -421.097964) (xy 359.88429 -421.098486) (xy 359.772988 -421.106827) (xy 359.662619 -421.123462)
			(xy 359.553802 -421.148298) (xy 359.447146 -421.181197) (xy 359.343246 -421.221974) (xy 359.242684 -421.270401)
			(xy 359.146022 -421.326208) (xy 359.053801 -421.389082) (xy 358.966536 -421.458672) (xy 358.884716 -421.534589)
			(xy 358.808797 -421.616407) (xy 358.739205 -421.70367) (xy 358.676328 -421.79589) (xy 358.620519 -421.892551)
			(xy 358.572089 -421.993111) (xy 358.53131 -422.09701) (xy 358.498408 -422.203666) (xy 358.473569 -422.312482)
			(xy 358.456931 -422.42285) (xy 358.448587 -422.534152) (xy 358.448102 -422.58996) (xy 358.448102 -429.090074)
			(xy 358.447618 -429.160429) (xy 358.43973 -429.300916) (xy 358.423977 -429.440741) (xy 358.400409 -429.579462)
			(xy 358.369099 -429.716643) (xy 358.330147 -429.851853) (xy 358.283675 -429.984667) (xy 358.229829 -430.114665)
			(xy 358.168779 -430.24144) (xy 358.100716 -430.364593) (xy 358.025856 -430.483735) (xy 357.944432 -430.598492)
			(xy 357.856702 -430.708504) (xy 357.762942 -430.813423) (xy 357.663446 -430.91292) (xy 357.558528 -431.006682)
			(xy 357.448518 -431.094413) (xy 357.333762 -431.175838) (xy 357.21462 -431.2507) (xy 357.091469 -431.318764)
			(xy 356.964695 -431.379816) (xy 356.834697 -431.433664) (xy 356.701884 -431.480138) (xy 356.566674 -431.519091)
			(xy 356.429493 -431.550403) (xy 356.290772 -431.573973) (xy 356.150948 -431.589728) (xy 356.010461 -431.597618)
			(xy 355.940106 -431.59807) (xy 283.239972 -431.59807) (xy 283.169619 -431.597576) (xy 283.029135 -431.589685)
			(xy 282.889313 -431.573929) (xy 282.750596 -431.550359) (xy 282.613418 -431.519047) (xy 282.478212 -431.480093)
			(xy 282.345402 -431.43362) (xy 282.215407 -431.379772) (xy 282.088636 -431.318721) (xy 281.965488 -431.250657)
			(xy 281.84635 -431.175796) (xy 281.731596 -431.094372) (xy 281.621589 -431.006642) (xy 281.516674 -430.912882)
			(xy 281.417181 -430.813387) (xy 281.323423 -430.70847) (xy 281.235695 -430.598461) (xy 281.154274 -430.483705)
			(xy 281.079415 -430.364565) (xy 281.011354 -430.241416) (xy 280.950306 -430.114643) (xy 280.896461 -429.984647)
			(xy 280.84999 -429.851837) (xy 280.811039 -429.71663) (xy 280.779731 -429.579451) (xy 280.756163 -429.440733)
			(xy 280.740411 -429.300912) (xy 280.732523 -429.160427) (xy 280.731976 -429.090074) (xy 280.731976 -422.58996)
			(xy 280.731453 -422.534154) (xy 280.723109 -422.422855) (xy 280.706471 -422.31249) (xy 280.681633 -422.203678)
			(xy 280.648732 -422.097025) (xy 280.607953 -421.99313) (xy 280.559525 -421.892573) (xy 280.503717 -421.795915)
			(xy 280.440842 -421.703699) (xy 280.371251 -421.616439) (xy 280.295334 -421.534623) (xy 280.213516 -421.45871)
			(xy 280.126253 -421.389123) (xy 280.034034 -421.326251) (xy 279.937374 -421.270447) (xy 279.836815 -421.222023)
			(xy 279.732918 -421.181248) (xy 279.626264 -421.148352) (xy 279.517451 -421.123517) (xy 279.407085 -421.106884)
			(xy 279.295786 -421.098545) (xy 279.23998 -421.097964) (xy 276.880066 -421.097964) (xy 276.824259 -421.098487)
			(xy 276.712958 -421.10683) (xy 276.602591 -421.123467) (xy 276.493777 -421.148305) (xy 276.387122 -421.181205)
			(xy 276.283225 -421.221984) (xy 276.182665 -421.270412) (xy 276.086005 -421.326219) (xy 275.993786 -421.389094)
			(xy 275.906523 -421.458684) (xy 275.824704 -421.5346) (xy 275.748787 -421.616418) (xy 275.679197 -421.703681)
			(xy 275.616322 -421.7959) (xy 275.560514 -421.892559) (xy 275.512086 -421.993119) (xy 275.471307 -422.097017)
			(xy 275.438407 -422.203671) (xy 275.413568 -422.312485) (xy 275.396931 -422.422852) (xy 275.388587 -422.534153)
			(xy 275.38807 -422.58996) (xy 275.38807 -430.55794) (xy 275.387576 -430.628293) (xy 275.379684 -430.768777)
			(xy 275.363928 -430.908597) (xy 275.340357 -431.047314) (xy 275.309045 -431.184492) (xy 275.27009 -431.319698)
			(xy 275.223616 -431.452506) (xy 275.169769 -431.582501) (xy 275.108717 -431.709271) (xy 275.040653 -431.832419)
			(xy 274.965792 -431.951557) (xy 274.884368 -432.066309) (xy 274.796638 -432.176316) (xy 274.702878 -432.281231)
			(xy 274.603383 -432.380723) (xy 274.498466 -432.474481) (xy 274.388457 -432.562208) (xy 274.273702 -432.643629)
			(xy 274.154562 -432.718487) (xy 274.031412 -432.786547) (xy 273.90464 -432.847596) (xy 273.774645 -432.90144)
			(xy 273.641835 -432.94791) (xy 273.506628 -432.986861) (xy 273.36945 -433.018169) (xy 273.230732 -433.041737)
			(xy 273.090911 -433.05749) (xy 272.950427 -433.065377) (xy 272.880074 -433.065936) (xy 202.360022 -433.065936)
			(xy 202.289667 -433.065443) (xy 202.14918 -433.057555) (xy 202.009355 -433.041802) (xy 201.870634 -433.018234)
			(xy 201.733452 -432.986924) (xy 201.598242 -432.947972) (xy 201.465429 -432.9015) (xy 201.33543 -432.847655)
			(xy 201.208655 -432.786605) (xy 201.085502 -432.718542) (xy 200.96636 -432.643682) (xy 200.851602 -432.562259)
			(xy 200.74159 -432.47453) (xy 200.63667 -432.38077) (xy 200.537173 -432.281275) (xy 200.44341 -432.176357)
			(xy 200.355678 -432.066348) (xy 200.274252 -431.951592) (xy 200.199389 -431.832451) (xy 200.131324 -431.7093)
			(xy 200.070271 -431.582527) (xy 200.016422 -431.452529) (xy 199.969947 -431.319717) (xy 199.930991 -431.184508)
			(xy 199.899679 -431.047327) (xy 199.876107 -430.908606) (xy 199.86035 -430.768782) (xy 199.852458 -430.628295)
			(xy 199.852026 -430.55794) (xy 199.852026 -422.58996) (xy 199.851503 -422.534154) (xy 199.843159 -422.422853)
			(xy 199.826522 -422.312487) (xy 199.801683 -422.203673) (xy 199.768783 -422.097019) (xy 199.728004 -421.993122)
			(xy 199.679576 -421.892563) (xy 199.623769 -421.795904) (xy 199.560894 -421.703685) (xy 199.491304 -421.616423)
			(xy 199.415387 -421.534606) (xy 199.333569 -421.45869) (xy 199.246306 -421.3891) (xy 199.154088 -421.326226)
			(xy 199.057428 -421.270419) (xy 198.956869 -421.221992) (xy 198.852972 -421.181214) (xy 198.746318 -421.148314)
			(xy 198.637503 -421.123476) (xy 198.527137 -421.10684) (xy 198.415836 -421.098497) (xy 198.36003 -421.097964)
			(xy 188.36005 -421.097964) (xy 188.304244 -421.098488) (xy 188.192943 -421.106832) (xy 188.082578 -421.12347)
			(xy 187.973764 -421.148309) (xy 187.86711 -421.18121) (xy 187.763214 -421.221988) (xy 187.662655 -421.270417)
			(xy 187.565996 -421.326225) (xy 187.473778 -421.389099) (xy 187.386516 -421.458689) (xy 187.304699 -421.534606)
			(xy 187.228783 -421.616424) (xy 187.159193 -421.703686) (xy 187.096319 -421.795905) (xy 187.040512 -421.892564)
			(xy 186.992084 -421.993123) (xy 186.951306 -422.09702) (xy 186.918406 -422.203673) (xy 186.893568 -422.312487)
			(xy 186.876931 -422.422853) (xy 186.868587 -422.534154) (xy 186.868054 -422.58996) (xy 186.868054 -429.090074)
			(xy 186.86757 -429.160428) (xy 186.859682 -429.300915) (xy 186.843929 -429.440738) (xy 186.820361 -429.579458)
			(xy 186.789051 -429.716639) (xy 186.750099 -429.851848) (xy 186.703626 -429.98466) (xy 186.64978 -430.114658)
			(xy 186.58873 -430.241431) (xy 186.520667 -430.364582) (xy 186.445806 -430.483723) (xy 186.364382 -430.598479)
			(xy 186.276652 -430.708489) (xy 186.182891 -430.813407) (xy 186.083395 -430.912902) (xy 185.978477 -431.006662)
			(xy 185.868467 -431.094392) (xy 185.75371 -431.175815) (xy 185.634569 -431.250675) (xy 185.511417 -431.318737)
			(xy 185.384643 -431.379787) (xy 185.254645 -431.433632) (xy 185.121833 -431.480104) (xy 184.986623 -431.519055)
			(xy 184.849443 -431.550364) (xy 184.710722 -431.573931) (xy 184.570899 -431.589684) (xy 184.430412 -431.597571)
			(xy 184.360058 -431.59807) (xy 111.660178 -431.59807) (xy 111.589825 -431.597585) (xy 111.449339 -431.589694)
			(xy 111.309518 -431.573939) (xy 111.170799 -431.550369) (xy 111.033621 -431.519057) (xy 110.898414 -431.480103)
			(xy 110.765603 -431.43363) (xy 110.635608 -431.379782) (xy 110.508836 -431.318731) (xy 110.385687 -431.250667)
			(xy 110.266548 -431.175806) (xy 110.151794 -431.094382) (xy 110.041786 -431.006651) (xy 109.93687 -430.912891)
			(xy 109.837376 -430.813395) (xy 109.743618 -430.708478) (xy 109.65589 -430.598468) (xy 109.574468 -430.483712)
			(xy 109.499608 -430.364572) (xy 109.431547 -430.241421) (xy 109.370498 -430.114648) (xy 109.316653 -429.984652)
			(xy 109.270182 -429.851841) (xy 109.231231 -429.716633) (xy 109.199922 -429.579454) (xy 109.176354 -429.440735)
			(xy 109.160602 -429.300913) (xy 109.152714 -429.160427) (xy 109.152182 -429.090074) (xy 109.152182 -422.58996)
			(xy 109.151659 -422.534154) (xy 109.143315 -422.422855) (xy 109.126678 -422.31249) (xy 109.101839 -422.203677)
			(xy 109.068938 -422.097025) (xy 109.02816 -421.993129) (xy 108.979731 -421.892571) (xy 108.923923 -421.795914)
			(xy 108.861048 -421.703697) (xy 108.791457 -421.616437) (xy 108.715541 -421.534621) (xy 108.633722 -421.458707)
			(xy 108.546459 -421.38912) (xy 108.45424 -421.326248) (xy 108.357581 -421.270444) (xy 108.257021 -421.222019)
			(xy 108.153124 -421.181244) (xy 108.046471 -421.148347) (xy 107.937657 -421.123512) (xy 107.827292 -421.106879)
			(xy 107.715992 -421.098539) (xy 107.660186 -421.097964) (xy 100.359972 -421.097964) (xy 100.304165 -421.098487)
			(xy 100.192864 -421.106829) (xy 100.082497 -421.123466) (xy 99.973681 -421.148304) (xy 99.867027 -421.181204)
			(xy 99.763129 -421.221982) (xy 99.662568 -421.27041) (xy 99.565908 -421.326217) (xy 99.473689 -421.389091)
			(xy 99.386425 -421.458681) (xy 99.304606 -421.534598) (xy 99.228689 -421.616416) (xy 99.159099 -421.703679)
			(xy 99.096223 -421.795898) (xy 99.040415 -421.892558) (xy 98.991987 -421.993118) (xy 98.951208 -422.097015)
			(xy 98.918307 -422.20367) (xy 98.893468 -422.312485) (xy 98.876831 -422.422852) (xy 98.868487 -422.534153)
			(xy 98.867976 -422.58996) (xy 98.867976 -429.090074) (xy 98.867492 -429.160428) (xy 98.859604 -429.300915)
			(xy 98.843851 -429.440739) (xy 98.820283 -429.57946) (xy 98.788973 -429.716641) (xy 98.750021 -429.85185)
			(xy 98.703549 -429.984663) (xy 98.649703 -430.114661) (xy 98.588652 -430.241435) (xy 98.520589 -430.364587)
			(xy 98.445729 -430.483729) (xy 98.364305 -430.598485) (xy 98.276575 -430.708496) (xy 98.182814 -430.813414)
			(xy 98.083319 -430.91291) (xy 97.9784 -431.006671) (xy 97.86839 -431.094401) (xy 97.753634 -431.175825)
			(xy 97.634492 -431.250686) (xy 97.511341 -431.31875) (xy 97.384567 -431.3798) (xy 97.254569 -431.433647)
			(xy 97.121756 -431.480119) (xy 96.986547 -431.519072) (xy 96.849366 -431.550382) (xy 96.710645 -431.57395)
			(xy 96.570821 -431.589704) (xy 96.430334 -431.597592) (xy 96.35998 -431.59807) (xy 23.6601 -431.59807)
			(xy 23.589746 -431.597586) (xy 23.44926 -431.589696) (xy 23.309437 -431.573942) (xy 23.170718 -431.550372)
			(xy 23.033539 -431.519062) (xy 22.89833 -431.480109) (xy 22.765519 -431.433636) (xy 22.635522 -431.379789)
			(xy 22.50875 -431.318738) (xy 22.385599 -431.250675) (xy 22.266459 -431.175813) (xy 22.151704 -431.094389)
			(xy 22.041695 -431.006659) (xy 21.936778 -430.912899) (xy 21.837283 -430.813403) (xy 21.743524 -430.708485)
			(xy 21.655795 -430.598475) (xy 21.574372 -430.483719) (xy 21.499512 -430.364578) (xy 21.43145 -430.241427)
			(xy 21.370401 -430.114654) (xy 21.316555 -429.984657) (xy 21.270083 -429.851845) (xy 21.231132 -429.716636)
			(xy 21.199823 -429.579456) (xy 21.176255 -429.440737) (xy 21.160502 -429.300914) (xy 21.152614 -429.160428)
			(xy 21.152104 -429.090074) (xy 21.152104 -422.58996) (xy 21.151595 -422.534153) (xy 21.143254 -422.42285)
			(xy 21.126618 -422.312481) (xy 21.101782 -422.203665) (xy 21.068883 -422.097009) (xy 21.028105 -421.993109)
			(xy 20.979677 -421.892548) (xy 20.92387 -421.795886) (xy 20.860995 -421.703666) (xy 20.791404 -421.616402)
			(xy 20.715486 -421.534582) (xy 20.633667 -421.458665) (xy 20.546403 -421.389074) (xy 20.454182 -421.326199)
			(xy 20.357521 -421.270392) (xy 20.256959 -421.221964) (xy 20.153059 -421.181187) (xy 20.046403 -421.148288)
			(xy 19.937587 -421.123451) (xy 19.827218 -421.106816) (xy 19.715915 -421.098475) (xy 19.660108 -421.097964)
			(xy 1.999996 -421.097964) (xy 1.944189 -421.098486) (xy 1.832887 -421.106827) (xy 1.72252 -421.123463)
			(xy 1.613705 -421.148299) (xy 1.50705 -421.181198) (xy 1.403151 -421.221976) (xy 1.302591 -421.270403)
			(xy 1.20593 -421.32621) (xy 1.113711 -421.389085) (xy 1.026448 -421.458675) (xy 0.944629 -421.534592)
			(xy 0.868712 -421.616411) (xy 0.799122 -421.703674) (xy 0.736248 -421.795894) (xy 0.680441 -421.892554)
			(xy 0.632014 -421.993115) (xy 0.591237 -422.097013) (xy 0.558338 -422.203669) (xy 0.533502 -422.312484)
			(xy 0.516867 -422.422851) (xy 0.508526 -422.534153) (xy 0.508 -422.58996) (xy 0.508 -457.5681) (xy 2.904225 -457.5681)
			(xy 2.904225 -457.43896) (xy 2.912175 -457.310065) (xy 2.928045 -457.181905) (xy 2.951774 -457.054964)
			(xy 2.983273 -456.929725) (xy 3.022422 -456.806662) (xy 3.069073 -456.686243) (xy 3.123048 -456.568924)
			(xy 3.184143 -456.45515) (xy 3.252126 -456.345353) (xy 3.32674 -456.23995) (xy 3.407701 -456.13934)
			(xy 3.494701 -456.043905) (xy 3.587412 -455.954006) (xy 3.685482 -455.869985) (xy 3.788537 -455.792161)
			(xy 3.896188 -455.720829) (xy 4.008027 -455.656259) (xy 4.123628 -455.598697) (xy 4.242553 -455.54836)
			(xy 4.364352 -455.50544) (xy 4.488562 -455.470099) (xy 4.614711 -455.442472) (xy 4.742323 -455.422663)
			(xy 4.870912 -455.410747) (xy 4.99999 -455.406771) (xy 5.129068 -455.410747) (xy 5.257657 -455.422663)
			(xy 5.385269 -455.442472) (xy 5.511418 -455.470099) (xy 5.635628 -455.50544) (xy 5.757427 -455.54836)
			(xy 5.876352 -455.598697) (xy 5.991953 -455.656259) (xy 6.103792 -455.720829) (xy 6.211443 -455.792161)
			(xy 6.314498 -455.869985) (xy 6.412568 -455.954006) (xy 6.505279 -456.043905) (xy 6.592279 -456.13934)
			(xy 6.67324 -456.23995) (xy 6.747854 -456.345353) (xy 6.815837 -456.45515) (xy 6.876932 -456.568924)
			(xy 6.930907 -456.686243) (xy 6.977558 -456.806662) (xy 7.016707 -456.929725) (xy 7.048206 -457.054964)
			(xy 7.071935 -457.181905) (xy 7.087805 -457.310065) (xy 7.095755 -457.43896) (xy 7.096252 -457.50353)
			(xy 7.095755 -457.5681) (xy 460.504275 -457.5681) (xy 460.504275 -457.43896) (xy 460.512225 -457.310065)
			(xy 460.528095 -457.181905) (xy 460.551824 -457.054964) (xy 460.583323 -456.929725) (xy 460.622472 -456.806662)
			(xy 460.669123 -456.686243) (xy 460.723098 -456.568924) (xy 460.784193 -456.45515) (xy 460.852176 -456.345353)
			(xy 460.92679 -456.23995) (xy 461.007751 -456.13934) (xy 461.094751 -456.043905) (xy 461.187462 -455.954006)
			(xy 461.285532 -455.869985) (xy 461.388587 -455.792161) (xy 461.496238 -455.720829) (xy 461.608077 -455.656259)
			(xy 461.723678 -455.598697) (xy 461.842603 -455.54836) (xy 461.964402 -455.50544) (xy 462.088612 -455.470099)
			(xy 462.214761 -455.442472) (xy 462.342373 -455.422663) (xy 462.470962 -455.410747) (xy 462.60004 -455.406771)
			(xy 462.729118 -455.410747) (xy 462.857707 -455.422663) (xy 462.985319 -455.442472) (xy 463.111468 -455.470099)
			(xy 463.235678 -455.50544) (xy 463.357477 -455.54836) (xy 463.476402 -455.598697) (xy 463.592003 -455.656259)
			(xy 463.703842 -455.720829) (xy 463.811493 -455.792161) (xy 463.914548 -455.869985) (xy 464.012618 -455.954006)
			(xy 464.105329 -456.043905) (xy 464.192329 -456.13934) (xy 464.27329 -456.23995) (xy 464.347904 -456.345353)
			(xy 464.415887 -456.45515) (xy 464.476982 -456.568924) (xy 464.530957 -456.686243) (xy 464.577608 -456.806662)
			(xy 464.616757 -456.929725) (xy 464.648256 -457.054964) (xy 464.671985 -457.181905) (xy 464.687855 -457.310065)
			(xy 464.695805 -457.43896) (xy 464.696302 -457.50353) (xy 464.695805 -457.5681) (xy 464.687855 -457.696995)
			(xy 464.671985 -457.825155) (xy 464.648256 -457.952096) (xy 464.616757 -458.077335) (xy 464.577608 -458.200398)
			(xy 464.530957 -458.320817) (xy 464.476982 -458.438136) (xy 464.415887 -458.55191) (xy 464.347904 -458.661707)
			(xy 464.27329 -458.76711) (xy 464.192329 -458.86772) (xy 464.105329 -458.963155) (xy 464.012618 -459.053054)
			(xy 463.914548 -459.137075) (xy 463.811493 -459.214899) (xy 463.703842 -459.286231) (xy 463.592003 -459.350801)
			(xy 463.476402 -459.408363) (xy 463.357477 -459.4587) (xy 463.235678 -459.50162) (xy 463.111468 -459.536961)
			(xy 462.985319 -459.564588) (xy 462.857707 -459.584397) (xy 462.729118 -459.596313) (xy 462.60004 -459.60029)
			(xy 462.470962 -459.596313) (xy 462.342373 -459.584397) (xy 462.214761 -459.564588) (xy 462.088612 -459.536961)
			(xy 461.964402 -459.50162) (xy 461.842603 -459.4587) (xy 461.723678 -459.408363) (xy 461.608077 -459.350801)
			(xy 461.496238 -459.286231) (xy 461.388587 -459.214899) (xy 461.285532 -459.137075) (xy 461.187462 -459.053054)
			(xy 461.094751 -458.963155) (xy 461.007751 -458.86772) (xy 460.92679 -458.76711) (xy 460.852176 -458.661707)
			(xy 460.784193 -458.55191) (xy 460.723098 -458.438136) (xy 460.669123 -458.320817) (xy 460.622472 -458.200398)
			(xy 460.583323 -458.077335) (xy 460.551824 -457.952096) (xy 460.528095 -457.825155) (xy 460.512225 -457.696995)
			(xy 460.504275 -457.5681) (xy 7.095755 -457.5681) (xy 7.087805 -457.696995) (xy 7.071935 -457.825155)
			(xy 7.048206 -457.952096) (xy 7.016707 -458.077335) (xy 6.977558 -458.200398) (xy 6.930907 -458.320817)
			(xy 6.876932 -458.438136) (xy 6.815837 -458.55191) (xy 6.747854 -458.661707) (xy 6.67324 -458.76711)
			(xy 6.592279 -458.86772) (xy 6.505279 -458.963155) (xy 6.412568 -459.053054) (xy 6.314498 -459.137075)
			(xy 6.211443 -459.214899) (xy 6.103792 -459.286231) (xy 5.991953 -459.350801) (xy 5.876352 -459.408363)
			(xy 5.757427 -459.4587) (xy 5.635628 -459.50162) (xy 5.511418 -459.536961) (xy 5.385269 -459.564588)
			(xy 5.257657 -459.584397) (xy 5.129068 -459.596313) (xy 4.99999 -459.60029) (xy 4.870912 -459.596313)
			(xy 4.742323 -459.584397) (xy 4.614711 -459.564588) (xy 4.488562 -459.536961) (xy 4.364352 -459.50162)
			(xy 4.242553 -459.4587) (xy 4.123628 -459.408363) (xy 4.008027 -459.350801) (xy 3.896188 -459.286231)
			(xy 3.788537 -459.214899) (xy 3.685482 -459.137075) (xy 3.587412 -459.053054) (xy 3.494701 -458.963155)
			(xy 3.407701 -458.86772) (xy 3.32674 -458.76711) (xy 3.252126 -458.661707) (xy 3.184143 -458.55191)
			(xy 3.123048 -458.438136) (xy 3.069073 -458.320817) (xy 3.022422 -458.200398) (xy 2.983273 -458.077335)
			(xy 2.951774 -457.952096) (xy 2.928045 -457.825155) (xy 2.912175 -457.696995) (xy 2.904225 -457.5681)
			(xy 0.508 -457.5681) (xy 0.508 -460.503524) (xy 0.508522 -460.559331) (xy 0.516863 -460.670633) (xy 0.533498 -460.781)
			(xy 0.558335 -460.889816) (xy 0.591234 -460.996471) (xy 0.632011 -461.10037) (xy 0.680438 -461.20093)
			(xy 0.736246 -461.297591) (xy 0.79912 -461.389811) (xy 0.86871 -461.477074) (xy 0.944627 -461.558893)
			(xy 1.026446 -461.63481) (xy 1.113709 -461.7044) (xy 1.205929 -461.767274) (xy 1.30259 -461.823082)
			(xy 1.40315 -461.871509) (xy 1.507049 -461.912286) (xy 1.613704 -461.945185) (xy 1.72252 -461.970022)
			(xy 1.832887 -461.986657) (xy 1.944189 -461.994998) (xy 1.999996 -461.99552)
		)
		(stroke
			(width 0)
			(type solid)
		)
		(fill yes)
		(layer "In4.Cu")
		(net "COUPON_GND1")
	)
	(gr_poly
		(pts
			(xy 13.96492 -10.342118) (xy 14.020727 -10.341596) (xy 14.132028 -10.333253) (xy 14.242395 -10.316617)
			(xy 14.35121 -10.29178) (xy 14.457865 -10.25888) (xy 14.561763 -10.218102) (xy 14.662323 -10.169674)
			(xy 14.758983 -10.113867) (xy 14.851203 -10.050993) (xy 14.938466 -9.981402) (xy 15.020284 -9.905486)
			(xy 15.096201 -9.823667) (xy 15.165791 -9.736404) (xy 15.228666 -9.644185) (xy 15.284473 -9.547525)
			(xy 15.332901 -9.446965) (xy 15.373679 -9.343067) (xy 15.406579 -9.236412) (xy 15.431417 -9.127597)
			(xy 15.448053 -9.01723) (xy 15.456395 -8.905929) (xy 15.456916 -8.850122) (xy 15.456916 0) (xy 15.4574 0.070354)
			(xy 15.46529 0.21084) (xy 15.481044 0.350663) (xy 15.504614 0.489383) (xy 15.535924 0.626563) (xy 15.574877 0.761771)
			(xy 15.62135 0.894583) (xy 15.675197 1.02458) (xy 15.736248 1.151353) (xy 15.804311 1.274504) (xy 15.879172 1.393644)
			(xy 15.960596 1.5084) (xy 16.048326 1.618409) (xy 16.142086 1.723327) (xy 16.241582 1.822822) (xy 16.3465 1.916582)
			(xy 16.45651 2.004311) (xy 16.571266 2.085734) (xy 16.690407 2.160595) (xy 16.813558 2.228658) (xy 16.940331 2.289708)
			(xy 17.070328 2.343554) (xy 17.20314 2.390026) (xy 17.338349 2.428979) (xy 17.475529 2.460289) (xy 17.614249 2.483858)
			(xy 17.754072 2.499611) (xy 17.894558 2.5075) (xy 17.964912 2.507996) (xy 33.96488 2.507996) (xy 34.035234 2.507512)
			(xy 34.175722 2.499624) (xy 34.315546 2.48387) (xy 34.454267 2.460302) (xy 34.591448 2.428992) (xy 34.726657 2.39004)
			(xy 34.85947 2.343568) (xy 34.989468 2.289721) (xy 35.116243 2.228671) (xy 35.239395 2.160608) (xy 35.358537 2.085747)
			(xy 35.473294 2.004324) (xy 35.583304 1.916594) (xy 35.688223 1.822833) (xy 35.78772 1.723338) (xy 35.881481 1.61842)
			(xy 35.969212 1.50841) (xy 36.050636 1.393653) (xy 36.125498 1.274512) (xy 36.193562 1.151361) (xy 36.254613 1.024587)
			(xy 36.30846 0.894589) (xy 36.354934 0.761776) (xy 36.393887 0.626567) (xy 36.425198 0.489386) (xy 36.448768 0.350666)
			(xy 36.464522 0.210842) (xy 36.472412 0.070354) (xy 36.472876 0) (xy 36.472876 -8.850122) (xy 36.473399 -8.905929)
			(xy 36.481741 -9.01723) (xy 36.498377 -9.127597) (xy 36.523215 -9.236413) (xy 36.556114 -9.343067)
			(xy 36.596892 -9.446965) (xy 36.64532 -9.547526) (xy 36.701127 -9.644186) (xy 36.764002 -9.736405)
			(xy 36.833592 -9.823668) (xy 36.909508 -9.905487) (xy 36.991327 -9.981404) (xy 37.07859 -10.050995)
			(xy 37.170809 -10.113869) (xy 37.267469 -10.169677) (xy 37.368029 -10.218105) (xy 37.471927 -10.258884)
			(xy 37.578582 -10.291784) (xy 37.687397 -10.316622) (xy 37.797764 -10.333258) (xy 37.909065 -10.341601)
			(xy 37.964872 -10.342118) (xy 39.965122 -10.342118) (xy 40.020929 -10.341595) (xy 40.13223 -10.333253)
			(xy 40.242597 -10.316617) (xy 40.351412 -10.291779) (xy 40.458067 -10.258879) (xy 40.561964 -10.218102)
			(xy 40.662525 -10.169674) (xy 40.759184 -10.113866) (xy 40.851404 -10.050992) (xy 40.938667 -9.981402)
			(xy 41.020485 -9.905485) (xy 41.096402 -9.823667) (xy 41.165992 -9.736404) (xy 41.228866 -9.644184)
			(xy 41.284674 -9.547525) (xy 41.333102 -9.446964) (xy 41.373879 -9.343067) (xy 41.406779 -9.236412)
			(xy 41.431617 -9.127597) (xy 41.448253 -9.01723) (xy 41.456595 -8.905929) (xy 41.457118 -8.850122)
			(xy 41.457118 0) (xy 41.457602 0.070354) (xy 41.465492 0.21084) (xy 41.481246 0.350663) (xy 41.504816 0.489383)
			(xy 41.536126 0.626563) (xy 41.575079 0.761771) (xy 41.621552 0.894583) (xy 41.675399 1.02458) (xy 41.73645 1.151353)
			(xy 41.804513 1.274503) (xy 41.879374 1.393644) (xy 41.960798 1.508399) (xy 42.048528 1.618409) (xy 42.142288 1.723326)
			(xy 42.241784 1.822821) (xy 42.346702 1.916581) (xy 42.456712 2.00431) (xy 42.571468 2.085733) (xy 42.690609 2.160594)
			(xy 42.81376 2.228657) (xy 42.940533 2.289707) (xy 43.07053 2.343553) (xy 43.203342 2.390025) (xy 43.338551 2.428977)
			(xy 43.475731 2.460287) (xy 43.614451 2.483856) (xy 43.754274 2.499609) (xy 43.89476 2.507498) (xy 43.965114 2.507996)
			(xy 59.965082 2.507996) (xy 60.035436 2.507512) (xy 60.175924 2.499624) (xy 60.315748 2.48387) (xy 60.454468 2.460301)
			(xy 60.591649 2.428992) (xy 60.726859 2.390039) (xy 60.859672 2.343567) (xy 60.98967 2.289721) (xy 61.116444 2.22867)
			(xy 61.239596 2.160607) (xy 61.358738 2.085747) (xy 61.473495 2.004323) (xy 61.583505 1.916593) (xy 61.688424 1.822833)
			(xy 61.78792 1.723337) (xy 61.881681 1.618419) (xy 61.969412 1.508409) (xy 62.050837 1.393653) (xy 62.125698 1.274512)
			(xy 62.193762 1.15136) (xy 62.254813 1.024586) (xy 62.308661 0.894588) (xy 62.355134 0.761776) (xy 62.394087 0.626567)
			(xy 62.425398 0.489386) (xy 62.448968 0.350665) (xy 62.464722 0.210842) (xy 62.472612 0.070354) (xy 62.473078 0)
			(xy 62.473078 -8.850122) (xy 62.473601 -8.905929) (xy 62.481943 -9.01723) (xy 62.498579 -9.127597)
			(xy 62.523417 -9.236412) (xy 62.556316 -9.343067) (xy 62.597094 -9.446965) (xy 62.645522 -9.547525)
			(xy 62.701329 -9.644185) (xy 62.764204 -9.736405) (xy 62.833794 -9.823668) (xy 62.909711 -9.905487)
			(xy 62.991529 -9.981403) (xy 63.078792 -10.050994) (xy 63.171011 -10.113868) (xy 63.267671 -10.169676)
			(xy 63.368231 -10.218104) (xy 63.472129 -10.258882) (xy 63.578784 -10.291782) (xy 63.687599 -10.31662)
			(xy 63.797966 -10.333257) (xy 63.909267 -10.341599) (xy 63.965074 -10.342118) (xy 65.96507 -10.342118)
			(xy 66.020879 -10.34161) (xy 66.132184 -10.333271) (xy 66.242554 -10.316637) (xy 66.351373 -10.291802)
			(xy 66.458032 -10.258905) (xy 66.561934 -10.218128) (xy 66.662499 -10.169702) (xy 66.759163 -10.113895)
			(xy 66.851386 -10.05102) (xy 66.938653 -9.98143) (xy 67.020476 -9.905512) (xy 67.096396 -9.823693)
			(xy 67.165989 -9.736428) (xy 67.228867 -9.644207) (xy 67.284677 -9.547545) (xy 67.333108 -9.446982)
			(xy 67.373888 -9.343081) (xy 67.406789 -9.236424) (xy 67.431628 -9.127605) (xy 67.448265 -9.017235)
			(xy 67.456608 -8.905931) (xy 67.457066 -8.850122) (xy 67.457066 0) (xy 67.457559 0.070354) (xy 67.465449 0.210841)
			(xy 67.481203 0.350665) (xy 67.504772 0.489385) (xy 67.536082 0.626565) (xy 67.575035 0.761774) (xy 67.621508 0.894587)
			(xy 67.675354 1.024584) (xy 67.736404 1.151358) (xy 67.804467 1.27451) (xy 67.879328 1.393651) (xy 67.960751 1.508408)
			(xy 68.04848 1.618419) (xy 68.14224 1.723337) (xy 68.241735 1.822834) (xy 68.346652 1.916595) (xy 68.456662 2.004326)
			(xy 68.571417 2.085751) (xy 68.690557 2.160614) (xy 68.813708 2.228678) (xy 68.940481 2.289731) (xy 69.070478 2.343579)
			(xy 69.203289 2.390053) (xy 69.338498 2.429008) (xy 69.475678 2.46032) (xy 69.614398 2.483892) (xy 69.754221 2.499648)
			(xy 69.894708 2.50754) (xy 69.965062 2.507996) (xy 85.96503 2.507996) (xy 86.035383 2.507502) (xy 86.175868 2.499611)
			(xy 86.31569 2.483855) (xy 86.454408 2.460284) (xy 86.591586 2.428973) (xy 86.726793 2.390019) (xy 86.859603 2.343545)
			(xy 86.989598 2.289698) (xy 87.11637 2.228647) (xy 87.239519 2.160584) (xy 87.358658 2.085722) (xy 87.473412 2.004299)
			(xy 87.58342 1.916569) (xy 87.688336 1.822809) (xy 87.78783 1.723314) (xy 87.881588 1.618397) (xy 87.969317 1.508388)
			(xy 88.050739 1.393633) (xy 88.125599 1.274493) (xy 88.193661 1.151343) (xy 88.254711 1.024571) (xy 88.308556 0.894575)
			(xy 88.355028 0.761764) (xy 88.39398 0.626557) (xy 88.42529 0.489378) (xy 88.448859 0.35066) (xy 88.464613 0.210838)
			(xy 88.472503 0.070353) (xy 88.473026 0) (xy 88.473026 -8.850122) (xy 88.473549 -8.905928) (xy 88.481891 -9.017228)
			(xy 88.498528 -9.127594) (xy 88.523365 -9.236408) (xy 88.556265 -9.343061) (xy 88.597043 -9.446957)
			(xy 88.645472 -9.547516) (xy 88.701279 -9.644174) (xy 88.764154 -9.736392) (xy 88.833745 -9.823653)
			(xy 88.909662 -9.90547) (xy 88.99148 -9.981384) (xy 89.078743 -10.050972) (xy 89.170963 -10.113844)
			(xy 89.267623 -10.169649) (xy 89.368183 -10.218074) (xy 89.472081 -10.258849) (xy 89.578735 -10.291746)
			(xy 89.687549 -10.316581) (xy 89.797915 -10.333214) (xy 89.909216 -10.341553) (xy 89.965022 -10.342118)
			(xy 91.965018 -10.342118) (xy 92.020825 -10.341596) (xy 92.132127 -10.333254) (xy 92.242494 -10.316617)
			(xy 92.351309 -10.29178) (xy 92.457964 -10.258881) (xy 92.561862 -10.218103) (xy 92.662422 -10.169675)
			(xy 92.759082 -10.113868) (xy 92.851302 -10.050993) (xy 92.938565 -9.981403) (xy 93.020384 -9.905487)
			(xy 93.096301 -9.823668) (xy 93.165891 -9.736405) (xy 93.228766 -9.644186) (xy 93.284573 -9.547526)
			(xy 93.333001 -9.446965) (xy 93.373779 -9.343067) (xy 93.406679 -9.236413) (xy 93.431517 -9.127597)
			(xy 93.448153 -9.01723) (xy 93.456495 -8.905929) (xy 93.457014 -8.850122) (xy 93.457014 0) (xy 93.457498 0.070354)
			(xy 93.465388 0.21084) (xy 93.481142 0.350663) (xy 93.504712 0.489383) (xy 93.536022 0.626563) (xy 93.574975 0.761771)
			(xy 93.621448 0.894583) (xy 93.675295 1.02458) (xy 93.736346 1.151353) (xy 93.804409 1.274504) (xy 93.87927 1.393645)
			(xy 93.960694 1.5084) (xy 94.048424 1.61841) (xy 94.142184 1.723327) (xy 94.24168 1.822823) (xy 94.346598 1.916583)
			(xy 94.456608 2.004312) (xy 94.571364 2.085735) (xy 94.690505 2.160596) (xy 94.813655 2.228659) (xy 94.940429 2.289709)
			(xy 95.070426 2.343555) (xy 95.203238 2.390028) (xy 95.338447 2.42898) (xy 95.475627 2.46029) (xy 95.614347 2.483859)
			(xy 95.75417 2.499613) (xy 95.894656 2.507502) (xy 95.96501 2.507996) (xy 124.06503 2.507996) (xy 124.135383 2.507502)
			(xy 124.275868 2.499611) (xy 124.41569 2.483855) (xy 124.554408 2.460284) (xy 124.691586 2.428973)
			(xy 124.826793 2.390019) (xy 124.959603 2.343545) (xy 125.089598 2.289698) (xy 125.21637 2.228647)
			(xy 125.339519 2.160584) (xy 125.458658 2.085722) (xy 125.573412 2.004299) (xy 125.68342 1.916569)
			(xy 125.788336 1.822809) (xy 125.88783 1.723314) (xy 125.981588 1.618397) (xy 126.069317 1.508388)
			(xy 126.150739 1.393633) (xy 126.225599 1.274493) (xy 126.293661 1.151343) (xy 126.354711 1.024571)
			(xy 126.408556 0.894575) (xy 126.455028 0.761764) (xy 126.49398 0.626557) (xy 126.52529 0.489378)
			(xy 126.548859 0.35066) (xy 126.564613 0.210838) (xy 126.572503 0.070353) (xy 126.573026 0) (xy 126.573026 -8.850122)
			(xy 126.573549 -8.905928) (xy 126.581891 -9.017228) (xy 126.598528 -9.127594) (xy 126.623365 -9.236408)
			(xy 126.656265 -9.343061) (xy 126.697043 -9.446957) (xy 126.745472 -9.547516) (xy 126.801279 -9.644174)
			(xy 126.864154 -9.736392) (xy 126.933745 -9.823653) (xy 127.009662 -9.90547) (xy 127.09148 -9.981384)
			(xy 127.178743 -10.050972) (xy 127.270963 -10.113844) (xy 127.367623 -10.169649) (xy 127.468183 -10.218074)
			(xy 127.572081 -10.258849) (xy 127.678735 -10.291746) (xy 127.787549 -10.316581) (xy 127.897915 -10.333214)
			(xy 128.009216 -10.341553) (xy 128.065022 -10.342118) (xy 130.065018 -10.342118) (xy 130.120825 -10.341596)
			(xy 130.232127 -10.333254) (xy 130.342494 -10.316617) (xy 130.451309 -10.29178) (xy 130.557964 -10.258881)
			(xy 130.661862 -10.218103) (xy 130.762422 -10.169675) (xy 130.859082 -10.113868) (xy 130.951302 -10.050993)
			(xy 131.038565 -9.981403) (xy 131.120384 -9.905487) (xy 131.196301 -9.823668) (xy 131.265891 -9.736405)
			(xy 131.328766 -9.644186) (xy 131.384573 -9.547526) (xy 131.433001 -9.446965) (xy 131.473779 -9.343067)
			(xy 131.506679 -9.236413) (xy 131.531517 -9.127597) (xy 131.548153 -9.01723) (xy 131.556495 -8.905929)
			(xy 131.557014 -8.850122) (xy 131.557014 0) (xy 131.557498 0.070354) (xy 131.565388 0.21084) (xy 131.581142 0.350663)
			(xy 131.604712 0.489383) (xy 131.636022 0.626563) (xy 131.674975 0.761771) (xy 131.721448 0.894583)
			(xy 131.775295 1.02458) (xy 131.836346 1.151353) (xy 131.904409 1.274504) (xy 131.97927 1.393645)
			(xy 132.060694 1.5084) (xy 132.148424 1.61841) (xy 132.242184 1.723327) (xy 132.34168 1.822823) (xy 132.446598 1.916583)
			(xy 132.556608 2.004312) (xy 132.671364 2.085735) (xy 132.790505 2.160596) (xy 132.913655 2.228659)
			(xy 133.040429 2.289709) (xy 133.170426 2.343555) (xy 133.303238 2.390028) (xy 133.438447 2.42898)
			(xy 133.575627 2.46029) (xy 133.714347 2.483859) (xy 133.85417 2.499613) (xy 133.994656 2.507502)
			(xy 134.06501 2.507996) (xy 150.064978 2.507996) (xy 150.135332 2.507512) (xy 150.27582 2.499624)
			(xy 150.415644 2.483871) (xy 150.554365 2.460302) (xy 150.691546 2.428993) (xy 150.826756 2.39004)
			(xy 150.959569 2.343568) (xy 151.089567 2.289722) (xy 151.216342 2.228672) (xy 151.339494 2.160609)
			(xy 151.458636 2.085748) (xy 151.573393 2.004324) (xy 151.683404 1.916594) (xy 151.788322 1.822834)
			(xy 151.887819 1.723338) (xy 151.98158 1.61842) (xy 152.069311 1.50841) (xy 152.150736 1.393654)
			(xy 152.225598 1.274513) (xy 152.293661 1.151361) (xy 152.354713 1.024587) (xy 152.40856 0.894589)
			(xy 152.455034 0.761777) (xy 152.493987 0.626567) (xy 152.525298 0.489386) (xy 152.548868 0.350666)
			(xy 152.564622 0.210842) (xy 152.572512 0.070354) (xy 152.572974 0) (xy 152.572974 -8.850122) (xy 152.573497 -8.905929)
			(xy 152.581839 -9.017231) (xy 152.598475 -9.127598) (xy 152.623313 -9.236413) (xy 152.656212 -9.343068)
			(xy 152.69699 -9.446966) (xy 152.745418 -9.547526) (xy 152.801225 -9.644186) (xy 152.8641 -9.736406)
			(xy 152.93369 -9.823669) (xy 153.009606 -9.905488) (xy 153.091425 -9.981405) (xy 153.178688 -10.050995)
			(xy 153.270907 -10.11387) (xy 153.367567 -10.169678) (xy 153.468127 -10.218107) (xy 153.572025 -10.258885)
			(xy 153.67868 -10.291785) (xy 153.787495 -10.316623) (xy 153.897862 -10.33326) (xy 154.009163 -10.341603)
			(xy 154.06497 -10.342118) (xy 156.064966 -10.342118) (xy 156.120775 -10.34161) (xy 156.23208 -10.333271)
			(xy 156.342451 -10.316638) (xy 156.45127 -10.291803) (xy 156.557929 -10.258906) (xy 156.661832 -10.21813)
			(xy 156.762396 -10.169703) (xy 156.859061 -10.113896) (xy 156.951284 -10.051022) (xy 157.038552 -9.981431)
			(xy 157.120374 -9.905514) (xy 157.196295 -9.823694) (xy 157.265888 -9.736429) (xy 157.328766 -9.644208)
			(xy 157.384577 -9.547546) (xy 157.433007 -9.446983) (xy 157.473787 -9.343082) (xy 157.506689 -9.236424)
			(xy 157.531528 -9.127606) (xy 157.548165 -9.017236) (xy 157.556508 -8.905931) (xy 157.556962 -8.850122)
			(xy 157.556962 0) (xy 157.557455 0.070354) (xy 157.565345 0.210841) (xy 157.581099 0.350665) (xy 157.604668 0.489385)
			(xy 157.635978 0.626566) (xy 157.674931 0.761775) (xy 157.721404 0.894587) (xy 157.77525 1.024585)
			(xy 157.8363 1.151359) (xy 157.904363 1.274511) (xy 157.979224 1.393652) (xy 158.060647 1.508409)
			(xy 158.148376 1.61842) (xy 158.242136 1.723339) (xy 158.341631 1.822835) (xy 158.446548 1.916597)
			(xy 158.556557 2.004328) (xy 158.671313 2.085753) (xy 158.790453 2.160616) (xy 158.913604 2.22868)
			(xy 159.040377 2.289733) (xy 159.170374 2.343581) (xy 159.303185 2.390056) (xy 159.438394 2.429011)
			(xy 159.575574 2.460324) (xy 159.714294 2.483895) (xy 159.854117 2.499652) (xy 159.994604 2.507544)
			(xy 160.064958 2.507996) (xy 176.064926 2.507996) (xy 176.135279 2.507502) (xy 176.275764 2.499611)
			(xy 176.415586 2.483856) (xy 176.554304 2.460285) (xy 176.691483 2.428974) (xy 176.82669 2.39002)
			(xy 176.9595 2.343547) (xy 177.089496 2.289699) (xy 177.216267 2.228648) (xy 177.339416 2.160585)
			(xy 177.458556 2.085724) (xy 177.57331 2.0043) (xy 177.683318 1.91657) (xy 177.788234 1.822811) (xy 177.887728 1.723315)
			(xy 177.981487 1.618398) (xy 178.069216 1.508389) (xy 178.150638 1.393634) (xy 178.225498 1.274494)
			(xy 178.29356 1.151344) (xy 178.35461 1.024572) (xy 178.408456 0.894576) (xy 178.454928 0.761765)
			(xy 178.49388 0.626558) (xy 178.52519 0.489379) (xy 178.548759 0.35066) (xy 178.564513 0.210838)
			(xy 178.572403 0.070353) (xy 178.572922 0) (xy 178.572922 -8.850122) (xy 178.573445 -8.905928) (xy 178.581787 -9.017229)
			(xy 178.598424 -9.127594) (xy 178.623261 -9.236408) (xy 178.656161 -9.343061) (xy 178.696939 -9.446958)
			(xy 178.745367 -9.547517) (xy 178.801175 -9.644175) (xy 178.86405 -9.736393) (xy 178.93364 -9.823654)
			(xy 179.009557 -9.905471) (xy 179.091376 -9.981386) (xy 179.178639 -10.050974) (xy 179.270859 -10.113846)
			(xy 179.367519 -10.169651) (xy 179.468079 -10.218077) (xy 179.571976 -10.258852) (xy 179.678631 -10.291749)
			(xy 179.787445 -10.316584) (xy 179.897811 -10.333218) (xy 180.009112 -10.341557) (xy 180.064918 -10.342118)
			(xy 182.064914 -10.342118) (xy 182.120721 -10.341596) (xy 182.232023 -10.333254) (xy 182.34239 -10.316618)
			(xy 182.451206 -10.291781) (xy 182.557861 -10.258882) (xy 182.661759 -10.218104) (xy 182.76232 -10.169676)
			(xy 182.85898 -10.113869) (xy 182.9512 -10.050995) (xy 183.038463 -9.981405) (xy 183.120282 -9.905488)
			(xy 183.196199 -9.823669) (xy 183.26579 -9.736406) (xy 183.328665 -9.644187) (xy 183.384473 -9.547527)
			(xy 183.432901 -9.446966) (xy 183.473679 -9.343068) (xy 183.506579 -9.236413) (xy 183.531416 -9.127598)
			(xy 183.548053 -9.017231) (xy 183.556395 -8.905929) (xy 183.55691 -8.850122) (xy 183.55691 0) (xy 183.557394 0.070354)
			(xy 183.565284 0.21084) (xy 183.581038 0.350664) (xy 183.604608 0.489383) (xy 183.635918 0.626563)
			(xy 183.674871 0.761772) (xy 183.721344 0.894584) (xy 183.775191 1.024581) (xy 183.836242 1.151354)
			(xy 183.904305 1.274505) (xy 183.979166 1.393646) (xy 184.06059 1.508401) (xy 184.14832 1.618411)
			(xy 184.24208 1.723329) (xy 184.341576 1.822824) (xy 184.446493 1.916584) (xy 184.556503 2.004314)
			(xy 184.671259 2.085737) (xy 184.7904 2.160598) (xy 184.913551 2.228661) (xy 185.040325 2.289712)
			(xy 185.170322 2.343558) (xy 185.303134 2.390031) (xy 185.438342 2.428983) (xy 185.575523 2.460294)
			(xy 185.714242 2.483863) (xy 185.854066 2.499617) (xy 185.994552 2.507506) (xy 186.064906 2.507996)
			(xy 202.064874 2.507996) (xy 202.135228 2.507512) (xy 202.275716 2.499624) (xy 202.41554 2.483871)
			(xy 202.554261 2.460303) (xy 202.691443 2.428993) (xy 202.826653 2.390041) (xy 202.959466 2.343569)
			(xy 203.089464 2.289723) (xy 203.216239 2.228673) (xy 203.339391 2.16061) (xy 203.458534 2.085749)
			(xy 203.573291 2.004326) (xy 203.683302 1.916596) (xy 203.788221 1.822836) (xy 203.887718 1.72334)
			(xy 203.981479 1.618422) (xy 204.06921 1.508412) (xy 204.150635 1.393655) (xy 204.225497 1.274514)
			(xy 204.293561 1.151362) (xy 204.354613 1.024588) (xy 204.40846 0.89459) (xy 204.454933 0.761778)
			(xy 204.493887 0.626568) (xy 204.525198 0.489387) (xy 204.548768 0.350666) (xy 204.564522 0.210842)
			(xy 204.572412 0.070354) (xy 204.57287 0) (xy 204.57287 -8.850122) (xy 204.573393 -8.905929) (xy 204.581735 -9.017231)
			(xy 204.598371 -9.127598) (xy 204.623209 -9.236413) (xy 204.656108 -9.343068) (xy 204.696886 -9.446966)
			(xy 204.745314 -9.547527) (xy 204.801121 -9.644187) (xy 204.863996 -9.736407) (xy 204.933586 -9.82367)
			(xy 205.009502 -9.905489) (xy 205.091321 -9.981407) (xy 205.178583 -10.050997) (xy 205.270803 -10.113872)
			(xy 205.367463 -10.16968) (xy 205.468023 -10.218109) (xy 205.571921 -10.258888) (xy 205.678575 -10.291788)
			(xy 205.78739 -10.316626) (xy 205.897757 -10.333264) (xy 206.009059 -10.341607) (xy 206.064866 -10.342118)
			(xy 208.065116 -10.342118) (xy 208.120923 -10.341596) (xy 208.232225 -10.333254) (xy 208.342592 -10.316618)
			(xy 208.451407 -10.29178) (xy 208.558062 -10.258881) (xy 208.66196 -10.218103) (xy 208.762521 -10.169676)
			(xy 208.859181 -10.113868) (xy 208.951401 -10.050994) (xy 209.038664 -9.981404) (xy 209.120483 -9.905487)
			(xy 209.1964 -9.823669) (xy 209.26599 -9.736406) (xy 209.328865 -9.644186) (xy 209.384673 -9.547526)
			(xy 209.433101 -9.446966) (xy 209.473879 -9.343068) (xy 209.506779 -9.236413) (xy 209.531617 -9.127598)
			(xy 209.548253 -9.017231) (xy 209.556595 -8.905929) (xy 209.557112 -8.850122) (xy 209.557112 0) (xy 209.557596 0.070354)
			(xy 209.565486 0.21084) (xy 209.58124 0.350663) (xy 209.60481 0.489383) (xy 209.63612 0.626563) (xy 209.675073 0.761772)
			(xy 209.721546 0.894583) (xy 209.775393 1.02458) (xy 209.836444 1.151354) (xy 209.904507 1.274505)
			(xy 209.979368 1.393645) (xy 210.060792 1.508401) (xy 210.148522 1.618411) (xy 210.242282 1.723328)
			(xy 210.341778 1.822823) (xy 210.446696 1.916583) (xy 210.556706 2.004313) (xy 210.671462 2.085736)
			(xy 210.790602 2.160597) (xy 210.913753 2.22866) (xy 211.040527 2.289711) (xy 211.170524 2.343557)
			(xy 211.303336 2.390029) (xy 211.438545 2.428982) (xy 211.575725 2.460292) (xy 211.714444 2.483861)
			(xy 211.854268 2.499615) (xy 211.994754 2.507504) (xy 212.065108 2.507996) (xy 240.164874 2.507996)
			(xy 240.235228 2.507512) (xy 240.375716 2.499624) (xy 240.51554 2.483871) (xy 240.654261 2.460303)
			(xy 240.791443 2.428993) (xy 240.926653 2.390041) (xy 241.059466 2.343569) (xy 241.189464 2.289723)
			(xy 241.316239 2.228673) (xy 241.439391 2.16061) (xy 241.558534 2.085749) (xy 241.673291 2.004326)
			(xy 241.783302 1.916596) (xy 241.888221 1.822836) (xy 241.987718 1.72334) (xy 242.081479 1.618422)
			(xy 242.16921 1.508412) (xy 242.250635 1.393655) (xy 242.325497 1.274514) (xy 242.393561 1.151362)
			(xy 242.454613 1.024588) (xy 242.50846 0.89459) (xy 242.554933 0.761778) (xy 242.593887 0.626568)
			(xy 242.625198 0.489387) (xy 242.648768 0.350666) (xy 242.664522 0.210842) (xy 242.672412 0.070354)
			(xy 242.67287 0) (xy 242.67287 -8.850122) (xy 242.673393 -8.905929) (xy 242.681735 -9.017231) (xy 242.698371 -9.127598)
			(xy 242.723209 -9.236413) (xy 242.756108 -9.343068) (xy 242.796886 -9.446966) (xy 242.845314 -9.547527)
			(xy 242.901121 -9.644187) (xy 242.963996 -9.736407) (xy 243.033586 -9.82367) (xy 243.109502 -9.905489)
			(xy 243.191321 -9.981407) (xy 243.278583 -10.050997) (xy 243.370803 -10.113872) (xy 243.467463 -10.16968)
			(xy 243.568023 -10.218109) (xy 243.671921 -10.258888) (xy 243.778575 -10.291788) (xy 243.88739 -10.316626)
			(xy 243.997757 -10.333264) (xy 244.109059 -10.341607) (xy 244.164866 -10.342118) (xy 246.165116 -10.342118)
			(xy 246.220923 -10.341596) (xy 246.332225 -10.333254) (xy 246.442592 -10.316618) (xy 246.551407 -10.29178)
			(xy 246.658062 -10.258881) (xy 246.76196 -10.218103) (xy 246.862521 -10.169676) (xy 246.959181 -10.113868)
			(xy 247.051401 -10.050994) (xy 247.138664 -9.981404) (xy 247.220483 -9.905487) (xy 247.2964 -9.823669)
			(xy 247.36599 -9.736406) (xy 247.428865 -9.644186) (xy 247.484673 -9.547526) (xy 247.533101 -9.446966)
			(xy 247.573879 -9.343068) (xy 247.606779 -9.236413) (xy 247.631617 -9.127598) (xy 247.648253 -9.017231)
			(xy 247.656595 -8.905929) (xy 247.657112 -8.850122) (xy 247.657112 0) (xy 247.657596 0.070354) (xy 247.665486 0.21084)
			(xy 247.68124 0.350663) (xy 247.70481 0.489383) (xy 247.73612 0.626563) (xy 247.775073 0.761772)
			(xy 247.821546 0.894583) (xy 247.875393 1.02458) (xy 247.936444 1.151354) (xy 248.004507 1.274505)
			(xy 248.079368 1.393645) (xy 248.160792 1.508401) (xy 248.248522 1.618411) (xy 248.342282 1.723328)
			(xy 248.441778 1.822823) (xy 248.546696 1.916583) (xy 248.656706 2.004313) (xy 248.771462 2.085736)
			(xy 248.890602 2.160597) (xy 249.013753 2.22866) (xy 249.140527 2.289711) (xy 249.270524 2.343557)
			(xy 249.403336 2.390029) (xy 249.538545 2.428982) (xy 249.675725 2.460292) (xy 249.814444 2.483861)
			(xy 249.954268 2.499615) (xy 250.094754 2.507504) (xy 250.165108 2.507996) (xy 266.165076 2.507996)
			(xy 266.23543 2.507512) (xy 266.375918 2.499624) (xy 266.515742 2.483871) (xy 266.654463 2.460303)
			(xy 266.791644 2.428993) (xy 266.926854 2.390041) (xy 267.059667 2.343569) (xy 267.189666 2.289723)
			(xy 267.31644 2.228672) (xy 267.439593 2.160609) (xy 267.558735 2.085749) (xy 267.673492 2.004325)
			(xy 267.783503 1.916595) (xy 267.888422 1.822835) (xy 267.987918 1.723339) (xy 268.08168 1.618421)
			(xy 268.169411 1.508411) (xy 268.250835 1.393655) (xy 268.325697 1.274513) (xy 268.393761 1.151362)
			(xy 268.454813 1.024588) (xy 268.50866 0.89459) (xy 268.555134 0.761777) (xy 268.594087 0.626568)
			(xy 268.625398 0.489387) (xy 268.648968 0.350666) (xy 268.664722 0.210842) (xy 268.672612 0.070354)
			(xy 268.673072 0) (xy 268.673072 -8.850122) (xy 268.673595 -8.905929) (xy 268.681937 -9.017231) (xy 268.698573 -9.127598)
			(xy 268.723411 -9.236413) (xy 268.75631 -9.343068) (xy 268.797088 -9.446966) (xy 268.845516 -9.547526)
			(xy 268.901323 -9.644187) (xy 268.964198 -9.736406) (xy 269.033788 -9.82367) (xy 269.109704 -9.905489)
			(xy 269.191523 -9.981406) (xy 269.278786 -10.050996) (xy 269.371005 -10.113871) (xy 269.467665 -10.169679)
			(xy 269.568225 -10.218108) (xy 269.672123 -10.258886) (xy 269.778777 -10.291787) (xy 269.887592 -10.316625)
			(xy 269.997959 -10.333262) (xy 270.109261 -10.341605) (xy 270.165068 -10.342118) (xy 272.165064 -10.342118)
			(xy 272.220873 -10.34161) (xy 272.332178 -10.333272) (xy 272.442549 -10.316638) (xy 272.551368 -10.291804)
			(xy 272.658028 -10.258906) (xy 272.76193 -10.21813) (xy 272.862495 -10.169703) (xy 272.95916 -10.113897)
			(xy 273.051383 -10.051022) (xy 273.138651 -9.981432) (xy 273.220473 -9.905515) (xy 273.296394 -9.823695)
			(xy 273.365988 -9.73643) (xy 273.428866 -9.644209) (xy 273.484676 -9.547546) (xy 273.533107 -9.446983)
			(xy 273.573887 -9.343082) (xy 273.606789 -9.236425) (xy 273.631628 -9.127606) (xy 273.648265 -9.017236)
			(xy 273.656608 -8.905931) (xy 273.65706 -8.850122) (xy 273.65706 0) (xy 273.657553 0.070354) (xy 273.665443 0.210841)
			(xy 273.681197 0.350665) (xy 273.704766 0.489385) (xy 273.736076 0.626566) (xy 273.775029 0.761775)
			(xy 273.821502 0.894588) (xy 273.875348 1.024585) (xy 273.936398 1.15136) (xy 274.004461 1.274511)
			(xy 274.079321 1.393653) (xy 274.160745 1.50841) (xy 274.248474 1.618421) (xy 274.342234 1.723339)
			(xy 274.441729 1.822836) (xy 274.546646 1.916598) (xy 274.656655 2.004329) (xy 274.771411 2.085754)
			(xy 274.890551 2.160617) (xy 275.013701 2.228682) (xy 275.140474 2.289734) (xy 275.270471 2.343583)
			(xy 275.403283 2.390058) (xy 275.538492 2.429013) (xy 275.675672 2.460325) (xy 275.814392 2.483897)
			(xy 275.954215 2.499654) (xy 276.094702 2.507545) (xy 276.165056 2.507996) (xy 292.165024 2.507996)
			(xy 292.235377 2.507502) (xy 292.375862 2.499611) (xy 292.515684 2.483856) (xy 292.654403 2.460285)
			(xy 292.791581 2.428974) (xy 292.926788 2.390021) (xy 293.059599 2.343547) (xy 293.189594 2.2897)
			(xy 293.316366 2.228649) (xy 293.439515 2.160586) (xy 293.558655 2.085724) (xy 293.673409 2.004301)
			(xy 293.783417 1.916571) (xy 293.888334 1.822811) (xy 293.987828 1.723316) (xy 294.081587 1.618399)
			(xy 294.169315 1.50839) (xy 294.250738 1.393635) (xy 294.325598 1.274495) (xy 294.39366 1.151345)
			(xy 294.45471 1.024572) (xy 294.508556 0.894576) (xy 294.555028 0.761765) (xy 294.59398 0.626558)
			(xy 294.62529 0.489379) (xy 294.648859 0.35066) (xy 294.664613 0.210839) (xy 294.672503 0.070353)
			(xy 294.67302 0) (xy 294.67302 -8.850122) (xy 294.673543 -8.905928) (xy 294.681885 -9.017229) (xy 294.698522 -9.127594)
			(xy 294.723359 -9.236408) (xy 294.756259 -9.343062) (xy 294.797037 -9.446958) (xy 294.845465 -9.547517)
			(xy 294.901273 -9.644176) (xy 294.964148 -9.736394) (xy 295.033738 -9.823655) (xy 295.109655 -9.905472)
			(xy 295.191474 -9.981387) (xy 295.278737 -10.050975) (xy 295.370956 -10.113847) (xy 295.467616 -10.169652)
			(xy 295.568176 -10.218078) (xy 295.672074 -10.258853) (xy 295.778728 -10.291751) (xy 295.887543 -10.316586)
			(xy 295.997909 -10.333219) (xy 296.10921 -10.341559) (xy 296.165016 -10.342118) (xy 298.165012 -10.342118)
			(xy 298.220819 -10.341596) (xy 298.332121 -10.333254) (xy 298.442488 -10.316618) (xy 298.551304 -10.291781)
			(xy 298.657959 -10.258882) (xy 298.761858 -10.218105) (xy 298.862418 -10.169677) (xy 298.959079 -10.11387)
			(xy 299.051299 -10.050995) (xy 299.138562 -9.981405) (xy 299.220382 -9.905489) (xy 299.296299 -9.82367)
			(xy 299.365889 -9.736407) (xy 299.428764 -9.644188) (xy 299.484572 -9.547527) (xy 299.533001 -9.446967)
			(xy 299.573779 -9.343069) (xy 299.606679 -9.236414) (xy 299.631516 -9.127598) (xy 299.648153 -9.017231)
			(xy 299.656495 -8.905929) (xy 299.657008 -8.850122) (xy 299.657008 0) (xy 299.657492 0.070354) (xy 299.665382 0.21084)
			(xy 299.681136 0.350664) (xy 299.704706 0.489383) (xy 299.736016 0.626564) (xy 299.774969 0.761772)
			(xy 299.821442 0.894584) (xy 299.875289 1.024581) (xy 299.93634 1.151355) (xy 300.004403 1.274505)
			(xy 300.079264 1.393646) (xy 300.160688 1.508402) (xy 300.248418 1.618412) (xy 300.342178 1.723329)
			(xy 300.441673 1.822825) (xy 300.546591 1.916585) (xy 300.656601 2.004315) (xy 300.771357 2.085738)
			(xy 300.890498 2.160599) (xy 301.013649 2.228662) (xy 301.140423 2.289713) (xy 301.27042 2.343559)
			(xy 301.403232 2.390032) (xy 301.53844 2.428985) (xy 301.67562 2.460295) (xy 301.81434 2.483864)
			(xy 301.954163 2.499618) (xy 302.09465 2.507508) (xy 302.165004 2.507996) (xy 318.164972 2.507996)
			(xy 318.235326 2.507512) (xy 318.375814 2.499624) (xy 318.515639 2.483871) (xy 318.65436 2.460303)
			(xy 318.791541 2.428994) (xy 318.926751 2.390042) (xy 319.059564 2.34357) (xy 319.189563 2.289724)
			(xy 319.316338 2.228673) (xy 319.43949 2.160611) (xy 319.558633 2.08575) (xy 319.67339 2.004327)
			(xy 319.783401 1.916597) (xy 319.88832 1.822836) (xy 319.987817 1.723341) (xy 320.081579 1.618423)
			(xy 320.16931 1.508412) (xy 320.250734 1.393656) (xy 320.325597 1.274514) (xy 320.393661 1.151363)
			(xy 320.454712 1.024589) (xy 320.50856 0.894591) (xy 320.555033 0.761778) (xy 320.593987 0.626568)
			(xy 320.625298 0.489387) (xy 320.648868 0.350666) (xy 320.664622 0.210842) (xy 320.672512 0.070354)
			(xy 320.672968 0) (xy 320.672968 -8.850122) (xy 320.673491 -8.905929) (xy 320.681833 -9.017231) (xy 320.698469 -9.127598)
			(xy 320.723307 -9.236413) (xy 320.756206 -9.343068) (xy 320.796984 -9.446967) (xy 320.845412 -9.547527)
			(xy 320.901219 -9.644188) (xy 320.964093 -9.736408) (xy 321.033684 -9.823671) (xy 321.1096 -9.90549)
			(xy 321.191418 -9.981407) (xy 321.278681 -10.050998) (xy 321.3709 -10.113873) (xy 321.46756 -10.169682)
			(xy 321.56812 -10.21811) (xy 321.672018 -10.258889) (xy 321.778673 -10.29179) (xy 321.887488 -10.316628)
			(xy 321.997855 -10.333266) (xy 322.109157 -10.341609) (xy 322.164964 -10.342118) (xy 324.16496 -10.342118)
			(xy 324.220769 -10.34161) (xy 324.332074 -10.333272) (xy 324.442446 -10.316639) (xy 324.551265 -10.291805)
			(xy 324.657925 -10.258907) (xy 324.761827 -10.218131) (xy 324.862393 -10.169705) (xy 324.959057 -10.113898)
			(xy 325.051281 -10.051024) (xy 325.138549 -9.981433) (xy 325.220372 -9.905516) (xy 325.296293 -9.823696)
			(xy 325.365887 -9.736431) (xy 325.428765 -9.64421) (xy 325.484576 -9.547547) (xy 325.533007 -9.446984)
			(xy 325.573787 -9.343083) (xy 325.606689 -9.236425) (xy 325.631528 -9.127607) (xy 325.648165 -9.017236)
			(xy 325.656508 -8.905931) (xy 325.656956 -8.850122) (xy 325.656956 0) (xy 325.657449 0.070354) (xy 325.665339 0.210841)
			(xy 325.681093 0.350665) (xy 325.704662 0.489386) (xy 325.735972 0.626566) (xy 325.774925 0.761776)
			(xy 325.821398 0.894588) (xy 325.875244 1.024586) (xy 325.936294 1.15136) (xy 326.004357 1.274512)
			(xy 326.079217 1.393654) (xy 326.16064 1.508411) (xy 326.24837 1.618422) (xy 326.342129 1.723341)
			(xy 326.441624 1.822838) (xy 326.546542 1.916599) (xy 326.656551 2.004331) (xy 326.771306 2.085756)
			(xy 326.890447 2.160619) (xy 327.013597 2.228684) (xy 327.14037 2.289737) (xy 327.270367 2.343585)
			(xy 327.403179 2.39006) (xy 327.538387 2.429016) (xy 327.675567 2.460328) (xy 327.814287 2.4839)
			(xy 327.954111 2.499657) (xy 328.094598 2.507549) (xy 328.164952 2.507996) (xy 356.264972 2.507996)
			(xy 356.335326 2.507512) (xy 356.475814 2.499624) (xy 356.615639 2.483871) (xy 356.75436 2.460303)
			(xy 356.891541 2.428994) (xy 357.026751 2.390042) (xy 357.159564 2.34357) (xy 357.289563 2.289724)
			(xy 357.416338 2.228673) (xy 357.53949 2.160611) (xy 357.658633 2.08575) (xy 357.77339 2.004327)
			(xy 357.883401 1.916597) (xy 357.98832 1.822836) (xy 358.087817 1.723341) (xy 358.181579 1.618423)
			(xy 358.26931 1.508412) (xy 358.350734 1.393656) (xy 358.425597 1.274514) (xy 358.493661 1.151363)
			(xy 358.554712 1.024589) (xy 358.60856 0.894591) (xy 358.655033 0.761778) (xy 358.693987 0.626568)
			(xy 358.725298 0.489387) (xy 358.748868 0.350666) (xy 358.764622 0.210842) (xy 358.772512 0.070354)
			(xy 358.772968 0) (xy 358.772968 -8.850122) (xy 358.773491 -8.905929) (xy 358.781833 -9.017231) (xy 358.798469 -9.127598)
			(xy 358.823307 -9.236413) (xy 358.856206 -9.343068) (xy 358.896984 -9.446967) (xy 358.945412 -9.547527)
			(xy 359.001219 -9.644188) (xy 359.064093 -9.736408) (xy 359.133684 -9.823671) (xy 359.2096 -9.90549)
			(xy 359.291418 -9.981407) (xy 359.378681 -10.050998) (xy 359.4709 -10.113873) (xy 359.56756 -10.169682)
			(xy 359.66812 -10.21811) (xy 359.772018 -10.258889) (xy 359.878673 -10.29179) (xy 359.987488 -10.316628)
			(xy 360.097855 -10.333266) (xy 360.209157 -10.341609) (xy 360.264964 -10.342118) (xy 362.26496 -10.342118)
			(xy 362.320769 -10.34161) (xy 362.432074 -10.333272) (xy 362.542446 -10.316639) (xy 362.651265 -10.291805)
			(xy 362.757925 -10.258907) (xy 362.861827 -10.218131) (xy 362.962393 -10.169705) (xy 363.059057 -10.113898)
			(xy 363.151281 -10.051024) (xy 363.238549 -9.981433) (xy 363.320372 -9.905516) (xy 363.396293 -9.823696)
			(xy 363.465887 -9.736431) (xy 363.528765 -9.64421) (xy 363.584576 -9.547547) (xy 363.633007 -9.446984)
			(xy 363.673787 -9.343083) (xy 363.706689 -9.236425) (xy 363.731528 -9.127607) (xy 363.748165 -9.017236)
			(xy 363.756508 -8.905931) (xy 363.756956 -8.850122) (xy 363.756956 0) (xy 363.757449 0.070354) (xy 363.765339 0.210841)
			(xy 363.781093 0.350665) (xy 363.804662 0.489386) (xy 363.835972 0.626566) (xy 363.874925 0.761776)
			(xy 363.921398 0.894588) (xy 363.975244 1.024586) (xy 364.036294 1.15136) (xy 364.104357 1.274512)
			(xy 364.179217 1.393654) (xy 364.26064 1.508411) (xy 364.34837 1.618422) (xy 364.442129 1.723341)
			(xy 364.541624 1.822838) (xy 364.646542 1.916599) (xy 364.756551 2.004331) (xy 364.871306 2.085756)
			(xy 364.990447 2.160619) (xy 365.113597 2.228684) (xy 365.24037 2.289737) (xy 365.370367 2.343585)
			(xy 365.503179 2.39006) (xy 365.638387 2.429016) (xy 365.775567 2.460328) (xy 365.914287 2.4839)
			(xy 366.054111 2.499657) (xy 366.194598 2.507549) (xy 366.264952 2.507996) (xy 382.26492 2.507996)
			(xy 382.335273 2.507502) (xy 382.475759 2.499612) (xy 382.615581 2.483856) (xy 382.754299 2.460286)
			(xy 382.891478 2.428975) (xy 383.026685 2.390022) (xy 383.159496 2.343548) (xy 383.289491 2.289701)
			(xy 383.416264 2.22865) (xy 383.539413 2.160587) (xy 383.658552 2.085726) (xy 383.773307 2.004302)
			(xy 383.883316 1.916573) (xy 383.988232 1.822813) (xy 384.087726 1.723318) (xy 384.181485 1.6184)
			(xy 384.269214 1.508391) (xy 384.350637 1.393636) (xy 384.425497 1.274496) (xy 384.493559 1.151346)
			(xy 384.554609 1.024573) (xy 384.608455 0.894577) (xy 384.654928 0.761766) (xy 384.69388 0.626559)
			(xy 384.72519 0.48938) (xy 384.748759 0.350661) (xy 384.764513 0.210839) (xy 384.772403 0.070353)
			(xy 384.772916 0) (xy 384.772916 -8.850122) (xy 384.773439 -8.905928) (xy 384.781781 -9.017229) (xy 384.798418 -9.127595)
			(xy 384.823255 -9.236409) (xy 384.856155 -9.343062) (xy 384.896933 -9.446959) (xy 384.945361 -9.547518)
			(xy 385.001169 -9.644177) (xy 385.064044 -9.736395) (xy 385.133634 -9.823656) (xy 385.209551 -9.905473)
			(xy 385.29137 -9.981388) (xy 385.378633 -10.050977) (xy 385.470852 -10.113849) (xy 385.567512 -10.169655)
			(xy 385.668072 -10.218081) (xy 385.77197 -10.258856) (xy 385.878624 -10.291754) (xy 385.987439 -10.316589)
			(xy 386.097805 -10.333223) (xy 386.209106 -10.341563) (xy 386.264912 -10.342118) (xy 388.264908 -10.342118)
			(xy 388.320715 -10.341596) (xy 388.432017 -10.333255) (xy 388.542385 -10.316619) (xy 388.651201 -10.291782)
			(xy 388.757856 -10.258883) (xy 388.861755 -10.218106) (xy 388.962316 -10.169678) (xy 389.058977 -10.113871)
			(xy 389.151197 -10.050997) (xy 389.238461 -9.981407) (xy 389.32028 -9.90549) (xy 389.396198 -9.823671)
			(xy 389.465789 -9.736408) (xy 389.528664 -9.644189) (xy 389.584472 -9.547528) (xy 389.6329 -9.446968)
			(xy 389.673678 -9.343069) (xy 389.706579 -9.236414) (xy 389.731416 -9.127599) (xy 389.748053 -9.017231)
			(xy 389.756395 -8.905929) (xy 389.756904 -8.850122) (xy 389.756904 0) (xy 389.757397 0.070354) (xy 389.765287 0.21084)
			(xy 389.781041 0.350663) (xy 389.80461 0.489382) (xy 389.835921 0.626562) (xy 389.874874 0.76177)
			(xy 389.921346 0.894581) (xy 389.975193 1.024578) (xy 390.036243 1.151351) (xy 390.104306 1.274502)
			(xy 390.179167 1.393642) (xy 390.260591 1.508398) (xy 390.34832 1.618407) (xy 390.44208 1.723325)
			(xy 390.541575 1.82282) (xy 390.646493 1.91658) (xy 390.756502 2.004309) (xy 390.871258 2.085733)
			(xy 390.990398 2.160594) (xy 391.113549 2.228657) (xy 391.240322 2.289707) (xy 391.370319 2.343554)
			(xy 391.50313 2.390026) (xy 391.638338 2.428979) (xy 391.775518 2.46029) (xy 391.914237 2.483859)
			(xy 392.05406 2.499613) (xy 392.194546 2.507503) (xy 392.2649 2.507996) (xy 408.265122 2.507996)
			(xy 408.335475 2.507502) (xy 408.475961 2.499611) (xy 408.615782 2.483856) (xy 408.754501 2.460286)
			(xy 408.89168 2.428975) (xy 409.026887 2.390021) (xy 409.159697 2.343548) (xy 409.289693 2.289701)
			(xy 409.416465 2.22865) (xy 409.539614 2.160586) (xy 409.658754 2.085725) (xy 409.773508 2.004302)
			(xy 409.883516 1.916572) (xy 409.988433 1.822812) (xy 410.087927 1.723317) (xy 410.181686 1.6184)
			(xy 410.269415 1.50839) (xy 410.350837 1.393635) (xy 410.425697 1.274495) (xy 410.49376 1.151345)
			(xy 410.55481 1.024573) (xy 410.608655 0.894577) (xy 410.655128 0.761766) (xy 410.69408 0.626558)
			(xy 410.72539 0.489379) (xy 410.748959 0.350661) (xy 410.764713 0.210839) (xy 410.772603 0.070353)
			(xy 410.773118 0) (xy 410.773118 -8.850122) (xy 410.773641 -8.905928) (xy 410.781983 -9.017229) (xy 410.79862 -9.127595)
			(xy 410.823457 -9.236408) (xy 410.856357 -9.343062) (xy 410.897135 -9.446959) (xy 410.945563 -9.547518)
			(xy 411.001371 -9.644176) (xy 411.064246 -9.736394) (xy 411.133836 -9.823656) (xy 411.209753 -9.905472)
			(xy 411.291572 -9.981387) (xy 411.378835 -10.050976) (xy 411.471054 -10.113848) (xy 411.567714 -10.169653)
			(xy 411.668274 -10.218079) (xy 411.772172 -10.258855) (xy 411.878826 -10.291752) (xy 411.987641 -10.316587)
			(xy 412.098007 -10.333221) (xy 412.209308 -10.341561) (xy 412.265114 -10.342118) (xy 414.26511 -10.342118)
			(xy 414.320917 -10.341596) (xy 414.432219 -10.333254) (xy 414.542587 -10.316619) (xy 414.651402 -10.291782)
			(xy 414.758058 -10.258883) (xy 414.861956 -10.218105) (xy 414.962517 -10.169678) (xy 415.059178 -10.11387)
			(xy 415.151398 -10.050996) (xy 415.238662 -9.981406) (xy 415.320481 -9.905489) (xy 415.396398 -9.823671)
			(xy 415.465989 -9.736408) (xy 415.528864 -9.644188) (xy 415.584672 -9.547528) (xy 415.6331 -9.446967)
			(xy 415.673879 -9.343069) (xy 415.706779 -9.236414) (xy 415.731616 -9.127598) (xy 415.748253 -9.017231)
			(xy 415.756595 -8.905929) (xy 415.757106 -8.850122) (xy 415.757106 0) (xy 415.75759 0.070354) (xy 415.76548 0.210841)
			(xy 415.781234 0.350664) (xy 415.804804 0.489384) (xy 415.836114 0.626564) (xy 415.875067 0.761772)
			(xy 415.92154 0.894584) (xy 415.975387 1.024581) (xy 416.036438 1.151355) (xy 416.104501 1.274506)
			(xy 416.179362 1.393647) (xy 416.260785 1.508402) (xy 416.348515 1.618412) (xy 416.442276 1.72333)
			(xy 416.541771 1.822826) (xy 416.646689 1.916586) (xy 416.756699 2.004316) (xy 416.871455 2.085739)
			(xy 416.990596 2.1606) (xy 417.113747 2.228663) (xy 417.24052 2.289714) (xy 417.370518 2.343561)
			(xy 417.503329 2.390034) (xy 417.638538 2.428986) (xy 417.775718 2.460297) (xy 417.914438 2.483866)
			(xy 418.054261 2.49962) (xy 418.194748 2.50751) (xy 418.265102 2.507996) (xy 434.26507 2.507996)
			(xy 434.335425 2.507513) (xy 434.475912 2.499625) (xy 434.615737 2.483872) (xy 434.754458 2.460304)
			(xy 434.89164 2.428994) (xy 435.02685 2.390042) (xy 435.159663 2.34357) (xy 435.289662 2.289724)
			(xy 435.416437 2.228674) (xy 435.539589 2.160612) (xy 435.658732 2.085751) (xy 435.773489 2.004327)
			(xy 435.8835 1.916597) (xy 435.988419 1.822837) (xy 436.087916 1.723341) (xy 436.181678 1.618423)
			(xy 436.269409 1.508413) (xy 436.350834 1.393656) (xy 436.425696 1.274515) (xy 436.49376 1.151363)
			(xy 436.554812 1.024589) (xy 436.60866 0.894591) (xy 436.655133 0.761778) (xy 436.694087 0.626569)
			(xy 436.725398 0.489387) (xy 436.748967 0.350667) (xy 436.764722 0.210842) (xy 436.772612 0.070355)
			(xy 436.773066 0) (xy 436.773066 -8.850122) (xy 436.773589 -8.905929) (xy 436.781931 -9.017231) (xy 436.798567 -9.127598)
			(xy 436.823405 -9.236414) (xy 436.856304 -9.343069) (xy 436.897082 -9.446967) (xy 436.94551 -9.547528)
			(xy 437.001317 -9.644188) (xy 437.064191 -9.736408) (xy 437.133781 -9.823672) (xy 437.209698 -9.905491)
			(xy 437.291516 -9.981408) (xy 437.378779 -10.050999) (xy 437.470998 -10.113874) (xy 437.567658 -10.169683)
			(xy 437.668218 -10.218112) (xy 437.772116 -10.25889) (xy 437.878771 -10.291791) (xy 437.987586 -10.31663)
			(xy 438.097953 -10.333267) (xy 438.209255 -10.341611) (xy 438.265062 -10.342118) (xy 440.265058 -10.342118)
			(xy 440.320867 -10.34161) (xy 440.432173 -10.333272) (xy 440.542544 -10.316639) (xy 440.651364 -10.291805)
			(xy 440.758023 -10.258908) (xy 440.861926 -10.218132) (xy 440.962491 -10.169705) (xy 441.059156 -10.113899)
			(xy 441.151381 -10.051025) (xy 441.238648 -9.981434) (xy 441.320471 -9.905517) (xy 441.396392 -9.823697)
			(xy 441.465987 -9.736432) (xy 441.528865 -9.64421) (xy 441.584675 -9.547548) (xy 441.633106 -9.446985)
			(xy 441.673887 -9.343084) (xy 441.706788 -9.236425) (xy 441.731628 -9.127607) (xy 441.748265 -9.017236)
			(xy 441.756608 -8.905931) (xy 441.757054 -8.850122) (xy 441.757054 0) (xy 441.757538 0.070353) (xy 441.765428 0.210839)
			(xy 441.781182 0.350661) (xy 441.804752 0.48938) (xy 441.836062 0.626559) (xy 441.875016 0.761767)
			(xy 441.921489 0.894578) (xy 441.975336 1.024574) (xy 442.036387 1.151346) (xy 442.10445 1.274495)
			(xy 442.179312 1.393635) (xy 442.260736 1.508389) (xy 442.348466 1.618398) (xy 442.442227 1.723314)
			(xy 442.541722 1.822808) (xy 442.64664 1.916566) (xy 442.756651 2.004294) (xy 442.871407 2.085716)
			(xy 442.990548 2.160575) (xy 443.113699 2.228636) (xy 443.240472 2.289685) (xy 443.370469 2.343529)
			(xy 443.503281 2.39) (xy 443.638489 2.42895) (xy 443.775669 2.460258) (xy 443.914388 2.483825) (xy 444.054211 2.499576)
			(xy 444.194697 2.507463) (xy 444.26505 2.507996) (xy 465.600034 2.507996) (xy 465.65584 2.508519)
			(xy 465.767141 2.516862) (xy 465.877506 2.533499) (xy 465.98632 2.558338) (xy 466.092974 2.591238)
			(xy 466.19687 2.632016) (xy 466.297429 2.680445) (xy 466.394088 2.736252) (xy 466.486306 2.799127)
			(xy 466.573567 2.868717) (xy 466.655384 2.944634) (xy 466.7313 3.026452) (xy 466.800888 3.113715)
			(xy 466.863762 3.205934) (xy 466.919568 3.302594) (xy 466.967994 3.403154) (xy 467.008771 3.507051)
			(xy 467.041669 3.613705) (xy 467.066505 3.722519) (xy 467.083141 3.832885) (xy 467.091482 3.944186)
			(xy 467.09203 3.999992) (xy 467.09203 24.157686) (xy 467.091509 24.213494) (xy 467.083169 24.324797)
			(xy 467.066535 24.435167) (xy 467.041699 24.543984) (xy 467.008801 24.650641) (xy 466.968025 24.754542)
			(xy 466.919598 24.855105) (xy 466.863791 24.951768) (xy 466.800917 25.04399) (xy 466.731327 25.131255)
			(xy 466.655411 25.213077) (xy 466.573592 25.288996) (xy 466.486328 25.358589) (xy 466.394108 25.421466)
			(xy 466.297447 25.477275) (xy 466.196886 25.525705) (xy 466.092987 25.566485) (xy 465.986331 25.599387)
			(xy 465.877514 25.624226) (xy 465.767145 25.640863) (xy 465.655842 25.649207) (xy 465.600034 25.649682)
			(xy 160.11398 25.649682) (xy 160.058174 25.64916) (xy 159.946873 25.640817) (xy 159.836507 25.624181)
			(xy 159.727693 25.599343) (xy 159.62104 25.566443) (xy 159.517143 25.525665) (xy 159.416584 25.477237)
			(xy 159.319925 25.42143) (xy 159.227707 25.358555) (xy 159.140445 25.288965) (xy 159.058628 25.213048)
			(xy 158.982713 25.131229) (xy 158.913125 25.043966) (xy 158.850252 24.951746) (xy 158.794447 24.855086)
			(xy 158.746021 24.754526) (xy 158.705245 24.650628) (xy 158.672348 24.543974) (xy 158.647513 24.435159)
			(xy 158.630879 24.324793) (xy 158.622539 24.213492) (xy 158.621984 24.157686) (xy 158.621984 21.802649)
			(xy 269.304757 21.802649) (xy 269.304757 21.888399) (xy 269.312669 21.973782) (xy 269.328425 22.058072)
			(xy 269.351892 22.140548) (xy 269.382868 22.220507) (xy 269.42109 22.297267) (xy 269.466231 22.370173)
			(xy 269.517907 22.438602) (xy 269.575676 22.501972) (xy 269.639046 22.559741) (xy 269.707475 22.611417)
			(xy 269.780381 22.656558) (xy 269.857141 22.69478) (xy 269.9371 22.725756) (xy 270.019576 22.749223)
			(xy 270.103866 22.764979) (xy 270.189249 22.772891) (xy 270.274999 22.772891) (xy 270.360382 22.764979)
			(xy 270.444672 22.749223) (xy 270.527148 22.725756) (xy 270.607107 22.69478) (xy 270.683867 22.656558)
			(xy 270.756773 22.611417) (xy 270.825202 22.559741) (xy 270.888572 22.501972) (xy 270.946341 22.438602)
			(xy 270.998017 22.370173) (xy 271.043158 22.297267) (xy 271.08138 22.220507) (xy 271.112356 22.140548)
			(xy 271.135823 22.058072) (xy 271.151579 21.973782) (xy 271.159491 21.888399) (xy 271.159986 21.845524)
			(xy 271.159491 21.802649) (xy 275.654757 21.802649) (xy 275.654757 21.888399) (xy 275.662669 21.973782)
			(xy 275.678425 22.058072) (xy 275.701892 22.140548) (xy 275.732868 22.220507) (xy 275.77109 22.297267)
			(xy 275.816231 22.370173) (xy 275.867907 22.438602) (xy 275.925676 22.501972) (xy 275.989046 22.559741)
			(xy 276.057475 22.611417) (xy 276.130381 22.656558) (xy 276.207141 22.69478) (xy 276.2871 22.725756)
			(xy 276.369576 22.749223) (xy 276.453866 22.764979) (xy 276.539249 22.772891) (xy 276.624999 22.772891)
			(xy 276.710382 22.764979) (xy 276.794672 22.749223) (xy 276.877148 22.725756) (xy 276.957107 22.69478)
			(xy 277.033867 22.656558) (xy 277.106773 22.611417) (xy 277.175202 22.559741) (xy 277.238572 22.501972)
			(xy 277.296341 22.438602) (xy 277.348017 22.370173) (xy 277.393158 22.297267) (xy 277.43138 22.220507)
			(xy 277.462356 22.140548) (xy 277.485823 22.058072) (xy 277.501579 21.973782) (xy 277.509491 21.888399)
			(xy 277.509986 21.845524) (xy 277.509491 21.802649) (xy 277.508832 21.795537) (xy 308.364877 21.795537)
			(xy 308.364877 21.881287) (xy 308.372789 21.96667) (xy 308.388545 22.05096) (xy 308.412012 22.133436)
			(xy 308.442988 22.213395) (xy 308.48121 22.290155) (xy 308.526351 22.363061) (xy 308.578027 22.43149)
			(xy 308.635796 22.49486) (xy 308.699166 22.552629) (xy 308.767595 22.604305) (xy 308.840501 22.649446)
			(xy 308.917261 22.687668) (xy 308.99722 22.718644) (xy 309.079696 22.742111) (xy 309.163986 22.757867)
			(xy 309.249369 22.765779) (xy 309.335119 22.765779) (xy 309.420502 22.757867) (xy 309.504792 22.742111)
			(xy 309.587268 22.718644) (xy 309.667227 22.687668) (xy 309.743987 22.649446) (xy 309.816893 22.604305)
			(xy 309.885322 22.552629) (xy 309.948692 22.49486) (xy 310.006461 22.43149) (xy 310.058137 22.363061)
			(xy 310.103278 22.290155) (xy 310.1415 22.213395) (xy 310.172476 22.133436) (xy 310.195943 22.05096)
			(xy 310.211699 21.96667) (xy 310.219611 21.881287) (xy 310.220106 21.838412) (xy 310.219611 21.795537)
			(xy 314.714877 21.795537) (xy 314.714877 21.881287) (xy 314.722789 21.96667) (xy 314.738545 22.05096)
			(xy 314.762012 22.133436) (xy 314.792988 22.213395) (xy 314.83121 22.290155) (xy 314.876351 22.363061)
			(xy 314.928027 22.43149) (xy 314.985796 22.49486) (xy 315.049166 22.552629) (xy 315.117595 22.604305)
			(xy 315.190501 22.649446) (xy 315.267261 22.687668) (xy 315.34722 22.718644) (xy 315.429696 22.742111)
			(xy 315.513986 22.757867) (xy 315.599369 22.765779) (xy 315.685119 22.765779) (xy 315.770502 22.757867)
			(xy 315.854792 22.742111) (xy 315.937268 22.718644) (xy 316.017227 22.687668) (xy 316.093987 22.649446)
			(xy 316.166893 22.604305) (xy 316.235322 22.552629) (xy 316.298692 22.49486) (xy 316.356461 22.43149)
			(xy 316.408137 22.363061) (xy 316.453278 22.290155) (xy 316.4915 22.213395) (xy 316.522476 22.133436)
			(xy 316.545943 22.05096) (xy 316.561699 21.96667) (xy 316.569611 21.881287) (xy 316.570106 21.838412)
			(xy 316.569693 21.802649) (xy 334.455757 21.802649) (xy 334.455757 21.888399) (xy 334.463669 21.973782)
			(xy 334.479425 22.058072) (xy 334.502892 22.140548) (xy 334.533868 22.220507) (xy 334.57209 22.297267)
			(xy 334.617231 22.370173) (xy 334.668907 22.438602) (xy 334.726676 22.501972) (xy 334.790046 22.559741)
			(xy 334.858475 22.611417) (xy 334.931381 22.656558) (xy 335.008141 22.69478) (xy 335.0881 22.725756)
			(xy 335.170576 22.749223) (xy 335.254866 22.764979) (xy 335.340249 22.772891) (xy 335.425999 22.772891)
			(xy 335.511382 22.764979) (xy 335.595672 22.749223) (xy 335.678148 22.725756) (xy 335.758107 22.69478)
			(xy 335.834867 22.656558) (xy 335.907773 22.611417) (xy 335.976202 22.559741) (xy 336.039572 22.501972)
			(xy 336.097341 22.438602) (xy 336.149017 22.370173) (xy 336.194158 22.297267) (xy 336.23238 22.220507)
			(xy 336.263356 22.140548) (xy 336.286823 22.058072) (xy 336.302579 21.973782) (xy 336.310491 21.888399)
			(xy 336.310986 21.845524) (xy 336.310491 21.802649) (xy 340.805757 21.802649) (xy 340.805757 21.888399)
			(xy 340.813669 21.973782) (xy 340.829425 22.058072) (xy 340.852892 22.140548) (xy 340.883868 22.220507)
			(xy 340.92209 22.297267) (xy 340.967231 22.370173) (xy 341.018907 22.438602) (xy 341.076676 22.501972)
			(xy 341.140046 22.559741) (xy 341.208475 22.611417) (xy 341.281381 22.656558) (xy 341.358141 22.69478)
			(xy 341.4381 22.725756) (xy 341.520576 22.749223) (xy 341.604866 22.764979) (xy 341.690249 22.772891)
			(xy 341.775999 22.772891) (xy 341.861382 22.764979) (xy 341.945672 22.749223) (xy 342.028148 22.725756)
			(xy 342.108107 22.69478) (xy 342.184867 22.656558) (xy 342.257773 22.611417) (xy 342.326202 22.559741)
			(xy 342.389572 22.501972) (xy 342.447341 22.438602) (xy 342.499017 22.370173) (xy 342.544158 22.297267)
			(xy 342.58238 22.220507) (xy 342.613356 22.140548) (xy 342.636823 22.058072) (xy 342.652579 21.973782)
			(xy 342.660491 21.888399) (xy 342.660986 21.845524) (xy 342.660491 21.802649) (xy 342.659832 21.795537)
			(xy 373.515877 21.795537) (xy 373.515877 21.881287) (xy 373.523789 21.96667) (xy 373.539545 22.05096)
			(xy 373.563012 22.133436) (xy 373.593988 22.213395) (xy 373.63221 22.290155) (xy 373.677351 22.363061)
			(xy 373.729027 22.43149) (xy 373.786796 22.49486) (xy 373.850166 22.552629) (xy 373.918595 22.604305)
			(xy 373.991501 22.649446) (xy 374.068261 22.687668) (xy 374.14822 22.718644) (xy 374.230696 22.742111)
			(xy 374.314986 22.757867) (xy 374.400369 22.765779) (xy 374.486119 22.765779) (xy 374.571502 22.757867)
			(xy 374.655792 22.742111) (xy 374.738268 22.718644) (xy 374.818227 22.687668) (xy 374.894987 22.649446)
			(xy 374.967893 22.604305) (xy 375.036322 22.552629) (xy 375.099692 22.49486) (xy 375.157461 22.43149)
			(xy 375.209137 22.363061) (xy 375.254278 22.290155) (xy 375.2925 22.213395) (xy 375.323476 22.133436)
			(xy 375.346943 22.05096) (xy 375.362699 21.96667) (xy 375.370611 21.881287) (xy 375.371106 21.838412)
			(xy 375.370611 21.795537) (xy 379.865877 21.795537) (xy 379.865877 21.881287) (xy 379.873789 21.96667)
			(xy 379.889545 22.05096) (xy 379.913012 22.133436) (xy 379.943988 22.213395) (xy 379.98221 22.290155)
			(xy 380.027351 22.363061) (xy 380.079027 22.43149) (xy 380.136796 22.49486) (xy 380.200166 22.552629)
			(xy 380.268595 22.604305) (xy 380.341501 22.649446) (xy 380.418261 22.687668) (xy 380.49822 22.718644)
			(xy 380.580696 22.742111) (xy 380.664986 22.757867) (xy 380.750369 22.765779) (xy 380.836119 22.765779)
			(xy 380.921502 22.757867) (xy 381.005792 22.742111) (xy 381.088268 22.718644) (xy 381.168227 22.687668)
			(xy 381.244987 22.649446) (xy 381.317893 22.604305) (xy 381.386322 22.552629) (xy 381.449692 22.49486)
			(xy 381.507461 22.43149) (xy 381.559137 22.363061) (xy 381.604278 22.290155) (xy 381.6425 22.213395)
			(xy 381.673476 22.133436) (xy 381.696943 22.05096) (xy 381.712699 21.96667) (xy 381.720611 21.881287)
			(xy 381.721106 21.838412) (xy 381.720693 21.802649) (xy 399.098757 21.802649) (xy 399.098757 21.888399)
			(xy 399.106669 21.973782) (xy 399.122425 22.058072) (xy 399.145892 22.140548) (xy 399.176868 22.220507)
			(xy 399.21509 22.297267) (xy 399.260231 22.370173) (xy 399.311907 22.438602) (xy 399.369676 22.501972)
			(xy 399.433046 22.559741) (xy 399.501475 22.611417) (xy 399.574381 22.656558) (xy 399.651141 22.69478)
			(xy 399.7311 22.725756) (xy 399.813576 22.749223) (xy 399.897866 22.764979) (xy 399.983249 22.772891)
			(xy 400.068999 22.772891) (xy 400.154382 22.764979) (xy 400.238672 22.749223) (xy 400.321148 22.725756)
			(xy 400.401107 22.69478) (xy 400.477867 22.656558) (xy 400.550773 22.611417) (xy 400.619202 22.559741)
			(xy 400.682572 22.501972) (xy 400.740341 22.438602) (xy 400.792017 22.370173) (xy 400.837158 22.297267)
			(xy 400.87538 22.220507) (xy 400.906356 22.140548) (xy 400.929823 22.058072) (xy 400.945579 21.973782)
			(xy 400.953491 21.888399) (xy 400.953986 21.845524) (xy 400.953491 21.802649) (xy 405.448757 21.802649)
			(xy 405.448757 21.888399) (xy 405.456669 21.973782) (xy 405.472425 22.058072) (xy 405.495892 22.140548)
			(xy 405.526868 22.220507) (xy 405.56509 22.297267) (xy 405.610231 22.370173) (xy 405.661907 22.438602)
			(xy 405.719676 22.501972) (xy 405.783046 22.559741) (xy 405.851475 22.611417) (xy 405.924381 22.656558)
			(xy 406.001141 22.69478) (xy 406.0811 22.725756) (xy 406.163576 22.749223) (xy 406.247866 22.764979)
			(xy 406.333249 22.772891) (xy 406.418999 22.772891) (xy 406.504382 22.764979) (xy 406.588672 22.749223)
			(xy 406.671148 22.725756) (xy 406.751107 22.69478) (xy 406.827867 22.656558) (xy 406.900773 22.611417)
			(xy 406.969202 22.559741) (xy 407.032572 22.501972) (xy 407.090341 22.438602) (xy 407.142017 22.370173)
			(xy 407.187158 22.297267) (xy 407.22538 22.220507) (xy 407.256356 22.140548) (xy 407.279823 22.058072)
			(xy 407.295579 21.973782) (xy 407.303491 21.888399) (xy 407.303986 21.845524) (xy 407.303491 21.802649)
			(xy 407.302832 21.795537) (xy 438.158877 21.795537) (xy 438.158877 21.881287) (xy 438.166789 21.96667)
			(xy 438.182545 22.05096) (xy 438.206012 22.133436) (xy 438.236988 22.213395) (xy 438.27521 22.290155)
			(xy 438.320351 22.363061) (xy 438.372027 22.43149) (xy 438.429796 22.49486) (xy 438.493166 22.552629)
			(xy 438.561595 22.604305) (xy 438.634501 22.649446) (xy 438.711261 22.687668) (xy 438.79122 22.718644)
			(xy 438.873696 22.742111) (xy 438.957986 22.757867) (xy 439.043369 22.765779) (xy 439.129119 22.765779)
			(xy 439.214502 22.757867) (xy 439.298792 22.742111) (xy 439.381268 22.718644) (xy 439.461227 22.687668)
			(xy 439.537987 22.649446) (xy 439.610893 22.604305) (xy 439.679322 22.552629) (xy 439.742692 22.49486)
			(xy 439.800461 22.43149) (xy 439.852137 22.363061) (xy 439.897278 22.290155) (xy 439.9355 22.213395)
			(xy 439.966476 22.133436) (xy 439.989943 22.05096) (xy 440.005699 21.96667) (xy 440.013611 21.881287)
			(xy 440.014106 21.838412) (xy 440.013611 21.795537) (xy 444.508877 21.795537) (xy 444.508877 21.881287)
			(xy 444.516789 21.96667) (xy 444.532545 22.05096) (xy 444.556012 22.133436) (xy 444.586988 22.213395)
			(xy 444.62521 22.290155) (xy 444.670351 22.363061) (xy 444.722027 22.43149) (xy 444.779796 22.49486)
			(xy 444.843166 22.552629) (xy 444.911595 22.604305) (xy 444.984501 22.649446) (xy 445.061261 22.687668)
			(xy 445.14122 22.718644) (xy 445.223696 22.742111) (xy 445.307986 22.757867) (xy 445.393369 22.765779)
			(xy 445.479119 22.765779) (xy 445.564502 22.757867) (xy 445.648792 22.742111) (xy 445.731268 22.718644)
			(xy 445.811227 22.687668) (xy 445.887987 22.649446) (xy 445.960893 22.604305) (xy 446.029322 22.552629)
			(xy 446.092692 22.49486) (xy 446.150461 22.43149) (xy 446.202137 22.363061) (xy 446.247278 22.290155)
			(xy 446.2855 22.213395) (xy 446.316476 22.133436) (xy 446.339943 22.05096) (xy 446.355699 21.96667)
			(xy 446.363611 21.881287) (xy 446.364106 21.838412) (xy 446.363611 21.795537) (xy 446.355699 21.710154)
			(xy 446.339943 21.625864) (xy 446.316476 21.543388) (xy 446.2855 21.463429) (xy 446.247278 21.386669)
			(xy 446.202137 21.313763) (xy 446.150461 21.245334) (xy 446.092692 21.181964) (xy 446.029322 21.124195)
			(xy 445.988175 21.093122) (xy 460.504275 21.093122) (xy 460.504275 21.222262) (xy 460.512225 21.351157)
			(xy 460.528095 21.479317) (xy 460.551824 21.606258) (xy 460.583323 21.731497) (xy 460.622472 21.85456)
			(xy 460.669123 21.974979) (xy 460.723098 22.092298) (xy 460.784193 22.206072) (xy 460.852176 22.315869)
			(xy 460.92679 22.421272) (xy 461.007751 22.521882) (xy 461.094751 22.617317) (xy 461.187462 22.707216)
			(xy 461.285532 22.791237) (xy 461.388587 22.869061) (xy 461.496238 22.940393) (xy 461.608077 23.004963)
			(xy 461.723678 23.062525) (xy 461.842603 23.112862) (xy 461.964402 23.155782) (xy 462.088612 23.191123)
			(xy 462.214761 23.21875) (xy 462.342373 23.238559) (xy 462.470962 23.250475) (xy 462.60004 23.254452)
			(xy 462.729118 23.250475) (xy 462.857707 23.238559) (xy 462.985319 23.21875) (xy 463.111468 23.191123)
			(xy 463.235678 23.155782) (xy 463.357477 23.112862) (xy 463.476402 23.062525) (xy 463.592003 23.004963)
			(xy 463.703842 22.940393) (xy 463.811493 22.869061) (xy 463.914548 22.791237) (xy 464.012618 22.707216)
			(xy 464.105329 22.617317) (xy 464.192329 22.521882) (xy 464.27329 22.421272) (xy 464.347904 22.315869)
			(xy 464.415887 22.206072) (xy 464.476982 22.092298) (xy 464.530957 21.974979) (xy 464.577608 21.85456)
			(xy 464.616757 21.731497) (xy 464.648256 21.606258) (xy 464.671985 21.479317) (xy 464.687855 21.351157)
			(xy 464.695805 21.222262) (xy 464.696302 21.157692) (xy 464.695805 21.093122) (xy 464.687855 20.964227)
			(xy 464.671985 20.836067) (xy 464.648256 20.709126) (xy 464.616757 20.583887) (xy 464.577608 20.460824)
			(xy 464.530957 20.340405) (xy 464.476982 20.223086) (xy 464.415887 20.109312) (xy 464.347904 19.999515)
			(xy 464.27329 19.894112) (xy 464.192329 19.793502) (xy 464.105329 19.698067) (xy 464.012618 19.608168)
			(xy 463.914548 19.524147) (xy 463.811493 19.446323) (xy 463.703842 19.374991) (xy 463.592003 19.310421)
			(xy 463.476402 19.252859) (xy 463.357477 19.202522) (xy 463.235678 19.159602) (xy 463.111468 19.124261)
			(xy 462.985319 19.096634) (xy 462.857707 19.076825) (xy 462.729118 19.064909) (xy 462.60004 19.060933)
			(xy 462.470962 19.064909) (xy 462.342373 19.076825) (xy 462.214761 19.096634) (xy 462.088612 19.124261)
			(xy 461.964402 19.159602) (xy 461.842603 19.202522) (xy 461.723678 19.252859) (xy 461.608077 19.310421)
			(xy 461.496238 19.374991) (xy 461.388587 19.446323) (xy 461.285532 19.524147) (xy 461.187462 19.608168)
			(xy 461.094751 19.698067) (xy 461.007751 19.793502) (xy 460.92679 19.894112) (xy 460.852176 19.999515)
			(xy 460.784193 20.109312) (xy 460.723098 20.223086) (xy 460.669123 20.340405) (xy 460.622472 20.460824)
			(xy 460.583323 20.583887) (xy 460.551824 20.709126) (xy 460.528095 20.836067) (xy 460.512225 20.964227)
			(xy 460.504275 21.093122) (xy 445.988175 21.093122) (xy 445.960893 21.072519) (xy 445.887987 21.027378)
			(xy 445.811227 20.989156) (xy 445.731268 20.95818) (xy 445.648792 20.934713) (xy 445.564502 20.918957)
			(xy 445.479119 20.911045) (xy 445.393369 20.911045) (xy 445.307986 20.918957) (xy 445.223696 20.934713)
			(xy 445.14122 20.95818) (xy 445.061261 20.989156) (xy 444.984501 21.027378) (xy 444.911595 21.072519)
			(xy 444.843166 21.124195) (xy 444.779796 21.181964) (xy 444.722027 21.245334) (xy 444.670351 21.313763)
			(xy 444.62521 21.386669) (xy 444.586988 21.463429) (xy 444.556012 21.543388) (xy 444.532545 21.625864)
			(xy 444.516789 21.710154) (xy 444.508877 21.795537) (xy 440.013611 21.795537) (xy 440.005699 21.710154)
			(xy 439.989943 21.625864) (xy 439.966476 21.543388) (xy 439.9355 21.463429) (xy 439.897278 21.386669)
			(xy 439.852137 21.313763) (xy 439.800461 21.245334) (xy 439.742692 21.181964) (xy 439.679322 21.124195)
			(xy 439.610893 21.072519) (xy 439.537987 21.027378) (xy 439.461227 20.989156) (xy 439.381268 20.95818)
			(xy 439.298792 20.934713) (xy 439.214502 20.918957) (xy 439.129119 20.911045) (xy 439.043369 20.911045)
			(xy 438.957986 20.918957) (xy 438.873696 20.934713) (xy 438.79122 20.95818) (xy 438.711261 20.989156)
			(xy 438.634501 21.027378) (xy 438.561595 21.072519) (xy 438.493166 21.124195) (xy 438.429796 21.181964)
			(xy 438.372027 21.245334) (xy 438.320351 21.313763) (xy 438.27521 21.386669) (xy 438.236988 21.463429)
			(xy 438.206012 21.543388) (xy 438.182545 21.625864) (xy 438.166789 21.710154) (xy 438.158877 21.795537)
			(xy 407.302832 21.795537) (xy 407.295579 21.717266) (xy 407.279823 21.632976) (xy 407.256356 21.5505)
			(xy 407.22538 21.470541) (xy 407.187158 21.393781) (xy 407.142017 21.320875) (xy 407.090341 21.252446)
			(xy 407.032572 21.189076) (xy 406.969202 21.131307) (xy 406.900773 21.079631) (xy 406.827867 21.03449)
			(xy 406.751107 20.996268) (xy 406.671148 20.965292) (xy 406.588672 20.941825) (xy 406.504382 20.926069)
			(xy 406.418999 20.918157) (xy 406.333249 20.918157) (xy 406.247866 20.926069) (xy 406.163576 20.941825)
			(xy 406.0811 20.965292) (xy 406.001141 20.996268) (xy 405.924381 21.03449) (xy 405.851475 21.079631)
			(xy 405.783046 21.131307) (xy 405.719676 21.189076) (xy 405.661907 21.252446) (xy 405.610231 21.320875)
			(xy 405.56509 21.393781) (xy 405.526868 21.470541) (xy 405.495892 21.5505) (xy 405.472425 21.632976)
			(xy 405.456669 21.717266) (xy 405.448757 21.802649) (xy 400.953491 21.802649) (xy 400.945579 21.717266)
			(xy 400.929823 21.632976) (xy 400.906356 21.5505) (xy 400.87538 21.470541) (xy 400.837158 21.393781)
			(xy 400.792017 21.320875) (xy 400.740341 21.252446) (xy 400.682572 21.189076) (xy 400.619202 21.131307)
			(xy 400.550773 21.079631) (xy 400.477867 21.03449) (xy 400.401107 20.996268) (xy 400.321148 20.965292)
			(xy 400.238672 20.941825) (xy 400.154382 20.926069) (xy 400.068999 20.918157) (xy 399.983249 20.918157)
			(xy 399.897866 20.926069) (xy 399.813576 20.941825) (xy 399.7311 20.965292) (xy 399.651141 20.996268)
			(xy 399.574381 21.03449) (xy 399.501475 21.079631) (xy 399.433046 21.131307) (xy 399.369676 21.189076)
			(xy 399.311907 21.252446) (xy 399.260231 21.320875) (xy 399.21509 21.393781) (xy 399.176868 21.470541)
			(xy 399.145892 21.5505) (xy 399.122425 21.632976) (xy 399.106669 21.717266) (xy 399.098757 21.802649)
			(xy 381.720693 21.802649) (xy 381.720611 21.795537) (xy 381.712699 21.710154) (xy 381.696943 21.625864)
			(xy 381.673476 21.543388) (xy 381.6425 21.463429) (xy 381.604278 21.386669) (xy 381.559137 21.313763)
			(xy 381.507461 21.245334) (xy 381.449692 21.181964) (xy 381.386322 21.124195) (xy 381.317893 21.072519)
			(xy 381.244987 21.027378) (xy 381.168227 20.989156) (xy 381.088268 20.95818) (xy 381.005792 20.934713)
			(xy 380.921502 20.918957) (xy 380.836119 20.911045) (xy 380.750369 20.911045) (xy 380.664986 20.918957)
			(xy 380.580696 20.934713) (xy 380.49822 20.95818) (xy 380.418261 20.989156) (xy 380.341501 21.027378)
			(xy 380.268595 21.072519) (xy 380.200166 21.124195) (xy 380.136796 21.181964) (xy 380.079027 21.245334)
			(xy 380.027351 21.313763) (xy 379.98221 21.386669) (xy 379.943988 21.463429) (xy 379.913012 21.543388)
			(xy 379.889545 21.625864) (xy 379.873789 21.710154) (xy 379.865877 21.795537) (xy 375.370611 21.795537)
			(xy 375.362699 21.710154) (xy 375.346943 21.625864) (xy 375.323476 21.543388) (xy 375.2925 21.463429)
			(xy 375.254278 21.386669) (xy 375.209137 21.313763) (xy 375.157461 21.245334) (xy 375.099692 21.181964)
			(xy 375.036322 21.124195) (xy 374.967893 21.072519) (xy 374.894987 21.027378) (xy 374.818227 20.989156)
			(xy 374.738268 20.95818) (xy 374.655792 20.934713) (xy 374.571502 20.918957) (xy 374.486119 20.911045)
			(xy 374.400369 20.911045) (xy 374.314986 20.918957) (xy 374.230696 20.934713) (xy 374.14822 20.95818)
			(xy 374.068261 20.989156) (xy 373.991501 21.027378) (xy 373.918595 21.072519) (xy 373.850166 21.124195)
			(xy 373.786796 21.181964) (xy 373.729027 21.245334) (xy 373.677351 21.313763) (xy 373.63221 21.386669)
			(xy 373.593988 21.463429) (xy 373.563012 21.543388) (xy 373.539545 21.625864) (xy 373.523789 21.710154)
			(xy 373.515877 21.795537) (xy 342.659832 21.795537) (xy 342.652579 21.717266) (xy 342.636823 21.632976)
			(xy 342.613356 21.5505) (xy 342.58238 21.470541) (xy 342.544158 21.393781) (xy 342.499017 21.320875)
			(xy 342.447341 21.252446) (xy 342.389572 21.189076) (xy 342.326202 21.131307) (xy 342.257773 21.079631)
			(xy 342.184867 21.03449) (xy 342.108107 20.996268) (xy 342.028148 20.965292) (xy 341.945672 20.941825)
			(xy 341.861382 20.926069) (xy 341.775999 20.918157) (xy 341.690249 20.918157) (xy 341.604866 20.926069)
			(xy 341.520576 20.941825) (xy 341.4381 20.965292) (xy 341.358141 20.996268) (xy 341.281381 21.03449)
			(xy 341.208475 21.079631) (xy 341.140046 21.131307) (xy 341.076676 21.189076) (xy 341.018907 21.252446)
			(xy 340.967231 21.320875) (xy 340.92209 21.393781) (xy 340.883868 21.470541) (xy 340.852892 21.5505)
			(xy 340.829425 21.632976) (xy 340.813669 21.717266) (xy 340.805757 21.802649) (xy 336.310491 21.802649)
			(xy 336.302579 21.717266) (xy 336.286823 21.632976) (xy 336.263356 21.5505) (xy 336.23238 21.470541)
			(xy 336.194158 21.393781) (xy 336.149017 21.320875) (xy 336.097341 21.252446) (xy 336.039572 21.189076)
			(xy 335.976202 21.131307) (xy 335.907773 21.079631) (xy 335.834867 21.03449) (xy 335.758107 20.996268)
			(xy 335.678148 20.965292) (xy 335.595672 20.941825) (xy 335.511382 20.926069) (xy 335.425999 20.918157)
			(xy 335.340249 20.918157) (xy 335.254866 20.926069) (xy 335.170576 20.941825) (xy 335.0881 20.965292)
			(xy 335.008141 20.996268) (xy 334.931381 21.03449) (xy 334.858475 21.079631) (xy 334.790046 21.131307)
			(xy 334.726676 21.189076) (xy 334.668907 21.252446) (xy 334.617231 21.320875) (xy 334.57209 21.393781)
			(xy 334.533868 21.470541) (xy 334.502892 21.5505) (xy 334.479425 21.632976) (xy 334.463669 21.717266)
			(xy 334.455757 21.802649) (xy 316.569693 21.802649) (xy 316.569611 21.795537) (xy 316.561699 21.710154)
			(xy 316.545943 21.625864) (xy 316.522476 21.543388) (xy 316.4915 21.463429) (xy 316.453278 21.386669)
			(xy 316.408137 21.313763) (xy 316.356461 21.245334) (xy 316.298692 21.181964) (xy 316.235322 21.124195)
			(xy 316.166893 21.072519) (xy 316.093987 21.027378) (xy 316.017227 20.989156) (xy 315.937268 20.95818)
			(xy 315.854792 20.934713) (xy 315.770502 20.918957) (xy 315.685119 20.911045) (xy 315.599369 20.911045)
			(xy 315.513986 20.918957) (xy 315.429696 20.934713) (xy 315.34722 20.95818) (xy 315.267261 20.989156)
			(xy 315.190501 21.027378) (xy 315.117595 21.072519) (xy 315.049166 21.124195) (xy 314.985796 21.181964)
			(xy 314.928027 21.245334) (xy 314.876351 21.313763) (xy 314.83121 21.386669) (xy 314.792988 21.463429)
			(xy 314.762012 21.543388) (xy 314.738545 21.625864) (xy 314.722789 21.710154) (xy 314.714877 21.795537)
			(xy 310.219611 21.795537) (xy 310.211699 21.710154) (xy 310.195943 21.625864) (xy 310.172476 21.543388)
			(xy 310.1415 21.463429) (xy 310.103278 21.386669) (xy 310.058137 21.313763) (xy 310.006461 21.245334)
			(xy 309.948692 21.181964) (xy 309.885322 21.124195) (xy 309.816893 21.072519) (xy 309.743987 21.027378)
			(xy 309.667227 20.989156) (xy 309.587268 20.95818) (xy 309.504792 20.934713) (xy 309.420502 20.918957)
			(xy 309.335119 20.911045) (xy 309.249369 20.911045) (xy 309.163986 20.918957) (xy 309.079696 20.934713)
			(xy 308.99722 20.95818) (xy 308.917261 20.989156) (xy 308.840501 21.027378) (xy 308.767595 21.072519)
			(xy 308.699166 21.124195) (xy 308.635796 21.181964) (xy 308.578027 21.245334) (xy 308.526351 21.313763)
			(xy 308.48121 21.386669) (xy 308.442988 21.463429) (xy 308.412012 21.543388) (xy 308.388545 21.625864)
			(xy 308.372789 21.710154) (xy 308.364877 21.795537) (xy 277.508832 21.795537) (xy 277.501579 21.717266)
			(xy 277.485823 21.632976) (xy 277.462356 21.5505) (xy 277.43138 21.470541) (xy 277.393158 21.393781)
			(xy 277.348017 21.320875) (xy 277.296341 21.252446) (xy 277.238572 21.189076) (xy 277.175202 21.131307)
			(xy 277.106773 21.079631) (xy 277.033867 21.03449) (xy 276.957107 20.996268) (xy 276.877148 20.965292)
			(xy 276.794672 20.941825) (xy 276.710382 20.926069) (xy 276.624999 20.918157) (xy 276.539249 20.918157)
			(xy 276.453866 20.926069) (xy 276.369576 20.941825) (xy 276.2871 20.965292) (xy 276.207141 20.996268)
			(xy 276.130381 21.03449) (xy 276.057475 21.079631) (xy 275.989046 21.131307) (xy 275.925676 21.189076)
			(xy 275.867907 21.252446) (xy 275.816231 21.320875) (xy 275.77109 21.393781) (xy 275.732868 21.470541)
			(xy 275.701892 21.5505) (xy 275.678425 21.632976) (xy 275.662669 21.717266) (xy 275.654757 21.802649)
			(xy 271.159491 21.802649) (xy 271.151579 21.717266) (xy 271.135823 21.632976) (xy 271.112356 21.5505)
			(xy 271.08138 21.470541) (xy 271.043158 21.393781) (xy 270.998017 21.320875) (xy 270.946341 21.252446)
			(xy 270.888572 21.189076) (xy 270.825202 21.131307) (xy 270.756773 21.079631) (xy 270.683867 21.03449)
			(xy 270.607107 20.996268) (xy 270.527148 20.965292) (xy 270.444672 20.941825) (xy 270.360382 20.926069)
			(xy 270.274999 20.918157) (xy 270.189249 20.918157) (xy 270.103866 20.926069) (xy 270.019576 20.941825)
			(xy 269.9371 20.965292) (xy 269.857141 20.996268) (xy 269.780381 21.03449) (xy 269.707475 21.079631)
			(xy 269.639046 21.131307) (xy 269.575676 21.189076) (xy 269.517907 21.252446) (xy 269.466231 21.320875)
			(xy 269.42109 21.393781) (xy 269.382868 21.470541) (xy 269.351892 21.5505) (xy 269.328425 21.632976)
			(xy 269.312669 21.717266) (xy 269.304757 21.802649) (xy 158.621984 21.802649) (xy 158.621984 19.262649)
			(xy 209.995757 19.262649) (xy 209.995757 19.348399) (xy 210.003669 19.433782) (xy 210.019425 19.518072)
			(xy 210.042892 19.600548) (xy 210.073868 19.680507) (xy 210.11209 19.757267) (xy 210.157231 19.830173)
			(xy 210.208907 19.898602) (xy 210.266676 19.961972) (xy 210.330046 20.019741) (xy 210.398475 20.071417)
			(xy 210.471381 20.116558) (xy 210.548141 20.15478) (xy 210.6281 20.185756) (xy 210.710576 20.209223)
			(xy 210.794866 20.224979) (xy 210.880249 20.232891) (xy 210.965999 20.232891) (xy 211.051382 20.224979)
			(xy 211.135672 20.209223) (xy 211.218148 20.185756) (xy 211.298107 20.15478) (xy 211.374867 20.116558)
			(xy 211.447773 20.071417) (xy 211.516202 20.019741) (xy 211.579572 19.961972) (xy 211.637341 19.898602)
			(xy 211.689017 19.830173) (xy 211.734158 19.757267) (xy 211.77238 19.680507) (xy 211.803356 19.600548)
			(xy 211.826823 19.518072) (xy 211.842579 19.433782) (xy 211.850491 19.348399) (xy 211.850986 19.305524)
			(xy 211.850491 19.262649) (xy 216.345757 19.262649) (xy 216.345757 19.348399) (xy 216.353669 19.433782)
			(xy 216.369425 19.518072) (xy 216.392892 19.600548) (xy 216.423868 19.680507) (xy 216.46209 19.757267)
			(xy 216.507231 19.830173) (xy 216.558907 19.898602) (xy 216.616676 19.961972) (xy 216.680046 20.019741)
			(xy 216.748475 20.071417) (xy 216.821381 20.116558) (xy 216.898141 20.15478) (xy 216.9781 20.185756)
			(xy 217.060576 20.209223) (xy 217.144866 20.224979) (xy 217.230249 20.232891) (xy 217.315999 20.232891)
			(xy 217.401382 20.224979) (xy 217.485672 20.209223) (xy 217.568148 20.185756) (xy 217.648107 20.15478)
			(xy 217.724867 20.116558) (xy 217.797773 20.071417) (xy 217.866202 20.019741) (xy 217.929572 19.961972)
			(xy 217.987341 19.898602) (xy 218.039017 19.830173) (xy 218.084158 19.757267) (xy 218.12238 19.680507)
			(xy 218.153356 19.600548) (xy 218.176823 19.518072) (xy 218.192579 19.433782) (xy 218.200491 19.348399)
			(xy 218.200986 19.305524) (xy 218.200491 19.262649) (xy 218.199832 19.255537) (xy 244.026677 19.255537)
			(xy 244.026677 19.341287) (xy 244.034589 19.42667) (xy 244.050345 19.51096) (xy 244.073812 19.593436)
			(xy 244.104788 19.673395) (xy 244.14301 19.750155) (xy 244.188151 19.823061) (xy 244.239827 19.89149)
			(xy 244.297596 19.95486) (xy 244.360966 20.012629) (xy 244.429395 20.064305) (xy 244.502301 20.109446)
			(xy 244.579061 20.147668) (xy 244.65902 20.178644) (xy 244.741496 20.202111) (xy 244.825786 20.217867)
			(xy 244.911169 20.225779) (xy 244.996919 20.225779) (xy 245.082302 20.217867) (xy 245.166592 20.202111)
			(xy 245.249068 20.178644) (xy 245.329027 20.147668) (xy 245.405787 20.109446) (xy 245.478693 20.064305)
			(xy 245.547122 20.012629) (xy 245.610492 19.95486) (xy 245.668261 19.89149) (xy 245.719937 19.823061)
			(xy 245.765078 19.750155) (xy 245.8033 19.673395) (xy 245.834276 19.593436) (xy 245.857743 19.51096)
			(xy 245.873499 19.42667) (xy 245.881411 19.341287) (xy 245.881906 19.298412) (xy 245.881411 19.255537)
			(xy 250.376677 19.255537) (xy 250.376677 19.341287) (xy 250.384589 19.42667) (xy 250.400345 19.51096)
			(xy 250.423812 19.593436) (xy 250.454788 19.673395) (xy 250.49301 19.750155) (xy 250.538151 19.823061)
			(xy 250.589827 19.89149) (xy 250.647596 19.95486) (xy 250.710966 20.012629) (xy 250.779395 20.064305)
			(xy 250.852301 20.109446) (xy 250.929061 20.147668) (xy 251.00902 20.178644) (xy 251.091496 20.202111)
			(xy 251.175786 20.217867) (xy 251.261169 20.225779) (xy 251.346919 20.225779) (xy 251.432302 20.217867)
			(xy 251.516592 20.202111) (xy 251.599068 20.178644) (xy 251.679027 20.147668) (xy 251.755787 20.109446)
			(xy 251.828693 20.064305) (xy 251.897122 20.012629) (xy 251.960492 19.95486) (xy 252.018261 19.89149)
			(xy 252.069937 19.823061) (xy 252.115078 19.750155) (xy 252.1533 19.673395) (xy 252.184276 19.593436)
			(xy 252.207743 19.51096) (xy 252.223499 19.42667) (xy 252.231411 19.341287) (xy 252.231906 19.298412)
			(xy 252.231493 19.262649) (xy 269.304757 19.262649) (xy 269.304757 19.348399) (xy 269.312669 19.433782)
			(xy 269.328425 19.518072) (xy 269.351892 19.600548) (xy 269.382868 19.680507) (xy 269.42109 19.757267)
			(xy 269.466231 19.830173) (xy 269.517907 19.898602) (xy 269.575676 19.961972) (xy 269.639046 20.019741)
			(xy 269.707475 20.071417) (xy 269.780381 20.116558) (xy 269.857141 20.15478) (xy 269.9371 20.185756)
			(xy 270.019576 20.209223) (xy 270.103866 20.224979) (xy 270.189249 20.232891) (xy 270.274999 20.232891)
			(xy 270.360382 20.224979) (xy 270.444672 20.209223) (xy 270.527148 20.185756) (xy 270.607107 20.15478)
			(xy 270.62931 20.143724) (xy 274.239736 20.143724) (xy 274.239736 21.007324) (xy 274.240222 21.034593)
			(xy 274.247984 21.088577) (xy 274.263349 21.140907) (xy 274.286006 21.190517) (xy 274.315492 21.236398)
			(xy 274.351207 21.277615) (xy 274.392424 21.31333) (xy 274.438305 21.342816) (xy 274.487915 21.365473)
			(xy 274.540245 21.380838) (xy 274.594229 21.3886) (xy 274.648767 21.3886) (xy 274.702751 21.380838)
			(xy 274.755081 21.365473) (xy 274.804691 21.342816) (xy 274.850572 21.31333) (xy 274.891789 21.277615)
			(xy 274.927504 21.236398) (xy 274.95699 21.190517) (xy 274.979647 21.140907) (xy 274.995012 21.088577)
			(xy 275.002774 21.034593) (xy 275.00326 21.007324) (xy 275.00326 20.143724) (xy 275.002774 20.116455)
			(xy 274.995012 20.062471) (xy 274.979647 20.010141) (xy 274.95699 19.960531) (xy 274.927504 19.91465)
			(xy 274.891789 19.873433) (xy 274.850572 19.837718) (xy 274.804691 19.808232) (xy 274.755081 19.785575)
			(xy 274.702751 19.77021) (xy 274.648767 19.762448) (xy 274.594229 19.762448) (xy 274.540245 19.77021)
			(xy 274.487915 19.785575) (xy 274.438305 19.808232) (xy 274.392424 19.837718) (xy 274.351207 19.873433)
			(xy 274.315492 19.91465) (xy 274.286006 19.960531) (xy 274.263349 20.010141) (xy 274.247984 20.062471)
			(xy 274.240222 20.116455) (xy 274.239736 20.143724) (xy 270.62931 20.143724) (xy 270.683867 20.116558)
			(xy 270.756773 20.071417) (xy 270.825202 20.019741) (xy 270.888572 19.961972) (xy 270.946341 19.898602)
			(xy 270.998017 19.830173) (xy 271.043158 19.757267) (xy 271.08138 19.680507) (xy 271.112356 19.600548)
			(xy 271.135823 19.518072) (xy 271.151579 19.433782) (xy 271.159491 19.348399) (xy 271.159986 19.305524)
			(xy 271.159491 19.262649) (xy 275.654757 19.262649) (xy 275.654757 19.348399) (xy 275.662669 19.433782)
			(xy 275.678425 19.518072) (xy 275.701892 19.600548) (xy 275.732868 19.680507) (xy 275.77109 19.757267)
			(xy 275.816231 19.830173) (xy 275.867907 19.898602) (xy 275.925676 19.961972) (xy 275.989046 20.019741)
			(xy 276.057475 20.071417) (xy 276.130381 20.116558) (xy 276.207141 20.15478) (xy 276.2871 20.185756)
			(xy 276.369576 20.209223) (xy 276.453866 20.224979) (xy 276.539249 20.232891) (xy 276.624999 20.232891)
			(xy 276.710382 20.224979) (xy 276.794672 20.209223) (xy 276.877148 20.185756) (xy 276.957107 20.15478)
			(xy 277.033867 20.116558) (xy 277.106773 20.071417) (xy 277.175202 20.019741) (xy 277.238572 19.961972)
			(xy 277.296341 19.898602) (xy 277.348017 19.830173) (xy 277.393158 19.757267) (xy 277.43138 19.680507)
			(xy 277.462356 19.600548) (xy 277.485823 19.518072) (xy 277.501579 19.433782) (xy 277.509491 19.348399)
			(xy 277.509986 19.305524) (xy 277.509491 19.262649) (xy 277.508832 19.255537) (xy 308.364877 19.255537)
			(xy 308.364877 19.341287) (xy 308.372789 19.42667) (xy 308.388545 19.51096) (xy 308.412012 19.593436)
			(xy 308.442988 19.673395) (xy 308.48121 19.750155) (xy 308.526351 19.823061) (xy 308.578027 19.89149)
			(xy 308.635796 19.95486) (xy 308.699166 20.012629) (xy 308.767595 20.064305) (xy 308.840501 20.109446)
			(xy 308.917261 20.147668) (xy 308.99722 20.178644) (xy 309.079696 20.202111) (xy 309.163986 20.217867)
			(xy 309.249369 20.225779) (xy 309.335119 20.225779) (xy 309.420502 20.217867) (xy 309.504792 20.202111)
			(xy 309.587268 20.178644) (xy 309.667227 20.147668) (xy 309.68943 20.136612) (xy 310.871108 20.136612)
			(xy 310.871108 21.000212) (xy 310.871594 21.027481) (xy 310.879356 21.081465) (xy 310.894721 21.133795)
			(xy 310.917378 21.183405) (xy 310.946864 21.229286) (xy 310.982579 21.270503) (xy 311.023796 21.306218)
			(xy 311.069677 21.335704) (xy 311.119287 21.358361) (xy 311.171617 21.373726) (xy 311.225601 21.381488)
			(xy 311.280139 21.381488) (xy 311.334123 21.373726) (xy 311.386453 21.358361) (xy 311.436063 21.335704)
			(xy 311.481944 21.306218) (xy 311.523161 21.270503) (xy 311.558876 21.229286) (xy 311.588362 21.183405)
			(xy 311.611019 21.133795) (xy 311.626384 21.081465) (xy 311.634146 21.027481) (xy 311.634632 21.000212)
			(xy 311.634632 20.136612) (xy 311.634146 20.109343) (xy 311.626384 20.055359) (xy 311.611019 20.003029)
			(xy 311.588362 19.953419) (xy 311.558876 19.907538) (xy 311.523161 19.866321) (xy 311.481944 19.830606)
			(xy 311.436063 19.80112) (xy 311.386453 19.778463) (xy 311.334123 19.763098) (xy 311.280139 19.755336)
			(xy 311.225601 19.755336) (xy 311.171617 19.763098) (xy 311.119287 19.778463) (xy 311.069677 19.80112)
			(xy 311.023796 19.830606) (xy 310.982579 19.866321) (xy 310.946864 19.907538) (xy 310.917378 19.953419)
			(xy 310.894721 20.003029) (xy 310.879356 20.055359) (xy 310.871594 20.109343) (xy 310.871108 20.136612)
			(xy 309.68943 20.136612) (xy 309.743987 20.109446) (xy 309.816893 20.064305) (xy 309.885322 20.012629)
			(xy 309.948692 19.95486) (xy 310.006461 19.89149) (xy 310.058137 19.823061) (xy 310.103278 19.750155)
			(xy 310.1415 19.673395) (xy 310.172476 19.593436) (xy 310.195943 19.51096) (xy 310.211699 19.42667)
			(xy 310.219611 19.341287) (xy 310.220106 19.298412) (xy 310.219611 19.255537) (xy 314.714877 19.255537)
			(xy 314.714877 19.341287) (xy 314.722789 19.42667) (xy 314.738545 19.51096) (xy 314.762012 19.593436)
			(xy 314.792988 19.673395) (xy 314.83121 19.750155) (xy 314.876351 19.823061) (xy 314.928027 19.89149)
			(xy 314.985796 19.95486) (xy 315.049166 20.012629) (xy 315.117595 20.064305) (xy 315.190501 20.109446)
			(xy 315.267261 20.147668) (xy 315.34722 20.178644) (xy 315.429696 20.202111) (xy 315.513986 20.217867)
			(xy 315.599369 20.225779) (xy 315.685119 20.225779) (xy 315.770502 20.217867) (xy 315.854792 20.202111)
			(xy 315.937268 20.178644) (xy 316.017227 20.147668) (xy 316.093987 20.109446) (xy 316.166893 20.064305)
			(xy 316.235322 20.012629) (xy 316.298692 19.95486) (xy 316.356461 19.89149) (xy 316.408137 19.823061)
			(xy 316.453278 19.750155) (xy 316.4915 19.673395) (xy 316.522476 19.593436) (xy 316.545943 19.51096)
			(xy 316.561699 19.42667) (xy 316.569611 19.341287) (xy 316.570106 19.298412) (xy 316.569693 19.262649)
			(xy 334.455757 19.262649) (xy 334.455757 19.348399) (xy 334.463669 19.433782) (xy 334.479425 19.518072)
			(xy 334.502892 19.600548) (xy 334.533868 19.680507) (xy 334.57209 19.757267) (xy 334.617231 19.830173)
			(xy 334.668907 19.898602) (xy 334.726676 19.961972) (xy 334.790046 20.019741) (xy 334.858475 20.071417)
			(xy 334.931381 20.116558) (xy 335.008141 20.15478) (xy 335.0881 20.185756) (xy 335.170576 20.209223)
			(xy 335.254866 20.224979) (xy 335.340249 20.232891) (xy 335.425999 20.232891) (xy 335.511382 20.224979)
			(xy 335.595672 20.209223) (xy 335.678148 20.185756) (xy 335.758107 20.15478) (xy 335.78031 20.143724)
			(xy 339.390736 20.143724) (xy 339.390736 21.007324) (xy 339.391222 21.034593) (xy 339.398984 21.088577)
			(xy 339.414349 21.140907) (xy 339.437006 21.190517) (xy 339.466492 21.236398) (xy 339.502207 21.277615)
			(xy 339.543424 21.31333) (xy 339.589305 21.342816) (xy 339.638915 21.365473) (xy 339.691245 21.380838)
			(xy 339.745229 21.3886) (xy 339.799767 21.3886) (xy 339.853751 21.380838) (xy 339.906081 21.365473)
			(xy 339.955691 21.342816) (xy 340.001572 21.31333) (xy 340.042789 21.277615) (xy 340.078504 21.236398)
			(xy 340.10799 21.190517) (xy 340.130647 21.140907) (xy 340.146012 21.088577) (xy 340.153774 21.034593)
			(xy 340.15426 21.007324) (xy 340.15426 20.143724) (xy 340.153774 20.116455) (xy 340.146012 20.062471)
			(xy 340.130647 20.010141) (xy 340.10799 19.960531) (xy 340.078504 19.91465) (xy 340.042789 19.873433)
			(xy 340.001572 19.837718) (xy 339.955691 19.808232) (xy 339.906081 19.785575) (xy 339.853751 19.77021)
			(xy 339.799767 19.762448) (xy 339.745229 19.762448) (xy 339.691245 19.77021) (xy 339.638915 19.785575)
			(xy 339.589305 19.808232) (xy 339.543424 19.837718) (xy 339.502207 19.873433) (xy 339.466492 19.91465)
			(xy 339.437006 19.960531) (xy 339.414349 20.010141) (xy 339.398984 20.062471) (xy 339.391222 20.116455)
			(xy 339.390736 20.143724) (xy 335.78031 20.143724) (xy 335.834867 20.116558) (xy 335.907773 20.071417)
			(xy 335.976202 20.019741) (xy 336.039572 19.961972) (xy 336.097341 19.898602) (xy 336.149017 19.830173)
			(xy 336.194158 19.757267) (xy 336.23238 19.680507) (xy 336.263356 19.600548) (xy 336.286823 19.518072)
			(xy 336.302579 19.433782) (xy 336.310491 19.348399) (xy 336.310986 19.305524) (xy 336.310491 19.262649)
			(xy 340.805757 19.262649) (xy 340.805757 19.348399) (xy 340.813669 19.433782) (xy 340.829425 19.518072)
			(xy 340.852892 19.600548) (xy 340.883868 19.680507) (xy 340.92209 19.757267) (xy 340.967231 19.830173)
			(xy 341.018907 19.898602) (xy 341.076676 19.961972) (xy 341.140046 20.019741) (xy 341.208475 20.071417)
			(xy 341.281381 20.116558) (xy 341.358141 20.15478) (xy 341.4381 20.185756) (xy 341.520576 20.209223)
			(xy 341.604866 20.224979) (xy 341.690249 20.232891) (xy 341.775999 20.232891) (xy 341.861382 20.224979)
			(xy 341.945672 20.209223) (xy 342.028148 20.185756) (xy 342.108107 20.15478) (xy 342.184867 20.116558)
			(xy 342.257773 20.071417) (xy 342.326202 20.019741) (xy 342.389572 19.961972) (xy 342.447341 19.898602)
			(xy 342.499017 19.830173) (xy 342.544158 19.757267) (xy 342.58238 19.680507) (xy 342.613356 19.600548)
			(xy 342.636823 19.518072) (xy 342.652579 19.433782) (xy 342.660491 19.348399) (xy 342.660986 19.305524)
			(xy 342.660491 19.262649) (xy 342.659832 19.255537) (xy 373.515877 19.255537) (xy 373.515877 19.341287)
			(xy 373.523789 19.42667) (xy 373.539545 19.51096) (xy 373.563012 19.593436) (xy 373.593988 19.673395)
			(xy 373.63221 19.750155) (xy 373.677351 19.823061) (xy 373.729027 19.89149) (xy 373.786796 19.95486)
			(xy 373.850166 20.012629) (xy 373.918595 20.064305) (xy 373.991501 20.109446) (xy 374.068261 20.147668)
			(xy 374.14822 20.178644) (xy 374.230696 20.202111) (xy 374.314986 20.217867) (xy 374.400369 20.225779)
			(xy 374.486119 20.225779) (xy 374.571502 20.217867) (xy 374.655792 20.202111) (xy 374.738268 20.178644)
			(xy 374.818227 20.147668) (xy 374.84043 20.136612) (xy 376.022108 20.136612) (xy 376.022108 21.000212)
			(xy 376.022594 21.027481) (xy 376.030356 21.081465) (xy 376.045721 21.133795) (xy 376.068378 21.183405)
			(xy 376.097864 21.229286) (xy 376.133579 21.270503) (xy 376.174796 21.306218) (xy 376.220677 21.335704)
			(xy 376.270287 21.358361) (xy 376.322617 21.373726) (xy 376.376601 21.381488) (xy 376.431139 21.381488)
			(xy 376.485123 21.373726) (xy 376.537453 21.358361) (xy 376.587063 21.335704) (xy 376.632944 21.306218)
			(xy 376.674161 21.270503) (xy 376.709876 21.229286) (xy 376.739362 21.183405) (xy 376.762019 21.133795)
			(xy 376.777384 21.081465) (xy 376.785146 21.027481) (xy 376.785632 21.000212) (xy 376.785632 20.136612)
			(xy 376.785146 20.109343) (xy 376.777384 20.055359) (xy 376.762019 20.003029) (xy 376.739362 19.953419)
			(xy 376.709876 19.907538) (xy 376.674161 19.866321) (xy 376.632944 19.830606) (xy 376.587063 19.80112)
			(xy 376.537453 19.778463) (xy 376.485123 19.763098) (xy 376.431139 19.755336) (xy 376.376601 19.755336)
			(xy 376.322617 19.763098) (xy 376.270287 19.778463) (xy 376.220677 19.80112) (xy 376.174796 19.830606)
			(xy 376.133579 19.866321) (xy 376.097864 19.907538) (xy 376.068378 19.953419) (xy 376.045721 20.003029)
			(xy 376.030356 20.055359) (xy 376.022594 20.109343) (xy 376.022108 20.136612) (xy 374.84043 20.136612)
			(xy 374.894987 20.109446) (xy 374.967893 20.064305) (xy 375.036322 20.012629) (xy 375.099692 19.95486)
			(xy 375.157461 19.89149) (xy 375.209137 19.823061) (xy 375.254278 19.750155) (xy 375.2925 19.673395)
			(xy 375.323476 19.593436) (xy 375.346943 19.51096) (xy 375.362699 19.42667) (xy 375.370611 19.341287)
			(xy 375.371106 19.298412) (xy 375.370611 19.255537) (xy 379.865877 19.255537) (xy 379.865877 19.341287)
			(xy 379.873789 19.42667) (xy 379.889545 19.51096) (xy 379.913012 19.593436) (xy 379.943988 19.673395)
			(xy 379.98221 19.750155) (xy 380.027351 19.823061) (xy 380.079027 19.89149) (xy 380.136796 19.95486)
			(xy 380.200166 20.012629) (xy 380.268595 20.064305) (xy 380.341501 20.109446) (xy 380.418261 20.147668)
			(xy 380.49822 20.178644) (xy 380.580696 20.202111) (xy 380.664986 20.217867) (xy 380.750369 20.225779)
			(xy 380.836119 20.225779) (xy 380.921502 20.217867) (xy 381.005792 20.202111) (xy 381.088268 20.178644)
			(xy 381.168227 20.147668) (xy 381.244987 20.109446) (xy 381.317893 20.064305) (xy 381.386322 20.012629)
			(xy 381.449692 19.95486) (xy 381.507461 19.89149) (xy 381.559137 19.823061) (xy 381.604278 19.750155)
			(xy 381.6425 19.673395) (xy 381.673476 19.593436) (xy 381.696943 19.51096) (xy 381.712699 19.42667)
			(xy 381.720611 19.341287) (xy 381.721106 19.298412) (xy 381.720693 19.262649) (xy 399.098757 19.262649)
			(xy 399.098757 19.348399) (xy 399.106669 19.433782) (xy 399.122425 19.518072) (xy 399.145892 19.600548)
			(xy 399.176868 19.680507) (xy 399.21509 19.757267) (xy 399.260231 19.830173) (xy 399.311907 19.898602)
			(xy 399.369676 19.961972) (xy 399.433046 20.019741) (xy 399.501475 20.071417) (xy 399.574381 20.116558)
			(xy 399.651141 20.15478) (xy 399.7311 20.185756) (xy 399.813576 20.209223) (xy 399.897866 20.224979)
			(xy 399.983249 20.232891) (xy 400.068999 20.232891) (xy 400.154382 20.224979) (xy 400.238672 20.209223)
			(xy 400.321148 20.185756) (xy 400.401107 20.15478) (xy 400.42331 20.143724) (xy 404.033736 20.143724)
			(xy 404.033736 21.007324) (xy 404.034222 21.034593) (xy 404.041984 21.088577) (xy 404.057349 21.140907)
			(xy 404.080006 21.190517) (xy 404.109492 21.236398) (xy 404.145207 21.277615) (xy 404.186424 21.31333)
			(xy 404.232305 21.342816) (xy 404.281915 21.365473) (xy 404.334245 21.380838) (xy 404.388229 21.3886)
			(xy 404.442767 21.3886) (xy 404.496751 21.380838) (xy 404.549081 21.365473) (xy 404.598691 21.342816)
			(xy 404.644572 21.31333) (xy 404.685789 21.277615) (xy 404.721504 21.236398) (xy 404.75099 21.190517)
			(xy 404.773647 21.140907) (xy 404.789012 21.088577) (xy 404.796774 21.034593) (xy 404.79726 21.007324)
			(xy 404.79726 20.143724) (xy 404.796774 20.116455) (xy 404.789012 20.062471) (xy 404.773647 20.010141)
			(xy 404.75099 19.960531) (xy 404.721504 19.91465) (xy 404.685789 19.873433) (xy 404.644572 19.837718)
			(xy 404.598691 19.808232) (xy 404.549081 19.785575) (xy 404.496751 19.77021) (xy 404.442767 19.762448)
			(xy 404.388229 19.762448) (xy 404.334245 19.77021) (xy 404.281915 19.785575) (xy 404.232305 19.808232)
			(xy 404.186424 19.837718) (xy 404.145207 19.873433) (xy 404.109492 19.91465) (xy 404.080006 19.960531)
			(xy 404.057349 20.010141) (xy 404.041984 20.062471) (xy 404.034222 20.116455) (xy 404.033736 20.143724)
			(xy 400.42331 20.143724) (xy 400.477867 20.116558) (xy 400.550773 20.071417) (xy 400.619202 20.019741)
			(xy 400.682572 19.961972) (xy 400.740341 19.898602) (xy 400.792017 19.830173) (xy 400.837158 19.757267)
			(xy 400.87538 19.680507) (xy 400.906356 19.600548) (xy 400.929823 19.518072) (xy 400.945579 19.433782)
			(xy 400.953491 19.348399) (xy 400.953986 19.305524) (xy 400.953491 19.262649) (xy 405.448757 19.262649)
			(xy 405.448757 19.348399) (xy 405.456669 19.433782) (xy 405.472425 19.518072) (xy 405.495892 19.600548)
			(xy 405.526868 19.680507) (xy 405.56509 19.757267) (xy 405.610231 19.830173) (xy 405.661907 19.898602)
			(xy 405.719676 19.961972) (xy 405.783046 20.019741) (xy 405.851475 20.071417) (xy 405.924381 20.116558)
			(xy 406.001141 20.15478) (xy 406.0811 20.185756) (xy 406.163576 20.209223) (xy 406.247866 20.224979)
			(xy 406.333249 20.232891) (xy 406.418999 20.232891) (xy 406.504382 20.224979) (xy 406.588672 20.209223)
			(xy 406.671148 20.185756) (xy 406.751107 20.15478) (xy 406.827867 20.116558) (xy 406.900773 20.071417)
			(xy 406.969202 20.019741) (xy 407.032572 19.961972) (xy 407.090341 19.898602) (xy 407.142017 19.830173)
			(xy 407.187158 19.757267) (xy 407.22538 19.680507) (xy 407.256356 19.600548) (xy 407.279823 19.518072)
			(xy 407.295579 19.433782) (xy 407.303491 19.348399) (xy 407.303986 19.305524) (xy 407.303491 19.262649)
			(xy 407.302832 19.255537) (xy 438.158877 19.255537) (xy 438.158877 19.341287) (xy 438.166789 19.42667)
			(xy 438.182545 19.51096) (xy 438.206012 19.593436) (xy 438.236988 19.673395) (xy 438.27521 19.750155)
			(xy 438.320351 19.823061) (xy 438.372027 19.89149) (xy 438.429796 19.95486) (xy 438.493166 20.012629)
			(xy 438.561595 20.064305) (xy 438.634501 20.109446) (xy 438.711261 20.147668) (xy 438.79122 20.178644)
			(xy 438.873696 20.202111) (xy 438.957986 20.217867) (xy 439.043369 20.225779) (xy 439.129119 20.225779)
			(xy 439.214502 20.217867) (xy 439.298792 20.202111) (xy 439.381268 20.178644) (xy 439.461227 20.147668)
			(xy 439.48343 20.136612) (xy 440.665108 20.136612) (xy 440.665108 21.000212) (xy 440.665594 21.027481)
			(xy 440.673356 21.081465) (xy 440.688721 21.133795) (xy 440.711378 21.183405) (xy 440.740864 21.229286)
			(xy 440.776579 21.270503) (xy 440.817796 21.306218) (xy 440.863677 21.335704) (xy 440.913287 21.358361)
			(xy 440.965617 21.373726) (xy 441.019601 21.381488) (xy 441.074139 21.381488) (xy 441.128123 21.373726)
			(xy 441.180453 21.358361) (xy 441.230063 21.335704) (xy 441.275944 21.306218) (xy 441.317161 21.270503)
			(xy 441.352876 21.229286) (xy 441.382362 21.183405) (xy 441.405019 21.133795) (xy 441.420384 21.081465)
			(xy 441.428146 21.027481) (xy 441.428632 21.000212) (xy 441.428632 20.136612) (xy 441.428146 20.109343)
			(xy 441.420384 20.055359) (xy 441.405019 20.003029) (xy 441.382362 19.953419) (xy 441.352876 19.907538)
			(xy 441.317161 19.866321) (xy 441.275944 19.830606) (xy 441.230063 19.80112) (xy 441.180453 19.778463)
			(xy 441.128123 19.763098) (xy 441.074139 19.755336) (xy 441.019601 19.755336) (xy 440.965617 19.763098)
			(xy 440.913287 19.778463) (xy 440.863677 19.80112) (xy 440.817796 19.830606) (xy 440.776579 19.866321)
			(xy 440.740864 19.907538) (xy 440.711378 19.953419) (xy 440.688721 20.003029) (xy 440.673356 20.055359)
			(xy 440.665594 20.109343) (xy 440.665108 20.136612) (xy 439.48343 20.136612) (xy 439.537987 20.109446)
			(xy 439.610893 20.064305) (xy 439.679322 20.012629) (xy 439.742692 19.95486) (xy 439.800461 19.89149)
			(xy 439.852137 19.823061) (xy 439.897278 19.750155) (xy 439.9355 19.673395) (xy 439.966476 19.593436)
			(xy 439.989943 19.51096) (xy 440.005699 19.42667) (xy 440.013611 19.341287) (xy 440.014106 19.298412)
			(xy 440.013611 19.255537) (xy 444.508877 19.255537) (xy 444.508877 19.341287) (xy 444.516789 19.42667)
			(xy 444.532545 19.51096) (xy 444.556012 19.593436) (xy 444.586988 19.673395) (xy 444.62521 19.750155)
			(xy 444.670351 19.823061) (xy 444.722027 19.89149) (xy 444.779796 19.95486) (xy 444.843166 20.012629)
			(xy 444.911595 20.064305) (xy 444.984501 20.109446) (xy 445.061261 20.147668) (xy 445.14122 20.178644)
			(xy 445.223696 20.202111) (xy 445.307986 20.217867) (xy 445.393369 20.225779) (xy 445.479119 20.225779)
			(xy 445.564502 20.217867) (xy 445.648792 20.202111) (xy 445.731268 20.178644) (xy 445.811227 20.147668)
			(xy 445.887987 20.109446) (xy 445.960893 20.064305) (xy 446.029322 20.012629) (xy 446.092692 19.95486)
			(xy 446.150461 19.89149) (xy 446.202137 19.823061) (xy 446.247278 19.750155) (xy 446.2855 19.673395)
			(xy 446.316476 19.593436) (xy 446.339943 19.51096) (xy 446.355699 19.42667) (xy 446.363611 19.341287)
			(xy 446.364106 19.298412) (xy 446.363611 19.255537) (xy 446.355699 19.170154) (xy 446.339943 19.085864)
			(xy 446.316476 19.003388) (xy 446.2855 18.923429) (xy 446.247278 18.846669) (xy 446.202137 18.773763)
			(xy 446.150461 18.705334) (xy 446.092692 18.641964) (xy 446.029322 18.584195) (xy 445.960893 18.532519)
			(xy 445.887987 18.487378) (xy 445.811227 18.449156) (xy 445.731268 18.41818) (xy 445.648792 18.394713)
			(xy 445.564502 18.378957) (xy 445.479119 18.371045) (xy 445.393369 18.371045) (xy 445.307986 18.378957)
			(xy 445.223696 18.394713) (xy 445.14122 18.41818) (xy 445.061261 18.449156) (xy 444.984501 18.487378)
			(xy 444.911595 18.532519) (xy 444.843166 18.584195) (xy 444.779796 18.641964) (xy 444.722027 18.705334)
			(xy 444.670351 18.773763) (xy 444.62521 18.846669) (xy 444.586988 18.923429) (xy 444.556012 19.003388)
			(xy 444.532545 19.085864) (xy 444.516789 19.170154) (xy 444.508877 19.255537) (xy 440.013611 19.255537)
			(xy 440.005699 19.170154) (xy 439.989943 19.085864) (xy 439.966476 19.003388) (xy 439.9355 18.923429)
			(xy 439.897278 18.846669) (xy 439.852137 18.773763) (xy 439.800461 18.705334) (xy 439.742692 18.641964)
			(xy 439.679322 18.584195) (xy 439.610893 18.532519) (xy 439.537987 18.487378) (xy 439.461227 18.449156)
			(xy 439.381268 18.41818) (xy 439.298792 18.394713) (xy 439.214502 18.378957) (xy 439.129119 18.371045)
			(xy 439.043369 18.371045) (xy 438.957986 18.378957) (xy 438.873696 18.394713) (xy 438.79122 18.41818)
			(xy 438.711261 18.449156) (xy 438.634501 18.487378) (xy 438.561595 18.532519) (xy 438.493166 18.584195)
			(xy 438.429796 18.641964) (xy 438.372027 18.705334) (xy 438.320351 18.773763) (xy 438.27521 18.846669)
			(xy 438.236988 18.923429) (xy 438.206012 19.003388) (xy 438.182545 19.085864) (xy 438.166789 19.170154)
			(xy 438.158877 19.255537) (xy 407.302832 19.255537) (xy 407.295579 19.177266) (xy 407.279823 19.092976)
			(xy 407.256356 19.0105) (xy 407.22538 18.930541) (xy 407.187158 18.853781) (xy 407.142017 18.780875)
			(xy 407.090341 18.712446) (xy 407.032572 18.649076) (xy 406.969202 18.591307) (xy 406.900773 18.539631)
			(xy 406.827867 18.49449) (xy 406.751107 18.456268) (xy 406.671148 18.425292) (xy 406.588672 18.401825)
			(xy 406.504382 18.386069) (xy 406.418999 18.378157) (xy 406.333249 18.378157) (xy 406.247866 18.386069)
			(xy 406.163576 18.401825) (xy 406.0811 18.425292) (xy 406.001141 18.456268) (xy 405.924381 18.49449)
			(xy 405.851475 18.539631) (xy 405.783046 18.591307) (xy 405.719676 18.649076) (xy 405.661907 18.712446)
			(xy 405.610231 18.780875) (xy 405.56509 18.853781) (xy 405.526868 18.930541) (xy 405.495892 19.0105)
			(xy 405.472425 19.092976) (xy 405.456669 19.177266) (xy 405.448757 19.262649) (xy 400.953491 19.262649)
			(xy 400.945579 19.177266) (xy 400.929823 19.092976) (xy 400.906356 19.0105) (xy 400.87538 18.930541)
			(xy 400.837158 18.853781) (xy 400.792017 18.780875) (xy 400.740341 18.712446) (xy 400.682572 18.649076)
			(xy 400.619202 18.591307) (xy 400.550773 18.539631) (xy 400.477867 18.49449) (xy 400.401107 18.456268)
			(xy 400.321148 18.425292) (xy 400.238672 18.401825) (xy 400.154382 18.386069) (xy 400.068999 18.378157)
			(xy 399.983249 18.378157) (xy 399.897866 18.386069) (xy 399.813576 18.401825) (xy 399.7311 18.425292)
			(xy 399.651141 18.456268) (xy 399.574381 18.49449) (xy 399.501475 18.539631) (xy 399.433046 18.591307)
			(xy 399.369676 18.649076) (xy 399.311907 18.712446) (xy 399.260231 18.780875) (xy 399.21509 18.853781)
			(xy 399.176868 18.930541) (xy 399.145892 19.0105) (xy 399.122425 19.092976) (xy 399.106669 19.177266)
			(xy 399.098757 19.262649) (xy 381.720693 19.262649) (xy 381.720611 19.255537) (xy 381.712699 19.170154)
			(xy 381.696943 19.085864) (xy 381.673476 19.003388) (xy 381.6425 18.923429) (xy 381.604278 18.846669)
			(xy 381.559137 18.773763) (xy 381.507461 18.705334) (xy 381.449692 18.641964) (xy 381.386322 18.584195)
			(xy 381.317893 18.532519) (xy 381.244987 18.487378) (xy 381.168227 18.449156) (xy 381.088268 18.41818)
			(xy 381.005792 18.394713) (xy 380.921502 18.378957) (xy 380.836119 18.371045) (xy 380.750369 18.371045)
			(xy 380.664986 18.378957) (xy 380.580696 18.394713) (xy 380.49822 18.41818) (xy 380.418261 18.449156)
			(xy 380.341501 18.487378) (xy 380.268595 18.532519) (xy 380.200166 18.584195) (xy 380.136796 18.641964)
			(xy 380.079027 18.705334) (xy 380.027351 18.773763) (xy 379.98221 18.846669) (xy 379.943988 18.923429)
			(xy 379.913012 19.003388) (xy 379.889545 19.085864) (xy 379.873789 19.170154) (xy 379.865877 19.255537)
			(xy 375.370611 19.255537) (xy 375.362699 19.170154) (xy 375.346943 19.085864) (xy 375.323476 19.003388)
			(xy 375.2925 18.923429) (xy 375.254278 18.846669) (xy 375.209137 18.773763) (xy 375.157461 18.705334)
			(xy 375.099692 18.641964) (xy 375.036322 18.584195) (xy 374.967893 18.532519) (xy 374.894987 18.487378)
			(xy 374.818227 18.449156) (xy 374.738268 18.41818) (xy 374.655792 18.394713) (xy 374.571502 18.378957)
			(xy 374.486119 18.371045) (xy 374.400369 18.371045) (xy 374.314986 18.378957) (xy 374.230696 18.394713)
			(xy 374.14822 18.41818) (xy 374.068261 18.449156) (xy 373.991501 18.487378) (xy 373.918595 18.532519)
			(xy 373.850166 18.584195) (xy 373.786796 18.641964) (xy 373.729027 18.705334) (xy 373.677351 18.773763)
			(xy 373.63221 18.846669) (xy 373.593988 18.923429) (xy 373.563012 19.003388) (xy 373.539545 19.085864)
			(xy 373.523789 19.170154) (xy 373.515877 19.255537) (xy 342.659832 19.255537) (xy 342.652579 19.177266)
			(xy 342.636823 19.092976) (xy 342.613356 19.0105) (xy 342.58238 18.930541) (xy 342.544158 18.853781)
			(xy 342.499017 18.780875) (xy 342.447341 18.712446) (xy 342.389572 18.649076) (xy 342.326202 18.591307)
			(xy 342.257773 18.539631) (xy 342.184867 18.49449) (xy 342.108107 18.456268) (xy 342.028148 18.425292)
			(xy 341.945672 18.401825) (xy 341.861382 18.386069) (xy 341.775999 18.378157) (xy 341.690249 18.378157)
			(xy 341.604866 18.386069) (xy 341.520576 18.401825) (xy 341.4381 18.425292) (xy 341.358141 18.456268)
			(xy 341.281381 18.49449) (xy 341.208475 18.539631) (xy 341.140046 18.591307) (xy 341.076676 18.649076)
			(xy 341.018907 18.712446) (xy 340.967231 18.780875) (xy 340.92209 18.853781) (xy 340.883868 18.930541)
			(xy 340.852892 19.0105) (xy 340.829425 19.092976) (xy 340.813669 19.177266) (xy 340.805757 19.262649)
			(xy 336.310491 19.262649) (xy 336.302579 19.177266) (xy 336.286823 19.092976) (xy 336.263356 19.0105)
			(xy 336.23238 18.930541) (xy 336.194158 18.853781) (xy 336.149017 18.780875) (xy 336.097341 18.712446)
			(xy 336.039572 18.649076) (xy 335.976202 18.591307) (xy 335.907773 18.539631) (xy 335.834867 18.49449)
			(xy 335.758107 18.456268) (xy 335.678148 18.425292) (xy 335.595672 18.401825) (xy 335.511382 18.386069)
			(xy 335.425999 18.378157) (xy 335.340249 18.378157) (xy 335.254866 18.386069) (xy 335.170576 18.401825)
			(xy 335.0881 18.425292) (xy 335.008141 18.456268) (xy 334.931381 18.49449) (xy 334.858475 18.539631)
			(xy 334.790046 18.591307) (xy 334.726676 18.649076) (xy 334.668907 18.712446) (xy 334.617231 18.780875)
			(xy 334.57209 18.853781) (xy 334.533868 18.930541) (xy 334.502892 19.0105) (xy 334.479425 19.092976)
			(xy 334.463669 19.177266) (xy 334.455757 19.262649) (xy 316.569693 19.262649) (xy 316.569611 19.255537)
			(xy 316.561699 19.170154) (xy 316.545943 19.085864) (xy 316.522476 19.003388) (xy 316.4915 18.923429)
			(xy 316.453278 18.846669) (xy 316.408137 18.773763) (xy 316.356461 18.705334) (xy 316.298692 18.641964)
			(xy 316.235322 18.584195) (xy 316.166893 18.532519) (xy 316.093987 18.487378) (xy 316.017227 18.449156)
			(xy 315.937268 18.41818) (xy 315.854792 18.394713) (xy 315.770502 18.378957) (xy 315.685119 18.371045)
			(xy 315.599369 18.371045) (xy 315.513986 18.378957) (xy 315.429696 18.394713) (xy 315.34722 18.41818)
			(xy 315.267261 18.449156) (xy 315.190501 18.487378) (xy 315.117595 18.532519) (xy 315.049166 18.584195)
			(xy 314.985796 18.641964) (xy 314.928027 18.705334) (xy 314.876351 18.773763) (xy 314.83121 18.846669)
			(xy 314.792988 18.923429) (xy 314.762012 19.003388) (xy 314.738545 19.085864) (xy 314.722789 19.170154)
			(xy 314.714877 19.255537) (xy 310.219611 19.255537) (xy 310.211699 19.170154) (xy 310.195943 19.085864)
			(xy 310.172476 19.003388) (xy 310.1415 18.923429) (xy 310.103278 18.846669) (xy 310.058137 18.773763)
			(xy 310.006461 18.705334) (xy 309.948692 18.641964) (xy 309.885322 18.584195) (xy 309.816893 18.532519)
			(xy 309.743987 18.487378) (xy 309.667227 18.449156) (xy 309.587268 18.41818) (xy 309.504792 18.394713)
			(xy 309.420502 18.378957) (xy 309.335119 18.371045) (xy 309.249369 18.371045) (xy 309.163986 18.378957)
			(xy 309.079696 18.394713) (xy 308.99722 18.41818) (xy 308.917261 18.449156) (xy 308.840501 18.487378)
			(xy 308.767595 18.532519) (xy 308.699166 18.584195) (xy 308.635796 18.641964) (xy 308.578027 18.705334)
			(xy 308.526351 18.773763) (xy 308.48121 18.846669) (xy 308.442988 18.923429) (xy 308.412012 19.003388)
			(xy 308.388545 19.085864) (xy 308.372789 19.170154) (xy 308.364877 19.255537) (xy 277.508832 19.255537)
			(xy 277.501579 19.177266) (xy 277.485823 19.092976) (xy 277.462356 19.0105) (xy 277.43138 18.930541)
			(xy 277.393158 18.853781) (xy 277.348017 18.780875) (xy 277.296341 18.712446) (xy 277.238572 18.649076)
			(xy 277.175202 18.591307) (xy 277.106773 18.539631) (xy 277.033867 18.49449) (xy 276.957107 18.456268)
			(xy 276.877148 18.425292) (xy 276.794672 18.401825) (xy 276.710382 18.386069) (xy 276.624999 18.378157)
			(xy 276.539249 18.378157) (xy 276.453866 18.386069) (xy 276.369576 18.401825) (xy 276.2871 18.425292)
			(xy 276.207141 18.456268) (xy 276.130381 18.49449) (xy 276.057475 18.539631) (xy 275.989046 18.591307)
			(xy 275.925676 18.649076) (xy 275.867907 18.712446) (xy 275.816231 18.780875) (xy 275.77109 18.853781)
			(xy 275.732868 18.930541) (xy 275.701892 19.0105) (xy 275.678425 19.092976) (xy 275.662669 19.177266)
			(xy 275.654757 19.262649) (xy 271.159491 19.262649) (xy 271.151579 19.177266) (xy 271.135823 19.092976)
			(xy 271.112356 19.0105) (xy 271.08138 18.930541) (xy 271.043158 18.853781) (xy 270.998017 18.780875)
			(xy 270.946341 18.712446) (xy 270.888572 18.649076) (xy 270.825202 18.591307) (xy 270.756773 18.539631)
			(xy 270.683867 18.49449) (xy 270.607107 18.456268) (xy 270.527148 18.425292) (xy 270.444672 18.401825)
			(xy 270.360382 18.386069) (xy 270.274999 18.378157) (xy 270.189249 18.378157) (xy 270.103866 18.386069)
			(xy 270.019576 18.401825) (xy 269.9371 18.425292) (xy 269.857141 18.456268) (xy 269.780381 18.49449)
			(xy 269.707475 18.539631) (xy 269.639046 18.591307) (xy 269.575676 18.649076) (xy 269.517907 18.712446)
			(xy 269.466231 18.780875) (xy 269.42109 18.853781) (xy 269.382868 18.930541) (xy 269.351892 19.0105)
			(xy 269.328425 19.092976) (xy 269.312669 19.177266) (xy 269.304757 19.262649) (xy 252.231493 19.262649)
			(xy 252.231411 19.255537) (xy 252.223499 19.170154) (xy 252.207743 19.085864) (xy 252.184276 19.003388)
			(xy 252.1533 18.923429) (xy 252.115078 18.846669) (xy 252.069937 18.773763) (xy 252.018261 18.705334)
			(xy 251.960492 18.641964) (xy 251.897122 18.584195) (xy 251.828693 18.532519) (xy 251.755787 18.487378)
			(xy 251.679027 18.449156) (xy 251.599068 18.41818) (xy 251.516592 18.394713) (xy 251.432302 18.378957)
			(xy 251.346919 18.371045) (xy 251.261169 18.371045) (xy 251.175786 18.378957) (xy 251.091496 18.394713)
			(xy 251.00902 18.41818) (xy 250.929061 18.449156) (xy 250.852301 18.487378) (xy 250.779395 18.532519)
			(xy 250.710966 18.584195) (xy 250.647596 18.641964) (xy 250.589827 18.705334) (xy 250.538151 18.773763)
			(xy 250.49301 18.846669) (xy 250.454788 18.923429) (xy 250.423812 19.003388) (xy 250.400345 19.085864)
			(xy 250.384589 19.170154) (xy 250.376677 19.255537) (xy 245.881411 19.255537) (xy 245.873499 19.170154)
			(xy 245.857743 19.085864) (xy 245.834276 19.003388) (xy 245.8033 18.923429) (xy 245.765078 18.846669)
			(xy 245.719937 18.773763) (xy 245.668261 18.705334) (xy 245.610492 18.641964) (xy 245.547122 18.584195)
			(xy 245.478693 18.532519) (xy 245.405787 18.487378) (xy 245.329027 18.449156) (xy 245.249068 18.41818)
			(xy 245.166592 18.394713) (xy 245.082302 18.378957) (xy 244.996919 18.371045) (xy 244.911169 18.371045)
			(xy 244.825786 18.378957) (xy 244.741496 18.394713) (xy 244.65902 18.41818) (xy 244.579061 18.449156)
			(xy 244.502301 18.487378) (xy 244.429395 18.532519) (xy 244.360966 18.584195) (xy 244.297596 18.641964)
			(xy 244.239827 18.705334) (xy 244.188151 18.773763) (xy 244.14301 18.846669) (xy 244.104788 18.923429)
			(xy 244.073812 19.003388) (xy 244.050345 19.085864) (xy 244.034589 19.170154) (xy 244.026677 19.255537)
			(xy 218.199832 19.255537) (xy 218.192579 19.177266) (xy 218.176823 19.092976) (xy 218.153356 19.0105)
			(xy 218.12238 18.930541) (xy 218.084158 18.853781) (xy 218.039017 18.780875) (xy 217.987341 18.712446)
			(xy 217.929572 18.649076) (xy 217.866202 18.591307) (xy 217.797773 18.539631) (xy 217.724867 18.49449)
			(xy 217.648107 18.456268) (xy 217.568148 18.425292) (xy 217.485672 18.401825) (xy 217.401382 18.386069)
			(xy 217.315999 18.378157) (xy 217.230249 18.378157) (xy 217.144866 18.386069) (xy 217.060576 18.401825)
			(xy 216.9781 18.425292) (xy 216.898141 18.456268) (xy 216.821381 18.49449) (xy 216.748475 18.539631)
			(xy 216.680046 18.591307) (xy 216.616676 18.649076) (xy 216.558907 18.712446) (xy 216.507231 18.780875)
			(xy 216.46209 18.853781) (xy 216.423868 18.930541) (xy 216.392892 19.0105) (xy 216.369425 19.092976)
			(xy 216.353669 19.177266) (xy 216.345757 19.262649) (xy 211.850491 19.262649) (xy 211.842579 19.177266)
			(xy 211.826823 19.092976) (xy 211.803356 19.0105) (xy 211.77238 18.930541) (xy 211.734158 18.853781)
			(xy 211.689017 18.780875) (xy 211.637341 18.712446) (xy 211.579572 18.649076) (xy 211.516202 18.591307)
			(xy 211.447773 18.539631) (xy 211.374867 18.49449) (xy 211.298107 18.456268) (xy 211.218148 18.425292)
			(xy 211.135672 18.401825) (xy 211.051382 18.386069) (xy 210.965999 18.378157) (xy 210.880249 18.378157)
			(xy 210.794866 18.386069) (xy 210.710576 18.401825) (xy 210.6281 18.425292) (xy 210.548141 18.456268)
			(xy 210.471381 18.49449) (xy 210.398475 18.539631) (xy 210.330046 18.591307) (xy 210.266676 18.649076)
			(xy 210.208907 18.712446) (xy 210.157231 18.780875) (xy 210.11209 18.853781) (xy 210.073868 18.930541)
			(xy 210.042892 19.0105) (xy 210.019425 19.092976) (xy 210.003669 19.177266) (xy 209.995757 19.262649)
			(xy 158.621984 19.262649) (xy 158.621984 16.722649) (xy 209.995757 16.722649) (xy 209.995757 16.808399)
			(xy 210.003669 16.893782) (xy 210.019425 16.978072) (xy 210.042892 17.060548) (xy 210.073868 17.140507)
			(xy 210.11209 17.217267) (xy 210.157231 17.290173) (xy 210.208907 17.358602) (xy 210.266676 17.421972)
			(xy 210.330046 17.479741) (xy 210.398475 17.531417) (xy 210.471381 17.576558) (xy 210.548141 17.61478)
			(xy 210.6281 17.645756) (xy 210.710576 17.669223) (xy 210.794866 17.684979) (xy 210.880249 17.692891)
			(xy 210.965999 17.692891) (xy 211.051382 17.684979) (xy 211.135672 17.669223) (xy 211.218148 17.645756)
			(xy 211.298107 17.61478) (xy 211.374867 17.576558) (xy 211.447773 17.531417) (xy 211.516202 17.479741)
			(xy 211.579572 17.421972) (xy 211.637341 17.358602) (xy 211.689017 17.290173) (xy 211.734158 17.217267)
			(xy 211.77238 17.140507) (xy 211.803356 17.060548) (xy 211.826823 16.978072) (xy 211.842579 16.893782)
			(xy 211.850491 16.808399) (xy 211.850986 16.765524) (xy 211.850491 16.722649) (xy 216.345757 16.722649)
			(xy 216.345757 16.808399) (xy 216.353669 16.893782) (xy 216.369425 16.978072) (xy 216.392892 17.060548)
			(xy 216.423868 17.140507) (xy 216.46209 17.217267) (xy 216.507231 17.290173) (xy 216.558907 17.358602)
			(xy 216.616676 17.421972) (xy 216.680046 17.479741) (xy 216.748475 17.531417) (xy 216.821381 17.576558)
			(xy 216.898141 17.61478) (xy 216.9781 17.645756) (xy 217.060576 17.669223) (xy 217.144866 17.684979)
			(xy 217.230249 17.692891) (xy 217.315999 17.692891) (xy 217.401382 17.684979) (xy 217.485672 17.669223)
			(xy 217.568148 17.645756) (xy 217.648107 17.61478) (xy 217.724867 17.576558) (xy 217.797773 17.531417)
			(xy 217.866202 17.479741) (xy 217.929572 17.421972) (xy 217.987341 17.358602) (xy 218.039017 17.290173)
			(xy 218.084158 17.217267) (xy 218.12238 17.140507) (xy 218.153356 17.060548) (xy 218.176823 16.978072)
			(xy 218.192579 16.893782) (xy 218.200491 16.808399) (xy 218.200986 16.765524) (xy 218.200491 16.722649)
			(xy 218.199832 16.715537) (xy 244.026677 16.715537) (xy 244.026677 16.801287) (xy 244.034589 16.88667)
			(xy 244.050345 16.97096) (xy 244.073812 17.053436) (xy 244.104788 17.133395) (xy 244.14301 17.210155)
			(xy 244.188151 17.283061) (xy 244.239827 17.35149) (xy 244.297596 17.41486) (xy 244.360966 17.472629)
			(xy 244.429395 17.524305) (xy 244.502301 17.569446) (xy 244.579061 17.607668) (xy 244.65902 17.638644)
			(xy 244.741496 17.662111) (xy 244.825786 17.677867) (xy 244.911169 17.685779) (xy 244.996919 17.685779)
			(xy 245.082302 17.677867) (xy 245.166592 17.662111) (xy 245.249068 17.638644) (xy 245.329027 17.607668)
			(xy 245.405787 17.569446) (xy 245.478693 17.524305) (xy 245.547122 17.472629) (xy 245.610492 17.41486)
			(xy 245.668261 17.35149) (xy 245.719937 17.283061) (xy 245.765078 17.210155) (xy 245.8033 17.133395)
			(xy 245.834276 17.053436) (xy 245.857743 16.97096) (xy 245.873499 16.88667) (xy 245.881411 16.801287)
			(xy 245.881906 16.758412) (xy 245.881411 16.715537) (xy 250.376677 16.715537) (xy 250.376677 16.801287)
			(xy 250.384589 16.88667) (xy 250.400345 16.97096) (xy 250.423812 17.053436) (xy 250.454788 17.133395)
			(xy 250.49301 17.210155) (xy 250.538151 17.283061) (xy 250.589827 17.35149) (xy 250.647596 17.41486)
			(xy 250.710966 17.472629) (xy 250.779395 17.524305) (xy 250.852301 17.569446) (xy 250.929061 17.607668)
			(xy 251.00902 17.638644) (xy 251.091496 17.662111) (xy 251.175786 17.677867) (xy 251.261169 17.685779)
			(xy 251.346919 17.685779) (xy 251.432302 17.677867) (xy 251.516592 17.662111) (xy 251.599068 17.638644)
			(xy 251.679027 17.607668) (xy 251.755787 17.569446) (xy 251.828693 17.524305) (xy 251.897122 17.472629)
			(xy 251.960492 17.41486) (xy 252.018261 17.35149) (xy 252.069937 17.283061) (xy 252.115078 17.210155)
			(xy 252.1533 17.133395) (xy 252.184276 17.053436) (xy 252.207743 16.97096) (xy 252.223499 16.88667)
			(xy 252.231411 16.801287) (xy 252.231906 16.758412) (xy 252.231493 16.722649) (xy 269.304757 16.722649)
			(xy 269.304757 16.808399) (xy 269.312669 16.893782) (xy 269.328425 16.978072) (xy 269.351892 17.060548)
			(xy 269.382868 17.140507) (xy 269.42109 17.217267) (xy 269.466231 17.290173) (xy 269.517907 17.358602)
			(xy 269.575676 17.421972) (xy 269.639046 17.479741) (xy 269.707475 17.531417) (xy 269.780381 17.576558)
			(xy 269.857141 17.61478) (xy 269.9371 17.645756) (xy 270.019576 17.669223) (xy 270.103866 17.684979)
			(xy 270.189249 17.692891) (xy 270.274999 17.692891) (xy 270.360382 17.684979) (xy 270.444672 17.669223)
			(xy 270.527148 17.645756) (xy 270.607107 17.61478) (xy 270.62931 17.603724) (xy 274.239736 17.603724)
			(xy 274.239736 18.467324) (xy 274.240222 18.494593) (xy 274.247984 18.548577) (xy 274.263349 18.600907)
			(xy 274.286006 18.650517) (xy 274.315492 18.696398) (xy 274.351207 18.737615) (xy 274.392424 18.77333)
			(xy 274.438305 18.802816) (xy 274.487915 18.825473) (xy 274.540245 18.840838) (xy 274.594229 18.8486)
			(xy 274.648767 18.8486) (xy 274.702751 18.840838) (xy 274.755081 18.825473) (xy 274.804691 18.802816)
			(xy 274.850572 18.77333) (xy 274.891789 18.737615) (xy 274.927504 18.696398) (xy 274.95699 18.650517)
			(xy 274.979647 18.600907) (xy 274.995012 18.548577) (xy 275.002774 18.494593) (xy 275.00326 18.467324)
			(xy 275.00326 17.603724) (xy 275.002774 17.576455) (xy 274.995012 17.522471) (xy 274.979647 17.470141)
			(xy 274.95699 17.420531) (xy 274.927504 17.37465) (xy 274.891789 17.333433) (xy 274.850572 17.297718)
			(xy 274.804691 17.268232) (xy 274.755081 17.245575) (xy 274.702751 17.23021) (xy 274.648767 17.222448)
			(xy 274.594229 17.222448) (xy 274.540245 17.23021) (xy 274.487915 17.245575) (xy 274.438305 17.268232)
			(xy 274.392424 17.297718) (xy 274.351207 17.333433) (xy 274.315492 17.37465) (xy 274.286006 17.420531)
			(xy 274.263349 17.470141) (xy 274.247984 17.522471) (xy 274.240222 17.576455) (xy 274.239736 17.603724)
			(xy 270.62931 17.603724) (xy 270.683867 17.576558) (xy 270.756773 17.531417) (xy 270.825202 17.479741)
			(xy 270.888572 17.421972) (xy 270.946341 17.358602) (xy 270.998017 17.290173) (xy 271.043158 17.217267)
			(xy 271.08138 17.140507) (xy 271.112356 17.060548) (xy 271.135823 16.978072) (xy 271.151579 16.893782)
			(xy 271.159491 16.808399) (xy 271.159986 16.765524) (xy 271.159491 16.722649) (xy 275.654757 16.722649)
			(xy 275.654757 16.808399) (xy 275.662669 16.893782) (xy 275.678425 16.978072) (xy 275.701892 17.060548)
			(xy 275.732868 17.140507) (xy 275.77109 17.217267) (xy 275.816231 17.290173) (xy 275.867907 17.358602)
			(xy 275.925676 17.421972) (xy 275.989046 17.479741) (xy 276.057475 17.531417) (xy 276.130381 17.576558)
			(xy 276.207141 17.61478) (xy 276.2871 17.645756) (xy 276.369576 17.669223) (xy 276.453866 17.684979)
			(xy 276.539249 17.692891) (xy 276.624999 17.692891) (xy 276.710382 17.684979) (xy 276.794672 17.669223)
			(xy 276.877148 17.645756) (xy 276.957107 17.61478) (xy 277.033867 17.576558) (xy 277.106773 17.531417)
			(xy 277.175202 17.479741) (xy 277.238572 17.421972) (xy 277.296341 17.358602) (xy 277.348017 17.290173)
			(xy 277.393158 17.217267) (xy 277.43138 17.140507) (xy 277.462356 17.060548) (xy 277.485823 16.978072)
			(xy 277.501579 16.893782) (xy 277.509491 16.808399) (xy 277.509986 16.765524) (xy 277.509491 16.722649)
			(xy 277.508832 16.715537) (xy 308.364877 16.715537) (xy 308.364877 16.801287) (xy 308.372789 16.88667)
			(xy 308.388545 16.97096) (xy 308.412012 17.053436) (xy 308.442988 17.133395) (xy 308.48121 17.210155)
			(xy 308.526351 17.283061) (xy 308.578027 17.35149) (xy 308.635796 17.41486) (xy 308.699166 17.472629)
			(xy 308.767595 17.524305) (xy 308.840501 17.569446) (xy 308.917261 17.607668) (xy 308.99722 17.638644)
			(xy 309.079696 17.662111) (xy 309.163986 17.677867) (xy 309.249369 17.685779) (xy 309.335119 17.685779)
			(xy 309.420502 17.677867) (xy 309.504792 17.662111) (xy 309.587268 17.638644) (xy 309.667227 17.607668)
			(xy 309.68943 17.596612) (xy 310.871108 17.596612) (xy 310.871108 18.460212) (xy 310.871594 18.487481)
			(xy 310.879356 18.541465) (xy 310.894721 18.593795) (xy 310.917378 18.643405) (xy 310.946864 18.689286)
			(xy 310.982579 18.730503) (xy 311.023796 18.766218) (xy 311.069677 18.795704) (xy 311.119287 18.818361)
			(xy 311.171617 18.833726) (xy 311.225601 18.841488) (xy 311.280139 18.841488) (xy 311.334123 18.833726)
			(xy 311.386453 18.818361) (xy 311.436063 18.795704) (xy 311.481944 18.766218) (xy 311.523161 18.730503)
			(xy 311.558876 18.689286) (xy 311.588362 18.643405) (xy 311.611019 18.593795) (xy 311.626384 18.541465)
			(xy 311.634146 18.487481) (xy 311.634632 18.460212) (xy 311.634632 17.596612) (xy 311.634146 17.569343)
			(xy 311.626384 17.515359) (xy 311.611019 17.463029) (xy 311.588362 17.413419) (xy 311.558876 17.367538)
			(xy 311.523161 17.326321) (xy 311.481944 17.290606) (xy 311.436063 17.26112) (xy 311.386453 17.238463)
			(xy 311.334123 17.223098) (xy 311.280139 17.215336) (xy 311.225601 17.215336) (xy 311.171617 17.223098)
			(xy 311.119287 17.238463) (xy 311.069677 17.26112) (xy 311.023796 17.290606) (xy 310.982579 17.326321)
			(xy 310.946864 17.367538) (xy 310.917378 17.413419) (xy 310.894721 17.463029) (xy 310.879356 17.515359)
			(xy 310.871594 17.569343) (xy 310.871108 17.596612) (xy 309.68943 17.596612) (xy 309.743987 17.569446)
			(xy 309.816893 17.524305) (xy 309.885322 17.472629) (xy 309.948692 17.41486) (xy 310.006461 17.35149)
			(xy 310.058137 17.283061) (xy 310.103278 17.210155) (xy 310.1415 17.133395) (xy 310.172476 17.053436)
			(xy 310.195943 16.97096) (xy 310.211699 16.88667) (xy 310.219611 16.801287) (xy 310.220106 16.758412)
			(xy 310.219611 16.715537) (xy 314.714877 16.715537) (xy 314.714877 16.801287) (xy 314.722789 16.88667)
			(xy 314.738545 16.97096) (xy 314.762012 17.053436) (xy 314.792988 17.133395) (xy 314.83121 17.210155)
			(xy 314.876351 17.283061) (xy 314.928027 17.35149) (xy 314.985796 17.41486) (xy 315.049166 17.472629)
			(xy 315.117595 17.524305) (xy 315.190501 17.569446) (xy 315.267261 17.607668) (xy 315.34722 17.638644)
			(xy 315.429696 17.662111) (xy 315.513986 17.677867) (xy 315.599369 17.685779) (xy 315.685119 17.685779)
			(xy 315.770502 17.677867) (xy 315.854792 17.662111) (xy 315.937268 17.638644) (xy 316.017227 17.607668)
			(xy 316.093987 17.569446) (xy 316.166893 17.524305) (xy 316.235322 17.472629) (xy 316.298692 17.41486)
			(xy 316.356461 17.35149) (xy 316.408137 17.283061) (xy 316.453278 17.210155) (xy 316.4915 17.133395)
			(xy 316.522476 17.053436) (xy 316.545943 16.97096) (xy 316.561699 16.88667) (xy 316.569611 16.801287)
			(xy 316.570106 16.758412) (xy 316.569693 16.722649) (xy 334.455757 16.722649) (xy 334.455757 16.808399)
			(xy 334.463669 16.893782) (xy 334.479425 16.978072) (xy 334.502892 17.060548) (xy 334.533868 17.140507)
			(xy 334.57209 17.217267) (xy 334.617231 17.290173) (xy 334.668907 17.358602) (xy 334.726676 17.421972)
			(xy 334.790046 17.479741) (xy 334.858475 17.531417) (xy 334.931381 17.576558) (xy 335.008141 17.61478)
			(xy 335.0881 17.645756) (xy 335.170576 17.669223) (xy 335.254866 17.684979) (xy 335.340249 17.692891)
			(xy 335.425999 17.692891) (xy 335.511382 17.684979) (xy 335.595672 17.669223) (xy 335.678148 17.645756)
			(xy 335.758107 17.61478) (xy 335.78031 17.603724) (xy 339.390736 17.603724) (xy 339.390736 18.467324)
			(xy 339.391222 18.494593) (xy 339.398984 18.548577) (xy 339.414349 18.600907) (xy 339.437006 18.650517)
			(xy 339.466492 18.696398) (xy 339.502207 18.737615) (xy 339.543424 18.77333) (xy 339.589305 18.802816)
			(xy 339.638915 18.825473) (xy 339.691245 18.840838) (xy 339.745229 18.8486) (xy 339.799767 18.8486)
			(xy 339.853751 18.840838) (xy 339.906081 18.825473) (xy 339.955691 18.802816) (xy 340.001572 18.77333)
			(xy 340.042789 18.737615) (xy 340.078504 18.696398) (xy 340.10799 18.650517) (xy 340.130647 18.600907)
			(xy 340.146012 18.548577) (xy 340.153774 18.494593) (xy 340.15426 18.467324) (xy 340.15426 17.603724)
			(xy 340.153774 17.576455) (xy 340.146012 17.522471) (xy 340.130647 17.470141) (xy 340.10799 17.420531)
			(xy 340.078504 17.37465) (xy 340.042789 17.333433) (xy 340.001572 17.297718) (xy 339.955691 17.268232)
			(xy 339.906081 17.245575) (xy 339.853751 17.23021) (xy 339.799767 17.222448) (xy 339.745229 17.222448)
			(xy 339.691245 17.23021) (xy 339.638915 17.245575) (xy 339.589305 17.268232) (xy 339.543424 17.297718)
			(xy 339.502207 17.333433) (xy 339.466492 17.37465) (xy 339.437006 17.420531) (xy 339.414349 17.470141)
			(xy 339.398984 17.522471) (xy 339.391222 17.576455) (xy 339.390736 17.603724) (xy 335.78031 17.603724)
			(xy 335.834867 17.576558) (xy 335.907773 17.531417) (xy 335.976202 17.479741) (xy 336.039572 17.421972)
			(xy 336.097341 17.358602) (xy 336.149017 17.290173) (xy 336.194158 17.217267) (xy 336.23238 17.140507)
			(xy 336.263356 17.060548) (xy 336.286823 16.978072) (xy 336.302579 16.893782) (xy 336.310491 16.808399)
			(xy 336.310986 16.765524) (xy 336.310491 16.722649) (xy 340.805757 16.722649) (xy 340.805757 16.808399)
			(xy 340.813669 16.893782) (xy 340.829425 16.978072) (xy 340.852892 17.060548) (xy 340.883868 17.140507)
			(xy 340.92209 17.217267) (xy 340.967231 17.290173) (xy 341.018907 17.358602) (xy 341.076676 17.421972)
			(xy 341.140046 17.479741) (xy 341.208475 17.531417) (xy 341.281381 17.576558) (xy 341.358141 17.61478)
			(xy 341.4381 17.645756) (xy 341.520576 17.669223) (xy 341.604866 17.684979) (xy 341.690249 17.692891)
			(xy 341.775999 17.692891) (xy 341.861382 17.684979) (xy 341.945672 17.669223) (xy 342.028148 17.645756)
			(xy 342.108107 17.61478) (xy 342.184867 17.576558) (xy 342.257773 17.531417) (xy 342.326202 17.479741)
			(xy 342.389572 17.421972) (xy 342.447341 17.358602) (xy 342.499017 17.290173) (xy 342.544158 17.217267)
			(xy 342.58238 17.140507) (xy 342.613356 17.060548) (xy 342.636823 16.978072) (xy 342.652579 16.893782)
			(xy 342.660491 16.808399) (xy 342.660986 16.765524) (xy 342.660491 16.722649) (xy 342.659832 16.715537)
			(xy 373.515877 16.715537) (xy 373.515877 16.801287) (xy 373.523789 16.88667) (xy 373.539545 16.97096)
			(xy 373.563012 17.053436) (xy 373.593988 17.133395) (xy 373.63221 17.210155) (xy 373.677351 17.283061)
			(xy 373.729027 17.35149) (xy 373.786796 17.41486) (xy 373.850166 17.472629) (xy 373.918595 17.524305)
			(xy 373.991501 17.569446) (xy 374.068261 17.607668) (xy 374.14822 17.638644) (xy 374.230696 17.662111)
			(xy 374.314986 17.677867) (xy 374.400369 17.685779) (xy 374.486119 17.685779) (xy 374.571502 17.677867)
			(xy 374.655792 17.662111) (xy 374.738268 17.638644) (xy 374.818227 17.607668) (xy 374.84043 17.596612)
			(xy 376.022108 17.596612) (xy 376.022108 18.460212) (xy 376.022594 18.487481) (xy 376.030356 18.541465)
			(xy 376.045721 18.593795) (xy 376.068378 18.643405) (xy 376.097864 18.689286) (xy 376.133579 18.730503)
			(xy 376.174796 18.766218) (xy 376.220677 18.795704) (xy 376.270287 18.818361) (xy 376.322617 18.833726)
			(xy 376.376601 18.841488) (xy 376.431139 18.841488) (xy 376.485123 18.833726) (xy 376.537453 18.818361)
			(xy 376.587063 18.795704) (xy 376.632944 18.766218) (xy 376.674161 18.730503) (xy 376.709876 18.689286)
			(xy 376.739362 18.643405) (xy 376.762019 18.593795) (xy 376.777384 18.541465) (xy 376.785146 18.487481)
			(xy 376.785632 18.460212) (xy 376.785632 17.596612) (xy 376.785146 17.569343) (xy 376.777384 17.515359)
			(xy 376.762019 17.463029) (xy 376.739362 17.413419) (xy 376.709876 17.367538) (xy 376.674161 17.326321)
			(xy 376.632944 17.290606) (xy 376.587063 17.26112) (xy 376.537453 17.238463) (xy 376.485123 17.223098)
			(xy 376.431139 17.215336) (xy 376.376601 17.215336) (xy 376.322617 17.223098) (xy 376.270287 17.238463)
			(xy 376.220677 17.26112) (xy 376.174796 17.290606) (xy 376.133579 17.326321) (xy 376.097864 17.367538)
			(xy 376.068378 17.413419) (xy 376.045721 17.463029) (xy 376.030356 17.515359) (xy 376.022594 17.569343)
			(xy 376.022108 17.596612) (xy 374.84043 17.596612) (xy 374.894987 17.569446) (xy 374.967893 17.524305)
			(xy 375.036322 17.472629) (xy 375.099692 17.41486) (xy 375.157461 17.35149) (xy 375.209137 17.283061)
			(xy 375.254278 17.210155) (xy 375.2925 17.133395) (xy 375.323476 17.053436) (xy 375.346943 16.97096)
			(xy 375.362699 16.88667) (xy 375.370611 16.801287) (xy 375.371106 16.758412) (xy 375.370611 16.715537)
			(xy 379.865877 16.715537) (xy 379.865877 16.801287) (xy 379.873789 16.88667) (xy 379.889545 16.97096)
			(xy 379.913012 17.053436) (xy 379.943988 17.133395) (xy 379.98221 17.210155) (xy 380.027351 17.283061)
			(xy 380.079027 17.35149) (xy 380.136796 17.41486) (xy 380.200166 17.472629) (xy 380.268595 17.524305)
			(xy 380.341501 17.569446) (xy 380.418261 17.607668) (xy 380.49822 17.638644) (xy 380.580696 17.662111)
			(xy 380.664986 17.677867) (xy 380.750369 17.685779) (xy 380.836119 17.685779) (xy 380.921502 17.677867)
			(xy 381.005792 17.662111) (xy 381.088268 17.638644) (xy 381.168227 17.607668) (xy 381.244987 17.569446)
			(xy 381.317893 17.524305) (xy 381.386322 17.472629) (xy 381.449692 17.41486) (xy 381.507461 17.35149)
			(xy 381.559137 17.283061) (xy 381.604278 17.210155) (xy 381.6425 17.133395) (xy 381.673476 17.053436)
			(xy 381.696943 16.97096) (xy 381.712699 16.88667) (xy 381.720611 16.801287) (xy 381.721106 16.758412)
			(xy 381.720693 16.722649) (xy 399.098757 16.722649) (xy 399.098757 16.808399) (xy 399.106669 16.893782)
			(xy 399.122425 16.978072) (xy 399.145892 17.060548) (xy 399.176868 17.140507) (xy 399.21509 17.217267)
			(xy 399.260231 17.290173) (xy 399.311907 17.358602) (xy 399.369676 17.421972) (xy 399.433046 17.479741)
			(xy 399.501475 17.531417) (xy 399.574381 17.576558) (xy 399.651141 17.61478) (xy 399.7311 17.645756)
			(xy 399.813576 17.669223) (xy 399.897866 17.684979) (xy 399.983249 17.692891) (xy 400.068999 17.692891)
			(xy 400.154382 17.684979) (xy 400.238672 17.669223) (xy 400.321148 17.645756) (xy 400.401107 17.61478)
			(xy 400.42331 17.603724) (xy 404.033736 17.603724) (xy 404.033736 18.467324) (xy 404.034222 18.494593)
			(xy 404.041984 18.548577) (xy 404.057349 18.600907) (xy 404.080006 18.650517) (xy 404.109492 18.696398)
			(xy 404.145207 18.737615) (xy 404.186424 18.77333) (xy 404.232305 18.802816) (xy 404.281915 18.825473)
			(xy 404.334245 18.840838) (xy 404.388229 18.8486) (xy 404.442767 18.8486) (xy 404.496751 18.840838)
			(xy 404.549081 18.825473) (xy 404.598691 18.802816) (xy 404.644572 18.77333) (xy 404.685789 18.737615)
			(xy 404.721504 18.696398) (xy 404.75099 18.650517) (xy 404.773647 18.600907) (xy 404.789012 18.548577)
			(xy 404.796774 18.494593) (xy 404.79726 18.467324) (xy 404.79726 17.603724) (xy 404.796774 17.576455)
			(xy 404.789012 17.522471) (xy 404.773647 17.470141) (xy 404.75099 17.420531) (xy 404.721504 17.37465)
			(xy 404.685789 17.333433) (xy 404.644572 17.297718) (xy 404.598691 17.268232) (xy 404.549081 17.245575)
			(xy 404.496751 17.23021) (xy 404.442767 17.222448) (xy 404.388229 17.222448) (xy 404.334245 17.23021)
			(xy 404.281915 17.245575) (xy 404.232305 17.268232) (xy 404.186424 17.297718) (xy 404.145207 17.333433)
			(xy 404.109492 17.37465) (xy 404.080006 17.420531) (xy 404.057349 17.470141) (xy 404.041984 17.522471)
			(xy 404.034222 17.576455) (xy 404.033736 17.603724) (xy 400.42331 17.603724) (xy 400.477867 17.576558)
			(xy 400.550773 17.531417) (xy 400.619202 17.479741) (xy 400.682572 17.421972) (xy 400.740341 17.358602)
			(xy 400.792017 17.290173) (xy 400.837158 17.217267) (xy 400.87538 17.140507) (xy 400.906356 17.060548)
			(xy 400.929823 16.978072) (xy 400.945579 16.893782) (xy 400.953491 16.808399) (xy 400.953986 16.765524)
			(xy 400.953491 16.722649) (xy 405.448757 16.722649) (xy 405.448757 16.808399) (xy 405.456669 16.893782)
			(xy 405.472425 16.978072) (xy 405.495892 17.060548) (xy 405.526868 17.140507) (xy 405.56509 17.217267)
			(xy 405.610231 17.290173) (xy 405.661907 17.358602) (xy 405.719676 17.421972) (xy 405.783046 17.479741)
			(xy 405.851475 17.531417) (xy 405.924381 17.576558) (xy 406.001141 17.61478) (xy 406.0811 17.645756)
			(xy 406.163576 17.669223) (xy 406.247866 17.684979) (xy 406.333249 17.692891) (xy 406.418999 17.692891)
			(xy 406.504382 17.684979) (xy 406.588672 17.669223) (xy 406.671148 17.645756) (xy 406.751107 17.61478)
			(xy 406.827867 17.576558) (xy 406.900773 17.531417) (xy 406.969202 17.479741) (xy 407.032572 17.421972)
			(xy 407.090341 17.358602) (xy 407.142017 17.290173) (xy 407.187158 17.217267) (xy 407.22538 17.140507)
			(xy 407.256356 17.060548) (xy 407.279823 16.978072) (xy 407.295579 16.893782) (xy 407.303491 16.808399)
			(xy 407.303986 16.765524) (xy 407.303491 16.722649) (xy 407.302832 16.715537) (xy 438.158877 16.715537)
			(xy 438.158877 16.801287) (xy 438.166789 16.88667) (xy 438.182545 16.97096) (xy 438.206012 17.053436)
			(xy 438.236988 17.133395) (xy 438.27521 17.210155) (xy 438.320351 17.283061) (xy 438.372027 17.35149)
			(xy 438.429796 17.41486) (xy 438.493166 17.472629) (xy 438.561595 17.524305) (xy 438.634501 17.569446)
			(xy 438.711261 17.607668) (xy 438.79122 17.638644) (xy 438.873696 17.662111) (xy 438.957986 17.677867)
			(xy 439.043369 17.685779) (xy 439.129119 17.685779) (xy 439.214502 17.677867) (xy 439.298792 17.662111)
			(xy 439.381268 17.638644) (xy 439.461227 17.607668) (xy 439.48343 17.596612) (xy 440.665108 17.596612)
			(xy 440.665108 18.460212) (xy 440.665594 18.487481) (xy 440.673356 18.541465) (xy 440.688721 18.593795)
			(xy 440.711378 18.643405) (xy 440.740864 18.689286) (xy 440.776579 18.730503) (xy 440.817796 18.766218)
			(xy 440.863677 18.795704) (xy 440.913287 18.818361) (xy 440.965617 18.833726) (xy 441.019601 18.841488)
			(xy 441.074139 18.841488) (xy 441.128123 18.833726) (xy 441.180453 18.818361) (xy 441.230063 18.795704)
			(xy 441.275944 18.766218) (xy 441.317161 18.730503) (xy 441.352876 18.689286) (xy 441.382362 18.643405)
			(xy 441.405019 18.593795) (xy 441.420384 18.541465) (xy 441.428146 18.487481) (xy 441.428632 18.460212)
			(xy 441.428632 17.596612) (xy 441.428146 17.569343) (xy 441.420384 17.515359) (xy 441.405019 17.463029)
			(xy 441.382362 17.413419) (xy 441.352876 17.367538) (xy 441.317161 17.326321) (xy 441.275944 17.290606)
			(xy 441.230063 17.26112) (xy 441.180453 17.238463) (xy 441.128123 17.223098) (xy 441.074139 17.215336)
			(xy 441.019601 17.215336) (xy 440.965617 17.223098) (xy 440.913287 17.238463) (xy 440.863677 17.26112)
			(xy 440.817796 17.290606) (xy 440.776579 17.326321) (xy 440.740864 17.367538) (xy 440.711378 17.413419)
			(xy 440.688721 17.463029) (xy 440.673356 17.515359) (xy 440.665594 17.569343) (xy 440.665108 17.596612)
			(xy 439.48343 17.596612) (xy 439.537987 17.569446) (xy 439.610893 17.524305) (xy 439.679322 17.472629)
			(xy 439.742692 17.41486) (xy 439.800461 17.35149) (xy 439.852137 17.283061) (xy 439.897278 17.210155)
			(xy 439.9355 17.133395) (xy 439.966476 17.053436) (xy 439.989943 16.97096) (xy 440.005699 16.88667)
			(xy 440.013611 16.801287) (xy 440.014106 16.758412) (xy 440.013611 16.715537) (xy 444.508877 16.715537)
			(xy 444.508877 16.801287) (xy 444.516789 16.88667) (xy 444.532545 16.97096) (xy 444.556012 17.053436)
			(xy 444.586988 17.133395) (xy 444.62521 17.210155) (xy 444.670351 17.283061) (xy 444.722027 17.35149)
			(xy 444.779796 17.41486) (xy 444.843166 17.472629) (xy 444.911595 17.524305) (xy 444.984501 17.569446)
			(xy 445.061261 17.607668) (xy 445.14122 17.638644) (xy 445.223696 17.662111) (xy 445.307986 17.677867)
			(xy 445.393369 17.685779) (xy 445.479119 17.685779) (xy 445.564502 17.677867) (xy 445.648792 17.662111)
			(xy 445.731268 17.638644) (xy 445.811227 17.607668) (xy 445.887987 17.569446) (xy 445.960893 17.524305)
			(xy 446.029322 17.472629) (xy 446.092692 17.41486) (xy 446.150461 17.35149) (xy 446.202137 17.283061)
			(xy 446.247278 17.210155) (xy 446.2855 17.133395) (xy 446.316476 17.053436) (xy 446.339943 16.97096)
			(xy 446.355699 16.88667) (xy 446.363611 16.801287) (xy 446.364106 16.758412) (xy 446.363611 16.715537)
			(xy 446.355699 16.630154) (xy 446.339943 16.545864) (xy 446.316476 16.463388) (xy 446.2855 16.383429)
			(xy 446.247278 16.306669) (xy 446.202137 16.233763) (xy 446.150461 16.165334) (xy 446.092692 16.101964)
			(xy 446.029322 16.044195) (xy 445.960893 15.992519) (xy 445.887987 15.947378) (xy 445.811227 15.909156)
			(xy 445.731268 15.87818) (xy 445.648792 15.854713) (xy 445.564502 15.838957) (xy 445.479119 15.831045)
			(xy 445.393369 15.831045) (xy 445.307986 15.838957) (xy 445.223696 15.854713) (xy 445.14122 15.87818)
			(xy 445.061261 15.909156) (xy 444.984501 15.947378) (xy 444.911595 15.992519) (xy 444.843166 16.044195)
			(xy 444.779796 16.101964) (xy 444.722027 16.165334) (xy 444.670351 16.233763) (xy 444.62521 16.306669)
			(xy 444.586988 16.383429) (xy 444.556012 16.463388) (xy 444.532545 16.545864) (xy 444.516789 16.630154)
			(xy 444.508877 16.715537) (xy 440.013611 16.715537) (xy 440.005699 16.630154) (xy 439.989943 16.545864)
			(xy 439.966476 16.463388) (xy 439.9355 16.383429) (xy 439.897278 16.306669) (xy 439.852137 16.233763)
			(xy 439.800461 16.165334) (xy 439.742692 16.101964) (xy 439.679322 16.044195) (xy 439.610893 15.992519)
			(xy 439.537987 15.947378) (xy 439.461227 15.909156) (xy 439.381268 15.87818) (xy 439.298792 15.854713)
			(xy 439.214502 15.838957) (xy 439.129119 15.831045) (xy 439.043369 15.831045) (xy 438.957986 15.838957)
			(xy 438.873696 15.854713) (xy 438.79122 15.87818) (xy 438.711261 15.909156) (xy 438.634501 15.947378)
			(xy 438.561595 15.992519) (xy 438.493166 16.044195) (xy 438.429796 16.101964) (xy 438.372027 16.165334)
			(xy 438.320351 16.233763) (xy 438.27521 16.306669) (xy 438.236988 16.383429) (xy 438.206012 16.463388)
			(xy 438.182545 16.545864) (xy 438.166789 16.630154) (xy 438.158877 16.715537) (xy 407.302832 16.715537)
			(xy 407.295579 16.637266) (xy 407.279823 16.552976) (xy 407.256356 16.4705) (xy 407.22538 16.390541)
			(xy 407.187158 16.313781) (xy 407.142017 16.240875) (xy 407.090341 16.172446) (xy 407.032572 16.109076)
			(xy 406.969202 16.051307) (xy 406.900773 15.999631) (xy 406.827867 15.95449) (xy 406.751107 15.916268)
			(xy 406.671148 15.885292) (xy 406.588672 15.861825) (xy 406.504382 15.846069) (xy 406.418999 15.838157)
			(xy 406.333249 15.838157) (xy 406.247866 15.846069) (xy 406.163576 15.861825) (xy 406.0811 15.885292)
			(xy 406.001141 15.916268) (xy 405.924381 15.95449) (xy 405.851475 15.999631) (xy 405.783046 16.051307)
			(xy 405.719676 16.109076) (xy 405.661907 16.172446) (xy 405.610231 16.240875) (xy 405.56509 16.313781)
			(xy 405.526868 16.390541) (xy 405.495892 16.4705) (xy 405.472425 16.552976) (xy 405.456669 16.637266)
			(xy 405.448757 16.722649) (xy 400.953491 16.722649) (xy 400.945579 16.637266) (xy 400.929823 16.552976)
			(xy 400.906356 16.4705) (xy 400.87538 16.390541) (xy 400.837158 16.313781) (xy 400.792017 16.240875)
			(xy 400.740341 16.172446) (xy 400.682572 16.109076) (xy 400.619202 16.051307) (xy 400.550773 15.999631)
			(xy 400.477867 15.95449) (xy 400.401107 15.916268) (xy 400.321148 15.885292) (xy 400.238672 15.861825)
			(xy 400.154382 15.846069) (xy 400.068999 15.838157) (xy 399.983249 15.838157) (xy 399.897866 15.846069)
			(xy 399.813576 15.861825) (xy 399.7311 15.885292) (xy 399.651141 15.916268) (xy 399.574381 15.95449)
			(xy 399.501475 15.999631) (xy 399.433046 16.051307) (xy 399.369676 16.109076) (xy 399.311907 16.172446)
			(xy 399.260231 16.240875) (xy 399.21509 16.313781) (xy 399.176868 16.390541) (xy 399.145892 16.4705)
			(xy 399.122425 16.552976) (xy 399.106669 16.637266) (xy 399.098757 16.722649) (xy 381.720693 16.722649)
			(xy 381.720611 16.715537) (xy 381.712699 16.630154) (xy 381.696943 16.545864) (xy 381.673476 16.463388)
			(xy 381.6425 16.383429) (xy 381.604278 16.306669) (xy 381.559137 16.233763) (xy 381.507461 16.165334)
			(xy 381.449692 16.101964) (xy 381.386322 16.044195) (xy 381.317893 15.992519) (xy 381.244987 15.947378)
			(xy 381.168227 15.909156) (xy 381.088268 15.87818) (xy 381.005792 15.854713) (xy 380.921502 15.838957)
			(xy 380.836119 15.831045) (xy 380.750369 15.831045) (xy 380.664986 15.838957) (xy 380.580696 15.854713)
			(xy 380.49822 15.87818) (xy 380.418261 15.909156) (xy 380.341501 15.947378) (xy 380.268595 15.992519)
			(xy 380.200166 16.044195) (xy 380.136796 16.101964) (xy 380.079027 16.165334) (xy 380.027351 16.233763)
			(xy 379.98221 16.306669) (xy 379.943988 16.383429) (xy 379.913012 16.463388) (xy 379.889545 16.545864)
			(xy 379.873789 16.630154) (xy 379.865877 16.715537) (xy 375.370611 16.715537) (xy 375.362699 16.630154)
			(xy 375.346943 16.545864) (xy 375.323476 16.463388) (xy 375.2925 16.383429) (xy 375.254278 16.306669)
			(xy 375.209137 16.233763) (xy 375.157461 16.165334) (xy 375.099692 16.101964) (xy 375.036322 16.044195)
			(xy 374.967893 15.992519) (xy 374.894987 15.947378) (xy 374.818227 15.909156) (xy 374.738268 15.87818)
			(xy 374.655792 15.854713) (xy 374.571502 15.838957) (xy 374.486119 15.831045) (xy 374.400369 15.831045)
			(xy 374.314986 15.838957) (xy 374.230696 15.854713) (xy 374.14822 15.87818) (xy 374.068261 15.909156)
			(xy 373.991501 15.947378) (xy 373.918595 15.992519) (xy 373.850166 16.044195) (xy 373.786796 16.101964)
			(xy 373.729027 16.165334) (xy 373.677351 16.233763) (xy 373.63221 16.306669) (xy 373.593988 16.383429)
			(xy 373.563012 16.463388) (xy 373.539545 16.545864) (xy 373.523789 16.630154) (xy 373.515877 16.715537)
			(xy 342.659832 16.715537) (xy 342.652579 16.637266) (xy 342.636823 16.552976) (xy 342.613356 16.4705)
			(xy 342.58238 16.390541) (xy 342.544158 16.313781) (xy 342.499017 16.240875) (xy 342.447341 16.172446)
			(xy 342.389572 16.109076) (xy 342.326202 16.051307) (xy 342.257773 15.999631) (xy 342.184867 15.95449)
			(xy 342.108107 15.916268) (xy 342.028148 15.885292) (xy 341.945672 15.861825) (xy 341.861382 15.846069)
			(xy 341.775999 15.838157) (xy 341.690249 15.838157) (xy 341.604866 15.846069) (xy 341.520576 15.861825)
			(xy 341.4381 15.885292) (xy 341.358141 15.916268) (xy 341.281381 15.95449) (xy 341.208475 15.999631)
			(xy 341.140046 16.051307) (xy 341.076676 16.109076) (xy 341.018907 16.172446) (xy 340.967231 16.240875)
			(xy 340.92209 16.313781) (xy 340.883868 16.390541) (xy 340.852892 16.4705) (xy 340.829425 16.552976)
			(xy 340.813669 16.637266) (xy 340.805757 16.722649) (xy 336.310491 16.722649) (xy 336.302579 16.637266)
			(xy 336.286823 16.552976) (xy 336.263356 16.4705) (xy 336.23238 16.390541) (xy 336.194158 16.313781)
			(xy 336.149017 16.240875) (xy 336.097341 16.172446) (xy 336.039572 16.109076) (xy 335.976202 16.051307)
			(xy 335.907773 15.999631) (xy 335.834867 15.95449) (xy 335.758107 15.916268) (xy 335.678148 15.885292)
			(xy 335.595672 15.861825) (xy 335.511382 15.846069) (xy 335.425999 15.838157) (xy 335.340249 15.838157)
			(xy 335.254866 15.846069) (xy 335.170576 15.861825) (xy 335.0881 15.885292) (xy 335.008141 15.916268)
			(xy 334.931381 15.95449) (xy 334.858475 15.999631) (xy 334.790046 16.051307) (xy 334.726676 16.109076)
			(xy 334.668907 16.172446) (xy 334.617231 16.240875) (xy 334.57209 16.313781) (xy 334.533868 16.390541)
			(xy 334.502892 16.4705) (xy 334.479425 16.552976) (xy 334.463669 16.637266) (xy 334.455757 16.722649)
			(xy 316.569693 16.722649) (xy 316.569611 16.715537) (xy 316.561699 16.630154) (xy 316.545943 16.545864)
			(xy 316.522476 16.463388) (xy 316.4915 16.383429) (xy 316.453278 16.306669) (xy 316.408137 16.233763)
			(xy 316.356461 16.165334) (xy 316.298692 16.101964) (xy 316.235322 16.044195) (xy 316.166893 15.992519)
			(xy 316.093987 15.947378) (xy 316.017227 15.909156) (xy 315.937268 15.87818) (xy 315.854792 15.854713)
			(xy 315.770502 15.838957) (xy 315.685119 15.831045) (xy 315.599369 15.831045) (xy 315.513986 15.838957)
			(xy 315.429696 15.854713) (xy 315.34722 15.87818) (xy 315.267261 15.909156) (xy 315.190501 15.947378)
			(xy 315.117595 15.992519) (xy 315.049166 16.044195) (xy 314.985796 16.101964) (xy 314.928027 16.165334)
			(xy 314.876351 16.233763) (xy 314.83121 16.306669) (xy 314.792988 16.383429) (xy 314.762012 16.463388)
			(xy 314.738545 16.545864) (xy 314.722789 16.630154) (xy 314.714877 16.715537) (xy 310.219611 16.715537)
			(xy 310.211699 16.630154) (xy 310.195943 16.545864) (xy 310.172476 16.463388) (xy 310.1415 16.383429)
			(xy 310.103278 16.306669) (xy 310.058137 16.233763) (xy 310.006461 16.165334) (xy 309.948692 16.101964)
			(xy 309.885322 16.044195) (xy 309.816893 15.992519) (xy 309.743987 15.947378) (xy 309.667227 15.909156)
			(xy 309.587268 15.87818) (xy 309.504792 15.854713) (xy 309.420502 15.838957) (xy 309.335119 15.831045)
			(xy 309.249369 15.831045) (xy 309.163986 15.838957) (xy 309.079696 15.854713) (xy 308.99722 15.87818)
			(xy 308.917261 15.909156) (xy 308.840501 15.947378) (xy 308.767595 15.992519) (xy 308.699166 16.044195)
			(xy 308.635796 16.101964) (xy 308.578027 16.165334) (xy 308.526351 16.233763) (xy 308.48121 16.306669)
			(xy 308.442988 16.383429) (xy 308.412012 16.463388) (xy 308.388545 16.545864) (xy 308.372789 16.630154)
			(xy 308.364877 16.715537) (xy 277.508832 16.715537) (xy 277.501579 16.637266) (xy 277.485823 16.552976)
			(xy 277.462356 16.4705) (xy 277.43138 16.390541) (xy 277.393158 16.313781) (xy 277.348017 16.240875)
			(xy 277.296341 16.172446) (xy 277.238572 16.109076) (xy 277.175202 16.051307) (xy 277.106773 15.999631)
			(xy 277.033867 15.95449) (xy 276.957107 15.916268) (xy 276.877148 15.885292) (xy 276.794672 15.861825)
			(xy 276.710382 15.846069) (xy 276.624999 15.838157) (xy 276.539249 15.838157) (xy 276.453866 15.846069)
			(xy 276.369576 15.861825) (xy 276.2871 15.885292) (xy 276.207141 15.916268) (xy 276.130381 15.95449)
			(xy 276.057475 15.999631) (xy 275.989046 16.051307) (xy 275.925676 16.109076) (xy 275.867907 16.172446)
			(xy 275.816231 16.240875) (xy 275.77109 16.313781) (xy 275.732868 16.390541) (xy 275.701892 16.4705)
			(xy 275.678425 16.552976) (xy 275.662669 16.637266) (xy 275.654757 16.722649) (xy 271.159491 16.722649)
			(xy 271.151579 16.637266) (xy 271.135823 16.552976) (xy 271.112356 16.4705) (xy 271.08138 16.390541)
			(xy 271.043158 16.313781) (xy 270.998017 16.240875) (xy 270.946341 16.172446) (xy 270.888572 16.109076)
			(xy 270.825202 16.051307) (xy 270.756773 15.999631) (xy 270.683867 15.95449) (xy 270.607107 15.916268)
			(xy 270.527148 15.885292) (xy 270.444672 15.861825) (xy 270.360382 15.846069) (xy 270.274999 15.838157)
			(xy 270.189249 15.838157) (xy 270.103866 15.846069) (xy 270.019576 15.861825) (xy 269.9371 15.885292)
			(xy 269.857141 15.916268) (xy 269.780381 15.95449) (xy 269.707475 15.999631) (xy 269.639046 16.051307)
			(xy 269.575676 16.109076) (xy 269.517907 16.172446) (xy 269.466231 16.240875) (xy 269.42109 16.313781)
			(xy 269.382868 16.390541) (xy 269.351892 16.4705) (xy 269.328425 16.552976) (xy 269.312669 16.637266)
			(xy 269.304757 16.722649) (xy 252.231493 16.722649) (xy 252.231411 16.715537) (xy 252.223499 16.630154)
			(xy 252.207743 16.545864) (xy 252.184276 16.463388) (xy 252.1533 16.383429) (xy 252.115078 16.306669)
			(xy 252.069937 16.233763) (xy 252.018261 16.165334) (xy 251.960492 16.101964) (xy 251.897122 16.044195)
			(xy 251.828693 15.992519) (xy 251.755787 15.947378) (xy 251.679027 15.909156) (xy 251.599068 15.87818)
			(xy 251.516592 15.854713) (xy 251.432302 15.838957) (xy 251.346919 15.831045) (xy 251.261169 15.831045)
			(xy 251.175786 15.838957) (xy 251.091496 15.854713) (xy 251.00902 15.87818) (xy 250.929061 15.909156)
			(xy 250.852301 15.947378) (xy 250.779395 15.992519) (xy 250.710966 16.044195) (xy 250.647596 16.101964)
			(xy 250.589827 16.165334) (xy 250.538151 16.233763) (xy 250.49301 16.306669) (xy 250.454788 16.383429)
			(xy 250.423812 16.463388) (xy 250.400345 16.545864) (xy 250.384589 16.630154) (xy 250.376677 16.715537)
			(xy 245.881411 16.715537) (xy 245.873499 16.630154) (xy 245.857743 16.545864) (xy 245.834276 16.463388)
			(xy 245.8033 16.383429) (xy 245.765078 16.306669) (xy 245.719937 16.233763) (xy 245.668261 16.165334)
			(xy 245.610492 16.101964) (xy 245.547122 16.044195) (xy 245.478693 15.992519) (xy 245.405787 15.947378)
			(xy 245.329027 15.909156) (xy 245.249068 15.87818) (xy 245.166592 15.854713) (xy 245.082302 15.838957)
			(xy 244.996919 15.831045) (xy 244.911169 15.831045) (xy 244.825786 15.838957) (xy 244.741496 15.854713)
			(xy 244.65902 15.87818) (xy 244.579061 15.909156) (xy 244.502301 15.947378) (xy 244.429395 15.992519)
			(xy 244.360966 16.044195) (xy 244.297596 16.101964) (xy 244.239827 16.165334) (xy 244.188151 16.233763)
			(xy 244.14301 16.306669) (xy 244.104788 16.383429) (xy 244.073812 16.463388) (xy 244.050345 16.545864)
			(xy 244.034589 16.630154) (xy 244.026677 16.715537) (xy 218.199832 16.715537) (xy 218.192579 16.637266)
			(xy 218.176823 16.552976) (xy 218.153356 16.4705) (xy 218.12238 16.390541) (xy 218.084158 16.313781)
			(xy 218.039017 16.240875) (xy 217.987341 16.172446) (xy 217.929572 16.109076) (xy 217.866202 16.051307)
			(xy 217.797773 15.999631) (xy 217.724867 15.95449) (xy 217.648107 15.916268) (xy 217.568148 15.885292)
			(xy 217.485672 15.861825) (xy 217.401382 15.846069) (xy 217.315999 15.838157) (xy 217.230249 15.838157)
			(xy 217.144866 15.846069) (xy 217.060576 15.861825) (xy 216.9781 15.885292) (xy 216.898141 15.916268)
			(xy 216.821381 15.95449) (xy 216.748475 15.999631) (xy 216.680046 16.051307) (xy 216.616676 16.109076)
			(xy 216.558907 16.172446) (xy 216.507231 16.240875) (xy 216.46209 16.313781) (xy 216.423868 16.390541)
			(xy 216.392892 16.4705) (xy 216.369425 16.552976) (xy 216.353669 16.637266) (xy 216.345757 16.722649)
			(xy 211.850491 16.722649) (xy 211.842579 16.637266) (xy 211.826823 16.552976) (xy 211.803356 16.4705)
			(xy 211.77238 16.390541) (xy 211.734158 16.313781) (xy 211.689017 16.240875) (xy 211.637341 16.172446)
			(xy 211.579572 16.109076) (xy 211.516202 16.051307) (xy 211.447773 15.999631) (xy 211.374867 15.95449)
			(xy 211.298107 15.916268) (xy 211.218148 15.885292) (xy 211.135672 15.861825) (xy 211.051382 15.846069)
			(xy 210.965999 15.838157) (xy 210.880249 15.838157) (xy 210.794866 15.846069) (xy 210.710576 15.861825)
			(xy 210.6281 15.885292) (xy 210.548141 15.916268) (xy 210.471381 15.95449) (xy 210.398475 15.999631)
			(xy 210.330046 16.051307) (xy 210.266676 16.109076) (xy 210.208907 16.172446) (xy 210.157231 16.240875)
			(xy 210.11209 16.313781) (xy 210.073868 16.390541) (xy 210.042892 16.4705) (xy 210.019425 16.552976)
			(xy 210.003669 16.637266) (xy 209.995757 16.722649) (xy 158.621984 16.722649) (xy 158.621984 11.850929)
			(xy 251.524757 11.850929) (xy 251.524757 11.936679) (xy 251.532669 12.022062) (xy 251.548425 12.106352)
			(xy 251.571892 12.188828) (xy 251.602868 12.268787) (xy 251.64109 12.345547) (xy 251.686231 12.418453)
			(xy 251.737907 12.486882) (xy 251.795676 12.550252) (xy 251.859046 12.608021) (xy 251.927475 12.659697)
			(xy 252.000381 12.704838) (xy 252.077141 12.74306) (xy 252.1571 12.774036) (xy 252.239576 12.797503)
			(xy 252.323866 12.813259) (xy 252.409249 12.821171) (xy 252.494999 12.821171) (xy 252.580382 12.813259)
			(xy 252.664672 12.797503) (xy 252.747148 12.774036) (xy 252.827107 12.74306) (xy 252.903867 12.704838)
			(xy 252.976773 12.659697) (xy 253.045202 12.608021) (xy 253.108572 12.550252) (xy 253.166341 12.486882)
			(xy 253.218017 12.418453) (xy 253.263158 12.345547) (xy 253.30138 12.268787) (xy 253.332356 12.188828)
			(xy 253.355823 12.106352) (xy 253.371579 12.022062) (xy 253.379491 11.936679) (xy 253.379986 11.893804)
			(xy 253.379491 11.850929) (xy 257.874757 11.850929) (xy 257.874757 11.936679) (xy 257.882669 12.022062)
			(xy 257.898425 12.106352) (xy 257.921892 12.188828) (xy 257.952868 12.268787) (xy 257.99109 12.345547)
			(xy 258.036231 12.418453) (xy 258.087907 12.486882) (xy 258.145676 12.550252) (xy 258.209046 12.608021)
			(xy 258.277475 12.659697) (xy 258.350381 12.704838) (xy 258.427141 12.74306) (xy 258.5071 12.774036)
			(xy 258.589576 12.797503) (xy 258.673866 12.813259) (xy 258.759249 12.821171) (xy 258.844999 12.821171)
			(xy 258.930382 12.813259) (xy 259.014672 12.797503) (xy 259.097148 12.774036) (xy 259.177107 12.74306)
			(xy 259.253867 12.704838) (xy 259.326773 12.659697) (xy 259.395202 12.608021) (xy 259.458572 12.550252)
			(xy 259.516341 12.486882) (xy 259.568017 12.418453) (xy 259.613158 12.345547) (xy 259.65138 12.268787)
			(xy 259.682356 12.188828) (xy 259.705823 12.106352) (xy 259.721579 12.022062) (xy 259.729491 11.936679)
			(xy 259.729986 11.893804) (xy 259.72979 11.876837) (xy 309.725301 11.876837) (xy 309.725301 11.962587)
			(xy 309.733213 12.04797) (xy 309.748969 12.13226) (xy 309.772436 12.214736) (xy 309.803412 12.294695)
			(xy 309.841634 12.371455) (xy 309.886775 12.444361) (xy 309.938451 12.51279) (xy 309.99622 12.57616)
			(xy 310.05959 12.633929) (xy 310.128019 12.685605) (xy 310.200925 12.730746) (xy 310.277685 12.768968)
			(xy 310.357644 12.799944) (xy 310.44012 12.823411) (xy 310.52441 12.839167) (xy 310.609793 12.847079)
			(xy 310.695543 12.847079) (xy 310.780926 12.839167) (xy 310.865216 12.823411) (xy 310.947692 12.799944)
			(xy 311.027651 12.768968) (xy 311.104411 12.730746) (xy 311.177317 12.685605) (xy 311.245746 12.633929)
			(xy 311.309116 12.57616) (xy 311.366885 12.51279) (xy 311.418561 12.444361) (xy 311.463702 12.371455)
			(xy 311.501924 12.294695) (xy 311.5329 12.214736) (xy 311.556367 12.13226) (xy 311.572123 12.04797)
			(xy 311.580035 11.962587) (xy 311.58053 11.919712) (xy 311.580035 11.876837) (xy 316.075301 11.876837)
			(xy 316.075301 11.962587) (xy 316.083213 12.04797) (xy 316.098969 12.13226) (xy 316.122436 12.214736)
			(xy 316.153412 12.294695) (xy 316.191634 12.371455) (xy 316.236775 12.444361) (xy 316.288451 12.51279)
			(xy 316.34622 12.57616) (xy 316.40959 12.633929) (xy 316.478019 12.685605) (xy 316.550925 12.730746)
			(xy 316.627685 12.768968) (xy 316.707644 12.799944) (xy 316.79012 12.823411) (xy 316.87441 12.839167)
			(xy 316.959793 12.847079) (xy 317.045543 12.847079) (xy 317.130926 12.839167) (xy 317.215216 12.823411)
			(xy 317.297692 12.799944) (xy 317.377651 12.768968) (xy 317.454411 12.730746) (xy 317.527317 12.685605)
			(xy 317.595746 12.633929) (xy 317.659116 12.57616) (xy 317.716885 12.51279) (xy 317.768561 12.444361)
			(xy 317.813702 12.371455) (xy 317.851924 12.294695) (xy 317.8829 12.214736) (xy 317.906367 12.13226)
			(xy 317.922123 12.04797) (xy 317.930035 11.962587) (xy 317.93053 11.919712) (xy 317.930117 11.883949)
			(xy 324.295757 11.883949) (xy 324.295757 11.969699) (xy 324.303669 12.055082) (xy 324.319425 12.139372)
			(xy 324.342892 12.221848) (xy 324.373868 12.301807) (xy 324.41209 12.378567) (xy 324.457231 12.451473)
			(xy 324.508907 12.519902) (xy 324.566676 12.583272) (xy 324.630046 12.641041) (xy 324.698475 12.692717)
			(xy 324.771381 12.737858) (xy 324.848141 12.77608) (xy 324.9281 12.807056) (xy 325.010576 12.830523)
			(xy 325.094866 12.846279) (xy 325.180249 12.854191) (xy 325.265999 12.854191) (xy 325.351382 12.846279)
			(xy 325.435672 12.830523) (xy 325.518148 12.807056) (xy 325.598107 12.77608) (xy 325.674867 12.737858)
			(xy 325.747773 12.692717) (xy 325.816202 12.641041) (xy 325.879572 12.583272) (xy 325.937341 12.519902)
			(xy 325.989017 12.451473) (xy 326.034158 12.378567) (xy 326.07238 12.301807) (xy 326.103356 12.221848)
			(xy 326.126823 12.139372) (xy 326.142579 12.055082) (xy 326.150491 11.969699) (xy 326.150986 11.926824)
			(xy 326.150491 11.883949) (xy 330.645757 11.883949) (xy 330.645757 11.969699) (xy 330.653669 12.055082)
			(xy 330.669425 12.139372) (xy 330.692892 12.221848) (xy 330.723868 12.301807) (xy 330.76209 12.378567)
			(xy 330.807231 12.451473) (xy 330.858907 12.519902) (xy 330.916676 12.583272) (xy 330.980046 12.641041)
			(xy 331.048475 12.692717) (xy 331.121381 12.737858) (xy 331.198141 12.77608) (xy 331.2781 12.807056)
			(xy 331.360576 12.830523) (xy 331.444866 12.846279) (xy 331.530249 12.854191) (xy 331.615999 12.854191)
			(xy 331.701382 12.846279) (xy 331.785672 12.830523) (xy 331.868148 12.807056) (xy 331.948107 12.77608)
			(xy 332.024867 12.737858) (xy 332.097773 12.692717) (xy 332.166202 12.641041) (xy 332.229572 12.583272)
			(xy 332.287341 12.519902) (xy 332.339017 12.451473) (xy 332.384158 12.378567) (xy 332.42238 12.301807)
			(xy 332.453356 12.221848) (xy 332.476823 12.139372) (xy 332.492579 12.055082) (xy 332.500491 11.969699)
			(xy 332.500986 11.926824) (xy 332.50079 11.909857) (xy 382.496301 11.909857) (xy 382.496301 11.995607)
			(xy 382.504213 12.08099) (xy 382.519969 12.16528) (xy 382.543436 12.247756) (xy 382.574412 12.327715)
			(xy 382.612634 12.404475) (xy 382.657775 12.477381) (xy 382.709451 12.54581) (xy 382.76722 12.60918)
			(xy 382.83059 12.666949) (xy 382.899019 12.718625) (xy 382.971925 12.763766) (xy 383.048685 12.801988)
			(xy 383.128644 12.832964) (xy 383.21112 12.856431) (xy 383.29541 12.872187) (xy 383.380793 12.880099)
			(xy 383.466543 12.880099) (xy 383.551926 12.872187) (xy 383.636216 12.856431) (xy 383.718692 12.832964)
			(xy 383.798651 12.801988) (xy 383.875411 12.763766) (xy 383.948317 12.718625) (xy 384.016746 12.666949)
			(xy 384.080116 12.60918) (xy 384.137885 12.54581) (xy 384.189561 12.477381) (xy 384.234702 12.404475)
			(xy 384.272924 12.327715) (xy 384.3039 12.247756) (xy 384.327367 12.16528) (xy 384.343123 12.08099)
			(xy 384.351035 11.995607) (xy 384.35153 11.952732) (xy 384.351035 11.909857) (xy 388.846301 11.909857)
			(xy 388.846301 11.995607) (xy 388.854213 12.08099) (xy 388.869969 12.16528) (xy 388.893436 12.247756)
			(xy 388.924412 12.327715) (xy 388.962634 12.404475) (xy 389.007775 12.477381) (xy 389.059451 12.54581)
			(xy 389.11722 12.60918) (xy 389.18059 12.666949) (xy 389.249019 12.718625) (xy 389.321925 12.763766)
			(xy 389.398685 12.801988) (xy 389.478644 12.832964) (xy 389.56112 12.856431) (xy 389.64541 12.872187)
			(xy 389.730793 12.880099) (xy 389.816543 12.880099) (xy 389.901926 12.872187) (xy 389.986216 12.856431)
			(xy 390.068692 12.832964) (xy 390.148651 12.801988) (xy 390.225411 12.763766) (xy 390.298317 12.718625)
			(xy 390.366746 12.666949) (xy 390.430116 12.60918) (xy 390.487885 12.54581) (xy 390.539561 12.477381)
			(xy 390.584702 12.404475) (xy 390.622924 12.327715) (xy 390.6539 12.247756) (xy 390.677367 12.16528)
			(xy 390.693123 12.08099) (xy 390.701035 11.995607) (xy 390.70153 11.952732) (xy 390.701117 11.916969)
			(xy 396.558757 11.916969) (xy 396.558757 12.002719) (xy 396.566669 12.088102) (xy 396.582425 12.172392)
			(xy 396.605892 12.254868) (xy 396.636868 12.334827) (xy 396.67509 12.411587) (xy 396.720231 12.484493)
			(xy 396.771907 12.552922) (xy 396.829676 12.616292) (xy 396.893046 12.674061) (xy 396.961475 12.725737)
			(xy 397.034381 12.770878) (xy 397.111141 12.8091) (xy 397.1911 12.840076) (xy 397.273576 12.863543)
			(xy 397.357866 12.879299) (xy 397.443249 12.887211) (xy 397.528999 12.887211) (xy 397.614382 12.879299)
			(xy 397.698672 12.863543) (xy 397.781148 12.840076) (xy 397.861107 12.8091) (xy 397.937867 12.770878)
			(xy 398.010773 12.725737) (xy 398.079202 12.674061) (xy 398.142572 12.616292) (xy 398.200341 12.552922)
			(xy 398.252017 12.484493) (xy 398.297158 12.411587) (xy 398.33538 12.334827) (xy 398.366356 12.254868)
			(xy 398.389823 12.172392) (xy 398.405579 12.088102) (xy 398.413491 12.002719) (xy 398.413986 11.959844)
			(xy 398.413491 11.916969) (xy 402.908757 11.916969) (xy 402.908757 12.002719) (xy 402.916669 12.088102)
			(xy 402.932425 12.172392) (xy 402.955892 12.254868) (xy 402.986868 12.334827) (xy 403.02509 12.411587)
			(xy 403.070231 12.484493) (xy 403.121907 12.552922) (xy 403.179676 12.616292) (xy 403.243046 12.674061)
			(xy 403.311475 12.725737) (xy 403.384381 12.770878) (xy 403.461141 12.8091) (xy 403.5411 12.840076)
			(xy 403.623576 12.863543) (xy 403.707866 12.879299) (xy 403.793249 12.887211) (xy 403.878999 12.887211)
			(xy 403.964382 12.879299) (xy 404.048672 12.863543) (xy 404.131148 12.840076) (xy 404.211107 12.8091)
			(xy 404.287867 12.770878) (xy 404.360773 12.725737) (xy 404.429202 12.674061) (xy 404.492572 12.616292)
			(xy 404.550341 12.552922) (xy 404.602017 12.484493) (xy 404.647158 12.411587) (xy 404.68538 12.334827)
			(xy 404.716356 12.254868) (xy 404.739823 12.172392) (xy 404.755579 12.088102) (xy 404.763491 12.002719)
			(xy 404.763986 11.959844) (xy 404.76379 11.942877) (xy 454.759301 11.942877) (xy 454.759301 12.028627)
			(xy 454.767213 12.11401) (xy 454.782969 12.1983) (xy 454.806436 12.280776) (xy 454.837412 12.360735)
			(xy 454.875634 12.437495) (xy 454.920775 12.510401) (xy 454.972451 12.57883) (xy 455.03022 12.6422)
			(xy 455.09359 12.699969) (xy 455.162019 12.751645) (xy 455.234925 12.796786) (xy 455.311685 12.835008)
			(xy 455.391644 12.865984) (xy 455.47412 12.889451) (xy 455.55841 12.905207) (xy 455.643793 12.913119)
			(xy 455.729543 12.913119) (xy 455.814926 12.905207) (xy 455.899216 12.889451) (xy 455.981692 12.865984)
			(xy 456.061651 12.835008) (xy 456.138411 12.796786) (xy 456.211317 12.751645) (xy 456.279746 12.699969)
			(xy 456.343116 12.6422) (xy 456.400885 12.57883) (xy 456.452561 12.510401) (xy 456.497702 12.437495)
			(xy 456.535924 12.360735) (xy 456.5669 12.280776) (xy 456.590367 12.1983) (xy 456.606123 12.11401)
			(xy 456.614035 12.028627) (xy 456.61453 11.985752) (xy 456.614035 11.942877) (xy 461.109301 11.942877)
			(xy 461.109301 12.028627) (xy 461.117213 12.11401) (xy 461.132969 12.1983) (xy 461.156436 12.280776)
			(xy 461.187412 12.360735) (xy 461.225634 12.437495) (xy 461.270775 12.510401) (xy 461.322451 12.57883)
			(xy 461.38022 12.6422) (xy 461.44359 12.699969) (xy 461.512019 12.751645) (xy 461.584925 12.796786)
			(xy 461.661685 12.835008) (xy 461.741644 12.865984) (xy 461.82412 12.889451) (xy 461.90841 12.905207)
			(xy 461.993793 12.913119) (xy 462.079543 12.913119) (xy 462.164926 12.905207) (xy 462.249216 12.889451)
			(xy 462.331692 12.865984) (xy 462.411651 12.835008) (xy 462.488411 12.796786) (xy 462.561317 12.751645)
			(xy 462.629746 12.699969) (xy 462.693116 12.6422) (xy 462.750885 12.57883) (xy 462.802561 12.510401)
			(xy 462.847702 12.437495) (xy 462.885924 12.360735) (xy 462.9169 12.280776) (xy 462.940367 12.1983)
			(xy 462.956123 12.11401) (xy 462.964035 12.028627) (xy 462.96453 11.985752) (xy 462.964035 11.942877)
			(xy 462.956123 11.857494) (xy 462.940367 11.773204) (xy 462.9169 11.690728) (xy 462.885924 11.610769)
			(xy 462.847702 11.534009) (xy 462.802561 11.461103) (xy 462.750885 11.392674) (xy 462.693116 11.329304)
			(xy 462.629746 11.271535) (xy 462.561317 11.219859) (xy 462.488411 11.174718) (xy 462.411651 11.136496)
			(xy 462.331692 11.10552) (xy 462.249216 11.082053) (xy 462.164926 11.066297) (xy 462.079543 11.058385)
			(xy 461.993793 11.058385) (xy 461.90841 11.066297) (xy 461.82412 11.082053) (xy 461.741644 11.10552)
			(xy 461.661685 11.136496) (xy 461.584925 11.174718) (xy 461.512019 11.219859) (xy 461.44359 11.271535)
			(xy 461.38022 11.329304) (xy 461.322451 11.392674) (xy 461.270775 11.461103) (xy 461.225634 11.534009)
			(xy 461.187412 11.610769) (xy 461.156436 11.690728) (xy 461.132969 11.773204) (xy 461.117213 11.857494)
			(xy 461.109301 11.942877) (xy 456.614035 11.942877) (xy 456.606123 11.857494) (xy 456.590367 11.773204)
			(xy 456.5669 11.690728) (xy 456.535924 11.610769) (xy 456.497702 11.534009) (xy 456.452561 11.461103)
			(xy 456.400885 11.392674) (xy 456.343116 11.329304) (xy 456.279746 11.271535) (xy 456.211317 11.219859)
			(xy 456.138411 11.174718) (xy 456.061651 11.136496) (xy 455.981692 11.10552) (xy 455.899216 11.082053)
			(xy 455.814926 11.066297) (xy 455.729543 11.058385) (xy 455.643793 11.058385) (xy 455.55841 11.066297)
			(xy 455.47412 11.082053) (xy 455.391644 11.10552) (xy 455.311685 11.136496) (xy 455.234925 11.174718)
			(xy 455.162019 11.219859) (xy 455.09359 11.271535) (xy 455.03022 11.329304) (xy 454.972451 11.392674)
			(xy 454.920775 11.461103) (xy 454.875634 11.534009) (xy 454.837412 11.610769) (xy 454.806436 11.690728)
			(xy 454.782969 11.773204) (xy 454.767213 11.857494) (xy 454.759301 11.942877) (xy 404.76379 11.942877)
			(xy 404.763491 11.916969) (xy 404.755579 11.831586) (xy 404.739823 11.747296) (xy 404.716356 11.66482)
			(xy 404.68538 11.584861) (xy 404.647158 11.508101) (xy 404.602017 11.435195) (xy 404.550341 11.366766)
			(xy 404.492572 11.303396) (xy 404.429202 11.245627) (xy 404.360773 11.193951) (xy 404.287867 11.14881)
			(xy 404.211107 11.110588) (xy 404.131148 11.079612) (xy 404.048672 11.056145) (xy 403.964382 11.040389)
			(xy 403.878999 11.032477) (xy 403.793249 11.032477) (xy 403.707866 11.040389) (xy 403.623576 11.056145)
			(xy 403.5411 11.079612) (xy 403.461141 11.110588) (xy 403.384381 11.14881) (xy 403.311475 11.193951)
			(xy 403.243046 11.245627) (xy 403.179676 11.303396) (xy 403.121907 11.366766) (xy 403.070231 11.435195)
			(xy 403.02509 11.508101) (xy 402.986868 11.584861) (xy 402.955892 11.66482) (xy 402.932425 11.747296)
			(xy 402.916669 11.831586) (xy 402.908757 11.916969) (xy 398.413491 11.916969) (xy 398.405579 11.831586)
			(xy 398.389823 11.747296) (xy 398.366356 11.66482) (xy 398.33538 11.584861) (xy 398.297158 11.508101)
			(xy 398.252017 11.435195) (xy 398.200341 11.366766) (xy 398.142572 11.303396) (xy 398.079202 11.245627)
			(xy 398.010773 11.193951) (xy 397.937867 11.14881) (xy 397.861107 11.110588) (xy 397.781148 11.079612)
			(xy 397.698672 11.056145) (xy 397.614382 11.040389) (xy 397.528999 11.032477) (xy 397.443249 11.032477)
			(xy 397.357866 11.040389) (xy 397.273576 11.056145) (xy 397.1911 11.079612) (xy 397.111141 11.110588)
			(xy 397.034381 11.14881) (xy 396.961475 11.193951) (xy 396.893046 11.245627) (xy 396.829676 11.303396)
			(xy 396.771907 11.366766) (xy 396.720231 11.435195) (xy 396.67509 11.508101) (xy 396.636868 11.584861)
			(xy 396.605892 11.66482) (xy 396.582425 11.747296) (xy 396.566669 11.831586) (xy 396.558757 11.916969)
			(xy 390.701117 11.916969) (xy 390.701035 11.909857) (xy 390.693123 11.824474) (xy 390.677367 11.740184)
			(xy 390.6539 11.657708) (xy 390.622924 11.577749) (xy 390.584702 11.500989) (xy 390.539561 11.428083)
			(xy 390.487885 11.359654) (xy 390.430116 11.296284) (xy 390.366746 11.238515) (xy 390.298317 11.186839)
			(xy 390.225411 11.141698) (xy 390.148651 11.103476) (xy 390.068692 11.0725) (xy 389.986216 11.049033)
			(xy 389.901926 11.033277) (xy 389.816543 11.025365) (xy 389.730793 11.025365) (xy 389.64541 11.033277)
			(xy 389.56112 11.049033) (xy 389.478644 11.0725) (xy 389.398685 11.103476) (xy 389.321925 11.141698)
			(xy 389.249019 11.186839) (xy 389.18059 11.238515) (xy 389.11722 11.296284) (xy 389.059451 11.359654)
			(xy 389.007775 11.428083) (xy 388.962634 11.500989) (xy 388.924412 11.577749) (xy 388.893436 11.657708)
			(xy 388.869969 11.740184) (xy 388.854213 11.824474) (xy 388.846301 11.909857) (xy 384.351035 11.909857)
			(xy 384.343123 11.824474) (xy 384.327367 11.740184) (xy 384.3039 11.657708) (xy 384.272924 11.577749)
			(xy 384.234702 11.500989) (xy 384.189561 11.428083) (xy 384.137885 11.359654) (xy 384.080116 11.296284)
			(xy 384.016746 11.238515) (xy 383.948317 11.186839) (xy 383.875411 11.141698) (xy 383.798651 11.103476)
			(xy 383.718692 11.0725) (xy 383.636216 11.049033) (xy 383.551926 11.033277) (xy 383.466543 11.025365)
			(xy 383.380793 11.025365) (xy 383.29541 11.033277) (xy 383.21112 11.049033) (xy 383.128644 11.0725)
			(xy 383.048685 11.103476) (xy 382.971925 11.141698) (xy 382.899019 11.186839) (xy 382.83059 11.238515)
			(xy 382.76722 11.296284) (xy 382.709451 11.359654) (xy 382.657775 11.428083) (xy 382.612634 11.500989)
			(xy 382.574412 11.577749) (xy 382.543436 11.657708) (xy 382.519969 11.740184) (xy 382.504213 11.824474)
			(xy 382.496301 11.909857) (xy 332.50079 11.909857) (xy 332.500491 11.883949) (xy 332.492579 11.798566)
			(xy 332.476823 11.714276) (xy 332.453356 11.6318) (xy 332.42238 11.551841) (xy 332.384158 11.475081)
			(xy 332.339017 11.402175) (xy 332.287341 11.333746) (xy 332.229572 11.270376) (xy 332.166202 11.212607)
			(xy 332.097773 11.160931) (xy 332.024867 11.11579) (xy 331.948107 11.077568) (xy 331.868148 11.046592)
			(xy 331.785672 11.023125) (xy 331.701382 11.007369) (xy 331.615999 10.999457) (xy 331.530249 10.999457)
			(xy 331.444866 11.007369) (xy 331.360576 11.023125) (xy 331.2781 11.046592) (xy 331.198141 11.077568)
			(xy 331.121381 11.11579) (xy 331.048475 11.160931) (xy 330.980046 11.212607) (xy 330.916676 11.270376)
			(xy 330.858907 11.333746) (xy 330.807231 11.402175) (xy 330.76209 11.475081) (xy 330.723868 11.551841)
			(xy 330.692892 11.6318) (xy 330.669425 11.714276) (xy 330.653669 11.798566) (xy 330.645757 11.883949)
			(xy 326.150491 11.883949) (xy 326.142579 11.798566) (xy 326.126823 11.714276) (xy 326.103356 11.6318)
			(xy 326.07238 11.551841) (xy 326.034158 11.475081) (xy 325.989017 11.402175) (xy 325.937341 11.333746)
			(xy 325.879572 11.270376) (xy 325.816202 11.212607) (xy 325.747773 11.160931) (xy 325.674867 11.11579)
			(xy 325.598107 11.077568) (xy 325.518148 11.046592) (xy 325.435672 11.023125) (xy 325.351382 11.007369)
			(xy 325.265999 10.999457) (xy 325.180249 10.999457) (xy 325.094866 11.007369) (xy 325.010576 11.023125)
			(xy 324.9281 11.046592) (xy 324.848141 11.077568) (xy 324.771381 11.11579) (xy 324.698475 11.160931)
			(xy 324.630046 11.212607) (xy 324.566676 11.270376) (xy 324.508907 11.333746) (xy 324.457231 11.402175)
			(xy 324.41209 11.475081) (xy 324.373868 11.551841) (xy 324.342892 11.6318) (xy 324.319425 11.714276)
			(xy 324.303669 11.798566) (xy 324.295757 11.883949) (xy 317.930117 11.883949) (xy 317.930035 11.876837)
			(xy 317.922123 11.791454) (xy 317.906367 11.707164) (xy 317.8829 11.624688) (xy 317.851924 11.544729)
			(xy 317.813702 11.467969) (xy 317.768561 11.395063) (xy 317.716885 11.326634) (xy 317.659116 11.263264)
			(xy 317.595746 11.205495) (xy 317.527317 11.153819) (xy 317.454411 11.108678) (xy 317.377651 11.070456)
			(xy 317.297692 11.03948) (xy 317.215216 11.016013) (xy 317.130926 11.000257) (xy 317.045543 10.992345)
			(xy 316.959793 10.992345) (xy 316.87441 11.000257) (xy 316.79012 11.016013) (xy 316.707644 11.03948)
			(xy 316.627685 11.070456) (xy 316.550925 11.108678) (xy 316.478019 11.153819) (xy 316.40959 11.205495)
			(xy 316.34622 11.263264) (xy 316.288451 11.326634) (xy 316.236775 11.395063) (xy 316.191634 11.467969)
			(xy 316.153412 11.544729) (xy 316.122436 11.624688) (xy 316.098969 11.707164) (xy 316.083213 11.791454)
			(xy 316.075301 11.876837) (xy 311.580035 11.876837) (xy 311.572123 11.791454) (xy 311.556367 11.707164)
			(xy 311.5329 11.624688) (xy 311.501924 11.544729) (xy 311.463702 11.467969) (xy 311.418561 11.395063)
			(xy 311.366885 11.326634) (xy 311.309116 11.263264) (xy 311.245746 11.205495) (xy 311.177317 11.153819)
			(xy 311.104411 11.108678) (xy 311.027651 11.070456) (xy 310.947692 11.03948) (xy 310.865216 11.016013)
			(xy 310.780926 11.000257) (xy 310.695543 10.992345) (xy 310.609793 10.992345) (xy 310.52441 11.000257)
			(xy 310.44012 11.016013) (xy 310.357644 11.03948) (xy 310.277685 11.070456) (xy 310.200925 11.108678)
			(xy 310.128019 11.153819) (xy 310.05959 11.205495) (xy 309.99622 11.263264) (xy 309.938451 11.326634)
			(xy 309.886775 11.395063) (xy 309.841634 11.467969) (xy 309.803412 11.544729) (xy 309.772436 11.624688)
			(xy 309.748969 11.707164) (xy 309.733213 11.791454) (xy 309.725301 11.876837) (xy 259.72979 11.876837)
			(xy 259.729491 11.850929) (xy 259.721579 11.765546) (xy 259.705823 11.681256) (xy 259.682356 11.59878)
			(xy 259.65138 11.518821) (xy 259.613158 11.442061) (xy 259.568017 11.369155) (xy 259.516341 11.300726)
			(xy 259.458572 11.237356) (xy 259.395202 11.179587) (xy 259.326773 11.127911) (xy 259.253867 11.08277)
			(xy 259.177107 11.044548) (xy 259.097148 11.013572) (xy 259.014672 10.990105) (xy 258.930382 10.974349)
			(xy 258.844999 10.966437) (xy 258.759249 10.966437) (xy 258.673866 10.974349) (xy 258.589576 10.990105)
			(xy 258.5071 11.013572) (xy 258.427141 11.044548) (xy 258.350381 11.08277) (xy 258.277475 11.127911)
			(xy 258.209046 11.179587) (xy 258.145676 11.237356) (xy 258.087907 11.300726) (xy 258.036231 11.369155)
			(xy 257.99109 11.442061) (xy 257.952868 11.518821) (xy 257.921892 11.59878) (xy 257.898425 11.681256)
			(xy 257.882669 11.765546) (xy 257.874757 11.850929) (xy 253.379491 11.850929) (xy 253.371579 11.765546)
			(xy 253.355823 11.681256) (xy 253.332356 11.59878) (xy 253.30138 11.518821) (xy 253.263158 11.442061)
			(xy 253.218017 11.369155) (xy 253.166341 11.300726) (xy 253.108572 11.237356) (xy 253.045202 11.179587)
			(xy 252.976773 11.127911) (xy 252.903867 11.08277) (xy 252.827107 11.044548) (xy 252.747148 11.013572)
			(xy 252.664672 10.990105) (xy 252.580382 10.974349) (xy 252.494999 10.966437) (xy 252.409249 10.966437)
			(xy 252.323866 10.974349) (xy 252.239576 10.990105) (xy 252.1571 11.013572) (xy 252.077141 11.044548)
			(xy 252.000381 11.08277) (xy 251.927475 11.127911) (xy 251.859046 11.179587) (xy 251.795676 11.237356)
			(xy 251.737907 11.300726) (xy 251.686231 11.369155) (xy 251.64109 11.442061) (xy 251.602868 11.518821)
			(xy 251.571892 11.59878) (xy 251.548425 11.681256) (xy 251.532669 11.765546) (xy 251.524757 11.850929)
			(xy 158.621984 11.850929) (xy 158.621984 9.310929) (xy 179.515757 9.310929) (xy 179.515757 9.396679)
			(xy 179.523669 9.482062) (xy 179.539425 9.566352) (xy 179.562892 9.648828) (xy 179.593868 9.728787)
			(xy 179.63209 9.805547) (xy 179.677231 9.878453) (xy 179.728907 9.946882) (xy 179.786676 10.010252)
			(xy 179.850046 10.068021) (xy 179.918475 10.119697) (xy 179.991381 10.164838) (xy 180.068141 10.20306)
			(xy 180.1481 10.234036) (xy 180.230576 10.257503) (xy 180.314866 10.273259) (xy 180.400249 10.281171)
			(xy 180.485999 10.281171) (xy 180.571382 10.273259) (xy 180.655672 10.257503) (xy 180.738148 10.234036)
			(xy 180.818107 10.20306) (xy 180.894867 10.164838) (xy 180.967773 10.119697) (xy 181.036202 10.068021)
			(xy 181.099572 10.010252) (xy 181.157341 9.946882) (xy 181.209017 9.878453) (xy 181.254158 9.805547)
			(xy 181.29238 9.728787) (xy 181.323356 9.648828) (xy 181.346823 9.566352) (xy 181.362579 9.482062)
			(xy 181.370491 9.396679) (xy 181.370986 9.353804) (xy 181.370491 9.310929) (xy 185.865757 9.310929)
			(xy 185.865757 9.396679) (xy 185.873669 9.482062) (xy 185.889425 9.566352) (xy 185.912892 9.648828)
			(xy 185.943868 9.728787) (xy 185.98209 9.805547) (xy 186.027231 9.878453) (xy 186.078907 9.946882)
			(xy 186.136676 10.010252) (xy 186.200046 10.068021) (xy 186.268475 10.119697) (xy 186.341381 10.164838)
			(xy 186.418141 10.20306) (xy 186.4981 10.234036) (xy 186.580576 10.257503) (xy 186.664866 10.273259)
			(xy 186.750249 10.281171) (xy 186.835999 10.281171) (xy 186.921382 10.273259) (xy 187.005672 10.257503)
			(xy 187.088148 10.234036) (xy 187.168107 10.20306) (xy 187.244867 10.164838) (xy 187.317773 10.119697)
			(xy 187.386202 10.068021) (xy 187.449572 10.010252) (xy 187.507341 9.946882) (xy 187.559017 9.878453)
			(xy 187.604158 9.805547) (xy 187.64238 9.728787) (xy 187.673356 9.648828) (xy 187.696823 9.566352)
			(xy 187.712579 9.482062) (xy 187.720491 9.396679) (xy 187.720986 9.353804) (xy 187.720491 9.310929)
			(xy 187.719832 9.303817) (xy 237.716301 9.303817) (xy 237.716301 9.389567) (xy 237.724213 9.47495)
			(xy 237.739969 9.55924) (xy 237.763436 9.641716) (xy 237.794412 9.721675) (xy 237.832634 9.798435)
			(xy 237.877775 9.871341) (xy 237.929451 9.93977) (xy 237.98722 10.00314) (xy 238.05059 10.060909)
			(xy 238.119019 10.112585) (xy 238.191925 10.157726) (xy 238.268685 10.195948) (xy 238.348644 10.226924)
			(xy 238.43112 10.250391) (xy 238.51541 10.266147) (xy 238.600793 10.274059) (xy 238.686543 10.274059)
			(xy 238.771926 10.266147) (xy 238.856216 10.250391) (xy 238.938692 10.226924) (xy 239.018651 10.195948)
			(xy 239.095411 10.157726) (xy 239.168317 10.112585) (xy 239.236746 10.060909) (xy 239.300116 10.00314)
			(xy 239.357885 9.93977) (xy 239.409561 9.871341) (xy 239.454702 9.798435) (xy 239.492924 9.721675)
			(xy 239.5239 9.641716) (xy 239.547367 9.55924) (xy 239.563123 9.47495) (xy 239.571035 9.389567) (xy 239.57153 9.346692)
			(xy 239.571035 9.303817) (xy 244.066301 9.303817) (xy 244.066301 9.389567) (xy 244.074213 9.47495)
			(xy 244.089969 9.55924) (xy 244.113436 9.641716) (xy 244.144412 9.721675) (xy 244.182634 9.798435)
			(xy 244.227775 9.871341) (xy 244.279451 9.93977) (xy 244.33722 10.00314) (xy 244.40059 10.060909)
			(xy 244.469019 10.112585) (xy 244.541925 10.157726) (xy 244.618685 10.195948) (xy 244.698644 10.226924)
			(xy 244.78112 10.250391) (xy 244.86541 10.266147) (xy 244.950793 10.274059) (xy 245.036543 10.274059)
			(xy 245.121926 10.266147) (xy 245.206216 10.250391) (xy 245.288692 10.226924) (xy 245.368651 10.195948)
			(xy 245.445411 10.157726) (xy 245.518317 10.112585) (xy 245.586746 10.060909) (xy 245.650116 10.00314)
			(xy 245.707885 9.93977) (xy 245.759561 9.871341) (xy 245.804702 9.798435) (xy 245.842924 9.721675)
			(xy 245.8739 9.641716) (xy 245.897367 9.55924) (xy 245.913123 9.47495) (xy 245.921035 9.389567) (xy 245.92153 9.346692)
			(xy 245.921117 9.310929) (xy 251.524757 9.310929) (xy 251.524757 9.396679) (xy 251.532669 9.482062)
			(xy 251.548425 9.566352) (xy 251.571892 9.648828) (xy 251.602868 9.728787) (xy 251.64109 9.805547)
			(xy 251.686231 9.878453) (xy 251.737907 9.946882) (xy 251.795676 10.010252) (xy 251.859046 10.068021)
			(xy 251.927475 10.119697) (xy 252.000381 10.164838) (xy 252.077141 10.20306) (xy 252.1571 10.234036)
			(xy 252.239576 10.257503) (xy 252.323866 10.273259) (xy 252.409249 10.281171) (xy 252.494999 10.281171)
			(xy 252.580382 10.273259) (xy 252.664672 10.257503) (xy 252.747148 10.234036) (xy 252.827107 10.20306)
			(xy 252.84931 10.192004) (xy 256.459736 10.192004) (xy 256.459736 11.055604) (xy 256.460222 11.082873)
			(xy 256.467984 11.136857) (xy 256.483349 11.189187) (xy 256.506006 11.238797) (xy 256.535492 11.284678)
			(xy 256.571207 11.325895) (xy 256.612424 11.36161) (xy 256.658305 11.391096) (xy 256.707915 11.413753)
			(xy 256.760245 11.429118) (xy 256.814229 11.43688) (xy 256.868767 11.43688) (xy 256.922751 11.429118)
			(xy 256.975081 11.413753) (xy 257.024691 11.391096) (xy 257.070572 11.36161) (xy 257.111789 11.325895)
			(xy 257.147504 11.284678) (xy 257.17699 11.238797) (xy 257.199647 11.189187) (xy 257.215012 11.136857)
			(xy 257.222774 11.082873) (xy 257.22326 11.055604) (xy 257.22326 10.192004) (xy 257.222774 10.164735)
			(xy 257.215012 10.110751) (xy 257.199647 10.058421) (xy 257.17699 10.008811) (xy 257.147504 9.96293)
			(xy 257.111789 9.921713) (xy 257.070572 9.885998) (xy 257.024691 9.856512) (xy 256.975081 9.833855)
			(xy 256.922751 9.81849) (xy 256.868767 9.810728) (xy 256.814229 9.810728) (xy 256.760245 9.81849)
			(xy 256.707915 9.833855) (xy 256.658305 9.856512) (xy 256.612424 9.885998) (xy 256.571207 9.921713)
			(xy 256.535492 9.96293) (xy 256.506006 10.008811) (xy 256.483349 10.058421) (xy 256.467984 10.110751)
			(xy 256.460222 10.164735) (xy 256.459736 10.192004) (xy 252.84931 10.192004) (xy 252.903867 10.164838)
			(xy 252.976773 10.119697) (xy 253.045202 10.068021) (xy 253.108572 10.010252) (xy 253.166341 9.946882)
			(xy 253.218017 9.878453) (xy 253.263158 9.805547) (xy 253.30138 9.728787) (xy 253.332356 9.648828)
			(xy 253.355823 9.566352) (xy 253.371579 9.482062) (xy 253.379491 9.396679) (xy 253.379986 9.353804)
			(xy 253.379491 9.310929) (xy 257.874757 9.310929) (xy 257.874757 9.396679) (xy 257.882669 9.482062)
			(xy 257.898425 9.566352) (xy 257.921892 9.648828) (xy 257.952868 9.728787) (xy 257.99109 9.805547)
			(xy 258.036231 9.878453) (xy 258.087907 9.946882) (xy 258.145676 10.010252) (xy 258.209046 10.068021)
			(xy 258.277475 10.119697) (xy 258.350381 10.164838) (xy 258.427141 10.20306) (xy 258.5071 10.234036)
			(xy 258.589576 10.257503) (xy 258.673866 10.273259) (xy 258.759249 10.281171) (xy 258.844999 10.281171)
			(xy 258.930382 10.273259) (xy 259.014672 10.257503) (xy 259.097148 10.234036) (xy 259.177107 10.20306)
			(xy 259.253867 10.164838) (xy 259.326773 10.119697) (xy 259.395202 10.068021) (xy 259.458572 10.010252)
			(xy 259.516341 9.946882) (xy 259.568017 9.878453) (xy 259.613158 9.805547) (xy 259.65138 9.728787)
			(xy 259.682356 9.648828) (xy 259.705823 9.566352) (xy 259.721579 9.482062) (xy 259.729491 9.396679)
			(xy 259.729986 9.353804) (xy 259.72979 9.336837) (xy 309.725301 9.336837) (xy 309.725301 9.422587)
			(xy 309.733213 9.50797) (xy 309.748969 9.59226) (xy 309.772436 9.674736) (xy 309.803412 9.754695)
			(xy 309.841634 9.831455) (xy 309.886775 9.904361) (xy 309.938451 9.97279) (xy 309.99622 10.03616)
			(xy 310.05959 10.093929) (xy 310.128019 10.145605) (xy 310.200925 10.190746) (xy 310.277685 10.228968)
			(xy 310.357644 10.259944) (xy 310.44012 10.283411) (xy 310.52441 10.299167) (xy 310.609793 10.307079)
			(xy 310.695543 10.307079) (xy 310.780926 10.299167) (xy 310.865216 10.283411) (xy 310.947692 10.259944)
			(xy 311.027651 10.228968) (xy 311.049854 10.217912) (xy 312.231532 10.217912) (xy 312.231532 11.081512)
			(xy 312.232018 11.108781) (xy 312.23978 11.162765) (xy 312.255145 11.215095) (xy 312.277802 11.264705)
			(xy 312.307288 11.310586) (xy 312.343003 11.351803) (xy 312.38422 11.387518) (xy 312.430101 11.417004)
			(xy 312.479711 11.439661) (xy 312.532041 11.455026) (xy 312.586025 11.462788) (xy 312.640563 11.462788)
			(xy 312.694547 11.455026) (xy 312.746877 11.439661) (xy 312.796487 11.417004) (xy 312.842368 11.387518)
			(xy 312.883585 11.351803) (xy 312.9193 11.310586) (xy 312.948786 11.264705) (xy 312.971443 11.215095)
			(xy 312.986808 11.162765) (xy 312.99457 11.108781) (xy 312.995056 11.081512) (xy 312.995056 10.217912)
			(xy 312.99457 10.190643) (xy 312.986808 10.136659) (xy 312.971443 10.084329) (xy 312.948786 10.034719)
			(xy 312.9193 9.988838) (xy 312.883585 9.947621) (xy 312.842368 9.911906) (xy 312.796487 9.88242)
			(xy 312.746877 9.859763) (xy 312.694547 9.844398) (xy 312.640563 9.836636) (xy 312.586025 9.836636)
			(xy 312.532041 9.844398) (xy 312.479711 9.859763) (xy 312.430101 9.88242) (xy 312.38422 9.911906)
			(xy 312.343003 9.947621) (xy 312.307288 9.988838) (xy 312.277802 10.034719) (xy 312.255145 10.084329)
			(xy 312.23978 10.136659) (xy 312.232018 10.190643) (xy 312.231532 10.217912) (xy 311.049854 10.217912)
			(xy 311.104411 10.190746) (xy 311.177317 10.145605) (xy 311.245746 10.093929) (xy 311.309116 10.03616)
			(xy 311.366885 9.97279) (xy 311.418561 9.904361) (xy 311.463702 9.831455) (xy 311.501924 9.754695)
			(xy 311.5329 9.674736) (xy 311.556367 9.59226) (xy 311.572123 9.50797) (xy 311.580035 9.422587) (xy 311.58053 9.379712)
			(xy 311.580035 9.336837) (xy 316.075301 9.336837) (xy 316.075301 9.422587) (xy 316.083213 9.50797)
			(xy 316.098969 9.59226) (xy 316.122436 9.674736) (xy 316.153412 9.754695) (xy 316.191634 9.831455)
			(xy 316.236775 9.904361) (xy 316.288451 9.97279) (xy 316.34622 10.03616) (xy 316.40959 10.093929)
			(xy 316.478019 10.145605) (xy 316.550925 10.190746) (xy 316.627685 10.228968) (xy 316.707644 10.259944)
			(xy 316.79012 10.283411) (xy 316.87441 10.299167) (xy 316.959793 10.307079) (xy 317.045543 10.307079)
			(xy 317.130926 10.299167) (xy 317.215216 10.283411) (xy 317.297692 10.259944) (xy 317.377651 10.228968)
			(xy 317.454411 10.190746) (xy 317.527317 10.145605) (xy 317.595746 10.093929) (xy 317.659116 10.03616)
			(xy 317.716885 9.97279) (xy 317.768561 9.904361) (xy 317.813702 9.831455) (xy 317.851924 9.754695)
			(xy 317.8829 9.674736) (xy 317.906367 9.59226) (xy 317.922123 9.50797) (xy 317.930035 9.422587) (xy 317.93053 9.379712)
			(xy 317.930117 9.343949) (xy 324.295757 9.343949) (xy 324.295757 9.429699) (xy 324.303669 9.515082)
			(xy 324.319425 9.599372) (xy 324.342892 9.681848) (xy 324.373868 9.761807) (xy 324.41209 9.838567)
			(xy 324.457231 9.911473) (xy 324.508907 9.979902) (xy 324.566676 10.043272) (xy 324.630046 10.101041)
			(xy 324.698475 10.152717) (xy 324.771381 10.197858) (xy 324.848141 10.23608) (xy 324.9281 10.267056)
			(xy 325.010576 10.290523) (xy 325.094866 10.306279) (xy 325.180249 10.314191) (xy 325.265999 10.314191)
			(xy 325.351382 10.306279) (xy 325.435672 10.290523) (xy 325.518148 10.267056) (xy 325.598107 10.23608)
			(xy 325.62031 10.225024) (xy 329.230736 10.225024) (xy 329.230736 11.088624) (xy 329.231222 11.115893)
			(xy 329.238984 11.169877) (xy 329.254349 11.222207) (xy 329.277006 11.271817) (xy 329.306492 11.317698)
			(xy 329.342207 11.358915) (xy 329.383424 11.39463) (xy 329.429305 11.424116) (xy 329.478915 11.446773)
			(xy 329.531245 11.462138) (xy 329.585229 11.4699) (xy 329.639767 11.4699) (xy 329.693751 11.462138)
			(xy 329.746081 11.446773) (xy 329.795691 11.424116) (xy 329.841572 11.39463) (xy 329.882789 11.358915)
			(xy 329.918504 11.317698) (xy 329.94799 11.271817) (xy 329.970647 11.222207) (xy 329.986012 11.169877)
			(xy 329.993774 11.115893) (xy 329.99426 11.088624) (xy 329.99426 10.225024) (xy 329.993774 10.197755)
			(xy 329.986012 10.143771) (xy 329.970647 10.091441) (xy 329.94799 10.041831) (xy 329.918504 9.99595)
			(xy 329.882789 9.954733) (xy 329.841572 9.919018) (xy 329.795691 9.889532) (xy 329.746081 9.866875)
			(xy 329.693751 9.85151) (xy 329.639767 9.843748) (xy 329.585229 9.843748) (xy 329.531245 9.85151)
			(xy 329.478915 9.866875) (xy 329.429305 9.889532) (xy 329.383424 9.919018) (xy 329.342207 9.954733)
			(xy 329.306492 9.99595) (xy 329.277006 10.041831) (xy 329.254349 10.091441) (xy 329.238984 10.143771)
			(xy 329.231222 10.197755) (xy 329.230736 10.225024) (xy 325.62031 10.225024) (xy 325.674867 10.197858)
			(xy 325.747773 10.152717) (xy 325.816202 10.101041) (xy 325.879572 10.043272) (xy 325.937341 9.979902)
			(xy 325.989017 9.911473) (xy 326.034158 9.838567) (xy 326.07238 9.761807) (xy 326.103356 9.681848)
			(xy 326.126823 9.599372) (xy 326.142579 9.515082) (xy 326.150491 9.429699) (xy 326.150986 9.386824)
			(xy 326.150491 9.343949) (xy 330.645757 9.343949) (xy 330.645757 9.429699) (xy 330.653669 9.515082)
			(xy 330.669425 9.599372) (xy 330.692892 9.681848) (xy 330.723868 9.761807) (xy 330.76209 9.838567)
			(xy 330.807231 9.911473) (xy 330.858907 9.979902) (xy 330.916676 10.043272) (xy 330.980046 10.101041)
			(xy 331.048475 10.152717) (xy 331.121381 10.197858) (xy 331.198141 10.23608) (xy 331.2781 10.267056)
			(xy 331.360576 10.290523) (xy 331.444866 10.306279) (xy 331.530249 10.314191) (xy 331.615999 10.314191)
			(xy 331.701382 10.306279) (xy 331.785672 10.290523) (xy 331.868148 10.267056) (xy 331.948107 10.23608)
			(xy 332.024867 10.197858) (xy 332.097773 10.152717) (xy 332.166202 10.101041) (xy 332.229572 10.043272)
			(xy 332.287341 9.979902) (xy 332.339017 9.911473) (xy 332.384158 9.838567) (xy 332.42238 9.761807)
			(xy 332.453356 9.681848) (xy 332.476823 9.599372) (xy 332.492579 9.515082) (xy 332.500491 9.429699)
			(xy 332.500986 9.386824) (xy 332.50079 9.369857) (xy 382.496301 9.369857) (xy 382.496301 9.455607)
			(xy 382.504213 9.54099) (xy 382.519969 9.62528) (xy 382.543436 9.707756) (xy 382.574412 9.787715)
			(xy 382.612634 9.864475) (xy 382.657775 9.937381) (xy 382.709451 10.00581) (xy 382.76722 10.06918)
			(xy 382.83059 10.126949) (xy 382.899019 10.178625) (xy 382.971925 10.223766) (xy 383.048685 10.261988)
			(xy 383.128644 10.292964) (xy 383.21112 10.316431) (xy 383.29541 10.332187) (xy 383.380793 10.340099)
			(xy 383.466543 10.340099) (xy 383.551926 10.332187) (xy 383.636216 10.316431) (xy 383.718692 10.292964)
			(xy 383.798651 10.261988) (xy 383.820854 10.250932) (xy 385.002532 10.250932) (xy 385.002532 11.114532)
			(xy 385.003018 11.141801) (xy 385.01078 11.195785) (xy 385.026145 11.248115) (xy 385.048802 11.297725)
			(xy 385.078288 11.343606) (xy 385.114003 11.384823) (xy 385.15522 11.420538) (xy 385.201101 11.450024)
			(xy 385.250711 11.472681) (xy 385.303041 11.488046) (xy 385.357025 11.495808) (xy 385.411563 11.495808)
			(xy 385.465547 11.488046) (xy 385.517877 11.472681) (xy 385.567487 11.450024) (xy 385.613368 11.420538)
			(xy 385.654585 11.384823) (xy 385.6903 11.343606) (xy 385.719786 11.297725) (xy 385.742443 11.248115)
			(xy 385.757808 11.195785) (xy 385.76557 11.141801) (xy 385.766056 11.114532) (xy 385.766056 10.250932)
			(xy 385.76557 10.223663) (xy 385.757808 10.169679) (xy 385.742443 10.117349) (xy 385.719786 10.067739)
			(xy 385.6903 10.021858) (xy 385.654585 9.980641) (xy 385.613368 9.944926) (xy 385.567487 9.91544)
			(xy 385.517877 9.892783) (xy 385.465547 9.877418) (xy 385.411563 9.869656) (xy 385.357025 9.869656)
			(xy 385.303041 9.877418) (xy 385.250711 9.892783) (xy 385.201101 9.91544) (xy 385.15522 9.944926)
			(xy 385.114003 9.980641) (xy 385.078288 10.021858) (xy 385.048802 10.067739) (xy 385.026145 10.117349)
			(xy 385.01078 10.169679) (xy 385.003018 10.223663) (xy 385.002532 10.250932) (xy 383.820854 10.250932)
			(xy 383.875411 10.223766) (xy 383.948317 10.178625) (xy 384.016746 10.126949) (xy 384.080116 10.06918)
			(xy 384.137885 10.00581) (xy 384.189561 9.937381) (xy 384.234702 9.864475) (xy 384.272924 9.787715)
			(xy 384.3039 9.707756) (xy 384.327367 9.62528) (xy 384.343123 9.54099) (xy 384.351035 9.455607) (xy 384.35153 9.412732)
			(xy 384.351035 9.369857) (xy 388.846301 9.369857) (xy 388.846301 9.455607) (xy 388.854213 9.54099)
			(xy 388.869969 9.62528) (xy 388.893436 9.707756) (xy 388.924412 9.787715) (xy 388.962634 9.864475)
			(xy 389.007775 9.937381) (xy 389.059451 10.00581) (xy 389.11722 10.06918) (xy 389.18059 10.126949)
			(xy 389.249019 10.178625) (xy 389.321925 10.223766) (xy 389.398685 10.261988) (xy 389.478644 10.292964)
			(xy 389.56112 10.316431) (xy 389.64541 10.332187) (xy 389.730793 10.340099) (xy 389.816543 10.340099)
			(xy 389.901926 10.332187) (xy 389.986216 10.316431) (xy 390.068692 10.292964) (xy 390.148651 10.261988)
			(xy 390.225411 10.223766) (xy 390.298317 10.178625) (xy 390.366746 10.126949) (xy 390.430116 10.06918)
			(xy 390.487885 10.00581) (xy 390.539561 9.937381) (xy 390.584702 9.864475) (xy 390.622924 9.787715)
			(xy 390.6539 9.707756) (xy 390.677367 9.62528) (xy 390.693123 9.54099) (xy 390.701035 9.455607) (xy 390.70153 9.412732)
			(xy 390.701117 9.376969) (xy 396.558757 9.376969) (xy 396.558757 9.462719) (xy 396.566669 9.548102)
			(xy 396.582425 9.632392) (xy 396.605892 9.714868) (xy 396.636868 9.794827) (xy 396.67509 9.871587)
			(xy 396.720231 9.944493) (xy 396.771907 10.012922) (xy 396.829676 10.076292) (xy 396.893046 10.134061)
			(xy 396.961475 10.185737) (xy 397.034381 10.230878) (xy 397.111141 10.2691) (xy 397.1911 10.300076)
			(xy 397.273576 10.323543) (xy 397.357866 10.339299) (xy 397.443249 10.347211) (xy 397.528999 10.347211)
			(xy 397.614382 10.339299) (xy 397.698672 10.323543) (xy 397.781148 10.300076) (xy 397.861107 10.2691)
			(xy 397.88331 10.258044) (xy 401.493736 10.258044) (xy 401.493736 11.121644) (xy 401.494222 11.148913)
			(xy 401.501984 11.202897) (xy 401.517349 11.255227) (xy 401.540006 11.304837) (xy 401.569492 11.350718)
			(xy 401.605207 11.391935) (xy 401.646424 11.42765) (xy 401.692305 11.457136) (xy 401.741915 11.479793)
			(xy 401.794245 11.495158) (xy 401.848229 11.50292) (xy 401.902767 11.50292) (xy 401.956751 11.495158)
			(xy 402.009081 11.479793) (xy 402.058691 11.457136) (xy 402.104572 11.42765) (xy 402.145789 11.391935)
			(xy 402.181504 11.350718) (xy 402.21099 11.304837) (xy 402.233647 11.255227) (xy 402.249012 11.202897)
			(xy 402.256774 11.148913) (xy 402.25726 11.121644) (xy 402.25726 10.258044) (xy 402.256774 10.230775)
			(xy 402.249012 10.176791) (xy 402.233647 10.124461) (xy 402.21099 10.074851) (xy 402.181504 10.02897)
			(xy 402.145789 9.987753) (xy 402.104572 9.952038) (xy 402.058691 9.922552) (xy 402.009081 9.899895)
			(xy 401.956751 9.88453) (xy 401.902767 9.876768) (xy 401.848229 9.876768) (xy 401.794245 9.88453)
			(xy 401.741915 9.899895) (xy 401.692305 9.922552) (xy 401.646424 9.952038) (xy 401.605207 9.987753)
			(xy 401.569492 10.02897) (xy 401.540006 10.074851) (xy 401.517349 10.124461) (xy 401.501984 10.176791)
			(xy 401.494222 10.230775) (xy 401.493736 10.258044) (xy 397.88331 10.258044) (xy 397.937867 10.230878)
			(xy 398.010773 10.185737) (xy 398.079202 10.134061) (xy 398.142572 10.076292) (xy 398.200341 10.012922)
			(xy 398.252017 9.944493) (xy 398.297158 9.871587) (xy 398.33538 9.794827) (xy 398.366356 9.714868)
			(xy 398.389823 9.632392) (xy 398.405579 9.548102) (xy 398.413491 9.462719) (xy 398.413986 9.419844)
			(xy 398.413491 9.376969) (xy 402.908757 9.376969) (xy 402.908757 9.462719) (xy 402.916669 9.548102)
			(xy 402.932425 9.632392) (xy 402.955892 9.714868) (xy 402.986868 9.794827) (xy 403.02509 9.871587)
			(xy 403.070231 9.944493) (xy 403.121907 10.012922) (xy 403.179676 10.076292) (xy 403.243046 10.134061)
			(xy 403.311475 10.185737) (xy 403.384381 10.230878) (xy 403.461141 10.2691) (xy 403.5411 10.300076)
			(xy 403.623576 10.323543) (xy 403.707866 10.339299) (xy 403.793249 10.347211) (xy 403.878999 10.347211)
			(xy 403.964382 10.339299) (xy 404.048672 10.323543) (xy 404.131148 10.300076) (xy 404.211107 10.2691)
			(xy 404.287867 10.230878) (xy 404.360773 10.185737) (xy 404.429202 10.134061) (xy 404.492572 10.076292)
			(xy 404.550341 10.012922) (xy 404.602017 9.944493) (xy 404.647158 9.871587) (xy 404.68538 9.794827)
			(xy 404.716356 9.714868) (xy 404.739823 9.632392) (xy 404.755579 9.548102) (xy 404.763491 9.462719)
			(xy 404.763986 9.419844) (xy 404.76379 9.402877) (xy 454.759301 9.402877) (xy 454.759301 9.488627)
			(xy 454.767213 9.57401) (xy 454.782969 9.6583) (xy 454.806436 9.740776) (xy 454.837412 9.820735)
			(xy 454.875634 9.897495) (xy 454.920775 9.970401) (xy 454.972451 10.03883) (xy 455.03022 10.1022)
			(xy 455.09359 10.159969) (xy 455.162019 10.211645) (xy 455.234925 10.256786) (xy 455.311685 10.295008)
			(xy 455.391644 10.325984) (xy 455.47412 10.349451) (xy 455.55841 10.365207) (xy 455.643793 10.373119)
			(xy 455.729543 10.373119) (xy 455.814926 10.365207) (xy 455.899216 10.349451) (xy 455.981692 10.325984)
			(xy 456.061651 10.295008) (xy 456.083854 10.283952) (xy 457.265532 10.283952) (xy 457.265532 11.147552)
			(xy 457.266018 11.174821) (xy 457.27378 11.228805) (xy 457.289145 11.281135) (xy 457.311802 11.330745)
			(xy 457.341288 11.376626) (xy 457.377003 11.417843) (xy 457.41822 11.453558) (xy 457.464101 11.483044)
			(xy 457.513711 11.505701) (xy 457.566041 11.521066) (xy 457.620025 11.528828) (xy 457.674563 11.528828)
			(xy 457.728547 11.521066) (xy 457.780877 11.505701) (xy 457.830487 11.483044) (xy 457.876368 11.453558)
			(xy 457.917585 11.417843) (xy 457.9533 11.376626) (xy 457.982786 11.330745) (xy 458.005443 11.281135)
			(xy 458.020808 11.228805) (xy 458.02857 11.174821) (xy 458.029056 11.147552) (xy 458.029056 10.283952)
			(xy 458.02857 10.256683) (xy 458.020808 10.202699) (xy 458.005443 10.150369) (xy 457.982786 10.100759)
			(xy 457.9533 10.054878) (xy 457.917585 10.013661) (xy 457.876368 9.977946) (xy 457.830487 9.94846)
			(xy 457.780877 9.925803) (xy 457.728547 9.910438) (xy 457.674563 9.902676) (xy 457.620025 9.902676)
			(xy 457.566041 9.910438) (xy 457.513711 9.925803) (xy 457.464101 9.94846) (xy 457.41822 9.977946)
			(xy 457.377003 10.013661) (xy 457.341288 10.054878) (xy 457.311802 10.100759) (xy 457.289145 10.150369)
			(xy 457.27378 10.202699) (xy 457.266018 10.256683) (xy 457.265532 10.283952) (xy 456.083854 10.283952)
			(xy 456.138411 10.256786) (xy 456.211317 10.211645) (xy 456.279746 10.159969) (xy 456.343116 10.1022)
			(xy 456.400885 10.03883) (xy 456.452561 9.970401) (xy 456.497702 9.897495) (xy 456.535924 9.820735)
			(xy 456.5669 9.740776) (xy 456.590367 9.6583) (xy 456.606123 9.57401) (xy 456.614035 9.488627) (xy 456.61453 9.445752)
			(xy 456.614035 9.402877) (xy 461.109301 9.402877) (xy 461.109301 9.488627) (xy 461.117213 9.57401)
			(xy 461.132969 9.6583) (xy 461.156436 9.740776) (xy 461.187412 9.820735) (xy 461.225634 9.897495)
			(xy 461.270775 9.970401) (xy 461.322451 10.03883) (xy 461.38022 10.1022) (xy 461.44359 10.159969)
			(xy 461.512019 10.211645) (xy 461.584925 10.256786) (xy 461.661685 10.295008) (xy 461.741644 10.325984)
			(xy 461.82412 10.349451) (xy 461.90841 10.365207) (xy 461.993793 10.373119) (xy 462.079543 10.373119)
			(xy 462.164926 10.365207) (xy 462.249216 10.349451) (xy 462.331692 10.325984) (xy 462.411651 10.295008)
			(xy 462.488411 10.256786) (xy 462.561317 10.211645) (xy 462.629746 10.159969) (xy 462.693116 10.1022)
			(xy 462.750885 10.03883) (xy 462.802561 9.970401) (xy 462.847702 9.897495) (xy 462.885924 9.820735)
			(xy 462.9169 9.740776) (xy 462.940367 9.6583) (xy 462.956123 9.57401) (xy 462.964035 9.488627) (xy 462.96453 9.445752)
			(xy 462.964035 9.402877) (xy 462.956123 9.317494) (xy 462.940367 9.233204) (xy 462.9169 9.150728)
			(xy 462.885924 9.070769) (xy 462.847702 8.994009) (xy 462.802561 8.921103) (xy 462.750885 8.852674)
			(xy 462.693116 8.789304) (xy 462.629746 8.731535) (xy 462.561317 8.679859) (xy 462.488411 8.634718)
			(xy 462.411651 8.596496) (xy 462.331692 8.56552) (xy 462.249216 8.542053) (xy 462.164926 8.526297)
			(xy 462.079543 8.518385) (xy 461.993793 8.518385) (xy 461.90841 8.526297) (xy 461.82412 8.542053)
			(xy 461.741644 8.56552) (xy 461.661685 8.596496) (xy 461.584925 8.634718) (xy 461.512019 8.679859)
			(xy 461.44359 8.731535) (xy 461.38022 8.789304) (xy 461.322451 8.852674) (xy 461.270775 8.921103)
			(xy 461.225634 8.994009) (xy 461.187412 9.070769) (xy 461.156436 9.150728) (xy 461.132969 9.233204)
			(xy 461.117213 9.317494) (xy 461.109301 9.402877) (xy 456.614035 9.402877) (xy 456.606123 9.317494)
			(xy 456.590367 9.233204) (xy 456.5669 9.150728) (xy 456.535924 9.070769) (xy 456.497702 8.994009)
			(xy 456.452561 8.921103) (xy 456.400885 8.852674) (xy 456.343116 8.789304) (xy 456.279746 8.731535)
			(xy 456.211317 8.679859) (xy 456.138411 8.634718) (xy 456.061651 8.596496) (xy 455.981692 8.56552)
			(xy 455.899216 8.542053) (xy 455.814926 8.526297) (xy 455.729543 8.518385) (xy 455.643793 8.518385)
			(xy 455.55841 8.526297) (xy 455.47412 8.542053) (xy 455.391644 8.56552) (xy 455.311685 8.596496)
			(xy 455.234925 8.634718) (xy 455.162019 8.679859) (xy 455.09359 8.731535) (xy 455.03022 8.789304)
			(xy 454.972451 8.852674) (xy 454.920775 8.921103) (xy 454.875634 8.994009) (xy 454.837412 9.070769)
			(xy 454.806436 9.150728) (xy 454.782969 9.233204) (xy 454.767213 9.317494) (xy 454.759301 9.402877)
			(xy 404.76379 9.402877) (xy 404.763491 9.376969) (xy 404.755579 9.291586) (xy 404.739823 9.207296)
			(xy 404.716356 9.12482) (xy 404.68538 9.044861) (xy 404.647158 8.968101) (xy 404.602017 8.895195)
			(xy 404.550341 8.826766) (xy 404.492572 8.763396) (xy 404.429202 8.705627) (xy 404.360773 8.653951)
			(xy 404.287867 8.60881) (xy 404.211107 8.570588) (xy 404.131148 8.539612) (xy 404.048672 8.516145)
			(xy 403.964382 8.500389) (xy 403.878999 8.492477) (xy 403.793249 8.492477) (xy 403.707866 8.500389)
			(xy 403.623576 8.516145) (xy 403.5411 8.539612) (xy 403.461141 8.570588) (xy 403.384381 8.60881)
			(xy 403.311475 8.653951) (xy 403.243046 8.705627) (xy 403.179676 8.763396) (xy 403.121907 8.826766)
			(xy 403.070231 8.895195) (xy 403.02509 8.968101) (xy 402.986868 9.044861) (xy 402.955892 9.12482)
			(xy 402.932425 9.207296) (xy 402.916669 9.291586) (xy 402.908757 9.376969) (xy 398.413491 9.376969)
			(xy 398.405579 9.291586) (xy 398.389823 9.207296) (xy 398.366356 9.12482) (xy 398.33538 9.044861)
			(xy 398.297158 8.968101) (xy 398.252017 8.895195) (xy 398.200341 8.826766) (xy 398.142572 8.763396)
			(xy 398.079202 8.705627) (xy 398.010773 8.653951) (xy 397.937867 8.60881) (xy 397.861107 8.570588)
			(xy 397.781148 8.539612) (xy 397.698672 8.516145) (xy 397.614382 8.500389) (xy 397.528999 8.492477)
			(xy 397.443249 8.492477) (xy 397.357866 8.500389) (xy 397.273576 8.516145) (xy 397.1911 8.539612)
			(xy 397.111141 8.570588) (xy 397.034381 8.60881) (xy 396.961475 8.653951) (xy 396.893046 8.705627)
			(xy 396.829676 8.763396) (xy 396.771907 8.826766) (xy 396.720231 8.895195) (xy 396.67509 8.968101)
			(xy 396.636868 9.044861) (xy 396.605892 9.12482) (xy 396.582425 9.207296) (xy 396.566669 9.291586)
			(xy 396.558757 9.376969) (xy 390.701117 9.376969) (xy 390.701035 9.369857) (xy 390.693123 9.284474)
			(xy 390.677367 9.200184) (xy 390.6539 9.117708) (xy 390.622924 9.037749) (xy 390.584702 8.960989)
			(xy 390.539561 8.888083) (xy 390.487885 8.819654) (xy 390.430116 8.756284) (xy 390.366746 8.698515)
			(xy 390.298317 8.646839) (xy 390.225411 8.601698) (xy 390.148651 8.563476) (xy 390.068692 8.5325)
			(xy 389.986216 8.509033) (xy 389.901926 8.493277) (xy 389.816543 8.485365) (xy 389.730793 8.485365)
			(xy 389.64541 8.493277) (xy 389.56112 8.509033) (xy 389.478644 8.5325) (xy 389.398685 8.563476) (xy 389.321925 8.601698)
			(xy 389.249019 8.646839) (xy 389.18059 8.698515) (xy 389.11722 8.756284) (xy 389.059451 8.819654)
			(xy 389.007775 8.888083) (xy 388.962634 8.960989) (xy 388.924412 9.037749) (xy 388.893436 9.117708)
			(xy 388.869969 9.200184) (xy 388.854213 9.284474) (xy 388.846301 9.369857) (xy 384.351035 9.369857)
			(xy 384.343123 9.284474) (xy 384.327367 9.200184) (xy 384.3039 9.117708) (xy 384.272924 9.037749)
			(xy 384.234702 8.960989) (xy 384.189561 8.888083) (xy 384.137885 8.819654) (xy 384.080116 8.756284)
			(xy 384.016746 8.698515) (xy 383.948317 8.646839) (xy 383.875411 8.601698) (xy 383.798651 8.563476)
			(xy 383.718692 8.5325) (xy 383.636216 8.509033) (xy 383.551926 8.493277) (xy 383.466543 8.485365)
			(xy 383.380793 8.485365) (xy 383.29541 8.493277) (xy 383.21112 8.509033) (xy 383.128644 8.5325) (xy 383.048685 8.563476)
			(xy 382.971925 8.601698) (xy 382.899019 8.646839) (xy 382.83059 8.698515) (xy 382.76722 8.756284)
			(xy 382.709451 8.819654) (xy 382.657775 8.888083) (xy 382.612634 8.960989) (xy 382.574412 9.037749)
			(xy 382.543436 9.117708) (xy 382.519969 9.200184) (xy 382.504213 9.284474) (xy 382.496301 9.369857)
			(xy 332.50079 9.369857) (xy 332.500491 9.343949) (xy 332.492579 9.258566) (xy 332.476823 9.174276)
			(xy 332.453356 9.0918) (xy 332.42238 9.011841) (xy 332.384158 8.935081) (xy 332.339017 8.862175)
			(xy 332.287341 8.793746) (xy 332.229572 8.730376) (xy 332.166202 8.672607) (xy 332.097773 8.620931)
			(xy 332.024867 8.57579) (xy 331.948107 8.537568) (xy 331.868148 8.506592) (xy 331.785672 8.483125)
			(xy 331.701382 8.467369) (xy 331.615999 8.459457) (xy 331.530249 8.459457) (xy 331.444866 8.467369)
			(xy 331.360576 8.483125) (xy 331.2781 8.506592) (xy 331.198141 8.537568) (xy 331.121381 8.57579)
			(xy 331.048475 8.620931) (xy 330.980046 8.672607) (xy 330.916676 8.730376) (xy 330.858907 8.793746)
			(xy 330.807231 8.862175) (xy 330.76209 8.935081) (xy 330.723868 9.011841) (xy 330.692892 9.0918)
			(xy 330.669425 9.174276) (xy 330.653669 9.258566) (xy 330.645757 9.343949) (xy 326.150491 9.343949)
			(xy 326.142579 9.258566) (xy 326.126823 9.174276) (xy 326.103356 9.0918) (xy 326.07238 9.011841)
			(xy 326.034158 8.935081) (xy 325.989017 8.862175) (xy 325.937341 8.793746) (xy 325.879572 8.730376)
			(xy 325.816202 8.672607) (xy 325.747773 8.620931) (xy 325.674867 8.57579) (xy 325.598107 8.537568)
			(xy 325.518148 8.506592) (xy 325.435672 8.483125) (xy 325.351382 8.467369) (xy 325.265999 8.459457)
			(xy 325.180249 8.459457) (xy 325.094866 8.467369) (xy 325.010576 8.483125) (xy 324.9281 8.506592)
			(xy 324.848141 8.537568) (xy 324.771381 8.57579) (xy 324.698475 8.620931) (xy 324.630046 8.672607)
			(xy 324.566676 8.730376) (xy 324.508907 8.793746) (xy 324.457231 8.862175) (xy 324.41209 8.935081)
			(xy 324.373868 9.011841) (xy 324.342892 9.0918) (xy 324.319425 9.174276) (xy 324.303669 9.258566)
			(xy 324.295757 9.343949) (xy 317.930117 9.343949) (xy 317.930035 9.336837) (xy 317.922123 9.251454)
			(xy 317.906367 9.167164) (xy 317.8829 9.084688) (xy 317.851924 9.004729) (xy 317.813702 8.927969)
			(xy 317.768561 8.855063) (xy 317.716885 8.786634) (xy 317.659116 8.723264) (xy 317.595746 8.665495)
			(xy 317.527317 8.613819) (xy 317.454411 8.568678) (xy 317.377651 8.530456) (xy 317.297692 8.49948)
			(xy 317.215216 8.476013) (xy 317.130926 8.460257) (xy 317.045543 8.452345) (xy 316.959793 8.452345)
			(xy 316.87441 8.460257) (xy 316.79012 8.476013) (xy 316.707644 8.49948) (xy 316.627685 8.530456)
			(xy 316.550925 8.568678) (xy 316.478019 8.613819) (xy 316.40959 8.665495) (xy 316.34622 8.723264)
			(xy 316.288451 8.786634) (xy 316.236775 8.855063) (xy 316.191634 8.927969) (xy 316.153412 9.004729)
			(xy 316.122436 9.084688) (xy 316.098969 9.167164) (xy 316.083213 9.251454) (xy 316.075301 9.336837)
			(xy 311.580035 9.336837) (xy 311.572123 9.251454) (xy 311.556367 9.167164) (xy 311.5329 9.084688)
			(xy 311.501924 9.004729) (xy 311.463702 8.927969) (xy 311.418561 8.855063) (xy 311.366885 8.786634)
			(xy 311.309116 8.723264) (xy 311.245746 8.665495) (xy 311.177317 8.613819) (xy 311.104411 8.568678)
			(xy 311.027651 8.530456) (xy 310.947692 8.49948) (xy 310.865216 8.476013) (xy 310.780926 8.460257)
			(xy 310.695543 8.452345) (xy 310.609793 8.452345) (xy 310.52441 8.460257) (xy 310.44012 8.476013)
			(xy 310.357644 8.49948) (xy 310.277685 8.530456) (xy 310.200925 8.568678) (xy 310.128019 8.613819)
			(xy 310.05959 8.665495) (xy 309.99622 8.723264) (xy 309.938451 8.786634) (xy 309.886775 8.855063)
			(xy 309.841634 8.927969) (xy 309.803412 9.004729) (xy 309.772436 9.084688) (xy 309.748969 9.167164)
			(xy 309.733213 9.251454) (xy 309.725301 9.336837) (xy 259.72979 9.336837) (xy 259.729491 9.310929)
			(xy 259.721579 9.225546) (xy 259.705823 9.141256) (xy 259.682356 9.05878) (xy 259.65138 8.978821)
			(xy 259.613158 8.902061) (xy 259.568017 8.829155) (xy 259.516341 8.760726) (xy 259.458572 8.697356)
			(xy 259.395202 8.639587) (xy 259.326773 8.587911) (xy 259.253867 8.54277) (xy 259.177107 8.504548)
			(xy 259.097148 8.473572) (xy 259.014672 8.450105) (xy 258.930382 8.434349) (xy 258.844999 8.426437)
			(xy 258.759249 8.426437) (xy 258.673866 8.434349) (xy 258.589576 8.450105) (xy 258.5071 8.473572)
			(xy 258.427141 8.504548) (xy 258.350381 8.54277) (xy 258.277475 8.587911) (xy 258.209046 8.639587)
			(xy 258.145676 8.697356) (xy 258.087907 8.760726) (xy 258.036231 8.829155) (xy 257.99109 8.902061)
			(xy 257.952868 8.978821) (xy 257.921892 9.05878) (xy 257.898425 9.141256) (xy 257.882669 9.225546)
			(xy 257.874757 9.310929) (xy 253.379491 9.310929) (xy 253.371579 9.225546) (xy 253.355823 9.141256)
			(xy 253.332356 9.05878) (xy 253.30138 8.978821) (xy 253.263158 8.902061) (xy 253.218017 8.829155)
			(xy 253.166341 8.760726) (xy 253.108572 8.697356) (xy 253.045202 8.639587) (xy 252.976773 8.587911)
			(xy 252.903867 8.54277) (xy 252.827107 8.504548) (xy 252.747148 8.473572) (xy 252.664672 8.450105)
			(xy 252.580382 8.434349) (xy 252.494999 8.426437) (xy 252.409249 8.426437) (xy 252.323866 8.434349)
			(xy 252.239576 8.450105) (xy 252.1571 8.473572) (xy 252.077141 8.504548) (xy 252.000381 8.54277)
			(xy 251.927475 8.587911) (xy 251.859046 8.639587) (xy 251.795676 8.697356) (xy 251.737907 8.760726)
			(xy 251.686231 8.829155) (xy 251.64109 8.902061) (xy 251.602868 8.978821) (xy 251.571892 9.05878)
			(xy 251.548425 9.141256) (xy 251.532669 9.225546) (xy 251.524757 9.310929) (xy 245.921117 9.310929)
			(xy 245.921035 9.303817) (xy 245.913123 9.218434) (xy 245.897367 9.134144) (xy 245.8739 9.051668)
			(xy 245.842924 8.971709) (xy 245.804702 8.894949) (xy 245.759561 8.822043) (xy 245.707885 8.753614)
			(xy 245.650116 8.690244) (xy 245.586746 8.632475) (xy 245.518317 8.580799) (xy 245.445411 8.535658)
			(xy 245.368651 8.497436) (xy 245.288692 8.46646) (xy 245.206216 8.442993) (xy 245.121926 8.427237)
			(xy 245.036543 8.419325) (xy 244.950793 8.419325) (xy 244.86541 8.427237) (xy 244.78112 8.442993)
			(xy 244.698644 8.46646) (xy 244.618685 8.497436) (xy 244.541925 8.535658) (xy 244.469019 8.580799)
			(xy 244.40059 8.632475) (xy 244.33722 8.690244) (xy 244.279451 8.753614) (xy 244.227775 8.822043)
			(xy 244.182634 8.894949) (xy 244.144412 8.971709) (xy 244.113436 9.051668) (xy 244.089969 9.134144)
			(xy 244.074213 9.218434) (xy 244.066301 9.303817) (xy 239.571035 9.303817) (xy 239.563123 9.218434)
			(xy 239.547367 9.134144) (xy 239.5239 9.051668) (xy 239.492924 8.971709) (xy 239.454702 8.894949)
			(xy 239.409561 8.822043) (xy 239.357885 8.753614) (xy 239.300116 8.690244) (xy 239.236746 8.632475)
			(xy 239.168317 8.580799) (xy 239.095411 8.535658) (xy 239.018651 8.497436) (xy 238.938692 8.46646)
			(xy 238.856216 8.442993) (xy 238.771926 8.427237) (xy 238.686543 8.419325) (xy 238.600793 8.419325)
			(xy 238.51541 8.427237) (xy 238.43112 8.442993) (xy 238.348644 8.46646) (xy 238.268685 8.497436)
			(xy 238.191925 8.535658) (xy 238.119019 8.580799) (xy 238.05059 8.632475) (xy 237.98722 8.690244)
			(xy 237.929451 8.753614) (xy 237.877775 8.822043) (xy 237.832634 8.894949) (xy 237.794412 8.971709)
			(xy 237.763436 9.051668) (xy 237.739969 9.134144) (xy 237.724213 9.218434) (xy 237.716301 9.303817)
			(xy 187.719832 9.303817) (xy 187.712579 9.225546) (xy 187.696823 9.141256) (xy 187.673356 9.05878)
			(xy 187.64238 8.978821) (xy 187.604158 8.902061) (xy 187.559017 8.829155) (xy 187.507341 8.760726)
			(xy 187.449572 8.697356) (xy 187.386202 8.639587) (xy 187.317773 8.587911) (xy 187.244867 8.54277)
			(xy 187.168107 8.504548) (xy 187.088148 8.473572) (xy 187.005672 8.450105) (xy 186.921382 8.434349)
			(xy 186.835999 8.426437) (xy 186.750249 8.426437) (xy 186.664866 8.434349) (xy 186.580576 8.450105)
			(xy 186.4981 8.473572) (xy 186.418141 8.504548) (xy 186.341381 8.54277) (xy 186.268475 8.587911)
			(xy 186.200046 8.639587) (xy 186.136676 8.697356) (xy 186.078907 8.760726) (xy 186.027231 8.829155)
			(xy 185.98209 8.902061) (xy 185.943868 8.978821) (xy 185.912892 9.05878) (xy 185.889425 9.141256)
			(xy 185.873669 9.225546) (xy 185.865757 9.310929) (xy 181.370491 9.310929) (xy 181.362579 9.225546)
			(xy 181.346823 9.141256) (xy 181.323356 9.05878) (xy 181.29238 8.978821) (xy 181.254158 8.902061)
			(xy 181.209017 8.829155) (xy 181.157341 8.760726) (xy 181.099572 8.697356) (xy 181.036202 8.639587)
			(xy 180.967773 8.587911) (xy 180.894867 8.54277) (xy 180.818107 8.504548) (xy 180.738148 8.473572)
			(xy 180.655672 8.450105) (xy 180.571382 8.434349) (xy 180.485999 8.426437) (xy 180.400249 8.426437)
			(xy 180.314866 8.434349) (xy 180.230576 8.450105) (xy 180.1481 8.473572) (xy 180.068141 8.504548)
			(xy 179.991381 8.54277) (xy 179.918475 8.587911) (xy 179.850046 8.639587) (xy 179.786676 8.697356)
			(xy 179.728907 8.760726) (xy 179.677231 8.829155) (xy 179.63209 8.902061) (xy 179.593868 8.978821)
			(xy 179.562892 9.05878) (xy 179.539425 9.141256) (xy 179.523669 9.225546) (xy 179.515757 9.310929)
			(xy 158.621984 9.310929) (xy 158.621984 8.377682) (xy 158.62149 8.307329) (xy 158.6136 8.166844)
			(xy 158.597845 8.027022) (xy 158.574274 7.888303) (xy 158.542963 7.751125) (xy 158.50401 7.615918)
			(xy 158.457537 7.483107) (xy 158.40369 7.353112) (xy 158.342638 7.22634) (xy 158.274575 7.103191)
			(xy 158.199714 6.984051) (xy 158.11829 6.869297) (xy 158.039844 6.770929) (xy 179.515757 6.770929)
			(xy 179.515757 6.856679) (xy 179.523669 6.942062) (xy 179.539425 7.026352) (xy 179.562892 7.108828)
			(xy 179.593868 7.188787) (xy 179.63209 7.265547) (xy 179.677231 7.338453) (xy 179.728907 7.406882)
			(xy 179.786676 7.470252) (xy 179.850046 7.528021) (xy 179.918475 7.579697) (xy 179.991381 7.624838)
			(xy 180.068141 7.66306) (xy 180.1481 7.694036) (xy 180.230576 7.717503) (xy 180.314866 7.733259)
			(xy 180.400249 7.741171) (xy 180.485999 7.741171) (xy 180.571382 7.733259) (xy 180.655672 7.717503)
			(xy 180.738148 7.694036) (xy 180.818107 7.66306) (xy 180.894867 7.624838) (xy 180.967773 7.579697)
			(xy 181.036202 7.528021) (xy 181.099572 7.470252) (xy 181.157341 7.406882) (xy 181.209017 7.338453)
			(xy 181.254158 7.265547) (xy 181.29238 7.188787) (xy 181.323356 7.108828) (xy 181.346823 7.026352)
			(xy 181.362579 6.942062) (xy 181.370491 6.856679) (xy 181.370986 6.813804) (xy 181.370491 6.770929)
			(xy 185.865757 6.770929) (xy 185.865757 6.856679) (xy 185.873669 6.942062) (xy 185.889425 7.026352)
			(xy 185.912892 7.108828) (xy 185.943868 7.188787) (xy 185.98209 7.265547) (xy 186.027231 7.338453)
			(xy 186.078907 7.406882) (xy 186.136676 7.470252) (xy 186.200046 7.528021) (xy 186.268475 7.579697)
			(xy 186.341381 7.624838) (xy 186.418141 7.66306) (xy 186.4981 7.694036) (xy 186.580576 7.717503)
			(xy 186.664866 7.733259) (xy 186.750249 7.741171) (xy 186.835999 7.741171) (xy 186.921382 7.733259)
			(xy 187.005672 7.717503) (xy 187.088148 7.694036) (xy 187.168107 7.66306) (xy 187.244867 7.624838)
			(xy 187.317773 7.579697) (xy 187.386202 7.528021) (xy 187.449572 7.470252) (xy 187.507341 7.406882)
			(xy 187.559017 7.338453) (xy 187.604158 7.265547) (xy 187.64238 7.188787) (xy 187.673356 7.108828)
			(xy 187.696823 7.026352) (xy 187.712579 6.942062) (xy 187.720491 6.856679) (xy 187.720986 6.813804)
			(xy 187.720491 6.770929) (xy 187.719832 6.763817) (xy 237.716301 6.763817) (xy 237.716301 6.849567)
			(xy 237.724213 6.93495) (xy 237.739969 7.01924) (xy 237.763436 7.101716) (xy 237.794412 7.181675)
			(xy 237.832634 7.258435) (xy 237.877775 7.331341) (xy 237.929451 7.39977) (xy 237.98722 7.46314)
			(xy 238.05059 7.520909) (xy 238.119019 7.572585) (xy 238.191925 7.617726) (xy 238.268685 7.655948)
			(xy 238.348644 7.686924) (xy 238.43112 7.710391) (xy 238.51541 7.726147) (xy 238.600793 7.734059)
			(xy 238.686543 7.734059) (xy 238.771926 7.726147) (xy 238.856216 7.710391) (xy 238.938692 7.686924)
			(xy 239.018651 7.655948) (xy 239.095411 7.617726) (xy 239.168317 7.572585) (xy 239.236746 7.520909)
			(xy 239.300116 7.46314) (xy 239.357885 7.39977) (xy 239.409561 7.331341) (xy 239.454702 7.258435)
			(xy 239.492924 7.181675) (xy 239.5239 7.101716) (xy 239.547367 7.01924) (xy 239.563123 6.93495) (xy 239.571035 6.849567)
			(xy 239.57153 6.806692) (xy 239.571035 6.763817) (xy 244.066301 6.763817) (xy 244.066301 6.849567)
			(xy 244.074213 6.93495) (xy 244.089969 7.01924) (xy 244.113436 7.101716) (xy 244.144412 7.181675)
			(xy 244.182634 7.258435) (xy 244.227775 7.331341) (xy 244.279451 7.39977) (xy 244.33722 7.46314)
			(xy 244.40059 7.520909) (xy 244.469019 7.572585) (xy 244.541925 7.617726) (xy 244.618685 7.655948)
			(xy 244.698644 7.686924) (xy 244.78112 7.710391) (xy 244.86541 7.726147) (xy 244.950793 7.734059)
			(xy 245.036543 7.734059) (xy 245.121926 7.726147) (xy 245.206216 7.710391) (xy 245.288692 7.686924)
			(xy 245.368651 7.655948) (xy 245.445411 7.617726) (xy 245.518317 7.572585) (xy 245.586746 7.520909)
			(xy 245.650116 7.46314) (xy 245.707885 7.39977) (xy 245.759561 7.331341) (xy 245.804702 7.258435)
			(xy 245.842924 7.181675) (xy 245.8739 7.101716) (xy 245.897367 7.01924) (xy 245.913123 6.93495) (xy 245.921035 6.849567)
			(xy 245.92153 6.806692) (xy 245.921117 6.770929) (xy 251.524757 6.770929) (xy 251.524757 6.856679)
			(xy 251.532669 6.942062) (xy 251.548425 7.026352) (xy 251.571892 7.108828) (xy 251.602868 7.188787)
			(xy 251.64109 7.265547) (xy 251.686231 7.338453) (xy 251.737907 7.406882) (xy 251.795676 7.470252)
			(xy 251.859046 7.528021) (xy 251.927475 7.579697) (xy 252.000381 7.624838) (xy 252.077141 7.66306)
			(xy 252.1571 7.694036) (xy 252.239576 7.717503) (xy 252.323866 7.733259) (xy 252.409249 7.741171)
			(xy 252.494999 7.741171) (xy 252.580382 7.733259) (xy 252.664672 7.717503) (xy 252.747148 7.694036)
			(xy 252.827107 7.66306) (xy 252.84931 7.652004) (xy 256.459736 7.652004) (xy 256.459736 8.515604)
			(xy 256.460222 8.542873) (xy 256.467984 8.596857) (xy 256.483349 8.649187) (xy 256.506006 8.698797)
			(xy 256.535492 8.744678) (xy 256.571207 8.785895) (xy 256.612424 8.82161) (xy 256.658305 8.851096)
			(xy 256.707915 8.873753) (xy 256.760245 8.889118) (xy 256.814229 8.89688) (xy 256.868767 8.89688)
			(xy 256.922751 8.889118) (xy 256.975081 8.873753) (xy 257.024691 8.851096) (xy 257.070572 8.82161)
			(xy 257.111789 8.785895) (xy 257.147504 8.744678) (xy 257.17699 8.698797) (xy 257.199647 8.649187)
			(xy 257.215012 8.596857) (xy 257.222774 8.542873) (xy 257.22326 8.515604) (xy 257.22326 7.652004)
			(xy 257.222774 7.624735) (xy 257.215012 7.570751) (xy 257.199647 7.518421) (xy 257.17699 7.468811)
			(xy 257.147504 7.42293) (xy 257.111789 7.381713) (xy 257.070572 7.345998) (xy 257.024691 7.316512)
			(xy 256.975081 7.293855) (xy 256.922751 7.27849) (xy 256.868767 7.270728) (xy 256.814229 7.270728)
			(xy 256.760245 7.27849) (xy 256.707915 7.293855) (xy 256.658305 7.316512) (xy 256.612424 7.345998)
			(xy 256.571207 7.381713) (xy 256.535492 7.42293) (xy 256.506006 7.468811) (xy 256.483349 7.518421)
			(xy 256.467984 7.570751) (xy 256.460222 7.624735) (xy 256.459736 7.652004) (xy 252.84931 7.652004)
			(xy 252.903867 7.624838) (xy 252.976773 7.579697) (xy 253.045202 7.528021) (xy 253.108572 7.470252)
			(xy 253.166341 7.406882) (xy 253.218017 7.338453) (xy 253.263158 7.265547) (xy 253.30138 7.188787)
			(xy 253.332356 7.108828) (xy 253.355823 7.026352) (xy 253.371579 6.942062) (xy 253.379491 6.856679)
			(xy 253.379986 6.813804) (xy 253.379491 6.770929) (xy 257.874757 6.770929) (xy 257.874757 6.856679)
			(xy 257.882669 6.942062) (xy 257.898425 7.026352) (xy 257.921892 7.108828) (xy 257.952868 7.188787)
			(xy 257.99109 7.265547) (xy 258.036231 7.338453) (xy 258.087907 7.406882) (xy 258.145676 7.470252)
			(xy 258.209046 7.528021) (xy 258.277475 7.579697) (xy 258.350381 7.624838) (xy 258.427141 7.66306)
			(xy 258.5071 7.694036) (xy 258.589576 7.717503) (xy 258.673866 7.733259) (xy 258.759249 7.741171)
			(xy 258.844999 7.741171) (xy 258.930382 7.733259) (xy 259.014672 7.717503) (xy 259.097148 7.694036)
			(xy 259.177107 7.66306) (xy 259.253867 7.624838) (xy 259.326773 7.579697) (xy 259.395202 7.528021)
			(xy 259.458572 7.470252) (xy 259.516341 7.406882) (xy 259.568017 7.338453) (xy 259.613158 7.265547)
			(xy 259.65138 7.188787) (xy 259.682356 7.108828) (xy 259.705823 7.026352) (xy 259.721579 6.942062)
			(xy 259.729491 6.856679) (xy 259.729986 6.813804) (xy 259.72979 6.796837) (xy 309.725301 6.796837)
			(xy 309.725301 6.882587) (xy 309.733213 6.96797) (xy 309.748969 7.05226) (xy 309.772436 7.134736)
			(xy 309.803412 7.214695) (xy 309.841634 7.291455) (xy 309.886775 7.364361) (xy 309.938451 7.43279)
			(xy 309.99622 7.49616) (xy 310.05959 7.553929) (xy 310.128019 7.605605) (xy 310.200925 7.650746)
			(xy 310.277685 7.688968) (xy 310.357644 7.719944) (xy 310.44012 7.743411) (xy 310.52441 7.759167)
			(xy 310.609793 7.767079) (xy 310.695543 7.767079) (xy 310.780926 7.759167) (xy 310.865216 7.743411)
			(xy 310.947692 7.719944) (xy 311.027651 7.688968) (xy 311.049854 7.677912) (xy 312.231532 7.677912)
			(xy 312.231532 8.541512) (xy 312.232018 8.568781) (xy 312.23978 8.622765) (xy 312.255145 8.675095)
			(xy 312.277802 8.724705) (xy 312.307288 8.770586) (xy 312.343003 8.811803) (xy 312.38422 8.847518)
			(xy 312.430101 8.877004) (xy 312.479711 8.899661) (xy 312.532041 8.915026) (xy 312.586025 8.922788)
			(xy 312.640563 8.922788) (xy 312.694547 8.915026) (xy 312.746877 8.899661) (xy 312.796487 8.877004)
			(xy 312.842368 8.847518) (xy 312.883585 8.811803) (xy 312.9193 8.770586) (xy 312.948786 8.724705)
			(xy 312.971443 8.675095) (xy 312.986808 8.622765) (xy 312.99457 8.568781) (xy 312.995056 8.541512)
			(xy 312.995056 7.677912) (xy 312.99457 7.650643) (xy 312.986808 7.596659) (xy 312.971443 7.544329)
			(xy 312.948786 7.494719) (xy 312.9193 7.448838) (xy 312.883585 7.407621) (xy 312.842368 7.371906)
			(xy 312.796487 7.34242) (xy 312.746877 7.319763) (xy 312.694547 7.304398) (xy 312.640563 7.296636)
			(xy 312.586025 7.296636) (xy 312.532041 7.304398) (xy 312.479711 7.319763) (xy 312.430101 7.34242)
			(xy 312.38422 7.371906) (xy 312.343003 7.407621) (xy 312.307288 7.448838) (xy 312.277802 7.494719)
			(xy 312.255145 7.544329) (xy 312.23978 7.596659) (xy 312.232018 7.650643) (xy 312.231532 7.677912)
			(xy 311.049854 7.677912) (xy 311.104411 7.650746) (xy 311.177317 7.605605) (xy 311.245746 7.553929)
			(xy 311.309116 7.49616) (xy 311.366885 7.43279) (xy 311.418561 7.364361) (xy 311.463702 7.291455)
			(xy 311.501924 7.214695) (xy 311.5329 7.134736) (xy 311.556367 7.05226) (xy 311.572123 6.96797) (xy 311.580035 6.882587)
			(xy 311.58053 6.839712) (xy 311.580035 6.796837) (xy 316.075301 6.796837) (xy 316.075301 6.882587)
			(xy 316.083213 6.96797) (xy 316.098969 7.05226) (xy 316.122436 7.134736) (xy 316.153412 7.214695)
			(xy 316.191634 7.291455) (xy 316.236775 7.364361) (xy 316.288451 7.43279) (xy 316.34622 7.49616)
			(xy 316.40959 7.553929) (xy 316.478019 7.605605) (xy 316.550925 7.650746) (xy 316.627685 7.688968)
			(xy 316.707644 7.719944) (xy 316.79012 7.743411) (xy 316.87441 7.759167) (xy 316.959793 7.767079)
			(xy 317.045543 7.767079) (xy 317.130926 7.759167) (xy 317.215216 7.743411) (xy 317.297692 7.719944)
			(xy 317.377651 7.688968) (xy 317.454411 7.650746) (xy 317.527317 7.605605) (xy 317.595746 7.553929)
			(xy 317.659116 7.49616) (xy 317.716885 7.43279) (xy 317.768561 7.364361) (xy 317.813702 7.291455)
			(xy 317.851924 7.214695) (xy 317.8829 7.134736) (xy 317.906367 7.05226) (xy 317.922123 6.96797) (xy 317.930035 6.882587)
			(xy 317.93053 6.839712) (xy 317.930117 6.803949) (xy 324.295757 6.803949) (xy 324.295757 6.889699)
			(xy 324.303669 6.975082) (xy 324.319425 7.059372) (xy 324.342892 7.141848) (xy 324.373868 7.221807)
			(xy 324.41209 7.298567) (xy 324.457231 7.371473) (xy 324.508907 7.439902) (xy 324.566676 7.503272)
			(xy 324.630046 7.561041) (xy 324.698475 7.612717) (xy 324.771381 7.657858) (xy 324.848141 7.69608)
			(xy 324.9281 7.727056) (xy 325.010576 7.750523) (xy 325.094866 7.766279) (xy 325.180249 7.774191)
			(xy 325.265999 7.774191) (xy 325.351382 7.766279) (xy 325.435672 7.750523) (xy 325.518148 7.727056)
			(xy 325.598107 7.69608) (xy 325.62031 7.685024) (xy 329.230736 7.685024) (xy 329.230736 8.548624)
			(xy 329.231222 8.575893) (xy 329.238984 8.629877) (xy 329.254349 8.682207) (xy 329.277006 8.731817)
			(xy 329.306492 8.777698) (xy 329.342207 8.818915) (xy 329.383424 8.85463) (xy 329.429305 8.884116)
			(xy 329.478915 8.906773) (xy 329.531245 8.922138) (xy 329.585229 8.9299) (xy 329.639767 8.9299) (xy 329.693751 8.922138)
			(xy 329.746081 8.906773) (xy 329.795691 8.884116) (xy 329.841572 8.85463) (xy 329.882789 8.818915)
			(xy 329.918504 8.777698) (xy 329.94799 8.731817) (xy 329.970647 8.682207) (xy 329.986012 8.629877)
			(xy 329.993774 8.575893) (xy 329.99426 8.548624) (xy 329.99426 7.685024) (xy 329.993774 7.657755)
			(xy 329.986012 7.603771) (xy 329.970647 7.551441) (xy 329.94799 7.501831) (xy 329.918504 7.45595)
			(xy 329.882789 7.414733) (xy 329.841572 7.379018) (xy 329.795691 7.349532) (xy 329.746081 7.326875)
			(xy 329.693751 7.31151) (xy 329.639767 7.303748) (xy 329.585229 7.303748) (xy 329.531245 7.31151)
			(xy 329.478915 7.326875) (xy 329.429305 7.349532) (xy 329.383424 7.379018) (xy 329.342207 7.414733)
			(xy 329.306492 7.45595) (xy 329.277006 7.501831) (xy 329.254349 7.551441) (xy 329.238984 7.603771)
			(xy 329.231222 7.657755) (xy 329.230736 7.685024) (xy 325.62031 7.685024) (xy 325.674867 7.657858)
			(xy 325.747773 7.612717) (xy 325.816202 7.561041) (xy 325.879572 7.503272) (xy 325.937341 7.439902)
			(xy 325.989017 7.371473) (xy 326.034158 7.298567) (xy 326.07238 7.221807) (xy 326.103356 7.141848)
			(xy 326.126823 7.059372) (xy 326.142579 6.975082) (xy 326.150491 6.889699) (xy 326.150986 6.846824)
			(xy 326.150491 6.803949) (xy 330.645757 6.803949) (xy 330.645757 6.889699) (xy 330.653669 6.975082)
			(xy 330.669425 7.059372) (xy 330.692892 7.141848) (xy 330.723868 7.221807) (xy 330.76209 7.298567)
			(xy 330.807231 7.371473) (xy 330.858907 7.439902) (xy 330.916676 7.503272) (xy 330.980046 7.561041)
			(xy 331.048475 7.612717) (xy 331.121381 7.657858) (xy 331.198141 7.69608) (xy 331.2781 7.727056)
			(xy 331.360576 7.750523) (xy 331.444866 7.766279) (xy 331.530249 7.774191) (xy 331.615999 7.774191)
			(xy 331.701382 7.766279) (xy 331.785672 7.750523) (xy 331.868148 7.727056) (xy 331.948107 7.69608)
			(xy 332.024867 7.657858) (xy 332.097773 7.612717) (xy 332.166202 7.561041) (xy 332.229572 7.503272)
			(xy 332.287341 7.439902) (xy 332.339017 7.371473) (xy 332.384158 7.298567) (xy 332.42238 7.221807)
			(xy 332.453356 7.141848) (xy 332.476823 7.059372) (xy 332.492579 6.975082) (xy 332.500491 6.889699)
			(xy 332.500986 6.846824) (xy 332.50079 6.829857) (xy 382.496301 6.829857) (xy 382.496301 6.915607)
			(xy 382.504213 7.00099) (xy 382.519969 7.08528) (xy 382.543436 7.167756) (xy 382.574412 7.247715)
			(xy 382.612634 7.324475) (xy 382.657775 7.397381) (xy 382.709451 7.46581) (xy 382.76722 7.52918)
			(xy 382.83059 7.586949) (xy 382.899019 7.638625) (xy 382.971925 7.683766) (xy 383.048685 7.721988)
			(xy 383.128644 7.752964) (xy 383.21112 7.776431) (xy 383.29541 7.792187) (xy 383.380793 7.800099)
			(xy 383.466543 7.800099) (xy 383.551926 7.792187) (xy 383.636216 7.776431) (xy 383.718692 7.752964)
			(xy 383.798651 7.721988) (xy 383.820854 7.710932) (xy 385.002532 7.710932) (xy 385.002532 8.574532)
			(xy 385.003018 8.601801) (xy 385.01078 8.655785) (xy 385.026145 8.708115) (xy 385.048802 8.757725)
			(xy 385.078288 8.803606) (xy 385.114003 8.844823) (xy 385.15522 8.880538) (xy 385.201101 8.910024)
			(xy 385.250711 8.932681) (xy 385.303041 8.948046) (xy 385.357025 8.955808) (xy 385.411563 8.955808)
			(xy 385.465547 8.948046) (xy 385.517877 8.932681) (xy 385.567487 8.910024) (xy 385.613368 8.880538)
			(xy 385.654585 8.844823) (xy 385.6903 8.803606) (xy 385.719786 8.757725) (xy 385.742443 8.708115)
			(xy 385.757808 8.655785) (xy 385.76557 8.601801) (xy 385.766056 8.574532) (xy 385.766056 7.710932)
			(xy 385.76557 7.683663) (xy 385.757808 7.629679) (xy 385.742443 7.577349) (xy 385.719786 7.527739)
			(xy 385.6903 7.481858) (xy 385.654585 7.440641) (xy 385.613368 7.404926) (xy 385.567487 7.37544)
			(xy 385.517877 7.352783) (xy 385.465547 7.337418) (xy 385.411563 7.329656) (xy 385.357025 7.329656)
			(xy 385.303041 7.337418) (xy 385.250711 7.352783) (xy 385.201101 7.37544) (xy 385.15522 7.404926)
			(xy 385.114003 7.440641) (xy 385.078288 7.481858) (xy 385.048802 7.527739) (xy 385.026145 7.577349)
			(xy 385.01078 7.629679) (xy 385.003018 7.683663) (xy 385.002532 7.710932) (xy 383.820854 7.710932)
			(xy 383.875411 7.683766) (xy 383.948317 7.638625) (xy 384.016746 7.586949) (xy 384.080116 7.52918)
			(xy 384.137885 7.46581) (xy 384.189561 7.397381) (xy 384.234702 7.324475) (xy 384.272924 7.247715)
			(xy 384.3039 7.167756) (xy 384.327367 7.08528) (xy 384.343123 7.00099) (xy 384.351035 6.915607) (xy 384.35153 6.872732)
			(xy 384.351035 6.829857) (xy 388.846301 6.829857) (xy 388.846301 6.915607) (xy 388.854213 7.00099)
			(xy 388.869969 7.08528) (xy 388.893436 7.167756) (xy 388.924412 7.247715) (xy 388.962634 7.324475)
			(xy 389.007775 7.397381) (xy 389.059451 7.46581) (xy 389.11722 7.52918) (xy 389.18059 7.586949) (xy 389.249019 7.638625)
			(xy 389.321925 7.683766) (xy 389.398685 7.721988) (xy 389.478644 7.752964) (xy 389.56112 7.776431)
			(xy 389.64541 7.792187) (xy 389.730793 7.800099) (xy 389.816543 7.800099) (xy 389.901926 7.792187)
			(xy 389.986216 7.776431) (xy 390.068692 7.752964) (xy 390.148651 7.721988) (xy 390.225411 7.683766)
			(xy 390.298317 7.638625) (xy 390.366746 7.586949) (xy 390.430116 7.52918) (xy 390.487885 7.46581)
			(xy 390.539561 7.397381) (xy 390.584702 7.324475) (xy 390.622924 7.247715) (xy 390.6539 7.167756)
			(xy 390.677367 7.08528) (xy 390.693123 7.00099) (xy 390.701035 6.915607) (xy 390.70153 6.872732)
			(xy 390.701117 6.836969) (xy 396.558757 6.836969) (xy 396.558757 6.922719) (xy 396.566669 7.008102)
			(xy 396.582425 7.092392) (xy 396.605892 7.174868) (xy 396.636868 7.254827) (xy 396.67509 7.331587)
			(xy 396.720231 7.404493) (xy 396.771907 7.472922) (xy 396.829676 7.536292) (xy 396.893046 7.594061)
			(xy 396.961475 7.645737) (xy 397.034381 7.690878) (xy 397.111141 7.7291) (xy 397.1911 7.760076) (xy 397.273576 7.783543)
			(xy 397.357866 7.799299) (xy 397.443249 7.807211) (xy 397.528999 7.807211) (xy 397.614382 7.799299)
			(xy 397.698672 7.783543) (xy 397.781148 7.760076) (xy 397.861107 7.7291) (xy 397.88331 7.718044)
			(xy 401.493736 7.718044) (xy 401.493736 8.581644) (xy 401.494222 8.608913) (xy 401.501984 8.662897)
			(xy 401.517349 8.715227) (xy 401.540006 8.764837) (xy 401.569492 8.810718) (xy 401.605207 8.851935)
			(xy 401.646424 8.88765) (xy 401.692305 8.917136) (xy 401.741915 8.939793) (xy 401.794245 8.955158)
			(xy 401.848229 8.96292) (xy 401.902767 8.96292) (xy 401.956751 8.955158) (xy 402.009081 8.939793)
			(xy 402.058691 8.917136) (xy 402.104572 8.88765) (xy 402.145789 8.851935) (xy 402.181504 8.810718)
			(xy 402.21099 8.764837) (xy 402.233647 8.715227) (xy 402.249012 8.662897) (xy 402.256774 8.608913)
			(xy 402.25726 8.581644) (xy 402.25726 7.718044) (xy 402.256774 7.690775) (xy 402.249012 7.636791)
			(xy 402.233647 7.584461) (xy 402.21099 7.534851) (xy 402.181504 7.48897) (xy 402.145789 7.447753)
			(xy 402.104572 7.412038) (xy 402.058691 7.382552) (xy 402.009081 7.359895) (xy 401.956751 7.34453)
			(xy 401.902767 7.336768) (xy 401.848229 7.336768) (xy 401.794245 7.34453) (xy 401.741915 7.359895)
			(xy 401.692305 7.382552) (xy 401.646424 7.412038) (xy 401.605207 7.447753) (xy 401.569492 7.48897)
			(xy 401.540006 7.534851) (xy 401.517349 7.584461) (xy 401.501984 7.636791) (xy 401.494222 7.690775)
			(xy 401.493736 7.718044) (xy 397.88331 7.718044) (xy 397.937867 7.690878) (xy 398.010773 7.645737)
			(xy 398.079202 7.594061) (xy 398.142572 7.536292) (xy 398.200341 7.472922) (xy 398.252017 7.404493)
			(xy 398.297158 7.331587) (xy 398.33538 7.254827) (xy 398.366356 7.174868) (xy 398.389823 7.092392)
			(xy 398.405579 7.008102) (xy 398.413491 6.922719) (xy 398.413986 6.879844) (xy 398.413491 6.836969)
			(xy 402.908757 6.836969) (xy 402.908757 6.922719) (xy 402.916669 7.008102) (xy 402.932425 7.092392)
			(xy 402.955892 7.174868) (xy 402.986868 7.254827) (xy 403.02509 7.331587) (xy 403.070231 7.404493)
			(xy 403.121907 7.472922) (xy 403.179676 7.536292) (xy 403.243046 7.594061) (xy 403.311475 7.645737)
			(xy 403.384381 7.690878) (xy 403.461141 7.7291) (xy 403.5411 7.760076) (xy 403.623576 7.783543) (xy 403.707866 7.799299)
			(xy 403.793249 7.807211) (xy 403.878999 7.807211) (xy 403.964382 7.799299) (xy 404.048672 7.783543)
			(xy 404.131148 7.760076) (xy 404.211107 7.7291) (xy 404.287867 7.690878) (xy 404.360773 7.645737)
			(xy 404.429202 7.594061) (xy 404.492572 7.536292) (xy 404.550341 7.472922) (xy 404.602017 7.404493)
			(xy 404.647158 7.331587) (xy 404.68538 7.254827) (xy 404.716356 7.174868) (xy 404.739823 7.092392)
			(xy 404.755579 7.008102) (xy 404.763491 6.922719) (xy 404.763986 6.879844) (xy 404.76379 6.862877)
			(xy 454.759301 6.862877) (xy 454.759301 6.948627) (xy 454.767213 7.03401) (xy 454.782969 7.1183)
			(xy 454.806436 7.200776) (xy 454.837412 7.280735) (xy 454.875634 7.357495) (xy 454.920775 7.430401)
			(xy 454.972451 7.49883) (xy 455.03022 7.5622) (xy 455.09359 7.619969) (xy 455.162019 7.671645) (xy 455.234925 7.716786)
			(xy 455.311685 7.755008) (xy 455.391644 7.785984) (xy 455.47412 7.809451) (xy 455.55841 7.825207)
			(xy 455.643793 7.833119) (xy 455.729543 7.833119) (xy 455.814926 7.825207) (xy 455.899216 7.809451)
			(xy 455.981692 7.785984) (xy 456.061651 7.755008) (xy 456.083854 7.743952) (xy 457.265532 7.743952)
			(xy 457.265532 8.607552) (xy 457.266018 8.634821) (xy 457.27378 8.688805) (xy 457.289145 8.741135)
			(xy 457.311802 8.790745) (xy 457.341288 8.836626) (xy 457.377003 8.877843) (xy 457.41822 8.913558)
			(xy 457.464101 8.943044) (xy 457.513711 8.965701) (xy 457.566041 8.981066) (xy 457.620025 8.988828)
			(xy 457.674563 8.988828) (xy 457.728547 8.981066) (xy 457.780877 8.965701) (xy 457.830487 8.943044)
			(xy 457.876368 8.913558) (xy 457.917585 8.877843) (xy 457.9533 8.836626) (xy 457.982786 8.790745)
			(xy 458.005443 8.741135) (xy 458.020808 8.688805) (xy 458.02857 8.634821) (xy 458.029056 8.607552)
			(xy 458.029056 7.743952) (xy 458.02857 7.716683) (xy 458.020808 7.662699) (xy 458.005443 7.610369)
			(xy 457.982786 7.560759) (xy 457.9533 7.514878) (xy 457.917585 7.473661) (xy 457.876368 7.437946)
			(xy 457.830487 7.40846) (xy 457.780877 7.385803) (xy 457.728547 7.370438) (xy 457.674563 7.362676)
			(xy 457.620025 7.362676) (xy 457.566041 7.370438) (xy 457.513711 7.385803) (xy 457.464101 7.40846)
			(xy 457.41822 7.437946) (xy 457.377003 7.473661) (xy 457.341288 7.514878) (xy 457.311802 7.560759)
			(xy 457.289145 7.610369) (xy 457.27378 7.662699) (xy 457.266018 7.716683) (xy 457.265532 7.743952)
			(xy 456.083854 7.743952) (xy 456.138411 7.716786) (xy 456.211317 7.671645) (xy 456.279746 7.619969)
			(xy 456.343116 7.5622) (xy 456.400885 7.49883) (xy 456.452561 7.430401) (xy 456.497702 7.357495)
			(xy 456.535924 7.280735) (xy 456.5669 7.200776) (xy 456.590367 7.1183) (xy 456.606123 7.03401) (xy 456.614035 6.948627)
			(xy 456.61453 6.905752) (xy 456.614035 6.862877) (xy 461.109301 6.862877) (xy 461.109301 6.948627)
			(xy 461.117213 7.03401) (xy 461.132969 7.1183) (xy 461.156436 7.200776) (xy 461.187412 7.280735)
			(xy 461.225634 7.357495) (xy 461.270775 7.430401) (xy 461.322451 7.49883) (xy 461.38022 7.5622) (xy 461.44359 7.619969)
			(xy 461.512019 7.671645) (xy 461.584925 7.716786) (xy 461.661685 7.755008) (xy 461.741644 7.785984)
			(xy 461.82412 7.809451) (xy 461.90841 7.825207) (xy 461.993793 7.833119) (xy 462.079543 7.833119)
			(xy 462.164926 7.825207) (xy 462.249216 7.809451) (xy 462.331692 7.785984) (xy 462.411651 7.755008)
			(xy 462.488411 7.716786) (xy 462.561317 7.671645) (xy 462.629746 7.619969) (xy 462.693116 7.5622)
			(xy 462.750885 7.49883) (xy 462.802561 7.430401) (xy 462.847702 7.357495) (xy 462.885924 7.280735)
			(xy 462.9169 7.200776) (xy 462.940367 7.1183) (xy 462.956123 7.03401) (xy 462.964035 6.948627) (xy 462.96453 6.905752)
			(xy 462.964035 6.862877) (xy 462.956123 6.777494) (xy 462.940367 6.693204) (xy 462.9169 6.610728)
			(xy 462.885924 6.530769) (xy 462.847702 6.454009) (xy 462.802561 6.381103) (xy 462.750885 6.312674)
			(xy 462.693116 6.249304) (xy 462.629746 6.191535) (xy 462.561317 6.139859) (xy 462.488411 6.094718)
			(xy 462.411651 6.056496) (xy 462.331692 6.02552) (xy 462.249216 6.002053) (xy 462.164926 5.986297)
			(xy 462.079543 5.978385) (xy 461.993793 5.978385) (xy 461.90841 5.986297) (xy 461.82412 6.002053)
			(xy 461.741644 6.02552) (xy 461.661685 6.056496) (xy 461.584925 6.094718) (xy 461.512019 6.139859)
			(xy 461.44359 6.191535) (xy 461.38022 6.249304) (xy 461.322451 6.312674) (xy 461.270775 6.381103)
			(xy 461.225634 6.454009) (xy 461.187412 6.530769) (xy 461.156436 6.610728) (xy 461.132969 6.693204)
			(xy 461.117213 6.777494) (xy 461.109301 6.862877) (xy 456.614035 6.862877) (xy 456.606123 6.777494)
			(xy 456.590367 6.693204) (xy 456.5669 6.610728) (xy 456.535924 6.530769) (xy 456.497702 6.454009)
			(xy 456.452561 6.381103) (xy 456.400885 6.312674) (xy 456.343116 6.249304) (xy 456.279746 6.191535)
			(xy 456.211317 6.139859) (xy 456.138411 6.094718) (xy 456.061651 6.056496) (xy 455.981692 6.02552)
			(xy 455.899216 6.002053) (xy 455.814926 5.986297) (xy 455.729543 5.978385) (xy 455.643793 5.978385)
			(xy 455.55841 5.986297) (xy 455.47412 6.002053) (xy 455.391644 6.02552) (xy 455.311685 6.056496)
			(xy 455.234925 6.094718) (xy 455.162019 6.139859) (xy 455.09359 6.191535) (xy 455.03022 6.249304)
			(xy 454.972451 6.312674) (xy 454.920775 6.381103) (xy 454.875634 6.454009) (xy 454.837412 6.530769)
			(xy 454.806436 6.610728) (xy 454.782969 6.693204) (xy 454.767213 6.777494) (xy 454.759301 6.862877)
			(xy 404.76379 6.862877) (xy 404.763491 6.836969) (xy 404.755579 6.751586) (xy 404.739823 6.667296)
			(xy 404.716356 6.58482) (xy 404.68538 6.504861) (xy 404.647158 6.428101) (xy 404.602017 6.355195)
			(xy 404.550341 6.286766) (xy 404.492572 6.223396) (xy 404.429202 6.165627) (xy 404.360773 6.113951)
			(xy 404.287867 6.06881) (xy 404.211107 6.030588) (xy 404.131148 5.999612) (xy 404.048672 5.976145)
			(xy 403.964382 5.960389) (xy 403.878999 5.952477) (xy 403.793249 5.952477) (xy 403.707866 5.960389)
			(xy 403.623576 5.976145) (xy 403.5411 5.999612) (xy 403.461141 6.030588) (xy 403.384381 6.06881)
			(xy 403.311475 6.113951) (xy 403.243046 6.165627) (xy 403.179676 6.223396) (xy 403.121907 6.286766)
			(xy 403.070231 6.355195) (xy 403.02509 6.428101) (xy 402.986868 6.504861) (xy 402.955892 6.58482)
			(xy 402.932425 6.667296) (xy 402.916669 6.751586) (xy 402.908757 6.836969) (xy 398.413491 6.836969)
			(xy 398.405579 6.751586) (xy 398.389823 6.667296) (xy 398.366356 6.58482) (xy 398.33538 6.504861)
			(xy 398.297158 6.428101) (xy 398.252017 6.355195) (xy 398.200341 6.286766) (xy 398.142572 6.223396)
			(xy 398.079202 6.165627) (xy 398.010773 6.113951) (xy 397.937867 6.06881) (xy 397.861107 6.030588)
			(xy 397.781148 5.999612) (xy 397.698672 5.976145) (xy 397.614382 5.960389) (xy 397.528999 5.952477)
			(xy 397.443249 5.952477) (xy 397.357866 5.960389) (xy 397.273576 5.976145) (xy 397.1911 5.999612)
			(xy 397.111141 6.030588) (xy 397.034381 6.06881) (xy 396.961475 6.113951) (xy 396.893046 6.165627)
			(xy 396.829676 6.223396) (xy 396.771907 6.286766) (xy 396.720231 6.355195) (xy 396.67509 6.428101)
			(xy 396.636868 6.504861) (xy 396.605892 6.58482) (xy 396.582425 6.667296) (xy 396.566669 6.751586)
			(xy 396.558757 6.836969) (xy 390.701117 6.836969) (xy 390.701035 6.829857) (xy 390.693123 6.744474)
			(xy 390.677367 6.660184) (xy 390.6539 6.577708) (xy 390.622924 6.497749) (xy 390.584702 6.420989)
			(xy 390.539561 6.348083) (xy 390.487885 6.279654) (xy 390.430116 6.216284) (xy 390.366746 6.158515)
			(xy 390.298317 6.106839) (xy 390.225411 6.061698) (xy 390.148651 6.023476) (xy 390.068692 5.9925)
			(xy 389.986216 5.969033) (xy 389.901926 5.953277) (xy 389.816543 5.945365) (xy 389.730793 5.945365)
			(xy 389.64541 5.953277) (xy 389.56112 5.969033) (xy 389.478644 5.9925) (xy 389.398685 6.023476) (xy 389.321925 6.061698)
			(xy 389.249019 6.106839) (xy 389.18059 6.158515) (xy 389.11722 6.216284) (xy 389.059451 6.279654)
			(xy 389.007775 6.348083) (xy 388.962634 6.420989) (xy 388.924412 6.497749) (xy 388.893436 6.577708)
			(xy 388.869969 6.660184) (xy 388.854213 6.744474) (xy 388.846301 6.829857) (xy 384.351035 6.829857)
			(xy 384.343123 6.744474) (xy 384.327367 6.660184) (xy 384.3039 6.577708) (xy 384.272924 6.497749)
			(xy 384.234702 6.420989) (xy 384.189561 6.348083) (xy 384.137885 6.279654) (xy 384.080116 6.216284)
			(xy 384.016746 6.158515) (xy 383.948317 6.106839) (xy 383.875411 6.061698) (xy 383.798651 6.023476)
			(xy 383.718692 5.9925) (xy 383.636216 5.969033) (xy 383.551926 5.953277) (xy 383.466543 5.945365)
			(xy 383.380793 5.945365) (xy 383.29541 5.953277) (xy 383.21112 5.969033) (xy 383.128644 5.9925) (xy 383.048685 6.023476)
			(xy 382.971925 6.061698) (xy 382.899019 6.106839) (xy 382.83059 6.158515) (xy 382.76722 6.216284)
			(xy 382.709451 6.279654) (xy 382.657775 6.348083) (xy 382.612634 6.420989) (xy 382.574412 6.497749)
			(xy 382.543436 6.577708) (xy 382.519969 6.660184) (xy 382.504213 6.744474) (xy 382.496301 6.829857)
			(xy 332.50079 6.829857) (xy 332.500491 6.803949) (xy 332.492579 6.718566) (xy 332.476823 6.634276)
			(xy 332.453356 6.5518) (xy 332.42238 6.471841) (xy 332.384158 6.395081) (xy 332.339017 6.322175)
			(xy 332.287341 6.253746) (xy 332.229572 6.190376) (xy 332.166202 6.132607) (xy 332.097773 6.080931)
			(xy 332.024867 6.03579) (xy 331.948107 5.997568) (xy 331.868148 5.966592) (xy 331.785672 5.943125)
			(xy 331.701382 5.927369) (xy 331.615999 5.919457) (xy 331.530249 5.919457) (xy 331.444866 5.927369)
			(xy 331.360576 5.943125) (xy 331.2781 5.966592) (xy 331.198141 5.997568) (xy 331.121381 6.03579)
			(xy 331.048475 6.080931) (xy 330.980046 6.132607) (xy 330.916676 6.190376) (xy 330.858907 6.253746)
			(xy 330.807231 6.322175) (xy 330.76209 6.395081) (xy 330.723868 6.471841) (xy 330.692892 6.5518)
			(xy 330.669425 6.634276) (xy 330.653669 6.718566) (xy 330.645757 6.803949) (xy 326.150491 6.803949)
			(xy 326.142579 6.718566) (xy 326.126823 6.634276) (xy 326.103356 6.5518) (xy 326.07238 6.471841)
			(xy 326.034158 6.395081) (xy 325.989017 6.322175) (xy 325.937341 6.253746) (xy 325.879572 6.190376)
			(xy 325.816202 6.132607) (xy 325.747773 6.080931) (xy 325.674867 6.03579) (xy 325.598107 5.997568)
			(xy 325.518148 5.966592) (xy 325.435672 5.943125) (xy 325.351382 5.927369) (xy 325.265999 5.919457)
			(xy 325.180249 5.919457) (xy 325.094866 5.927369) (xy 325.010576 5.943125) (xy 324.9281 5.966592)
			(xy 324.848141 5.997568) (xy 324.771381 6.03579) (xy 324.698475 6.080931) (xy 324.630046 6.132607)
			(xy 324.566676 6.190376) (xy 324.508907 6.253746) (xy 324.457231 6.322175) (xy 324.41209 6.395081)
			(xy 324.373868 6.471841) (xy 324.342892 6.5518) (xy 324.319425 6.634276) (xy 324.303669 6.718566)
			(xy 324.295757 6.803949) (xy 317.930117 6.803949) (xy 317.930035 6.796837) (xy 317.922123 6.711454)
			(xy 317.906367 6.627164) (xy 317.8829 6.544688) (xy 317.851924 6.464729) (xy 317.813702 6.387969)
			(xy 317.768561 6.315063) (xy 317.716885 6.246634) (xy 317.659116 6.183264) (xy 317.595746 6.125495)
			(xy 317.527317 6.073819) (xy 317.454411 6.028678) (xy 317.377651 5.990456) (xy 317.297692 5.95948)
			(xy 317.215216 5.936013) (xy 317.130926 5.920257) (xy 317.045543 5.912345) (xy 316.959793 5.912345)
			(xy 316.87441 5.920257) (xy 316.79012 5.936013) (xy 316.707644 5.95948) (xy 316.627685 5.990456)
			(xy 316.550925 6.028678) (xy 316.478019 6.073819) (xy 316.40959 6.125495) (xy 316.34622 6.183264)
			(xy 316.288451 6.246634) (xy 316.236775 6.315063) (xy 316.191634 6.387969) (xy 316.153412 6.464729)
			(xy 316.122436 6.544688) (xy 316.098969 6.627164) (xy 316.083213 6.711454) (xy 316.075301 6.796837)
			(xy 311.580035 6.796837) (xy 311.572123 6.711454) (xy 311.556367 6.627164) (xy 311.5329 6.544688)
			(xy 311.501924 6.464729) (xy 311.463702 6.387969) (xy 311.418561 6.315063) (xy 311.366885 6.246634)
			(xy 311.309116 6.183264) (xy 311.245746 6.125495) (xy 311.177317 6.073819) (xy 311.104411 6.028678)
			(xy 311.027651 5.990456) (xy 310.947692 5.95948) (xy 310.865216 5.936013) (xy 310.780926 5.920257)
			(xy 310.695543 5.912345) (xy 310.609793 5.912345) (xy 310.52441 5.920257) (xy 310.44012 5.936013)
			(xy 310.357644 5.95948) (xy 310.277685 5.990456) (xy 310.200925 6.028678) (xy 310.128019 6.073819)
			(xy 310.05959 6.125495) (xy 309.99622 6.183264) (xy 309.938451 6.246634) (xy 309.886775 6.315063)
			(xy 309.841634 6.387969) (xy 309.803412 6.464729) (xy 309.772436 6.544688) (xy 309.748969 6.627164)
			(xy 309.733213 6.711454) (xy 309.725301 6.796837) (xy 259.72979 6.796837) (xy 259.729491 6.770929)
			(xy 259.721579 6.685546) (xy 259.705823 6.601256) (xy 259.682356 6.51878) (xy 259.65138 6.438821)
			(xy 259.613158 6.362061) (xy 259.568017 6.289155) (xy 259.516341 6.220726) (xy 259.458572 6.157356)
			(xy 259.395202 6.099587) (xy 259.326773 6.047911) (xy 259.253867 6.00277) (xy 259.177107 5.964548)
			(xy 259.097148 5.933572) (xy 259.014672 5.910105) (xy 258.930382 5.894349) (xy 258.844999 5.886437)
			(xy 258.759249 5.886437) (xy 258.673866 5.894349) (xy 258.589576 5.910105) (xy 258.5071 5.933572)
			(xy 258.427141 5.964548) (xy 258.350381 6.00277) (xy 258.277475 6.047911) (xy 258.209046 6.099587)
			(xy 258.145676 6.157356) (xy 258.087907 6.220726) (xy 258.036231 6.289155) (xy 257.99109 6.362061)
			(xy 257.952868 6.438821) (xy 257.921892 6.51878) (xy 257.898425 6.601256) (xy 257.882669 6.685546)
			(xy 257.874757 6.770929) (xy 253.379491 6.770929) (xy 253.371579 6.685546) (xy 253.355823 6.601256)
			(xy 253.332356 6.51878) (xy 253.30138 6.438821) (xy 253.263158 6.362061) (xy 253.218017 6.289155)
			(xy 253.166341 6.220726) (xy 253.108572 6.157356) (xy 253.045202 6.099587) (xy 252.976773 6.047911)
			(xy 252.903867 6.00277) (xy 252.827107 5.964548) (xy 252.747148 5.933572) (xy 252.664672 5.910105)
			(xy 252.580382 5.894349) (xy 252.494999 5.886437) (xy 252.409249 5.886437) (xy 252.323866 5.894349)
			(xy 252.239576 5.910105) (xy 252.1571 5.933572) (xy 252.077141 5.964548) (xy 252.000381 6.00277)
			(xy 251.927475 6.047911) (xy 251.859046 6.099587) (xy 251.795676 6.157356) (xy 251.737907 6.220726)
			(xy 251.686231 6.289155) (xy 251.64109 6.362061) (xy 251.602868 6.438821) (xy 251.571892 6.51878)
			(xy 251.548425 6.601256) (xy 251.532669 6.685546) (xy 251.524757 6.770929) (xy 245.921117 6.770929)
			(xy 245.921035 6.763817) (xy 245.913123 6.678434) (xy 245.897367 6.594144) (xy 245.8739 6.511668)
			(xy 245.842924 6.431709) (xy 245.804702 6.354949) (xy 245.759561 6.282043) (xy 245.707885 6.213614)
			(xy 245.650116 6.150244) (xy 245.586746 6.092475) (xy 245.518317 6.040799) (xy 245.445411 5.995658)
			(xy 245.368651 5.957436) (xy 245.288692 5.92646) (xy 245.206216 5.902993) (xy 245.121926 5.887237)
			(xy 245.036543 5.879325) (xy 244.950793 5.879325) (xy 244.86541 5.887237) (xy 244.78112 5.902993)
			(xy 244.698644 5.92646) (xy 244.618685 5.957436) (xy 244.541925 5.995658) (xy 244.469019 6.040799)
			(xy 244.40059 6.092475) (xy 244.33722 6.150244) (xy 244.279451 6.213614) (xy 244.227775 6.282043)
			(xy 244.182634 6.354949) (xy 244.144412 6.431709) (xy 244.113436 6.511668) (xy 244.089969 6.594144)
			(xy 244.074213 6.678434) (xy 244.066301 6.763817) (xy 239.571035 6.763817) (xy 239.563123 6.678434)
			(xy 239.547367 6.594144) (xy 239.5239 6.511668) (xy 239.492924 6.431709) (xy 239.454702 6.354949)
			(xy 239.409561 6.282043) (xy 239.357885 6.213614) (xy 239.300116 6.150244) (xy 239.236746 6.092475)
			(xy 239.168317 6.040799) (xy 239.095411 5.995658) (xy 239.018651 5.957436) (xy 238.938692 5.92646)
			(xy 238.856216 5.902993) (xy 238.771926 5.887237) (xy 238.686543 5.879325) (xy 238.600793 5.879325)
			(xy 238.51541 5.887237) (xy 238.43112 5.902993) (xy 238.348644 5.92646) (xy 238.268685 5.957436)
			(xy 238.191925 5.995658) (xy 238.119019 6.040799) (xy 238.05059 6.092475) (xy 237.98722 6.150244)
			(xy 237.929451 6.213614) (xy 237.877775 6.282043) (xy 237.832634 6.354949) (xy 237.794412 6.431709)
			(xy 237.763436 6.511668) (xy 237.739969 6.594144) (xy 237.724213 6.678434) (xy 237.716301 6.763817)
			(xy 187.719832 6.763817) (xy 187.712579 6.685546) (xy 187.696823 6.601256) (xy 187.673356 6.51878)
			(xy 187.64238 6.438821) (xy 187.604158 6.362061) (xy 187.559017 6.289155) (xy 187.507341 6.220726)
			(xy 187.449572 6.157356) (xy 187.386202 6.099587) (xy 187.317773 6.047911) (xy 187.244867 6.00277)
			(xy 187.168107 5.964548) (xy 187.088148 5.933572) (xy 187.005672 5.910105) (xy 186.921382 5.894349)
			(xy 186.835999 5.886437) (xy 186.750249 5.886437) (xy 186.664866 5.894349) (xy 186.580576 5.910105)
			(xy 186.4981 5.933572) (xy 186.418141 5.964548) (xy 186.341381 6.00277) (xy 186.268475 6.047911)
			(xy 186.200046 6.099587) (xy 186.136676 6.157356) (xy 186.078907 6.220726) (xy 186.027231 6.289155)
			(xy 185.98209 6.362061) (xy 185.943868 6.438821) (xy 185.912892 6.51878) (xy 185.889425 6.601256)
			(xy 185.873669 6.685546) (xy 185.865757 6.770929) (xy 181.370491 6.770929) (xy 181.362579 6.685546)
			(xy 181.346823 6.601256) (xy 181.323356 6.51878) (xy 181.29238 6.438821) (xy 181.254158 6.362061)
			(xy 181.209017 6.289155) (xy 181.157341 6.220726) (xy 181.099572 6.157356) (xy 181.036202 6.099587)
			(xy 180.967773 6.047911) (xy 180.894867 6.00277) (xy 180.818107 5.964548) (xy 180.738148 5.933572)
			(xy 180.655672 5.910105) (xy 180.571382 5.894349) (xy 180.485999 5.886437) (xy 180.400249 5.886437)
			(xy 180.314866 5.894349) (xy 180.230576 5.910105) (xy 180.1481 5.933572) (xy 180.068141 5.964548)
			(xy 179.991381 6.00277) (xy 179.918475 6.047911) (xy 179.850046 6.099587) (xy 179.786676 6.157356)
			(xy 179.728907 6.220726) (xy 179.677231 6.289155) (xy 179.63209 6.362061) (xy 179.593868 6.438821)
			(xy 179.562892 6.51878) (xy 179.539425 6.601256) (xy 179.523669 6.685546) (xy 179.515757 6.770929)
			(xy 158.039844 6.770929) (xy 158.030561 6.759289) (xy 157.936801 6.654373) (xy 157.837306 6.554879)
			(xy 157.732388 6.46112) (xy 157.622379 6.373391) (xy 157.507624 6.291969) (xy 157.388483 6.21711)
			(xy 157.265333 6.149048) (xy 157.138561 6.087998) (xy 157.008565 6.034153) (xy 156.875754 5.987681)
			(xy 156.740546 5.948729) (xy 156.603367 5.91742) (xy 156.464649 5.893851) (xy 156.324827 5.878098)
			(xy 156.184341 5.870209) (xy 156.113988 5.869686) (xy 17.493996 5.869686) (xy 17.423642 5.870179)
			(xy 17.283156 5.878069) (xy 17.143333 5.893824) (xy 17.004613 5.917393) (xy 16.867433 5.948703) (xy 16.732225 5.987656)
			(xy 16.599413 6.034129) (xy 16.469416 6.087976) (xy 16.342643 6.149026) (xy 16.219492 6.217089) (xy 16.100351 6.29195)
			(xy 15.985596 6.373373) (xy 15.875586 6.461103) (xy 15.770668 6.554863) (xy 15.671172 6.654358) (xy 15.577412 6.759275)
			(xy 15.489682 6.869284) (xy 15.408258 6.98404) (xy 15.333396 7.10318) (xy 15.265333 7.22633) (xy 15.204281 7.353103)
			(xy 15.150434 7.4831) (xy 15.103961 7.615912) (xy 15.065007 7.75112) (xy 15.033696 7.8883) (xy 15.010125 8.027019)
			(xy 14.99437 8.166842) (xy 14.98648 8.307328) (xy 14.986 8.377682) (xy 14.986 24.157686) (xy 14.985478 24.213493)
			(xy 14.977137 24.324795) (xy 14.960501 24.435162) (xy 14.935664 24.543977) (xy 14.902765 24.650632)
			(xy 14.861988 24.754531) (xy 14.81356 24.855091) (xy 14.757753 24.951752) (xy 14.694879 25.043971)
			(xy 14.625289 25.131234) (xy 14.549372 25.213053) (xy 14.467553 25.28897) (xy 14.38029 25.35856)
			(xy 14.28807 25.421434) (xy 14.19141 25.477241) (xy 14.090849 25.525669) (xy 13.986951 25.566446)
			(xy 13.880295 25.599345) (xy 13.77148 25.624182) (xy 13.661113 25.640817) (xy 13.549811 25.649158)
			(xy 13.494004 25.649682) (xy 1.999996 25.649682) (xy 1.944189 25.64916) (xy 1.832887 25.640819) (xy 1.72252 25.624184)
			(xy 1.613704 25.599347) (xy 1.507049 25.566448) (xy 1.40315 25.525671) (xy 1.30259 25.477243) (xy 1.205929 25.421436)
			(xy 1.113709 25.358562) (xy 1.026446 25.288971) (xy 0.944627 25.213055) (xy 0.86871 25.131236) (xy 0.79912 25.043972)
			(xy 0.736245 24.951753) (xy 0.680438 24.855092) (xy 0.63201 24.754532) (xy 0.591233 24.650633) (xy 0.558334 24.543978)
			(xy 0.533497 24.435162) (xy 0.516861 24.324795) (xy 0.50852 24.213493) (xy 0.508 24.157686) (xy 0.508 21.093122)
			(xy 2.904225 21.093122) (xy 2.904225 21.222262) (xy 2.912175 21.351157) (xy 2.928045 21.479317) (xy 2.951774 21.606258)
			(xy 2.983273 21.731497) (xy 3.022422 21.85456) (xy 3.069073 21.974979) (xy 3.123048 22.092298) (xy 3.184143 22.206072)
			(xy 3.252126 22.315869) (xy 3.32674 22.421272) (xy 3.407701 22.521882) (xy 3.494701 22.617317) (xy 3.587412 22.707216)
			(xy 3.685482 22.791237) (xy 3.788537 22.869061) (xy 3.896188 22.940393) (xy 4.008027 23.004963) (xy 4.123628 23.062525)
			(xy 4.242553 23.112862) (xy 4.364352 23.155782) (xy 4.488562 23.191123) (xy 4.614711 23.21875) (xy 4.742323 23.238559)
			(xy 4.870912 23.250475) (xy 4.99999 23.254452) (xy 5.129068 23.250475) (xy 5.257657 23.238559) (xy 5.385269 23.21875)
			(xy 5.511418 23.191123) (xy 5.635628 23.155782) (xy 5.757427 23.112862) (xy 5.876352 23.062525) (xy 5.991953 23.004963)
			(xy 6.103792 22.940393) (xy 6.211443 22.869061) (xy 6.314498 22.791237) (xy 6.412568 22.707216) (xy 6.505279 22.617317)
			(xy 6.592279 22.521882) (xy 6.67324 22.421272) (xy 6.747854 22.315869) (xy 6.815837 22.206072) (xy 6.876932 22.092298)
			(xy 6.930907 21.974979) (xy 6.977558 21.85456) (xy 7.016707 21.731497) (xy 7.048206 21.606258) (xy 7.071935 21.479317)
			(xy 7.087805 21.351157) (xy 7.095755 21.222262) (xy 7.096252 21.157692) (xy 7.095755 21.093122) (xy 7.087805 20.964227)
			(xy 7.071935 20.836067) (xy 7.048206 20.709126) (xy 7.016707 20.583887) (xy 6.977558 20.460824) (xy 6.930907 20.340405)
			(xy 6.876932 20.223086) (xy 6.815837 20.109312) (xy 6.747854 19.999515) (xy 6.67324 19.894112) (xy 6.592279 19.793502)
			(xy 6.505279 19.698067) (xy 6.412568 19.608168) (xy 6.314498 19.524147) (xy 6.211443 19.446323) (xy 6.103792 19.374991)
			(xy 5.991953 19.310421) (xy 5.876352 19.252859) (xy 5.757427 19.202522) (xy 5.635628 19.159602) (xy 5.511418 19.124261)
			(xy 5.385269 19.096634) (xy 5.257657 19.076825) (xy 5.129068 19.064909) (xy 4.99999 19.060933) (xy 4.870912 19.064909)
			(xy 4.742323 19.076825) (xy 4.614711 19.096634) (xy 4.488562 19.124261) (xy 4.364352 19.159602) (xy 4.242553 19.202522)
			(xy 4.123628 19.252859) (xy 4.008027 19.310421) (xy 3.896188 19.374991) (xy 3.788537 19.446323) (xy 3.685482 19.524147)
			(xy 3.587412 19.608168) (xy 3.494701 19.698067) (xy 3.407701 19.793502) (xy 3.32674 19.894112) (xy 3.252126 19.999515)
			(xy 3.184143 20.109312) (xy 3.123048 20.223086) (xy 3.069073 20.340405) (xy 3.022422 20.460824) (xy 2.983273 20.583887)
			(xy 2.951774 20.709126) (xy 2.928045 20.836067) (xy 2.912175 20.964227) (xy 2.904225 21.093122) (xy 0.508 21.093122)
			(xy 0.508 3.999992) (xy 0.508522 3.944185) (xy 0.516863 3.832883) (xy 0.533498 3.722516) (xy 0.558335 3.6137)
			(xy 0.591234 3.507045) (xy 0.632011 3.403146) (xy 0.680438 3.302586) (xy 0.736246 3.205925) (xy 0.79912 3.113705)
			(xy 0.86871 3.026442) (xy 0.944627 2.944623) (xy 1.026446 2.868706) (xy 1.113709 2.799116) (xy 1.205929 2.736242)
			(xy 1.30259 2.680434) (xy 1.40315 2.632007) (xy 1.507049 2.59123) (xy 1.613704 2.558331) (xy 1.72252 2.533494)
			(xy 1.832887 2.516859) (xy 1.944189 2.508518) (xy 1.999996 2.507996) (xy 7.964932 2.507996) (xy 8.035286 2.507503)
			(xy 8.175772 2.499613) (xy 8.315594 2.483859) (xy 8.454314 2.460289) (xy 8.591493 2.428979) (xy 8.726701 2.390026)
			(xy 8.859513 2.343553) (xy 8.989509 2.289707) (xy 9.116282 2.228656) (xy 9.239433 2.160593) (xy 9.358573 2.085732)
			(xy 9.473329 2.004309) (xy 9.583338 1.916579) (xy 9.688255 1.822819) (xy 9.78775 1.723324) (xy 9.88151 1.618406)
			(xy 9.96924 1.508397) (xy 10.050663 1.393641) (xy 10.125524 1.274501) (xy 10.193587 1.151351) (xy 10.254637 1.024578)
			(xy 10.308484 0.894581) (xy 10.354957 0.76177) (xy 10.393909 0.626561) (xy 10.42522 0.489382) (xy 10.448789 0.350662)
			(xy 10.464543 0.21084) (xy 10.472433 0.070354) (xy 10.472928 0) (xy 10.472928 -8.850122) (xy 10.47345 -8.905929)
			(xy 10.481791 -9.017231) (xy 10.498426 -9.127599) (xy 10.523263 -9.236414) (xy 10.556162 -9.34307)
			(xy 10.596939 -9.446968) (xy 10.645366 -9.547529) (xy 10.701173 -9.64419) (xy 10.764048 -9.73641)
			(xy 10.833638 -9.823673) (xy 10.909555 -9.905492) (xy 10.991374 -9.981409) (xy 11.078637 -10.051)
			(xy 11.170857 -10.113875) (xy 11.267517 -10.169682) (xy 11.368078 -10.21811) (xy 11.471977 -10.258887)
			(xy 11.578632 -10.291786) (xy 11.687448 -10.316623) (xy 11.797815 -10.333259) (xy 11.909117 -10.3416)
			(xy 11.964924 -10.342118)
		)
		(stroke
			(width 0)
			(type solid)
		)
		(fill yes)
		(layer "In4.Cu")
		(net "COUPON_GND2")
	)
	(gr_poly
		(pts
			(xy 200.481692 -418.081968) (xy 200.538276 -418.081432) (xy 200.651116 -418.072836) (xy 200.76298 -418.055715)
			(xy 200.873227 -418.030169) (xy 200.98122 -417.996343) (xy 201.086341 -417.954433) (xy 201.187984 -417.904678)
			(xy 201.285565 -417.847366) (xy 201.378524 -417.782825) (xy 201.466326 -417.711427) (xy 201.548466 -417.633582)
			(xy 201.586846 -417.592002) (xy 201.634058 -417.54062) (xy 201.733379 -417.442584) (xy 201.837997 -417.350223)
			(xy 201.947589 -417.26382) (xy 202.061814 -417.183644) (xy 202.18032 -417.109943) (xy 202.302741 -417.042944)
			(xy 202.428697 -416.982855) (xy 202.557798 -416.929861) (xy 202.689647 -416.884127) (xy 202.823834 -416.845794)
			(xy 202.959945 -416.81498) (xy 203.097558 -416.791782) (xy 203.236248 -416.77627) (xy 203.375587 -416.768492)
			(xy 203.445364 -416.768026) (xy 271.794732 -416.768026) (xy 271.864502 -416.768512) (xy 272.003824 -416.776289)
			(xy 272.142499 -416.791801) (xy 272.280097 -416.814999) (xy 272.416192 -416.845812) (xy 272.550363 -416.884144)
			(xy 272.682195 -416.929877) (xy 272.811281 -416.982869) (xy 272.937221 -417.042957) (xy 273.059624 -417.109954)
			(xy 273.178113 -417.183654) (xy 273.292321 -417.263827) (xy 273.401895 -417.350227) (xy 273.434939 -417.379404)
			(xy 313.073796 -417.379404) (xy 313.073796 -394.27912) (xy 326.479662 -394.27912) (xy 326.525636 -394.325094)
			(xy 326.525636 -397.823826) (xy 330.929171 -397.823826) (xy 330.929175 -397.756517) (xy 330.937223 -397.689692)
			(xy 330.953201 -397.624307) (xy 330.976879 -397.561301) (xy 331.007918 -397.501576) (xy 331.045873 -397.44599)
			(xy 331.067664 -397.420338) (xy 331.073477 -397.413205) (xy 331.07998 -397.396005) (xy 331.080364 -397.38681)
			(xy 331.080364 -396.893542) (xy 331.079919 -396.884359) (xy 331.073428 -396.867175) (xy 331.067664 -396.860014)
			(xy 331.045866 -396.83437) (xy 331.007916 -396.778783) (xy 330.976881 -396.719059) (xy 330.953208 -396.656053)
			(xy 330.937235 -396.59067) (xy 330.929191 -396.523846) (xy 330.929192 -396.456539) (xy 330.937238 -396.389716)
			(xy 330.953213 -396.324333) (xy 330.976888 -396.261328) (xy 331.007923 -396.201604) (xy 331.045875 -396.146018)
			(xy 331.067664 -396.120366) (xy 331.073465 -396.113225) (xy 331.079975 -396.096031) (xy 331.080364 -396.086838)
			(xy 331.080364 -395.92885) (xy 331.080805 -395.918678) (xy 331.088579 -395.89988) (xy 331.10296 -395.885492)
			(xy 331.121755 -395.87771) (xy 331.131926 -395.877288) (xy 331.848206 -395.877288) (xy 331.858384 -395.87766)
			(xy 331.877189 -395.885456) (xy 331.891575 -395.899859) (xy 331.899351 -395.918671) (xy 331.899768 -395.92885)
			(xy 331.899768 -396.086838) (xy 331.900167 -396.096026) (xy 331.906689 -396.11321) (xy 331.912468 -396.120366)
			(xy 331.934246 -396.146026) (xy 331.972195 -396.201612) (xy 332.003228 -396.261334) (xy 332.026901 -396.324338)
			(xy 332.042874 -396.389719) (xy 332.050919 -396.45654) (xy 332.05092 -396.523845) (xy 332.042877 -396.590666)
			(xy 332.026905 -396.656048) (xy 332.003234 -396.719052) (xy 331.972202 -396.778775) (xy 331.934255 -396.834362)
			(xy 331.912468 -396.860014) (xy 331.906679 -396.867164) (xy 331.90016 -396.884351) (xy 331.899768 -396.893542)
			(xy 331.899768 -397.38681) (xy 331.90018 -397.395997) (xy 331.906693 -397.413181) (xy 331.912468 -397.420338)
			(xy 331.934218 -397.446021) (xy 331.972167 -397.501603) (xy 332.00059 -397.556296) (xy 333.128836 -397.556296)
			(xy 333.136911 -397.489358) (xy 333.152946 -397.423869) (xy 333.17671 -397.360773) (xy 333.20786 -397.300977)
			(xy 333.245948 -397.245343) (xy 333.267812 -397.219678) (xy 333.273602 -397.212528) (xy 333.28012 -397.195341)
			(xy 333.280512 -397.18615) (xy 333.280512 -397.028924) (xy 333.280936 -397.018802) (xy 333.288678 -397.000096)
			(xy 333.302993 -396.985781) (xy 333.321698 -396.978037) (xy 333.33182 -396.977616) (xy 334.0481 -396.977616)
			(xy 334.058224 -396.978016) (xy 334.076931 -396.985768) (xy 334.091246 -397.000089) (xy 334.098988 -397.018799)
			(xy 334.099408 -397.028924) (xy 334.099408 -397.18615) (xy 334.09984 -397.195335) (xy 334.106338 -397.21252)
			(xy 334.112108 -397.219678) (xy 334.133982 -397.245335) (xy 334.172069 -397.300971) (xy 334.203219 -397.360769)
			(xy 334.226982 -397.423866) (xy 334.243017 -397.489356) (xy 334.251092 -397.556295) (xy 334.251091 -397.62372)
			(xy 334.243014 -397.690658) (xy 334.226978 -397.756148) (xy 334.203213 -397.819245) (xy 334.200796 -397.823884)
			(xy 335.328964 -397.823884) (xy 335.328968 -397.756459) (xy 335.337047 -397.689518) (xy 335.353085 -397.624028)
			(xy 335.376852 -397.560929) (xy 335.408005 -397.501132) (xy 335.446095 -397.445496) (xy 335.46796 -397.41983)
			(xy 335.473776 -397.412699) (xy 335.480277 -397.395497) (xy 335.48066 -397.386302) (xy 335.48066 -396.89405)
			(xy 335.480213 -396.884867) (xy 335.473723 -396.867683) (xy 335.46796 -396.860522) (xy 335.446088 -396.834864)
			(xy 335.408002 -396.779228) (xy 335.376854 -396.71943) (xy 335.353092 -396.656332) (xy 335.337058 -396.590843)
			(xy 335.328984 -396.523904) (xy 335.328985 -396.456481) (xy 335.337061 -396.389542) (xy 335.353096 -396.324053)
			(xy 335.37686 -396.260956) (xy 335.40801 -396.201159) (xy 335.446097 -396.145524) (xy 335.46796 -396.119858)
			(xy 335.473764 -396.112719) (xy 335.480273 -396.095523) (xy 335.48066 -396.08633) (xy 335.48066 -395.92885)
			(xy 335.481168 -395.918724) (xy 335.488883 -395.9) (xy 335.503164 -395.885642) (xy 335.521845 -395.877824)
			(xy 335.531968 -395.877288) (xy 336.248248 -395.877288) (xy 336.258404 -395.877682) (xy 336.277155 -395.885491)
			(xy 336.291476 -395.899896) (xy 336.299176 -395.918692) (xy 336.299556 -395.92885) (xy 336.299556 -396.08633)
			(xy 336.299962 -396.095517) (xy 336.30648 -396.112701) (xy 336.312256 -396.119858) (xy 336.334112 -396.145531)
			(xy 336.372204 -396.201163) (xy 336.403357 -396.260958) (xy 336.427124 -396.324054) (xy 336.443161 -396.389542)
			(xy 336.451239 -396.456481) (xy 336.45124 -396.523904) (xy 336.443164 -396.590843) (xy 336.427128 -396.656332)
			(xy 336.403363 -396.719428) (xy 336.372211 -396.779224) (xy 336.334121 -396.834858) (xy 336.312256 -396.860522)
			(xy 336.306462 -396.867669) (xy 336.299947 -396.884858) (xy 336.299556 -396.89405) (xy 336.299556 -397.386302)
			(xy 336.299975 -397.395488) (xy 336.306484 -397.412672) (xy 336.312256 -397.41983) (xy 336.334084 -397.445525)
			(xy 336.372177 -397.501154) (xy 336.40094 -397.556356) (xy 337.529156 -397.556356) (xy 337.537198 -397.489535)
			(xy 337.553169 -397.424153) (xy 337.576839 -397.361149) (xy 337.607869 -397.301426) (xy 337.645814 -397.245839)
			(xy 337.6676 -397.220186) (xy 337.673385 -397.213033) (xy 337.679907 -397.195848) (xy 337.6803 -397.186658)
			(xy 337.6803 -397.028924) (xy 337.680741 -397.018771) (xy 337.688529 -397.000019) (xy 337.70292 -396.985695)
			(xy 337.721708 -396.977995) (xy 337.731862 -396.977616) (xy 338.448142 -396.977616) (xy 338.458268 -396.978091)
			(xy 338.476986 -396.985829) (xy 338.49134 -397.000118) (xy 338.499162 -397.0188) (xy 338.499704 -397.028924)
			(xy 338.499704 -397.186658) (xy 338.500133 -397.195843) (xy 338.506634 -397.213028) (xy 338.512404 -397.220186)
			(xy 338.5342 -397.245831) (xy 338.572146 -397.301419) (xy 338.603176 -397.361144) (xy 338.626847 -397.42415)
			(xy 338.642818 -397.489532) (xy 338.65086 -397.556355) (xy 338.650859 -397.62366) (xy 338.642815 -397.690483)
			(xy 338.626842 -397.755865) (xy 338.60317 -397.81887) (xy 338.600595 -397.823826) (xy 339.729259 -397.823826)
			(xy 339.729263 -397.756517) (xy 339.737311 -397.689692) (xy 339.753288 -397.624308) (xy 339.776965 -397.561301)
			(xy 339.808004 -397.501577) (xy 339.845958 -397.44599) (xy 339.867748 -397.420338) (xy 339.873559 -397.413204)
			(xy 339.880064 -397.396005) (xy 339.880448 -397.38681) (xy 339.880448 -396.893542) (xy 339.880007 -396.884358)
			(xy 339.873513 -396.867174) (xy 339.867748 -396.860014) (xy 339.84595 -396.83437) (xy 339.808001 -396.778783)
			(xy 339.776968 -396.719058) (xy 339.753295 -396.656052) (xy 339.737322 -396.590669) (xy 339.729279 -396.523845)
			(xy 339.72928 -396.456539) (xy 339.737325 -396.389716) (xy 339.753299 -396.324333) (xy 339.776974 -396.261328)
			(xy 339.808009 -396.201604) (xy 339.845959 -396.146018) (xy 339.867748 -396.120366) (xy 339.873547 -396.113223)
			(xy 339.880059 -396.096031) (xy 339.880448 -396.086838) (xy 339.880448 -395.92885) (xy 339.880905 -395.91868)
			(xy 339.888675 -395.899885) (xy 339.903051 -395.885498) (xy 339.921841 -395.877713) (xy 339.93201 -395.877288)
			(xy 340.64829 -395.877288) (xy 340.658467 -395.877673) (xy 340.677271 -395.885464) (xy 340.691658 -395.899862)
			(xy 340.699435 -395.918672) (xy 340.699852 -395.92885) (xy 340.699852 -396.086838) (xy 340.700255 -396.096026)
			(xy 340.706775 -396.113209) (xy 340.712552 -396.120366) (xy 340.73433 -396.146026) (xy 340.77228 -396.201611)
			(xy 340.803314 -396.261334) (xy 340.826988 -396.324337) (xy 340.842962 -396.389718) (xy 340.851007 -396.45654)
			(xy 340.851007 -396.523845) (xy 340.842964 -396.590667) (xy 340.826992 -396.656048) (xy 340.80332 -396.719053)
			(xy 340.772287 -396.778776) (xy 340.734339 -396.834362) (xy 340.712552 -396.860014) (xy 340.706761 -396.867163)
			(xy 340.700244 -396.884351) (xy 340.699852 -396.893542) (xy 340.699852 -397.38681) (xy 340.700268 -397.395996)
			(xy 340.706779 -397.41318) (xy 340.712552 -397.420338) (xy 340.734302 -397.446021) (xy 340.772253 -397.501603)
			(xy 340.800676 -397.556296) (xy 341.928924 -397.556296) (xy 341.936999 -397.489359) (xy 341.953033 -397.42387)
			(xy 341.976796 -397.360774) (xy 342.007946 -397.300978) (xy 342.046033 -397.245343) (xy 342.067896 -397.219678)
			(xy 342.073684 -397.212527) (xy 342.080204 -397.195341) (xy 342.080596 -397.18615) (xy 342.080596 -397.028924)
			(xy 342.081035 -397.018804) (xy 342.088775 -397.000101) (xy 342.103084 -396.985786) (xy 342.121784 -396.978039)
			(xy 342.131904 -396.977616) (xy 342.848184 -396.977616) (xy 342.858307 -396.978029) (xy 342.877014 -396.985775)
			(xy 342.891329 -397.000093) (xy 342.899072 -397.0188) (xy 342.899492 -397.028924) (xy 342.899492 -397.18615)
			(xy 342.899928 -397.195334) (xy 342.906424 -397.212519) (xy 342.912192 -397.219678) (xy 342.934066 -397.245335)
			(xy 342.972155 -397.300971) (xy 343.003306 -397.360768) (xy 343.02707 -397.423866) (xy 343.043105 -397.489356)
			(xy 343.05118 -397.556295) (xy 343.051179 -397.62372) (xy 343.043102 -397.690659) (xy 343.027065 -397.756149)
			(xy 343.0033 -397.819246) (xy 343.000914 -397.823825) (xy 344.12905 -397.823825) (xy 344.129054 -397.756517)
			(xy 344.137101 -397.689692) (xy 344.153078 -397.624308) (xy 344.176755 -397.561302) (xy 344.207793 -397.501577)
			(xy 344.245746 -397.44599) (xy 344.267536 -397.420338) (xy 344.273346 -397.413202) (xy 344.279852 -397.396004)
			(xy 344.280236 -397.38681) (xy 344.280236 -396.893542) (xy 344.279797 -396.884358) (xy 344.273303 -396.867174)
			(xy 344.267536 -396.860014) (xy 344.245738 -396.83437) (xy 344.20779 -396.778782) (xy 344.176757 -396.719058)
			(xy 344.153085 -396.656052) (xy 344.137113 -396.590669) (xy 344.12907 -396.523845) (xy 344.129071 -396.45654)
			(xy 344.137116 -396.389716) (xy 344.15309 -396.324334) (xy 344.176764 -396.261329) (xy 344.207798 -396.201605)
			(xy 344.245748 -396.146018) (xy 344.267536 -396.120366) (xy 344.273334 -396.113222) (xy 344.279847 -396.09603)
			(xy 344.280236 -396.086838) (xy 344.280236 -395.92885) (xy 344.280705 -395.918682) (xy 344.288473 -395.899889)
			(xy 344.302845 -395.885502) (xy 344.32163 -395.877715) (xy 344.331798 -395.877288) (xy 345.048078 -395.877288)
			(xy 345.058254 -395.877683) (xy 345.077058 -395.88547) (xy 345.091445 -395.899866) (xy 345.099222 -395.918673)
			(xy 345.09964 -395.92885) (xy 345.09964 -396.086838) (xy 345.100045 -396.096025) (xy 345.106564 -396.113209)
			(xy 345.11234 -396.120366) (xy 345.134118 -396.146026) (xy 345.172069 -396.201611) (xy 345.203104 -396.261333)
			(xy 345.226778 -396.324337) (xy 345.242752 -396.389718) (xy 345.250798 -396.45654) (xy 345.250798 -396.523845)
			(xy 345.242755 -396.590667) (xy 345.226782 -396.656049) (xy 345.20311 -396.719053) (xy 345.172077 -396.778776)
			(xy 345.134128 -396.834362) (xy 345.11234 -396.860014) (xy 345.106548 -396.867162) (xy 345.100032 -396.884351)
			(xy 345.09964 -396.893542) (xy 345.09964 -397.38681) (xy 345.100059 -397.395996) (xy 345.106568 -397.41318)
			(xy 345.11234 -397.420338) (xy 345.134091 -397.446021) (xy 345.172042 -397.501602) (xy 345.200497 -397.556355)
			(xy 346.32922 -397.556355) (xy 346.337264 -397.489532) (xy 346.353237 -397.42415) (xy 346.37691 -397.361146)
			(xy 346.407945 -397.301423) (xy 346.445896 -397.245838) (xy 346.467684 -397.220186) (xy 346.473467 -397.213031)
			(xy 346.47999 -397.195848) (xy 346.480384 -397.186658) (xy 346.480384 -397.028924) (xy 346.480841 -397.018773)
			(xy 346.488625 -397.000025) (xy 346.503011 -396.985701) (xy 346.521794 -396.977997) (xy 346.531946 -396.977616)
			(xy 347.248226 -396.977616) (xy 347.258351 -396.978104) (xy 347.277069 -396.985836) (xy 347.291423 -397.000121)
			(xy 347.299246 -397.018801) (xy 347.299788 -397.028924) (xy 347.299788 -397.186658) (xy 347.300221 -397.195843)
			(xy 347.306719 -397.213027) (xy 347.312488 -397.220186) (xy 347.334285 -397.24583) (xy 347.372232 -397.301419)
			(xy 347.403263 -397.361143) (xy 347.426934 -397.424149) (xy 347.442905 -397.489532) (xy 347.450948 -397.556355)
			(xy 347.450947 -397.62366) (xy 347.442903 -397.690483) (xy 347.426929 -397.755865) (xy 347.403257 -397.81887)
			(xy 347.400682 -397.823826) (xy 374.92908 -397.823826) (xy 374.929084 -397.756517) (xy 374.937132 -397.689691)
			(xy 374.95311 -397.624306) (xy 374.976789 -397.5613) (xy 375.007829 -397.501576) (xy 375.045785 -397.445989)
			(xy 375.067576 -397.420338) (xy 375.073379 -397.413197) (xy 375.07989 -397.396003) (xy 375.080276 -397.38681)
			(xy 375.080276 -396.893542) (xy 375.079851 -396.884356) (xy 375.073348 -396.867171) (xy 375.067576 -396.860014)
			(xy 375.045777 -396.83437) (xy 375.007826 -396.778784) (xy 374.976792 -396.719059) (xy 374.953118 -396.656053)
			(xy 374.937144 -396.59067) (xy 374.9291 -396.523846) (xy 374.929101 -396.456539) (xy 374.937147 -396.389715)
			(xy 374.953122 -396.324332) (xy 374.976798 -396.261327) (xy 375.007834 -396.201604) (xy 375.045787 -396.146018)
			(xy 375.067576 -396.120366) (xy 375.073367 -396.113216) (xy 375.079886 -396.096029) (xy 375.080276 -396.086838)
			(xy 375.080276 -395.92885) (xy 375.080706 -395.918677) (xy 375.088481 -395.899876) (xy 375.102866 -395.885488)
			(xy 375.121665 -395.877708) (xy 375.131838 -395.877288) (xy 375.848118 -395.877288) (xy 375.858297 -395.87765)
			(xy 375.877102 -395.885451) (xy 375.891487 -395.899856) (xy 375.899263 -395.91867) (xy 375.89968 -395.92885)
			(xy 375.89968 -396.086838) (xy 375.900076 -396.096027) (xy 375.9066 -396.113211) (xy 375.91238 -396.120366)
			(xy 375.934157 -396.146026) (xy 375.972105 -396.201612) (xy 376.003138 -396.261335) (xy 376.02681 -396.324338)
			(xy 376.042784 -396.389719) (xy 376.050828 -396.456541) (xy 376.050829 -396.523844) (xy 376.042786 -396.590666)
			(xy 376.026815 -396.656047) (xy 376.003144 -396.719051) (xy 375.972113 -396.778775) (xy 375.934167 -396.834362)
			(xy 375.91238 -396.860014) (xy 375.906593 -396.867166) (xy 375.900073 -396.884351) (xy 375.89968 -396.893542)
			(xy 375.89968 -397.38681) (xy 375.90009 -397.395997) (xy 375.906604 -397.413181) (xy 375.91238 -397.420338)
			(xy 375.93413 -397.446021) (xy 375.972078 -397.501604) (xy 376.0005 -397.556296) (xy 377.128745 -397.556296)
			(xy 377.136821 -397.489358) (xy 377.152856 -397.423869) (xy 377.17662 -397.360772) (xy 377.207771 -397.300977)
			(xy 377.24586 -397.245343) (xy 377.267724 -397.219678) (xy 377.273515 -397.212529) (xy 377.280032 -397.195341)
			(xy 377.280424 -397.18615) (xy 377.280424 -397.028924) (xy 377.280836 -397.0188) (xy 377.288581 -397.000092)
			(xy 377.302899 -396.985776) (xy 377.321608 -396.978034) (xy 377.331732 -396.977616) (xy 378.048012 -396.977616)
			(xy 378.058137 -396.978006) (xy 378.076844 -396.985761) (xy 378.091159 -397.000086) (xy 378.098901 -397.018798)
			(xy 378.09932 -397.028924) (xy 378.09932 -397.18615) (xy 378.09975 -397.195335) (xy 378.10625 -397.21252)
			(xy 378.11202 -397.219678) (xy 378.133893 -397.245335) (xy 378.17198 -397.300972) (xy 378.203129 -397.360769)
			(xy 378.226892 -397.423867) (xy 378.242926 -397.489357) (xy 378.251001 -397.556295) (xy 378.251 -397.62372)
			(xy 378.242924 -397.690658) (xy 378.226888 -397.756147) (xy 378.203123 -397.819245) (xy 378.200706 -397.823885)
			(xy 379.328873 -397.823885) (xy 379.328877 -397.756458) (xy 379.336956 -397.689518) (xy 379.352995 -397.624027)
			(xy 379.376762 -397.560929) (xy 379.407915 -397.501131) (xy 379.446007 -397.445496) (xy 379.467872 -397.41983)
			(xy 379.47369 -397.4127) (xy 379.48019 -397.395498) (xy 379.480572 -397.386302) (xy 379.480572 -396.89405)
			(xy 379.480144 -396.884865) (xy 379.473643 -396.86768) (xy 379.467872 -396.860522) (xy 379.445999 -396.834864)
			(xy 379.407913 -396.779228) (xy 379.376764 -396.719431) (xy 379.353002 -396.656333) (xy 379.336968 -396.590843)
			(xy 379.328893 -396.523904) (xy 379.328894 -396.456481) (xy 379.33697 -396.389542) (xy 379.353006 -396.324053)
			(xy 379.37677 -396.260956) (xy 379.40792 -396.201159) (xy 379.446008 -396.145524) (xy 379.467872 -396.119858)
			(xy 379.473678 -396.11272) (xy 379.480185 -396.095524) (xy 379.480572 -396.08633) (xy 379.480572 -395.92885)
			(xy 379.481069 -395.918723) (xy 379.488786 -395.899996) (xy 379.50307 -395.885637) (xy 379.521755 -395.877822)
			(xy 379.53188 -395.877288) (xy 380.24816 -395.877288) (xy 380.258278 -395.877749) (xy 380.276979 -395.885481)
			(xy 380.291294 -395.899784) (xy 380.299043 -395.918478) (xy 380.299468 -395.928596) (xy 380.299468 -396.08633)
			(xy 380.299871 -396.095518) (xy 380.30639 -396.112702) (xy 380.312168 -396.119858) (xy 380.334023 -396.145531)
			(xy 380.372114 -396.201163) (xy 380.403267 -396.260958) (xy 380.427033 -396.324054) (xy 380.443071 -396.389543)
			(xy 380.451148 -396.456481) (xy 380.451149 -396.523904) (xy 380.443073 -396.590842) (xy 380.427038 -396.656331)
			(xy 380.403273 -396.719428) (xy 380.372122 -396.779224) (xy 380.334032 -396.834857) (xy 380.312168 -396.860522)
			(xy 380.306375 -396.86767) (xy 380.299859 -396.884858) (xy 380.299468 -396.89405) (xy 380.299468 -397.386302)
			(xy 380.299884 -397.395488) (xy 380.306394 -397.412672) (xy 380.312168 -397.41983) (xy 380.333996 -397.445525)
			(xy 380.372088 -397.501155) (xy 380.40085 -397.556356) (xy 381.529065 -397.556356) (xy 381.537108 -397.489534)
			(xy 381.553079 -397.424153) (xy 381.576749 -397.361149) (xy 381.60778 -397.301425) (xy 381.645726 -397.245838)
			(xy 381.667512 -397.220186) (xy 381.673298 -397.213034) (xy 381.679819 -397.195849) (xy 381.680212 -397.186658)
			(xy 381.680212 -397.028924) (xy 381.680636 -397.018802) (xy 381.688378 -397.000096) (xy 381.702693 -396.985781)
			(xy 381.721398 -396.978037) (xy 381.73152 -396.977616) (xy 382.448054 -396.977616) (xy 382.458175 -396.978164)
			(xy 382.47689 -396.985872) (xy 382.491247 -397.000139) (xy 382.499072 -397.018806) (xy 382.499616 -397.028924)
			(xy 382.499616 -397.186658) (xy 382.500043 -397.195844) (xy 382.506544 -397.213028) (xy 382.512316 -397.220186)
			(xy 382.534115 -397.245829) (xy 382.572066 -397.301416) (xy 382.603102 -397.36114) (xy 382.626776 -397.424146)
			(xy 382.642749 -397.48953) (xy 382.650793 -397.556354) (xy 382.650793 -397.623661) (xy 382.642747 -397.690485)
			(xy 382.626771 -397.755868) (xy 382.603096 -397.818873) (xy 382.600522 -397.823826) (xy 383.729168 -397.823826)
			(xy 383.729172 -397.756517) (xy 383.73722 -397.689692) (xy 383.753198 -397.624307) (xy 383.776876 -397.561301)
			(xy 383.807914 -397.501576) (xy 383.845869 -397.44599) (xy 383.86766 -397.420338) (xy 383.873473 -397.413205)
			(xy 383.879976 -397.396005) (xy 383.88036 -397.38681) (xy 383.88036 -396.893542) (xy 383.879916 -396.884359)
			(xy 383.873425 -396.867175) (xy 383.86766 -396.860014) (xy 383.845862 -396.83437) (xy 383.807912 -396.778783)
			(xy 383.776878 -396.719058) (xy 383.753205 -396.656053) (xy 383.737232 -396.590669) (xy 383.729188 -396.523846)
			(xy 383.729189 -396.456539) (xy 383.737235 -396.389716) (xy 383.753209 -396.324333) (xy 383.776884 -396.261328)
			(xy 383.80792 -396.201604) (xy 383.845871 -396.146018) (xy 383.86766 -396.120366) (xy 383.873461 -396.113224)
			(xy 383.879971 -396.096031) (xy 383.88036 -396.086838) (xy 383.88036 -395.92885) (xy 383.880805 -395.918679)
			(xy 383.888578 -395.899881) (xy 383.902958 -395.885494) (xy 383.921751 -395.877711) (xy 383.931922 -395.877288)
			(xy 384.648202 -395.877288) (xy 384.65838 -395.877663) (xy 384.677184 -395.885458) (xy 384.691571 -395.899859)
			(xy 384.699347 -395.918672) (xy 384.699764 -395.92885) (xy 384.699764 -396.086838) (xy 384.700164 -396.096026)
			(xy 384.706686 -396.11321) (xy 384.712464 -396.120366) (xy 384.734242 -396.146026) (xy 384.772191 -396.201612)
			(xy 384.803224 -396.261334) (xy 384.826898 -396.324337) (xy 384.842871 -396.389719) (xy 384.850916 -396.45654)
			(xy 384.850917 -396.523845) (xy 384.842874 -396.590666) (xy 384.826902 -396.656048) (xy 384.803231 -396.719052)
			(xy 384.772199 -396.778776) (xy 384.734251 -396.834362) (xy 384.712464 -396.860014) (xy 384.706674 -396.867164)
			(xy 384.700156 -396.884351) (xy 384.699764 -396.893542) (xy 384.699764 -397.38681) (xy 384.700177 -397.395997)
			(xy 384.70669 -397.413181) (xy 384.712464 -397.420338) (xy 384.734214 -397.446021) (xy 384.772164 -397.501603)
			(xy 384.800587 -397.556296) (xy 385.928833 -397.556296) (xy 385.936908 -397.489358) (xy 385.952943 -397.42387)
			(xy 385.976706 -397.360773) (xy 386.007856 -397.300977) (xy 386.045944 -397.245343) (xy 386.067808 -397.219678)
			(xy 386.073597 -397.212528) (xy 386.080116 -397.195341) (xy 386.080508 -397.18615) (xy 386.080508 -397.028924)
			(xy 386.080936 -397.018802) (xy 386.088677 -397.000097) (xy 386.102991 -396.985782) (xy 386.121694 -396.978037)
			(xy 386.131816 -396.977616) (xy 386.848096 -396.977616) (xy 386.85822 -396.97802) (xy 386.876927 -396.985769)
			(xy 386.891242 -397.00009) (xy 386.898984 -397.0188) (xy 386.899404 -397.028924) (xy 386.899404 -397.18615)
			(xy 386.899837 -397.195335) (xy 386.906335 -397.212519) (xy 386.912104 -397.219678) (xy 386.933978 -397.245335)
			(xy 386.972066 -397.300971) (xy 387.003216 -397.360768) (xy 387.026979 -397.423866) (xy 387.043014 -397.489356)
			(xy 387.051089 -397.556295) (xy 387.051088 -397.62372) (xy 387.043011 -397.690659) (xy 387.026975 -397.756148)
			(xy 387.00321 -397.819245) (xy 387.000823 -397.823826) (xy 388.128959 -397.823826) (xy 388.128963 -397.756517)
			(xy 388.137011 -397.689692) (xy 388.152988 -397.624308) (xy 388.176665 -397.561301) (xy 388.207704 -397.501577)
			(xy 388.245658 -397.44599) (xy 388.267448 -397.420338) (xy 388.273259 -397.413204) (xy 388.279764 -397.396005)
			(xy 388.280148 -397.38681) (xy 388.280148 -396.893542) (xy 388.279707 -396.884358) (xy 388.273213 -396.867174)
			(xy 388.267448 -396.860014) (xy 388.24565 -396.83437) (xy 388.207701 -396.778783) (xy 388.176668 -396.719058)
			(xy 388.152995 -396.656052) (xy 388.137022 -396.590669) (xy 388.128979 -396.523845) (xy 388.12898 -396.456539)
			(xy 388.137025 -396.389716) (xy 388.152999 -396.324333) (xy 388.176674 -396.261328) (xy 388.207709 -396.201604)
			(xy 388.245659 -396.146018) (xy 388.267448 -396.120366) (xy 388.273247 -396.113223) (xy 388.279759 -396.096031)
			(xy 388.280148 -396.086838) (xy 388.280148 -395.92885) (xy 388.280605 -395.91868) (xy 388.288375 -395.899885)
			(xy 388.302751 -395.885498) (xy 388.321541 -395.877713) (xy 388.33171 -395.877288) (xy 389.04799 -395.877288)
			(xy 389.058167 -395.877673) (xy 389.076971 -395.885464) (xy 389.091358 -395.899862) (xy 389.099135 -395.918672)
			(xy 389.099552 -395.92885) (xy 389.099552 -396.086838) (xy 389.099955 -396.096026) (xy 389.106475 -396.113209)
			(xy 389.112252 -396.120366) (xy 389.13403 -396.146026) (xy 389.17198 -396.201611) (xy 389.203014 -396.261334)
			(xy 389.226688 -396.324337) (xy 389.242662 -396.389718) (xy 389.250707 -396.45654) (xy 389.250707 -396.523845)
			(xy 389.242664 -396.590667) (xy 389.226692 -396.656048) (xy 389.20302 -396.719053) (xy 389.171987 -396.778776)
			(xy 389.134039 -396.834362) (xy 389.112252 -396.860014) (xy 389.106461 -396.867163) (xy 389.099944 -396.884351)
			(xy 389.099552 -396.893542) (xy 389.099552 -397.38681) (xy 389.099968 -397.395996) (xy 389.106479 -397.41318)
			(xy 389.112252 -397.420338) (xy 389.134002 -397.446021) (xy 389.171953 -397.501603) (xy 389.200407 -397.556356)
			(xy 390.329153 -397.556356) (xy 390.337195 -397.489535) (xy 390.353166 -397.424153) (xy 390.376836 -397.36115)
			(xy 390.407865 -397.301426) (xy 390.44581 -397.245839) (xy 390.467596 -397.220186) (xy 390.473381 -397.213032)
			(xy 390.479903 -397.195848) (xy 390.480296 -397.186658) (xy 390.480296 -397.028924) (xy 390.480735 -397.018804)
			(xy 390.488475 -397.000101) (xy 390.502784 -396.985786) (xy 390.521484 -396.978039) (xy 390.531604 -396.977616)
			(xy 391.248138 -396.977616) (xy 391.258264 -396.978095) (xy 391.276982 -396.985831) (xy 391.291336 -397.000119)
			(xy 391.299158 -397.0188) (xy 391.2997 -397.028924) (xy 391.2997 -397.186658) (xy 391.30013 -397.195843)
			(xy 391.30663 -397.213028) (xy 391.3124 -397.220186) (xy 391.334196 -397.245831) (xy 391.372142 -397.301419)
			(xy 391.403173 -397.361144) (xy 391.426844 -397.424149) (xy 391.442815 -397.489532) (xy 391.450857 -397.556355)
			(xy 391.450856 -397.62366) (xy 391.442812 -397.690483) (xy 391.426839 -397.755865) (xy 391.403167 -397.81887)
			(xy 391.372135 -397.878594) (xy 391.334187 -397.934181) (xy 391.3124 -397.959834) (xy 391.306606 -397.966981)
			(xy 391.30009 -397.98417) (xy 391.2997 -397.993362) (xy 391.2997 -398.486884) (xy 391.300118 -398.49607)
			(xy 391.306626 -398.513255) (xy 391.3124 -398.520412) (xy 391.334222 -398.546036) (xy 391.372167 -398.601627)
			(xy 391.403197 -398.661355) (xy 391.426866 -398.724363) (xy 391.442835 -398.789748) (xy 391.450876 -398.856574)
			(xy 391.450872 -398.923881) (xy 391.442825 -398.990705) (xy 391.42685 -399.056089) (xy 391.403175 -399.119095)
			(xy 391.372139 -399.178819) (xy 391.334189 -399.234407) (xy 391.3124 -399.26006) (xy 391.306595 -399.2672)
			(xy 391.300086 -399.284394) (xy 391.2997 -399.293588) (xy 391.2997 -399.451576) (xy 391.299265 -399.461697)
			(xy 391.291524 -399.4804) (xy 391.277214 -399.494715) (xy 391.258513 -399.502461) (xy 391.248392 -399.502884)
			(xy 390.531858 -399.502884) (xy 390.521732 -399.502409) (xy 390.503014 -399.494671) (xy 390.48866 -399.480382)
			(xy 390.480838 -399.4617) (xy 390.480296 -399.451576) (xy 390.480296 -399.293588) (xy 390.479892 -399.2844)
			(xy 390.473374 -399.267216) (xy 390.467596 -399.26006) (xy 390.445845 -399.234378) (xy 390.407898 -399.178795)
			(xy 390.376865 -399.119075) (xy 390.353192 -399.056075) (xy 390.337218 -398.990696) (xy 390.329172 -398.923878)
			(xy 390.329169 -398.856576) (xy 390.337209 -398.789757) (xy 390.353176 -398.724377) (xy 390.376843 -398.661374)
			(xy 390.40787 -398.601652) (xy 390.445812 -398.546065) (xy 390.467596 -398.520412) (xy 390.473412 -398.51328)
			(xy 390.479915 -398.49608) (xy 390.480296 -398.486884) (xy 390.480296 -397.993362) (xy 390.479905 -397.984173)
			(xy 390.473378 -397.966988) (xy 390.467596 -397.959834) (xy 390.445819 -397.934173) (xy 390.407873 -397.878587)
			(xy 390.376842 -397.818864) (xy 390.35317 -397.755861) (xy 390.337198 -397.69048) (xy 390.329154 -397.623659)
			(xy 390.329153 -397.556356) (xy 389.200407 -397.556356) (xy 389.202988 -397.561322) (xy 389.226664 -397.624322)
			(xy 389.24264 -397.689701) (xy 389.250687 -397.75652) (xy 389.25069 -397.823823) (xy 389.24265 -397.890643)
			(xy 389.226681 -397.956023) (xy 389.203012 -398.019026) (xy 389.171982 -398.078748) (xy 389.134038 -398.134334)
			(xy 389.112252 -398.159986) (xy 389.10643 -398.167113) (xy 389.099932 -398.184318) (xy 389.099552 -398.193514)
			(xy 389.099552 -398.351502) (xy 389.099138 -398.361675) (xy 389.09135 -398.380472) (xy 389.076962 -398.394857)
			(xy 389.058163 -398.40264) (xy 389.04799 -398.403064) (xy 388.33171 -398.403064) (xy 388.321539 -398.402628)
			(xy 388.302745 -398.394847) (xy 388.28836 -398.380465) (xy 388.280574 -398.361673) (xy 388.280148 -398.351502)
			(xy 388.280148 -398.193514) (xy 388.27972 -398.184329) (xy 388.273218 -398.167145) (xy 388.267448 -398.159986)
			(xy 388.245622 -398.134365) (xy 388.207674 -398.078774) (xy 388.176642 -398.019046) (xy 388.152971 -397.956038)
			(xy 388.137 -397.890652) (xy 388.128959 -397.823826) (xy 387.000823 -397.823826) (xy 386.972058 -397.879042)
			(xy 386.933968 -397.934677) (xy 386.912104 -397.960342) (xy 386.906308 -397.967487) (xy 386.899793 -397.984678)
			(xy 386.899404 -397.99387) (xy 386.899404 -398.486376) (xy 386.899825 -398.495562) (xy 386.906331 -398.512747)
			(xy 386.912104 -398.519904) (xy 386.934003 -398.54554) (xy 386.972091 -398.601179) (xy 387.003239 -398.660979)
			(xy 387.027001 -398.72408) (xy 387.043034 -398.789572) (xy 387.051107 -398.856514) (xy 387.051104 -398.92394)
			(xy 387.043025 -398.990881) (xy 387.026985 -399.056372) (xy 387.003217 -399.11947) (xy 386.972063 -399.179268)
			(xy 386.93397 -399.234903) (xy 386.912104 -399.260568) (xy 386.906297 -399.267706) (xy 386.899788 -399.284902)
			(xy 386.899404 -399.294096) (xy 386.899404 -399.451576) (xy 386.898965 -399.461696) (xy 386.891225 -399.480399)
			(xy 386.876916 -399.494714) (xy 386.858216 -399.502461) (xy 386.848096 -399.502884) (xy 386.131816 -399.502884)
			(xy 386.121693 -399.502471) (xy 386.102986 -399.494725) (xy 386.088671 -399.480407) (xy 386.080928 -399.4617)
			(xy 386.080508 -399.451576) (xy 386.080508 -399.294096) (xy 386.080098 -399.284909) (xy 386.073584 -399.267725)
			(xy 386.067808 -399.260568) (xy 386.045979 -399.234874) (xy 386.007889 -399.179244) (xy 385.976736 -399.119451)
			(xy 385.95297 -399.056358) (xy 385.936931 -398.990873) (xy 385.928852 -398.923938) (xy 385.928849 -398.856517)
			(xy 385.936922 -398.789581) (xy 385.952954 -398.724093) (xy 385.976714 -398.660998) (xy 386.007861 -398.601203)
			(xy 386.045946 -398.545569) (xy 386.067808 -398.519904) (xy 386.073586 -398.512746) (xy 386.080112 -398.495565)
			(xy 386.080508 -398.486376) (xy 386.080508 -397.99387) (xy 386.080111 -397.984681) (xy 386.073588 -397.967497)
			(xy 386.067808 -397.960342) (xy 386.045954 -397.934669) (xy 386.007864 -397.879036) (xy 385.976712 -397.819241)
			(xy 385.952947 -397.756145) (xy 385.936911 -397.690657) (xy 385.928834 -397.623719) (xy 385.928833 -397.556296)
			(xy 384.800587 -397.556296) (xy 384.803199 -397.561322) (xy 384.826873 -397.624323) (xy 384.842849 -397.689701)
			(xy 384.850896 -397.75652) (xy 384.850899 -397.823822) (xy 384.842859 -397.890642) (xy 384.82689 -397.956022)
			(xy 384.803222 -398.019025) (xy 384.772193 -398.078748) (xy 384.734249 -398.134334) (xy 384.712464 -398.159986)
			(xy 384.706644 -398.167114) (xy 384.700144 -398.184318) (xy 384.699764 -398.193514) (xy 384.699764 -398.351502)
			(xy 384.699268 -398.36166) (xy 384.691494 -398.380428) (xy 384.677128 -398.394794) (xy 384.65836 -398.402568)
			(xy 384.648202 -398.403064) (xy 383.931922 -398.403064) (xy 383.921752 -398.402618) (xy 383.902958 -398.394841)
			(xy 383.888573 -398.380462) (xy 383.880787 -398.361672) (xy 383.88036 -398.351502) (xy 383.88036 -398.193514)
			(xy 383.87993 -398.184329) (xy 383.873429 -398.167145) (xy 383.86766 -398.159986) (xy 383.845834 -398.134365)
			(xy 383.807885 -398.078775) (xy 383.776852 -398.019047) (xy 383.753181 -397.956038) (xy 383.73721 -397.890652)
			(xy 383.729168 -397.823826) (xy 382.600522 -397.823826) (xy 382.572059 -397.878597) (xy 382.534106 -397.934182)
			(xy 382.512316 -397.959834) (xy 382.506524 -397.966983) (xy 382.500006 -397.98417) (xy 382.499616 -397.993362)
			(xy 382.499616 -398.486884) (xy 382.50003 -398.496071) (xy 382.506541 -398.513255) (xy 382.512316 -398.520412)
			(xy 382.53414 -398.546034) (xy 382.572091 -398.601624) (xy 382.603125 -398.661351) (xy 382.626798 -398.72436)
			(xy 382.64277 -398.789746) (xy 382.650812 -398.856573) (xy 382.650808 -398.923881) (xy 382.64276 -398.990707)
			(xy 382.626782 -399.056092) (xy 382.603103 -399.119098) (xy 382.572063 -399.178822) (xy 382.534107 -399.234408)
			(xy 382.512316 -399.26006) (xy 382.506513 -399.267201) (xy 382.500002 -399.284395) (xy 382.499616 -399.293588)
			(xy 382.499616 -399.451576) (xy 382.499165 -399.461695) (xy 382.491428 -399.480395) (xy 382.477122 -399.49471)
			(xy 382.458427 -399.502459) (xy 382.448308 -399.502884) (xy 381.731774 -399.502884) (xy 381.721649 -399.502396)
			(xy 381.702931 -399.494664) (xy 381.688577 -399.480379) (xy 381.680754 -399.461699) (xy 381.680212 -399.451576)
			(xy 381.680212 -399.293588) (xy 381.679805 -399.284401) (xy 381.673289 -399.267216) (xy 381.667512 -399.26006)
			(xy 381.64576 -399.234378) (xy 381.607812 -399.178796) (xy 381.576779 -399.119076) (xy 381.553105 -399.056075)
			(xy 381.537131 -398.990697) (xy 381.529084 -398.923878) (xy 381.529081 -398.856576) (xy 381.537121 -398.789757)
			(xy 381.553089 -398.724377) (xy 381.576757 -398.661374) (xy 381.607784 -398.601651) (xy 381.645727 -398.546064)
			(xy 381.667512 -398.520412) (xy 381.67333 -398.513282) (xy 381.679831 -398.49608) (xy 381.680212 -398.486884)
			(xy 381.680212 -397.993362) (xy 381.679818 -397.984173) (xy 381.673293 -397.966989) (xy 381.667512 -397.959834)
			(xy 381.645735 -397.934173) (xy 381.607788 -397.878588) (xy 381.576755 -397.818865) (xy 381.553083 -397.755862)
			(xy 381.53711 -397.690481) (xy 381.529066 -397.623659) (xy 381.529065 -397.556356) (xy 380.40085 -397.556356)
			(xy 380.403242 -397.560947) (xy 380.42701 -397.62404) (xy 380.443049 -397.689525) (xy 380.451128 -397.756461)
			(xy 380.451131 -397.823882) (xy 380.443059 -397.890818) (xy 380.427026 -397.956306) (xy 380.403265 -398.019401)
			(xy 380.372117 -398.079196) (xy 380.334031 -398.134829) (xy 380.312168 -398.160494) (xy 380.306387 -398.16765)
			(xy 380.299864 -398.184832) (xy 380.299468 -398.194022) (xy 380.299468 -398.351502) (xy 380.298975 -398.361628)
			(xy 380.291248 -398.380347) (xy 380.276964 -398.394703) (xy 380.258283 -398.402524) (xy 380.24816 -398.403064)
			(xy 379.53188 -398.403064) (xy 379.521752 -398.4027) (xy 379.503041 -398.394938) (xy 379.488726 -398.380605)
			(xy 379.480988 -398.361885) (xy 379.480572 -398.351756) (xy 379.480572 -398.194022) (xy 379.480158 -398.184835)
			(xy 379.473648 -398.16765) (xy 379.467872 -398.160494) (xy 379.445972 -398.134859) (xy 379.407886 -398.07922)
			(xy 379.376738 -398.019419) (xy 379.352978 -397.956318) (xy 379.336946 -397.890826) (xy 379.328873 -397.823885)
			(xy 378.200706 -397.823885) (xy 378.171972 -397.879041) (xy 378.133884 -397.934676) (xy 378.11202 -397.960342)
			(xy 378.106225 -397.967489) (xy 378.099709 -397.984678) (xy 378.09932 -397.99387) (xy 378.09932 -398.486376)
			(xy 378.099737 -398.495563) (xy 378.106245 -398.512747) (xy 378.11202 -398.519904) (xy 378.133919 -398.54554)
			(xy 378.172005 -398.60118) (xy 378.203153 -398.66098) (xy 378.226914 -398.724081) (xy 378.242947 -398.789573)
			(xy 378.251019 -398.856514) (xy 378.251016 -398.92394) (xy 378.242937 -398.99088) (xy 378.226898 -399.056371)
			(xy 378.203131 -399.11947) (xy 378.171977 -399.179267) (xy 378.133885 -399.234902) (xy 378.11202 -399.260568)
			(xy 378.106214 -399.267707) (xy 378.099704 -399.284902) (xy 378.09932 -399.294096) (xy 378.09932 -399.451576)
			(xy 378.098865 -399.461694) (xy 378.091128 -399.480394) (xy 378.076824 -399.494708) (xy 378.05813 -399.502458)
			(xy 378.048012 -399.502884) (xy 377.331732 -399.502884) (xy 377.32161 -399.502458) (xy 377.302903 -399.494717)
			(xy 377.288587 -399.480403) (xy 377.280844 -399.461698) (xy 377.280424 -399.451576) (xy 377.280424 -399.294096)
			(xy 377.280011 -399.284909) (xy 377.273499 -399.267725) (xy 377.267724 -399.260568) (xy 377.245895 -399.234874)
			(xy 377.207803 -399.179244) (xy 377.17665 -399.119452) (xy 377.152882 -399.056359) (xy 377.136844 -398.990873)
			(xy 377.128765 -398.923938) (xy 377.128761 -398.856516) (xy 377.136834 -398.78958) (xy 377.152866 -398.724093)
			(xy 377.176627 -398.660997) (xy 377.207775 -398.601202) (xy 377.245861 -398.545569) (xy 377.267724 -398.519904)
			(xy 377.273504 -398.512747) (xy 377.280028 -398.495565) (xy 377.280424 -398.486376) (xy 377.280424 -397.99387)
			(xy 377.280023 -397.984682) (xy 377.273502 -397.967498) (xy 377.267724 -397.960342) (xy 377.245869 -397.934669)
			(xy 377.207778 -397.879036) (xy 377.176626 -397.819241) (xy 377.15286 -397.756145) (xy 377.136823 -397.690657)
			(xy 377.128746 -397.623719) (xy 377.128745 -397.556296) (xy 376.0005 -397.556296) (xy 376.003112 -397.561323)
			(xy 376.026786 -397.624324) (xy 376.042761 -397.689702) (xy 376.050808 -397.756521) (xy 376.050811 -397.823822)
			(xy 376.042771 -397.890642) (xy 376.026803 -397.956022) (xy 376.003135 -398.019025) (xy 375.972108 -398.078747)
			(xy 375.934165 -398.134333) (xy 375.91238 -398.159986) (xy 375.906562 -398.167116) (xy 375.900061 -398.184318)
			(xy 375.89968 -398.193514) (xy 375.89968 -398.351502) (xy 375.899169 -398.361658) (xy 375.891397 -398.380423)
			(xy 375.877037 -398.394788) (xy 375.858274 -398.402565) (xy 375.848118 -398.403064) (xy 375.131838 -398.403064)
			(xy 375.121669 -398.402605) (xy 375.102876 -398.394833) (xy 375.08849 -398.380458) (xy 375.080703 -398.361671)
			(xy 375.080276 -398.351502) (xy 375.080276 -398.193514) (xy 375.079865 -398.184327) (xy 375.073352 -398.167142)
			(xy 375.067576 -398.159986) (xy 375.04575 -398.134365) (xy 375.007799 -398.078775) (xy 374.976766 -398.019048)
			(xy 374.953093 -397.956039) (xy 374.937122 -397.890652) (xy 374.92908 -397.823826) (xy 347.400682 -397.823826)
			(xy 347.372224 -397.878594) (xy 347.334276 -397.934182) (xy 347.312488 -397.959834) (xy 347.306693 -397.96698)
			(xy 347.300178 -397.98417) (xy 347.299788 -397.993362) (xy 347.299788 -398.486884) (xy 347.300209 -398.49607)
			(xy 347.306715 -398.513254) (xy 347.312488 -398.520412) (xy 347.33431 -398.546035) (xy 347.372256 -398.601627)
			(xy 347.403286 -398.661354) (xy 347.426956 -398.724363) (xy 347.442926 -398.789748) (xy 347.450967 -398.856573)
			(xy 347.450963 -398.923881) (xy 347.442916 -398.990705) (xy 347.42694 -399.056089) (xy 347.403264 -399.119095)
			(xy 347.372228 -399.17882) (xy 347.334277 -399.234407) (xy 347.312488 -399.26006) (xy 347.306682 -399.267199)
			(xy 347.300173 -399.284394) (xy 347.299788 -399.293588) (xy 347.299788 -399.451576) (xy 347.299359 -399.46173)
			(xy 347.291569 -399.480484) (xy 347.277174 -399.494809) (xy 347.258382 -399.502507) (xy 347.248226 -399.502884)
			(xy 346.531946 -399.502884) (xy 346.521825 -399.502336) (xy 346.50311 -399.494628) (xy 346.488753 -399.480361)
			(xy 346.480928 -399.461694) (xy 346.480384 -399.451576) (xy 346.480384 -399.293588) (xy 346.479983 -399.2844)
			(xy 346.473463 -399.267215) (xy 346.467684 -399.26006) (xy 346.44593 -399.234379) (xy 346.407977 -399.178798)
			(xy 346.37694 -399.119079) (xy 346.353263 -399.056078) (xy 346.337287 -398.990699) (xy 346.329239 -398.923879)
			(xy 346.329236 -398.856576) (xy 346.337277 -398.789755) (xy 346.353247 -398.724374) (xy 346.376918 -398.661371)
			(xy 346.40795 -398.601648) (xy 346.445897 -398.546064) (xy 346.467684 -398.520412) (xy 346.473499 -398.513279)
			(xy 346.480003 -398.496079) (xy 346.480384 -398.486884) (xy 346.480384 -397.993362) (xy 346.479996 -397.984172)
			(xy 346.473467 -397.966988) (xy 346.467684 -397.959834) (xy 346.445905 -397.934174) (xy 346.407953 -397.87859)
			(xy 346.376917 -397.818868) (xy 346.353241 -397.755864) (xy 346.337266 -397.690483) (xy 346.329221 -397.62366)
			(xy 346.32922 -397.556355) (xy 345.200497 -397.556355) (xy 345.203078 -397.561321) (xy 345.226754 -397.624322)
			(xy 345.24273 -397.689701) (xy 345.250778 -397.75652) (xy 345.250781 -397.823823) (xy 345.242741 -397.890643)
			(xy 345.226771 -397.956023) (xy 345.203102 -398.019026) (xy 345.172072 -398.078749) (xy 345.134126 -398.134334)
			(xy 345.11234 -398.159986) (xy 345.106517 -398.167112) (xy 345.10002 -398.184318) (xy 345.09964 -398.193514)
			(xy 345.09964 -398.351502) (xy 345.099237 -398.361676) (xy 345.091447 -398.380475) (xy 345.077055 -398.394861)
			(xy 345.058253 -398.402642) (xy 345.048078 -398.403064) (xy 344.331798 -398.403064) (xy 344.32164 -398.402568)
			(xy 344.302872 -398.394794) (xy 344.288506 -398.380428) (xy 344.280732 -398.36166) (xy 344.280236 -398.351502)
			(xy 344.280236 -398.193514) (xy 344.279811 -398.184329) (xy 344.273307 -398.167144) (xy 344.267536 -398.159986)
			(xy 344.245711 -398.134365) (xy 344.207763 -398.078774) (xy 344.176732 -398.019046) (xy 344.153061 -397.956037)
			(xy 344.137091 -397.890651) (xy 344.12905 -397.823825) (xy 343.000914 -397.823825) (xy 342.972147 -397.879042)
			(xy 342.934057 -397.934677) (xy 342.912192 -397.960342) (xy 342.906394 -397.967486) (xy 342.899881 -397.984678)
			(xy 342.899492 -397.99387) (xy 342.899492 -398.486376) (xy 342.899916 -398.495562) (xy 342.90642 -398.512746)
			(xy 342.912192 -398.519904) (xy 342.934092 -398.54554) (xy 342.97218 -398.601178) (xy 343.003329 -398.660979)
			(xy 343.027092 -398.724079) (xy 343.043125 -398.789572) (xy 343.051198 -398.856514) (xy 343.051195 -398.92394)
			(xy 343.043115 -398.990881) (xy 343.027076 -399.056372) (xy 343.003307 -399.119471) (xy 342.972152 -399.179268)
			(xy 342.934058 -399.234903) (xy 342.912192 -399.260568) (xy 342.906383 -399.267704) (xy 342.899876 -399.284902)
			(xy 342.899492 -399.294096) (xy 342.899492 -399.451576) (xy 342.899064 -399.461698) (xy 342.891323 -399.480403)
			(xy 342.877009 -399.494718) (xy 342.858306 -399.502463) (xy 342.848184 -399.502884) (xy 342.131904 -399.502884)
			(xy 342.12178 -399.50248) (xy 342.103073 -399.494731) (xy 342.088758 -399.48041) (xy 342.081016 -399.4617)
			(xy 342.080596 -399.451576) (xy 342.080596 -399.294096) (xy 342.080189 -399.284909) (xy 342.073673 -399.267724)
			(xy 342.067896 -399.260568) (xy 342.046068 -399.234874) (xy 342.007978 -399.179243) (xy 341.976826 -399.119451)
			(xy 341.95306 -399.056358) (xy 341.937022 -398.990872) (xy 341.928943 -398.923937) (xy 341.92894 -398.856517)
			(xy 341.937012 -398.789581) (xy 341.953044 -398.724094) (xy 341.976804 -398.660999) (xy 342.00795 -398.601203)
			(xy 342.046034 -398.545569) (xy 342.067896 -398.519904) (xy 342.073673 -398.512745) (xy 342.080199 -398.495565)
			(xy 342.080596 -398.486376) (xy 342.080596 -397.99387) (xy 342.080201 -397.984681) (xy 342.073677 -397.967497)
			(xy 342.067896 -397.960342) (xy 342.046042 -397.934669) (xy 342.007953 -397.879035) (xy 341.976802 -397.81924)
			(xy 341.953038 -397.756144) (xy 341.937002 -397.690656) (xy 341.928925 -397.623719) (xy 341.928924 -397.556296)
			(xy 340.800676 -397.556296) (xy 340.803288 -397.561322) (xy 340.826964 -397.624322) (xy 340.84294 -397.689701)
			(xy 340.850987 -397.75652) (xy 340.85099 -397.823823) (xy 340.84295 -397.890643) (xy 340.826981 -397.956023)
			(xy 340.803312 -398.019026) (xy 340.772282 -398.078748) (xy 340.734338 -398.134334) (xy 340.712552 -398.159986)
			(xy 340.70673 -398.167113) (xy 340.700232 -398.184318) (xy 340.699852 -398.193514) (xy 340.699852 -398.351502)
			(xy 340.699438 -398.361675) (xy 340.69165 -398.380472) (xy 340.677262 -398.394857) (xy 340.658463 -398.40264)
			(xy 340.64829 -398.403064) (xy 339.93201 -398.403064) (xy 339.921839 -398.402628) (xy 339.903045 -398.394847)
			(xy 339.88866 -398.380465) (xy 339.880874 -398.361673) (xy 339.880448 -398.351502) (xy 339.880448 -398.193514)
			(xy 339.88002 -398.184329) (xy 339.873518 -398.167145) (xy 339.867748 -398.159986) (xy 339.845922 -398.134365)
			(xy 339.807974 -398.078774) (xy 339.776942 -398.019046) (xy 339.753271 -397.956038) (xy 339.7373 -397.890652)
			(xy 339.729259 -397.823826) (xy 338.600595 -397.823826) (xy 338.572138 -397.878594) (xy 338.534191 -397.934181)
			(xy 338.512404 -397.959834) (xy 338.506611 -397.966982) (xy 338.500094 -397.98417) (xy 338.499704 -397.993362)
			(xy 338.499704 -398.486884) (xy 338.500121 -398.49607) (xy 338.50663 -398.513255) (xy 338.512404 -398.520412)
			(xy 338.534226 -398.546036) (xy 338.572171 -398.601627) (xy 338.6032 -398.661355) (xy 338.626869 -398.724363)
			(xy 338.642838 -398.789748) (xy 338.650879 -398.856574) (xy 338.650875 -398.923881) (xy 338.642828 -398.990705)
			(xy 338.626853 -399.056089) (xy 338.603178 -399.119094) (xy 338.572143 -399.178819) (xy 338.534193 -399.234407)
			(xy 338.512404 -399.26006) (xy 338.5066 -399.2672) (xy 338.50009 -399.284394) (xy 338.499704 -399.293588)
			(xy 338.499704 -399.451576) (xy 338.499259 -399.461728) (xy 338.491472 -399.480479) (xy 338.477082 -399.494803)
			(xy 338.458296 -399.502505) (xy 338.448142 -399.502884) (xy 337.731862 -399.502884) (xy 337.721736 -399.502405)
			(xy 337.703018 -399.494669) (xy 337.688664 -399.480381) (xy 337.680842 -399.4617) (xy 337.6803 -399.451576)
			(xy 337.6803 -399.293588) (xy 337.679895 -399.2844) (xy 337.673378 -399.267216) (xy 337.6676 -399.26006)
			(xy 337.645849 -399.234378) (xy 337.607901 -399.178795) (xy 337.576869 -399.119075) (xy 337.553196 -399.056075)
			(xy 337.537221 -398.990697) (xy 337.529175 -398.923878) (xy 337.529172 -398.856576) (xy 337.537212 -398.789757)
			(xy 337.55318 -398.724377) (xy 337.576847 -398.661374) (xy 337.607874 -398.601651) (xy 337.645816 -398.546065)
			(xy 337.6676 -398.520412) (xy 337.673416 -398.513281) (xy 337.679919 -398.49608) (xy 337.6803 -398.486884)
			(xy 337.6803 -397.993362) (xy 337.679908 -397.984173) (xy 337.673382 -397.966989) (xy 337.6676 -397.959834)
			(xy 337.645823 -397.934173) (xy 337.607877 -397.878587) (xy 337.576845 -397.818864) (xy 337.553174 -397.755861)
			(xy 337.537201 -397.69048) (xy 337.529157 -397.623659) (xy 337.529156 -397.556356) (xy 336.40094 -397.556356)
			(xy 336.403332 -397.560946) (xy 336.4271 -397.624039) (xy 336.443139 -397.689525) (xy 336.451219 -397.756461)
			(xy 336.451222 -397.823882) (xy 336.44315 -397.890819) (xy 336.427117 -397.956306) (xy 336.403355 -398.019402)
			(xy 336.372206 -398.079196) (xy 336.334119 -398.13483) (xy 336.312256 -398.160494) (xy 336.306474 -398.167649)
			(xy 336.299952 -398.184832) (xy 336.299556 -398.194022) (xy 336.299556 -398.351502) (xy 336.299075 -398.361629)
			(xy 336.291346 -398.380351) (xy 336.277058 -398.394708) (xy 336.258373 -398.402526) (xy 336.248248 -398.403064)
			(xy 335.531968 -398.403064) (xy 335.521807 -398.402704) (xy 335.503047 -398.394891) (xy 335.488724 -398.380475)
			(xy 335.481032 -398.361665) (xy 335.48066 -398.351502) (xy 335.48066 -398.194022) (xy 335.480226 -398.184838)
			(xy 335.473727 -398.167654) (xy 335.46796 -398.160494) (xy 335.44606 -398.134859) (xy 335.407975 -398.079219)
			(xy 335.376828 -398.019418) (xy 335.353068 -397.956318) (xy 335.337036 -397.890825) (xy 335.328964 -397.823884)
			(xy 334.200796 -397.823884) (xy 334.172062 -397.879042) (xy 334.133972 -397.934677) (xy 334.112108 -397.960342)
			(xy 334.106312 -397.967488) (xy 334.099797 -397.984678) (xy 334.099408 -397.99387) (xy 334.099408 -398.486376)
			(xy 334.099828 -398.495562) (xy 334.106335 -398.512747) (xy 334.112108 -398.519904) (xy 334.134007 -398.54554)
			(xy 334.172094 -398.601179) (xy 334.203243 -398.660979) (xy 334.227005 -398.72408) (xy 334.243037 -398.789573)
			(xy 334.25111 -398.856514) (xy 334.251107 -398.92394) (xy 334.243028 -398.990881) (xy 334.226989 -399.056372)
			(xy 334.203221 -399.11947) (xy 334.172066 -399.179267) (xy 334.133974 -399.234903) (xy 334.112108 -399.260568)
			(xy 334.106301 -399.267706) (xy 334.099792 -399.284902) (xy 334.099408 -399.294096) (xy 334.099408 -399.451576)
			(xy 334.098965 -399.461696) (xy 334.091226 -399.480398) (xy 334.076918 -399.494712) (xy 334.05822 -399.50246)
			(xy 334.0481 -399.502884) (xy 333.33182 -399.502884) (xy 333.321697 -399.502467) (xy 333.302991 -399.494723)
			(xy 333.288675 -399.480406) (xy 333.280932 -399.461699) (xy 333.280512 -399.451576) (xy 333.280512 -399.294096)
			(xy 333.280101 -399.284909) (xy 333.273587 -399.267725) (xy 333.267812 -399.260568) (xy 333.245983 -399.234874)
			(xy 333.207892 -399.179244) (xy 333.176739 -399.119452) (xy 333.152973 -399.056358) (xy 333.136934 -398.990873)
			(xy 333.128855 -398.923938) (xy 333.128852 -398.856516) (xy 333.136925 -398.78958) (xy 333.152957 -398.724093)
			(xy 333.176717 -398.660998) (xy 333.207865 -398.601203) (xy 333.24595 -398.545569) (xy 333.267812 -398.519904)
			(xy 333.273591 -398.512746) (xy 333.280116 -398.495565) (xy 333.280512 -398.486376) (xy 333.280512 -397.99387)
			(xy 333.280114 -397.984682) (xy 333.273592 -397.967497) (xy 333.267812 -397.960342) (xy 333.245957 -397.934669)
			(xy 333.207868 -397.879036) (xy 333.176716 -397.819241) (xy 333.152951 -397.756145) (xy 333.136914 -397.690657)
			(xy 333.128837 -397.623719) (xy 333.128836 -397.556296) (xy 332.00059 -397.556296) (xy 332.003202 -397.561323)
			(xy 332.026877 -397.624323) (xy 332.042852 -397.689701) (xy 332.050899 -397.75652) (xy 332.050902 -397.823822)
			(xy 332.042862 -397.890642) (xy 332.026893 -397.956022) (xy 332.003225 -398.019025) (xy 331.972197 -398.078748)
			(xy 331.934253 -398.134334) (xy 331.912468 -398.159986) (xy 331.906648 -398.167115) (xy 331.900148 -398.184318)
			(xy 331.899768 -398.193514) (xy 331.899768 -398.351502) (xy 331.899268 -398.361659) (xy 331.891494 -398.380427)
			(xy 331.877131 -398.394792) (xy 331.858363 -398.402568) (xy 331.848206 -398.403064) (xy 331.131926 -398.403064)
			(xy 331.121756 -398.402615) (xy 331.102963 -398.394839) (xy 331.088577 -398.380461) (xy 331.080791 -398.361671)
			(xy 331.080364 -398.351502) (xy 331.080364 -398.193514) (xy 331.079933 -398.184329) (xy 331.073432 -398.167146)
			(xy 331.067664 -398.159986) (xy 331.045838 -398.134365) (xy 331.007889 -398.078775) (xy 330.976856 -398.019047)
			(xy 330.953184 -397.956038) (xy 330.937213 -397.890652) (xy 330.929171 -397.823826) (xy 326.525636 -397.823826)
			(xy 326.525636 -401.723737) (xy 330.929183 -401.723737) (xy 330.929184 -401.65643) (xy 330.937231 -401.589605)
			(xy 330.953207 -401.524221) (xy 330.976884 -401.461216) (xy 331.007921 -401.401492) (xy 331.045874 -401.345906)
			(xy 331.067664 -401.320254) (xy 331.07347 -401.313116) (xy 331.079977 -401.29592) (xy 331.080364 -401.286726)
			(xy 331.080364 -400.793458) (xy 331.07996 -400.78427) (xy 331.073441 -400.767087) (xy 331.067664 -400.75993)
			(xy 331.045882 -400.734273) (xy 331.007931 -400.678688) (xy 330.976896 -400.618965) (xy 330.953222 -400.555961)
			(xy 330.937248 -400.490579) (xy 330.929203 -400.423757) (xy 330.929202 -400.356452) (xy 330.937246 -400.289629)
			(xy 330.953219 -400.224247) (xy 330.976892 -400.161243) (xy 331.007926 -400.10152) (xy 331.045876 -400.045934)
			(xy 331.067664 -400.020282) (xy 331.073459 -400.013136) (xy 331.079973 -399.995946) (xy 331.080364 -399.986754)
			(xy 331.080364 -399.828766) (xy 331.080806 -399.818603) (xy 331.088597 -399.799828) (xy 331.102978 -399.785463)
			(xy 331.121762 -399.777694) (xy 331.131926 -399.777204) (xy 331.848206 -399.777204) (xy 331.85836 -399.777728)
			(xy 331.877123 -399.785498) (xy 331.891486 -399.799854) (xy 331.899267 -399.818612) (xy 331.899768 -399.828766)
			(xy 331.899768 -399.986754) (xy 331.900208 -399.995938) (xy 331.906702 -400.013122) (xy 331.912468 -400.020282)
			(xy 331.934262 -400.045929) (xy 331.97221 -400.101517) (xy 332.003242 -400.161241) (xy 332.026915 -400.224246)
			(xy 332.042887 -400.289629) (xy 332.05093 -400.356452) (xy 332.05093 -400.423757) (xy 332.042885 -400.49058)
			(xy 332.026912 -400.555963) (xy 332.003239 -400.618967) (xy 331.972205 -400.678691) (xy 331.934256 -400.734278)
			(xy 331.912468 -400.75993) (xy 331.906672 -400.767076) (xy 331.900158 -400.784266) (xy 331.899768 -400.793458)
			(xy 331.899768 -401.286726) (xy 331.900173 -401.295914) (xy 331.906691 -401.313098) (xy 331.912468 -401.320254)
			(xy 331.934234 -401.345924) (xy 331.972183 -401.401508) (xy 332.003216 -401.461229) (xy 332.02689 -401.524231)
			(xy 332.042864 -401.589611) (xy 332.05091 -401.656432) (xy 332.050912 -401.723735) (xy 332.04287 -401.790556)
			(xy 332.0269 -401.855937) (xy 332.00323 -401.91894) (xy 331.9722 -401.978663) (xy 331.934254 -402.03425)
			(xy 331.912468 -402.059902) (xy 331.906684 -402.067056) (xy 331.900163 -402.08424) (xy 331.899768 -402.09343)
			(xy 331.899768 -402.251418) (xy 331.899282 -402.261576) (xy 331.891502 -402.280345) (xy 331.877135 -402.294709)
			(xy 331.858364 -402.302484) (xy 331.848206 -402.30298) (xy 331.131926 -402.30298) (xy 331.121758 -402.302515)
			(xy 331.102968 -402.294742) (xy 331.088583 -402.280369) (xy 331.080794 -402.261585) (xy 331.080364 -402.251418)
			(xy 331.080364 -402.09343) (xy 331.079925 -402.084246) (xy 331.07343 -402.067062) (xy 331.067664 -402.059902)
			(xy 331.045854 -402.034268) (xy 331.007904 -401.97868) (xy 330.97687 -401.918954) (xy 330.953197 -401.855947)
			(xy 330.937225 -401.790562) (xy 330.929183 -401.723737) (xy 326.525636 -401.723737) (xy 326.525636 -402.823878)
			(xy 333.128796 -402.823878) (xy 333.128801 -402.75645) (xy 333.136882 -402.689508) (xy 333.152922 -402.624016)
			(xy 333.176693 -402.560918) (xy 333.20785 -402.50112) (xy 333.245945 -402.445485) (xy 333.267812 -402.41982)
			(xy 333.273626 -402.412687) (xy 333.28013 -402.395487) (xy 333.280512 -402.386292) (xy 333.280512 -401.89404)
			(xy 333.28008 -401.884855) (xy 333.273581 -401.867671) (xy 333.267812 -401.860512) (xy 333.245928 -401.834863)
			(xy 333.207839 -401.779227) (xy 333.176689 -401.719428) (xy 333.152925 -401.656329) (xy 333.136891 -401.590838)
			(xy 333.128816 -401.523898) (xy 333.128818 -401.456472) (xy 333.136896 -401.389532) (xy 333.152934 -401.324042)
			(xy 333.176701 -401.260944) (xy 333.207855 -401.201148) (xy 333.245946 -401.145513) (xy 333.267812 -401.119848)
			(xy 333.273615 -401.112707) (xy 333.280125 -401.095513) (xy 333.280512 -401.08632) (xy 333.280512 -400.92884)
			(xy 333.280949 -400.918719) (xy 333.288686 -400.900014) (xy 333.302997 -400.885698) (xy 333.321699 -400.877953)
			(xy 333.33182 -400.877532) (xy 334.0481 -400.877532) (xy 334.058226 -400.877917) (xy 334.076936 -400.885671)
			(xy 334.091252 -400.899997) (xy 334.098991 -400.918713) (xy 334.099408 -400.92884) (xy 334.099408 -401.08632)
			(xy 334.099807 -401.095508) (xy 334.106328 -401.112693) (xy 334.112108 -401.119848) (xy 334.133952 -401.14553)
			(xy 334.172041 -401.201162) (xy 334.203192 -401.260956) (xy 334.226957 -401.324051) (xy 334.242994 -401.389538)
			(xy 334.251071 -401.456474) (xy 334.251073 -401.523896) (xy 334.242999 -401.590833) (xy 334.226966 -401.656321)
			(xy 334.203204 -401.719417) (xy 334.200923 -401.723796) (xy 335.328975 -401.723796) (xy 335.328977 -401.656371)
			(xy 335.337055 -401.589432) (xy 335.353091 -401.523942) (xy 335.376856 -401.460845) (xy 335.408007 -401.401048)
			(xy 335.446096 -401.345412) (xy 335.46796 -401.319746) (xy 335.473769 -401.31261) (xy 335.480275 -401.295412)
			(xy 335.48066 -401.286218) (xy 335.48066 -400.793966) (xy 335.480253 -400.784779) (xy 335.473735 -400.767595)
			(xy 335.46796 -400.760438) (xy 335.446103 -400.734767) (xy 335.408017 -400.679133) (xy 335.376868 -400.619337)
			(xy 335.353106 -400.556241) (xy 335.337071 -400.490753) (xy 335.328995 -400.423816) (xy 335.328995 -400.356393)
			(xy 335.337069 -400.289456) (xy 335.353103 -400.223968) (xy 335.376865 -400.160872) (xy 335.408012 -400.101075)
			(xy 335.446098 -400.04544) (xy 335.46796 -400.019774) (xy 335.473757 -400.01263) (xy 335.48027 -399.995438)
			(xy 335.48066 -399.986246) (xy 335.48066 -399.828766) (xy 335.481099 -399.818635) (xy 335.488842 -399.799909)
			(xy 335.503143 -399.785553) (xy 335.521839 -399.777739) (xy 335.531968 -399.777204) (xy 336.248248 -399.777204)
			(xy 336.258406 -399.777583) (xy 336.27716 -399.785395) (xy 336.291482 -399.799804) (xy 336.299179 -399.818606)
			(xy 336.299556 -399.828766) (xy 336.299556 -399.986246) (xy 336.300002 -399.995429) (xy 336.306492 -400.012613)
			(xy 336.312256 -400.019774) (xy 336.334127 -400.045434) (xy 336.372219 -400.101068) (xy 336.403372 -400.160864)
			(xy 336.427138 -400.223962) (xy 336.443174 -400.289452) (xy 336.45125 -400.356392) (xy 336.451249 -400.423817)
			(xy 336.443172 -400.490756) (xy 336.427135 -400.556246) (xy 336.403368 -400.619344) (xy 336.372214 -400.67914)
			(xy 336.334122 -400.734774) (xy 336.312256 -400.760438) (xy 336.306455 -400.76758) (xy 336.299944 -400.784773)
			(xy 336.299556 -400.793966) (xy 336.299556 -401.286218) (xy 336.299967 -401.295405) (xy 336.306481 -401.312589)
			(xy 336.312256 -401.319746) (xy 336.3341 -401.345428) (xy 336.372192 -401.401059) (xy 336.403346 -401.460853)
			(xy 336.427114 -401.523948) (xy 336.443152 -401.589435) (xy 336.45123 -401.656372) (xy 336.451232 -401.723795)
			(xy 336.443158 -401.790732) (xy 336.427123 -401.856221) (xy 336.40336 -401.919317) (xy 336.372209 -401.979112)
			(xy 336.33412 -402.034746) (xy 336.312256 -402.06041) (xy 336.306467 -402.06756) (xy 336.299949 -402.084747)
			(xy 336.299556 -402.093938) (xy 336.299556 -402.251418) (xy 336.299088 -402.261546) (xy 336.291354 -402.280269)
			(xy 336.277062 -402.294625) (xy 336.258374 -402.302443) (xy 336.248248 -402.30298) (xy 335.531968 -402.30298)
			(xy 335.521809 -402.302604) (xy 335.503052 -402.294794) (xy 335.488729 -402.280384) (xy 335.481034 -402.261579)
			(xy 335.48066 -402.251418) (xy 335.48066 -402.093938) (xy 335.480218 -402.084754) (xy 335.473725 -402.06757)
			(xy 335.46796 -402.06041) (xy 335.446076 -402.034762) (xy 335.40799 -401.979124) (xy 335.376843 -401.919325)
			(xy 335.353082 -401.856226) (xy 335.337049 -401.790735) (xy 335.328975 -401.723796) (xy 334.200923 -401.723796)
			(xy 334.172056 -401.779212) (xy 334.13397 -401.834847) (xy 334.112108 -401.860512) (xy 334.106325 -401.867667)
			(xy 334.099802 -401.88485) (xy 334.099408 -401.89404) (xy 334.099408 -402.386292) (xy 334.09982 -402.395479)
			(xy 334.106332 -402.412663) (xy 334.112108 -402.41982) (xy 334.133925 -402.445524) (xy 334.172014 -402.501153)
			(xy 334.203166 -402.560944) (xy 334.226933 -402.624036) (xy 334.242972 -402.68952) (xy 334.251051 -402.756454)
			(xy 334.251055 -402.823818) (xy 337.529116 -402.823818) (xy 337.52912 -402.75651) (xy 337.537169 -402.689685)
			(xy 337.553145 -402.6243) (xy 337.576822 -402.561294) (xy 337.607859 -402.501569) (xy 337.645811 -402.445981)
			(xy 337.6676 -402.420328) (xy 337.67341 -402.413192) (xy 337.679917 -402.395994) (xy 337.6803 -402.3868)
			(xy 337.6803 -401.893532) (xy 337.679874 -401.884346) (xy 337.673371 -401.867162) (xy 337.6676 -401.860004)
			(xy 337.645794 -401.834367) (xy 337.607848 -401.778778) (xy 337.576818 -401.719052) (xy 337.553148 -401.656045)
			(xy 337.537178 -401.590662) (xy 337.529136 -401.523838) (xy 337.529137 -401.456532) (xy 337.537183 -401.389709)
			(xy 337.553157 -401.324326) (xy 337.57683 -401.261321) (xy 337.607864 -401.201596) (xy 337.645812 -401.146009)
			(xy 337.6676 -401.120356) (xy 337.673398 -401.113212) (xy 337.679912 -401.09602) (xy 337.6803 -401.086828)
			(xy 337.6803 -400.92884) (xy 337.680755 -400.918688) (xy 337.688537 -400.899937) (xy 337.702924 -400.885612)
			(xy 337.721709 -400.877911) (xy 337.731862 -400.877532) (xy 338.448142 -400.877532) (xy 338.45827 -400.877992)
			(xy 338.476991 -400.885732) (xy 338.491346 -400.900026) (xy 338.499165 -400.918714) (xy 338.499704 -400.92884)
			(xy 338.499704 -401.086828) (xy 338.5001 -401.096017) (xy 338.506623 -401.113201) (xy 338.512404 -401.120356)
			(xy 338.534171 -401.146025) (xy 338.572117 -401.20161) (xy 338.603149 -401.261332) (xy 338.626821 -401.324334)
			(xy 338.642794 -401.389714) (xy 338.650839 -401.456534) (xy 338.650841 -401.523836) (xy 338.6428 -401.590657)
			(xy 338.62683 -401.656037) (xy 338.603161 -401.719041) (xy 338.600721 -401.723737) (xy 339.72927 -401.723737)
			(xy 339.729272 -401.65643) (xy 339.737319 -401.589606) (xy 339.753294 -401.524222) (xy 339.77697 -401.461217)
			(xy 339.808006 -401.401492) (xy 339.845959 -401.345906) (xy 339.867748 -401.320254) (xy 339.873553 -401.313115)
			(xy 339.880061 -401.295919) (xy 339.880448 -401.286726) (xy 339.880448 -400.793458) (xy 339.880047 -400.78427)
			(xy 339.873526 -400.767086) (xy 339.867748 -400.75993) (xy 339.845966 -400.734273) (xy 339.808017 -400.678687)
			(xy 339.776983 -400.618965) (xy 339.753309 -400.555961) (xy 339.737335 -400.490579) (xy 339.729291 -400.423757)
			(xy 339.72929 -400.356452) (xy 339.737334 -400.28963) (xy 339.753306 -400.224248) (xy 339.776979 -400.161244)
			(xy 339.808012 -400.10152) (xy 339.845961 -400.045934) (xy 339.867748 -400.020282) (xy 339.873541 -400.013134)
			(xy 339.880056 -399.995946) (xy 339.880448 -399.986754) (xy 339.880448 -399.828766) (xy 339.880906 -399.818605)
			(xy 339.888693 -399.799833) (xy 339.90307 -399.785469) (xy 339.921848 -399.777697) (xy 339.93201 -399.777204)
			(xy 340.64829 -399.777204) (xy 340.658443 -399.777741) (xy 340.677205 -399.785506) (xy 340.69157 -399.799858)
			(xy 340.699351 -399.818613) (xy 340.699852 -399.828766) (xy 340.699852 -399.986754) (xy 340.700295 -399.995937)
			(xy 340.706787 -400.013121) (xy 340.712552 -400.020282) (xy 340.734346 -400.045929) (xy 340.772295 -400.101516)
			(xy 340.803329 -400.16124) (xy 340.827002 -400.224245) (xy 340.842975 -400.289628) (xy 340.851018 -400.356452)
			(xy 340.851018 -400.423757) (xy 340.842973 -400.490581) (xy 340.826999 -400.555963) (xy 340.803325 -400.618968)
			(xy 340.772291 -400.678692) (xy 340.734341 -400.734278) (xy 340.712552 -400.75993) (xy 340.706754 -400.767074)
			(xy 340.700242 -400.784266) (xy 340.699852 -400.793458) (xy 340.699852 -401.286726) (xy 340.70026 -401.295913)
			(xy 340.706777 -401.313097) (xy 340.712552 -401.320254) (xy 340.734318 -401.345924) (xy 340.772268 -401.401508)
			(xy 340.803303 -401.461229) (xy 340.826977 -401.524231) (xy 340.842952 -401.589611) (xy 340.850998 -401.656432)
			(xy 340.851 -401.723735) (xy 340.842958 -401.790556) (xy 340.826987 -401.855937) (xy 340.803316 -401.918941)
			(xy 340.772285 -401.978664) (xy 340.734338 -402.03425) (xy 340.712552 -402.059902) (xy 340.706766 -402.067055)
			(xy 340.700246 -402.08424) (xy 340.699852 -402.09343) (xy 340.699852 -402.251418) (xy 340.699381 -402.261578)
			(xy 340.691599 -402.28035) (xy 340.677226 -402.294715) (xy 340.65845 -402.302487) (xy 340.64829 -402.30298)
			(xy 339.93201 -402.30298) (xy 339.921855 -402.302459) (xy 339.90309 -402.294691) (xy 339.888725 -402.280334)
			(xy 339.880947 -402.261573) (xy 339.880448 -402.251418) (xy 339.880448 -402.09343) (xy 339.880013 -402.084246)
			(xy 339.873515 -402.067062) (xy 339.867748 -402.059902) (xy 339.845938 -402.034268) (xy 339.807989 -401.978679)
			(xy 339.776957 -401.918953) (xy 339.753285 -401.855946) (xy 339.737313 -401.790562) (xy 339.72927 -401.723737)
			(xy 338.600721 -401.723737) (xy 338.572133 -401.778764) (xy 338.534189 -401.834351) (xy 338.512404 -401.860004)
			(xy 338.506624 -401.867161) (xy 338.500099 -401.884342) (xy 338.499704 -401.893532) (xy 338.499704 -402.3868)
			(xy 338.500113 -402.395987) (xy 338.506628 -402.413172) (xy 338.512404 -402.420328) (xy 338.534143 -402.44602)
			(xy 338.572091 -402.501601) (xy 338.603124 -402.56132) (xy 338.626797 -402.624319) (xy 338.642772 -402.689696)
			(xy 338.65082 -402.756514) (xy 338.650824 -402.823814) (xy 338.650816 -402.823878) (xy 341.928884 -402.823878)
			(xy 341.928889 -402.75645) (xy 341.936969 -402.689509) (xy 341.95301 -402.624017) (xy 341.976779 -402.560918)
			(xy 342.007935 -402.501121) (xy 342.046029 -402.445485) (xy 342.067896 -402.41982) (xy 342.073709 -402.412686)
			(xy 342.080214 -402.395487) (xy 342.080596 -402.386292) (xy 342.080596 -401.89404) (xy 342.080168 -401.884855)
			(xy 342.073667 -401.86767) (xy 342.067896 -401.860512) (xy 342.046013 -401.834863) (xy 342.007925 -401.779226)
			(xy 341.976775 -401.719428) (xy 341.953012 -401.656329) (xy 341.936978 -401.590838) (xy 341.928904 -401.523898)
			(xy 341.928906 -401.456472) (xy 341.936984 -401.389533) (xy 341.953021 -401.324043) (xy 341.976787 -401.260945)
			(xy 342.00794 -401.201148) (xy 342.046031 -401.145513) (xy 342.067896 -401.119848) (xy 342.073697 -401.112706)
			(xy 342.080209 -401.095513) (xy 342.080596 -401.08632) (xy 342.080596 -400.92884) (xy 342.081049 -400.918721)
			(xy 342.088783 -400.900019) (xy 342.103088 -400.885703) (xy 342.121785 -400.877956) (xy 342.131904 -400.877532)
			(xy 342.848184 -400.877532) (xy 342.858309 -400.87793) (xy 342.877019 -400.885679) (xy 342.891335 -400.900001)
			(xy 342.899075 -400.918714) (xy 342.899492 -400.92884) (xy 342.899492 -401.08632) (xy 342.899894 -401.095508)
			(xy 342.906413 -401.112692) (xy 342.912192 -401.119848) (xy 342.934037 -401.145529) (xy 342.972126 -401.201161)
			(xy 343.003278 -401.260955) (xy 343.027044 -401.32405) (xy 343.043081 -401.389537) (xy 343.051159 -401.456474)
			(xy 343.051161 -401.523896) (xy 343.043087 -401.590833) (xy 343.027053 -401.656321) (xy 343.003291 -401.719417)
			(xy 343.001041 -401.723737) (xy 344.129061 -401.723737) (xy 344.129063 -401.65643) (xy 344.13711 -401.589606)
			(xy 344.153085 -401.524223) (xy 344.17676 -401.461217) (xy 344.207796 -401.401493) (xy 344.245747 -401.345906)
			(xy 344.267536 -401.320254) (xy 344.273339 -401.313114) (xy 344.279849 -401.295919) (xy 344.280236 -401.286726)
			(xy 344.280236 -400.793458) (xy 344.279838 -400.78427) (xy 344.273315 -400.767086) (xy 344.267536 -400.75993)
			(xy 344.245754 -400.734273) (xy 344.207805 -400.678687) (xy 344.176772 -400.618964) (xy 344.153099 -400.55596)
			(xy 344.137126 -400.490579) (xy 344.129081 -400.423757) (xy 344.129081 -400.356452) (xy 344.137124 -400.28963)
			(xy 344.153096 -400.224248) (xy 344.176768 -400.161244) (xy 344.207801 -400.101521) (xy 344.245749 -400.045934)
			(xy 344.267536 -400.020282) (xy 344.273327 -400.013133) (xy 344.279844 -399.995945) (xy 344.280236 -399.986754)
			(xy 344.280236 -399.828766) (xy 344.280705 -399.818606) (xy 344.288491 -399.799837) (xy 344.302864 -399.785473)
			(xy 344.321638 -399.777699) (xy 344.331798 -399.777204) (xy 345.048078 -399.777204) (xy 345.05823 -399.77775)
			(xy 345.076992 -399.785511) (xy 345.091357 -399.799861) (xy 345.099139 -399.818614) (xy 345.09964 -399.828766)
			(xy 345.09964 -399.986754) (xy 345.100086 -399.995937) (xy 345.106576 -400.013121) (xy 345.11234 -400.020282)
			(xy 345.134134 -400.045929) (xy 345.172084 -400.101516) (xy 345.203118 -400.16124) (xy 345.226792 -400.224245)
			(xy 345.242765 -400.289628) (xy 345.250809 -400.356452) (xy 345.250808 -400.423757) (xy 345.242763 -400.490581)
			(xy 345.226789 -400.555964) (xy 345.203115 -400.618968) (xy 345.172079 -400.678692) (xy 345.134129 -400.734278)
			(xy 345.11234 -400.75993) (xy 345.106541 -400.767073) (xy 345.100029 -400.784265) (xy 345.09964 -400.793458)
			(xy 345.09964 -401.286726) (xy 345.100051 -401.295913) (xy 345.106566 -401.313096) (xy 345.11234 -401.320254)
			(xy 345.134107 -401.345924) (xy 345.172057 -401.401507) (xy 345.203093 -401.461228) (xy 345.226768 -401.52423)
			(xy 345.242743 -401.589611) (xy 345.250789 -401.656432) (xy 345.250791 -401.723735) (xy 345.242749 -401.790557)
			(xy 345.226778 -401.855938) (xy 345.203106 -401.918942) (xy 345.172074 -401.978664) (xy 345.134127 -402.03425)
			(xy 345.11234 -402.059902) (xy 345.106553 -402.067053) (xy 345.100034 -402.084239) (xy 345.09964 -402.09343)
			(xy 345.09964 -402.251418) (xy 345.09925 -402.261593) (xy 345.091455 -402.280393) (xy 345.077059 -402.294778)
			(xy 345.058254 -402.302558) (xy 345.048078 -402.30298) (xy 344.331798 -402.30298) (xy 344.321642 -402.302469)
			(xy 344.302877 -402.294697) (xy 344.288512 -402.280337) (xy 344.280735 -402.261574) (xy 344.280236 -402.251418)
			(xy 344.280236 -402.09343) (xy 344.279803 -402.084245) (xy 344.273304 -402.067061) (xy 344.267536 -402.059902)
			(xy 344.245727 -402.034268) (xy 344.207779 -401.978679) (xy 344.176746 -401.918953) (xy 344.153075 -401.855946)
			(xy 344.137104 -401.790561) (xy 344.129061 -401.723737) (xy 343.001041 -401.723737) (xy 342.972142 -401.779213)
			(xy 342.934055 -401.834847) (xy 342.912192 -401.860512) (xy 342.906407 -401.867665) (xy 342.899886 -401.88485)
			(xy 342.899492 -401.89404) (xy 342.899492 -402.386292) (xy 342.899908 -402.395479) (xy 342.906418 -402.412663)
			(xy 342.912192 -402.41982) (xy 342.934009 -402.445524) (xy 342.9721 -402.501153) (xy 343.003253 -402.560944)
			(xy 343.02702 -402.624035) (xy 343.043059 -402.68952) (xy 343.051139 -402.756454) (xy 343.051143 -402.823819)
			(xy 346.329179 -402.823819) (xy 346.329184 -402.756509) (xy 346.337233 -402.689682) (xy 346.353213 -402.624297)
			(xy 346.376893 -402.56129) (xy 346.407934 -402.501566) (xy 346.445892 -402.445979) (xy 346.467684 -402.420328)
			(xy 346.473492 -402.413191) (xy 346.48 -402.395994) (xy 346.480384 -402.3868) (xy 346.480384 -401.893532)
			(xy 346.479962 -401.884346) (xy 346.473457 -401.867161) (xy 346.467684 -401.860004) (xy 346.445875 -401.834369)
			(xy 346.407924 -401.778781) (xy 346.376889 -401.719055) (xy 346.353216 -401.656049) (xy 346.337243 -401.590664)
			(xy 346.3292 -401.523839) (xy 346.329201 -401.456531) (xy 346.337248 -401.389707) (xy 346.353225 -401.324323)
			(xy 346.376902 -401.261317) (xy 346.40794 -401.201593) (xy 346.445894 -401.146008) (xy 346.467684 -401.120356)
			(xy 346.47348 -401.11321) (xy 346.479995 -401.09602) (xy 346.480384 -401.086828) (xy 346.480384 -400.92884)
			(xy 346.480854 -400.91869) (xy 346.488634 -400.899942) (xy 346.503015 -400.885618) (xy 346.521795 -400.877914)
			(xy 346.531946 -400.877532) (xy 347.248226 -400.877532) (xy 347.258353 -400.878005) (xy 347.277074 -400.88574)
			(xy 347.291429 -400.90003) (xy 347.299249 -400.918715) (xy 347.299788 -400.92884) (xy 347.299788 -401.086828)
			(xy 347.300187 -401.096016) (xy 347.306709 -401.1132) (xy 347.312488 -401.120356) (xy 347.334255 -401.146025)
			(xy 347.372203 -401.201609) (xy 347.403236 -401.261331) (xy 347.426908 -401.324333) (xy 347.442882 -401.389713)
			(xy 347.450927 -401.456533) (xy 347.450929 -401.523836) (xy 347.442887 -401.590657) (xy 347.426917 -401.656038)
			(xy 347.403248 -401.719042) (xy 347.400809 -401.723737) (xy 374.929092 -401.723737) (xy 374.929094 -401.65643)
			(xy 374.937141 -401.589605) (xy 374.953117 -401.524221) (xy 374.976794 -401.461216) (xy 375.007832 -401.401492)
			(xy 375.045786 -401.345906) (xy 375.067576 -401.320254) (xy 375.073372 -401.313108) (xy 375.079888 -401.295918)
			(xy 375.080276 -401.286726) (xy 375.080276 -400.793458) (xy 375.079891 -400.784268) (xy 375.07336 -400.767084)
			(xy 375.067576 -400.75993) (xy 375.045793 -400.734273) (xy 375.007842 -400.678688) (xy 374.976806 -400.618966)
			(xy 374.953131 -400.555962) (xy 374.937157 -400.49058) (xy 374.929112 -400.423757) (xy 374.929111 -400.356452)
			(xy 374.937155 -400.289629) (xy 374.953129 -400.224247) (xy 374.976802 -400.161242) (xy 375.007837 -400.101519)
			(xy 375.045788 -400.045934) (xy 375.067576 -400.020282) (xy 375.07336 -400.013128) (xy 375.079883 -399.995944)
			(xy 375.080276 -399.986754) (xy 375.080276 -399.828766) (xy 375.080637 -399.818587) (xy 375.08844 -399.799785)
			(xy 375.102845 -399.7854) (xy 375.121659 -399.777623) (xy 375.131838 -399.777204) (xy 375.848118 -399.777204)
			(xy 375.858273 -399.777718) (xy 375.877036 -399.785492) (xy 375.891399 -399.799851) (xy 375.899179 -399.818611)
			(xy 375.89968 -399.828766) (xy 375.89968 -399.986754) (xy 375.900117 -399.995938) (xy 375.906612 -400.013123)
			(xy 375.91238 -400.020282) (xy 375.934173 -400.045929) (xy 375.972121 -400.101517) (xy 376.003152 -400.161241)
			(xy 376.026824 -400.224247) (xy 376.042796 -400.289629) (xy 376.050839 -400.356452) (xy 376.050839 -400.423757)
			(xy 376.042794 -400.49058) (xy 376.026821 -400.555962) (xy 376.003149 -400.618967) (xy 375.972116 -400.678691)
			(xy 375.934168 -400.734278) (xy 375.91238 -400.75993) (xy 375.906586 -400.767077) (xy 375.90007 -400.784266)
			(xy 375.89968 -400.793458) (xy 375.89968 -401.286726) (xy 375.900082 -401.295914) (xy 375.906602 -401.313098)
			(xy 375.91238 -401.320254) (xy 375.934146 -401.345924) (xy 375.972094 -401.401508) (xy 376.003127 -401.46123)
			(xy 376.0268 -401.524232) (xy 376.042774 -401.589612) (xy 376.05082 -401.656432) (xy 376.050822 -401.723735)
			(xy 376.04278 -401.790556) (xy 376.02681 -401.855937) (xy 376.003141 -401.91894) (xy 375.972111 -401.978663)
			(xy 375.934166 -402.03425) (xy 375.91238 -402.059902) (xy 375.906598 -402.067057) (xy 375.900075 -402.08424)
			(xy 375.89968 -402.09343) (xy 375.89968 -402.251418) (xy 375.899182 -402.261575) (xy 375.891405 -402.280341)
			(xy 375.877041 -402.294705) (xy 375.858275 -402.302482) (xy 375.848118 -402.30298) (xy 375.131838 -402.30298)
			(xy 375.121671 -402.302505) (xy 375.102881 -402.294736) (xy 375.088495 -402.280366) (xy 375.080706 -402.261584)
			(xy 375.080276 -402.251418) (xy 375.080276 -402.09343) (xy 375.079857 -402.084244) (xy 375.07335 -402.067059)
			(xy 375.067576 -402.059902) (xy 375.045766 -402.034268) (xy 375.007815 -401.97868) (xy 374.976781 -401.918954)
			(xy 374.953108 -401.855947) (xy 374.937135 -401.790562) (xy 374.929092 -401.723737) (xy 347.400809 -401.723737)
			(xy 347.372218 -401.778765) (xy 347.334274 -401.834352) (xy 347.312488 -401.860004) (xy 347.306706 -401.867159)
			(xy 347.300183 -401.884342) (xy 347.299788 -401.893532) (xy 347.299788 -402.3868) (xy 347.300201 -402.395987)
			(xy 347.306713 -402.413171) (xy 347.312488 -402.420328) (xy 347.334227 -402.44602) (xy 347.372176 -402.501601)
			(xy 347.40321 -402.561319) (xy 347.426884 -402.624319) (xy 347.442859 -402.689696) (xy 347.450907 -402.756514)
			(xy 347.450911 -402.823814) (xy 347.450903 -402.823878) (xy 377.128705 -402.823878) (xy 377.12871 -402.75645)
			(xy 377.136791 -402.689508) (xy 377.152832 -402.624016) (xy 377.176603 -402.560917) (xy 377.20776 -402.50112)
			(xy 377.245856 -402.445485) (xy 377.267724 -402.41982) (xy 377.27354 -402.412689) (xy 377.280042 -402.395487)
			(xy 377.280424 -402.386292) (xy 377.280424 -401.89404) (xy 377.279989 -401.884856) (xy 377.273492 -401.867671)
			(xy 377.267724 -401.860512) (xy 377.24584 -401.834863) (xy 377.20775 -401.779227) (xy 377.176599 -401.719429)
			(xy 377.152835 -401.65633) (xy 377.1368 -401.590838) (xy 377.128725 -401.523898) (xy 377.128727 -401.456472)
			(xy 377.136805 -401.389532) (xy 377.152843 -401.324042) (xy 377.176611 -401.260944) (xy 377.207765 -401.201147)
			(xy 377.245858 -401.145513) (xy 377.267724 -401.119848) (xy 377.273528 -401.112708) (xy 377.280037 -401.095513)
			(xy 377.280424 -401.08632) (xy 377.280424 -400.92884) (xy 377.280849 -400.918717) (xy 377.288589 -400.90001)
			(xy 377.302903 -400.885693) (xy 377.321609 -400.877951) (xy 377.331732 -400.877532) (xy 378.048012 -400.877532)
			(xy 378.058139 -400.877907) (xy 378.076849 -400.885665) (xy 378.091164 -400.899994) (xy 378.098904 -400.918712)
			(xy 378.09932 -400.92884) (xy 378.09932 -401.08632) (xy 378.099716 -401.095509) (xy 378.106239 -401.112693)
			(xy 378.11202 -401.119848) (xy 378.133864 -401.14553) (xy 378.171952 -401.201162) (xy 378.203102 -401.260957)
			(xy 378.226866 -401.324051) (xy 378.242903 -401.389538) (xy 378.25098 -401.456474) (xy 378.250982 -401.523896)
			(xy 378.242908 -401.590832) (xy 378.226875 -401.65632) (xy 378.203114 -401.719416) (xy 378.200833 -401.723796)
			(xy 379.328885 -401.723796) (xy 379.328887 -401.656371) (xy 379.336964 -401.589432) (xy 379.353001 -401.523942)
			(xy 379.376766 -401.460844) (xy 379.407918 -401.401047) (xy 379.446008 -401.345412) (xy 379.467872 -401.319746)
			(xy 379.473683 -401.312611) (xy 379.480187 -401.295412) (xy 379.480572 -401.286218) (xy 379.480572 -400.793966)
			(xy 379.480184 -400.784776) (xy 379.473656 -400.767592) (xy 379.467872 -400.760438) (xy 379.446015 -400.734767)
			(xy 379.407928 -400.679133) (xy 379.376778 -400.619337) (xy 379.353015 -400.556241) (xy 379.33698 -400.490753)
			(xy 379.328904 -400.423816) (xy 379.328904 -400.356393) (xy 379.336979 -400.289456) (xy 379.353013 -400.223967)
			(xy 379.376775 -400.160871) (xy 379.407923 -400.101075) (xy 379.446009 -400.04544) (xy 379.467872 -400.019774)
			(xy 379.473671 -400.012631) (xy 379.480182 -399.995438) (xy 379.480572 -399.986246) (xy 379.480572 -399.828766)
			(xy 379.481 -399.818633) (xy 379.488744 -399.799905) (xy 379.503049 -399.785549) (xy 379.521749 -399.777737)
			(xy 379.53188 -399.777204) (xy 380.24816 -399.777204) (xy 380.25828 -399.777649) (xy 380.276984 -399.785385)
			(xy 380.2913 -399.799693) (xy 380.299045 -399.818392) (xy 380.299468 -399.828512) (xy 380.299468 -399.986246)
			(xy 380.299911 -399.99543) (xy 380.306403 -400.012614) (xy 380.312168 -400.019774) (xy 380.334039 -400.045434)
			(xy 380.37213 -400.101068) (xy 380.403282 -400.160865) (xy 380.427047 -400.223963) (xy 380.443083 -400.289453)
			(xy 380.451159 -400.356392) (xy 380.451158 -400.423817) (xy 380.443082 -400.490756) (xy 380.427044 -400.556246)
			(xy 380.403278 -400.619343) (xy 380.372125 -400.679139) (xy 380.334033 -400.734773) (xy 380.312168 -400.760438)
			(xy 380.306369 -400.767581) (xy 380.299856 -400.784773) (xy 380.299468 -400.793966) (xy 380.299468 -401.286218)
			(xy 380.299877 -401.295405) (xy 380.306392 -401.312589) (xy 380.312168 -401.319746) (xy 380.334011 -401.345429)
			(xy 380.372103 -401.40106) (xy 380.403256 -401.460853) (xy 380.427023 -401.523948) (xy 380.443061 -401.589435)
			(xy 380.451139 -401.656372) (xy 380.451141 -401.723795) (xy 380.443067 -401.790732) (xy 380.427033 -401.85622)
			(xy 380.40327 -401.919316) (xy 380.37212 -401.979112) (xy 380.334032 -402.034745) (xy 380.312168 -402.06041)
			(xy 380.306381 -402.067562) (xy 380.299861 -402.084747) (xy 380.299468 -402.093938) (xy 380.299468 -402.251418)
			(xy 380.298989 -402.261545) (xy 380.291256 -402.280265) (xy 380.276968 -402.29462) (xy 380.258284 -402.30244)
			(xy 380.24816 -402.30298) (xy 379.53188 -402.30298) (xy 379.521754 -402.3026) (xy 379.503046 -402.294842)
			(xy 379.488731 -402.280514) (xy 379.48099 -402.261799) (xy 379.480572 -402.251672) (xy 379.480572 -402.093938)
			(xy 379.48015 -402.084752) (xy 379.473645 -402.067567) (xy 379.467872 -402.06041) (xy 379.445987 -402.034762)
			(xy 379.407901 -401.979124) (xy 379.376753 -401.919326) (xy 379.352991 -401.856227) (xy 379.336958 -401.790736)
			(xy 379.328885 -401.723796) (xy 378.200833 -401.723796) (xy 378.171967 -401.779212) (xy 378.133882 -401.834846)
			(xy 378.11202 -401.860512) (xy 378.106238 -401.867668) (xy 378.099714 -401.88485) (xy 378.09932 -401.89404)
			(xy 378.09932 -402.386292) (xy 378.099729 -402.395479) (xy 378.106243 -402.412664) (xy 378.11202 -402.41982)
			(xy 378.133836 -402.445524) (xy 378.171925 -402.501154) (xy 378.203077 -402.560945) (xy 378.226843 -402.624037)
			(xy 378.242881 -402.689521) (xy 378.25096 -402.756454) (xy 378.250965 -402.823818) (xy 381.529025 -402.823818)
			(xy 381.529029 -402.75651) (xy 381.537078 -402.689684) (xy 381.553055 -402.6243) (xy 381.576732 -402.561293)
			(xy 381.607769 -402.501568) (xy 381.645722 -402.445981) (xy 381.667512 -402.420328) (xy 381.673323 -402.413193)
			(xy 381.679829 -402.395995) (xy 381.680212 -402.3868) (xy 381.680212 -401.893532) (xy 381.679784 -401.884347)
			(xy 381.673282 -401.867162) (xy 381.667512 -401.860004) (xy 381.645705 -401.834368) (xy 381.607759 -401.778778)
			(xy 381.576728 -401.719052) (xy 381.553058 -401.656046) (xy 381.537087 -401.590662) (xy 381.529045 -401.523838)
			(xy 381.529046 -401.456532) (xy 381.537092 -401.389708) (xy 381.553066 -401.324325) (xy 381.57674 -401.26132)
			(xy 381.607774 -401.201596) (xy 381.645724 -401.146009) (xy 381.667512 -401.120356) (xy 381.673311 -401.113213)
			(xy 381.679824 -401.096021) (xy 381.680212 -401.086828) (xy 381.680212 -400.92884) (xy 381.680649 -400.918719)
			(xy 381.688386 -400.900014) (xy 381.702697 -400.885698) (xy 381.721399 -400.877953) (xy 381.73152 -400.877532)
			(xy 382.448054 -400.877532) (xy 382.458177 -400.878064) (xy 382.476895 -400.885775) (xy 382.491253 -400.900048)
			(xy 382.499075 -400.91872) (xy 382.499616 -400.92884) (xy 382.499616 -401.086828) (xy 382.500009 -401.096017)
			(xy 382.506534 -401.113201) (xy 382.512316 -401.120356) (xy 382.534085 -401.146024) (xy 382.572038 -401.201607)
			(xy 382.603074 -401.261328) (xy 382.62675 -401.32433) (xy 382.642726 -401.389711) (xy 382.650772 -401.456533)
			(xy 382.650774 -401.523837) (xy 382.642731 -401.590659) (xy 382.626759 -401.656041) (xy 382.603087 -401.719045)
			(xy 382.600649 -401.723737) (xy 383.729179 -401.723737) (xy 383.729181 -401.65643) (xy 383.737228 -401.589605)
			(xy 383.753204 -401.524222) (xy 383.77688 -401.461216) (xy 383.807917 -401.401492) (xy 383.84587 -401.345906)
			(xy 383.86766 -401.320254) (xy 383.873466 -401.313116) (xy 383.879973 -401.29592) (xy 383.88036 -401.286726)
			(xy 383.88036 -400.793458) (xy 383.879957 -400.78427) (xy 383.873437 -400.767087) (xy 383.86766 -400.75993)
			(xy 383.845878 -400.734273) (xy 383.807927 -400.678688) (xy 383.776893 -400.618965) (xy 383.753219 -400.555961)
			(xy 383.737245 -400.490579) (xy 383.7292 -400.423757) (xy 383.729199 -400.356452) (xy 383.737243 -400.28963)
			(xy 383.753216 -400.224247) (xy 383.776889 -400.161243) (xy 383.807923 -400.10152) (xy 383.845872 -400.045934)
			(xy 383.86766 -400.020282) (xy 383.873454 -400.013135) (xy 383.879969 -399.995946) (xy 383.88036 -399.986754)
			(xy 383.88036 -399.828766) (xy 383.880806 -399.818603) (xy 383.888596 -399.799829) (xy 383.902976 -399.785464)
			(xy 383.921759 -399.777695) (xy 383.931922 -399.777204) (xy 384.648202 -399.777204) (xy 384.658356 -399.777731)
			(xy 384.677118 -399.7855) (xy 384.691482 -399.799855) (xy 384.699263 -399.818613) (xy 384.699764 -399.828766)
			(xy 384.699764 -399.986754) (xy 384.700205 -399.995938) (xy 384.706698 -400.013122) (xy 384.712464 -400.020282)
			(xy 384.734258 -400.045929) (xy 384.772206 -400.101516) (xy 384.803239 -400.161241) (xy 384.826911 -400.224246)
			(xy 384.842884 -400.289629) (xy 384.850927 -400.356452) (xy 384.850927 -400.423757) (xy 384.842882 -400.49058)
			(xy 384.826909 -400.555963) (xy 384.803235 -400.618968) (xy 384.772201 -400.678691) (xy 384.734252 -400.734278)
			(xy 384.712464 -400.75993) (xy 384.706668 -400.767075) (xy 384.700154 -400.784266) (xy 384.699764 -400.793458)
			(xy 384.699764 -401.286726) (xy 384.70017 -401.295913) (xy 384.706687 -401.313097) (xy 384.712464 -401.320254)
			(xy 384.73423 -401.345924) (xy 384.772179 -401.401508) (xy 384.803213 -401.461229) (xy 384.826887 -401.524231)
			(xy 384.842861 -401.589611) (xy 384.850907 -401.656432) (xy 384.850909 -401.723735) (xy 384.842867 -401.790556)
			(xy 384.826897 -401.855937) (xy 384.803227 -401.918941) (xy 384.772196 -401.978663) (xy 384.73425 -402.03425)
			(xy 384.712464 -402.059902) (xy 384.706679 -402.067056) (xy 384.700158 -402.08424) (xy 384.699764 -402.09343)
			(xy 384.699764 -402.251418) (xy 384.699282 -402.261577) (xy 384.691502 -402.280346) (xy 384.677133 -402.294711)
			(xy 384.658361 -402.302485) (xy 384.648202 -402.30298) (xy 383.931922 -402.30298) (xy 383.921754 -402.302518)
			(xy 383.902963 -402.294744) (xy 383.888578 -402.28037) (xy 383.88079 -402.261586) (xy 383.88036 -402.251418)
			(xy 383.88036 -402.09343) (xy 383.879922 -402.084246) (xy 383.873426 -402.067062) (xy 383.86766 -402.059902)
			(xy 383.84585 -402.034268) (xy 383.8079 -401.97868) (xy 383.776867 -401.918954) (xy 383.753194 -401.855947)
			(xy 383.737222 -401.790562) (xy 383.729179 -401.723737) (xy 382.600649 -401.723737) (xy 382.572053 -401.778767)
			(xy 382.534104 -401.834352) (xy 382.512316 -401.860004) (xy 382.506537 -401.867162) (xy 382.500011 -401.884343)
			(xy 382.499616 -401.893532) (xy 382.499616 -402.3868) (xy 382.500023 -402.395988) (xy 382.506538 -402.413172)
			(xy 382.512316 -402.420328) (xy 382.534058 -402.446018) (xy 382.572011 -402.501598) (xy 382.603049 -402.561316)
			(xy 382.626726 -402.624316) (xy 382.642704 -402.689694) (xy 382.650753 -402.756513) (xy 382.650757 -402.823815)
			(xy 382.650749 -402.823878) (xy 385.928793 -402.823878) (xy 385.928798 -402.75645) (xy 385.936878 -402.689508)
			(xy 385.952919 -402.624017) (xy 385.976689 -402.560918) (xy 386.007846 -402.50112) (xy 386.045941 -402.445485)
			(xy 386.067808 -402.41982) (xy 386.073622 -402.412687) (xy 386.080126 -402.395487) (xy 386.080508 -402.386292)
			(xy 386.080508 -401.89404) (xy 386.080077 -401.884855) (xy 386.073578 -401.867671) (xy 386.067808 -401.860512)
			(xy 386.045924 -401.834863) (xy 386.007835 -401.779226) (xy 385.976685 -401.719428) (xy 385.952922 -401.656329)
			(xy 385.936887 -401.590838) (xy 385.928813 -401.523898) (xy 385.928815 -401.456472) (xy 385.936893 -401.389533)
			(xy 385.952931 -401.324042) (xy 385.976697 -401.260944) (xy 386.007851 -401.201148) (xy 386.045943 -401.145513)
			(xy 386.067808 -401.119848) (xy 386.07361 -401.112707) (xy 386.080121 -401.095513) (xy 386.080508 -401.08632)
			(xy 386.080508 -400.92884) (xy 386.080949 -400.918719) (xy 386.088686 -400.900015) (xy 386.102995 -400.885699)
			(xy 386.121695 -400.877954) (xy 386.131816 -400.877532) (xy 386.848096 -400.877532) (xy 386.858222 -400.87792)
			(xy 386.876932 -400.885673) (xy 386.891247 -400.899998) (xy 386.898987 -400.918714) (xy 386.899404 -400.92884)
			(xy 386.899404 -401.08632) (xy 386.899804 -401.095508) (xy 386.906325 -401.112692) (xy 386.912104 -401.119848)
			(xy 386.933948 -401.14553) (xy 386.972037 -401.201162) (xy 387.003189 -401.260956) (xy 387.026954 -401.324051)
			(xy 387.04299 -401.389538) (xy 387.051068 -401.456474) (xy 387.05107 -401.523896) (xy 387.042996 -401.590833)
			(xy 387.026963 -401.656321) (xy 387.003201 -401.719417) (xy 387.000951 -401.723737) (xy 388.12897 -401.723737)
			(xy 388.128972 -401.65643) (xy 388.137019 -401.589606) (xy 388.152994 -401.524222) (xy 388.17667 -401.461217)
			(xy 388.207706 -401.401492) (xy 388.245659 -401.345906) (xy 388.267448 -401.320254) (xy 388.273253 -401.313115)
			(xy 388.279761 -401.295919) (xy 388.280148 -401.286726) (xy 388.280148 -400.793458) (xy 388.279747 -400.78427)
			(xy 388.273226 -400.767086) (xy 388.267448 -400.75993) (xy 388.245666 -400.734273) (xy 388.207717 -400.678687)
			(xy 388.176683 -400.618965) (xy 388.153009 -400.555961) (xy 388.137035 -400.490579) (xy 388.128991 -400.423757)
			(xy 388.12899 -400.356452) (xy 388.137034 -400.28963) (xy 388.153006 -400.224248) (xy 388.176679 -400.161244)
			(xy 388.207712 -400.10152) (xy 388.245661 -400.045934) (xy 388.267448 -400.020282) (xy 388.273241 -400.013134)
			(xy 388.279756 -399.995946) (xy 388.280148 -399.986754) (xy 388.280148 -399.828766) (xy 388.280606 -399.818605)
			(xy 388.288393 -399.799833) (xy 388.30277 -399.785469) (xy 388.321548 -399.777697) (xy 388.33171 -399.777204)
			(xy 389.04799 -399.777204) (xy 389.058143 -399.777741) (xy 389.076905 -399.785506) (xy 389.09127 -399.799858)
			(xy 389.099051 -399.818613) (xy 389.099552 -399.828766) (xy 389.099552 -399.986754) (xy 389.099995 -399.995937)
			(xy 389.106487 -400.013121) (xy 389.112252 -400.020282) (xy 389.134046 -400.045929) (xy 389.171995 -400.101516)
			(xy 389.203029 -400.16124) (xy 389.226702 -400.224245) (xy 389.242675 -400.289628) (xy 389.250718 -400.356452)
			(xy 389.250718 -400.423757) (xy 389.242673 -400.490581) (xy 389.226699 -400.555963) (xy 389.203025 -400.618968)
			(xy 389.171991 -400.678692) (xy 389.134041 -400.734278) (xy 389.112252 -400.75993) (xy 389.106454 -400.767074)
			(xy 389.099942 -400.784266) (xy 389.099552 -400.793458) (xy 389.099552 -401.286726) (xy 389.09996 -401.295913)
			(xy 389.106477 -401.313097) (xy 389.112252 -401.320254) (xy 389.134018 -401.345924) (xy 389.171968 -401.401508)
			(xy 389.203003 -401.461229) (xy 389.226677 -401.524231) (xy 389.242652 -401.589611) (xy 389.250698 -401.656432)
			(xy 389.2507 -401.723735) (xy 389.242658 -401.790556) (xy 389.226687 -401.855937) (xy 389.203016 -401.918941)
			(xy 389.171985 -401.978664) (xy 389.134038 -402.03425) (xy 389.112252 -402.059902) (xy 389.106466 -402.067055)
			(xy 389.099946 -402.08424) (xy 389.099552 -402.09343) (xy 389.099552 -402.251418) (xy 389.099081 -402.261578)
			(xy 389.091299 -402.28035) (xy 389.076926 -402.294715) (xy 389.05815 -402.302487) (xy 389.04799 -402.30298)
			(xy 388.33171 -402.30298) (xy 388.321555 -402.302459) (xy 388.30279 -402.294691) (xy 388.288425 -402.280334)
			(xy 388.280647 -402.261573) (xy 388.280148 -402.251418) (xy 388.280148 -402.09343) (xy 388.279713 -402.084246)
			(xy 388.273215 -402.067062) (xy 388.267448 -402.059902) (xy 388.245638 -402.034268) (xy 388.207689 -401.978679)
			(xy 388.176657 -401.918953) (xy 388.152985 -401.855946) (xy 388.137013 -401.790562) (xy 388.12897 -401.723737)
			(xy 387.000951 -401.723737) (xy 386.972053 -401.779212) (xy 386.933967 -401.834847) (xy 386.912104 -401.860512)
			(xy 386.90632 -401.867666) (xy 386.899798 -401.88485) (xy 386.899404 -401.89404) (xy 386.899404 -402.386292)
			(xy 386.899817 -402.395479) (xy 386.906329 -402.412663) (xy 386.912104 -402.41982) (xy 386.933921 -402.445524)
			(xy 386.972011 -402.501153) (xy 387.003163 -402.560944) (xy 387.02693 -402.624036) (xy 387.042968 -402.68952)
			(xy 387.051048 -402.756454) (xy 387.051052 -402.823818) (xy 390.329113 -402.823818) (xy 390.329117 -402.75651)
			(xy 390.337166 -402.689685) (xy 390.353142 -402.6243) (xy 390.376819 -402.561294) (xy 390.407855 -402.501569)
			(xy 390.445807 -402.445981) (xy 390.467596 -402.420328) (xy 390.473405 -402.413192) (xy 390.479912 -402.395994)
			(xy 390.480296 -402.3868) (xy 390.480296 -401.893532) (xy 390.479871 -401.884346) (xy 390.473368 -401.867162)
			(xy 390.467596 -401.860004) (xy 390.44579 -401.834367) (xy 390.407845 -401.778778) (xy 390.376815 -401.719052)
			(xy 390.353145 -401.656045) (xy 390.337174 -401.590661) (xy 390.329133 -401.523838) (xy 390.329134 -401.456532)
			(xy 390.33718 -401.389709) (xy 390.353154 -401.324326) (xy 390.376827 -401.261321) (xy 390.40786 -401.201596)
			(xy 390.445808 -401.146009) (xy 390.467596 -401.120356) (xy 390.473393 -401.113211) (xy 390.479908 -401.09602)
			(xy 390.480296 -401.086828) (xy 390.480296 -400.92884) (xy 390.480749 -400.918721) (xy 390.488483 -400.900019)
			(xy 390.502788 -400.885703) (xy 390.521485 -400.877956) (xy 390.531604 -400.877532) (xy 391.248138 -400.877532)
			(xy 391.258266 -400.877995) (xy 391.276987 -400.885734) (xy 391.291341 -400.900027) (xy 391.299161 -400.918714)
			(xy 391.2997 -400.92884) (xy 391.2997 -401.086828) (xy 391.300096 -401.096017) (xy 391.30662 -401.113201)
			(xy 391.3124 -401.120356) (xy 391.334167 -401.146025) (xy 391.372114 -401.20161) (xy 391.403146 -401.261331)
			(xy 391.426818 -401.324334) (xy 391.442791 -401.389713) (xy 391.450836 -401.456534) (xy 391.450838 -401.523836)
			(xy 391.442797 -401.590657) (xy 391.426827 -401.656038) (xy 391.403158 -401.719041) (xy 391.372129 -401.778764)
			(xy 391.334185 -401.834351) (xy 391.3124 -401.860004) (xy 391.306619 -401.86716) (xy 391.300095 -401.884342)
			(xy 391.2997 -401.893532) (xy 391.2997 -402.3868) (xy 391.30011 -402.395987) (xy 391.306624 -402.413171)
			(xy 391.3124 -402.420328) (xy 391.334139 -402.446019) (xy 391.372087 -402.501601) (xy 391.40312 -402.56132)
			(xy 391.426794 -402.624319) (xy 391.442769 -402.689696) (xy 391.450817 -402.756514) (xy 391.450821 -402.823814)
			(xy 391.442782 -402.890633) (xy 391.426815 -402.956012) (xy 391.40315 -403.019014) (xy 391.372124 -403.078737)
			(xy 391.334184 -403.134323) (xy 391.3124 -403.159976) (xy 391.306589 -403.167111) (xy 391.300083 -403.184309)
			(xy 391.2997 -403.193504) (xy 391.2997 -403.351492) (xy 391.299277 -403.361614) (xy 391.291532 -403.380317)
			(xy 391.277217 -403.394632) (xy 391.258514 -403.402377) (xy 391.248392 -403.4028) (xy 390.531858 -403.4028)
			(xy 390.521734 -403.402309) (xy 390.503019 -403.394575) (xy 390.488666 -403.380291) (xy 390.480841 -403.361614)
			(xy 390.480296 -403.351492) (xy 390.480296 -403.193504) (xy 390.479885 -403.184317) (xy 390.473372 -403.167133)
			(xy 390.467596 -403.159976) (xy 390.445763 -403.134362) (xy 390.407818 -403.078769) (xy 390.376789 -403.01904)
			(xy 390.353121 -402.95603) (xy 390.337153 -402.890644) (xy 390.329113 -402.823818) (xy 387.051052 -402.823818)
			(xy 387.051052 -402.823874) (xy 387.042981 -402.890809) (xy 387.026951 -402.956295) (xy 387.003193 -403.01939)
			(xy 386.972048 -403.079185) (xy 386.933965 -403.134819) (xy 386.912104 -403.160484) (xy 386.90629 -403.167617)
			(xy 386.899785 -403.184817) (xy 386.899404 -403.194012) (xy 386.899404 -403.351492) (xy 386.898978 -403.361613)
			(xy 386.891233 -403.380316) (xy 386.87692 -403.394631) (xy 386.858217 -403.402377) (xy 386.848096 -403.4028)
			(xy 386.131816 -403.4028) (xy 386.121695 -403.402371) (xy 386.102991 -403.394628) (xy 386.088676 -403.380315)
			(xy 386.080931 -403.361613) (xy 386.080508 -403.351492) (xy 386.080508 -403.194012) (xy 386.08009 -403.184826)
			(xy 386.073582 -403.167641) (xy 386.067808 -403.160484) (xy 386.045897 -403.134858) (xy 386.007809 -403.079218)
			(xy 385.97666 -403.019416) (xy 385.952898 -402.956314) (xy 385.936865 -402.89082) (xy 385.928793 -402.823878)
			(xy 382.650749 -402.823878) (xy 382.642717 -402.890635) (xy 382.626748 -402.956015) (xy 382.603078 -403.019018)
			(xy 382.572048 -403.07874) (xy 382.534102 -403.134324) (xy 382.512316 -403.159976) (xy 382.506507 -403.167112)
			(xy 382.499999 -403.18431) (xy 382.499616 -403.193504) (xy 382.499616 -403.351492) (xy 382.499109 -403.361598)
			(xy 382.491377 -403.380273) (xy 382.477087 -403.394568) (xy 382.458414 -403.402306) (xy 382.448308 -403.4028)
			(xy 381.731774 -403.4028) (xy 381.721651 -403.402296) (xy 381.702936 -403.394567) (xy 381.688582 -403.380287)
			(xy 381.680757 -403.361613) (xy 381.680212 -403.351492) (xy 381.680212 -403.193504) (xy 381.679797 -403.184317)
			(xy 381.673286 -403.167133) (xy 381.667512 -403.159976) (xy 381.645678 -403.134362) (xy 381.607732 -403.07877)
			(xy 381.576703 -403.019041) (xy 381.553034 -402.956031) (xy 381.537065 -402.890644) (xy 381.529025 -402.823818)
			(xy 378.250965 -402.823818) (xy 378.250965 -402.823874) (xy 378.242894 -402.890808) (xy 378.226864 -402.956294)
			(xy 378.203106 -403.019389) (xy 378.171962 -403.079184) (xy 378.13388 -403.134818) (xy 378.11202 -403.160484)
			(xy 378.106208 -403.167618) (xy 378.099702 -403.184817) (xy 378.09932 -403.194012) (xy 378.09932 -403.351492)
			(xy 378.098809 -403.361598) (xy 378.091078 -403.380272) (xy 378.076789 -403.394566) (xy 378.058118 -403.402305)
			(xy 378.048012 -403.4028) (xy 377.331732 -403.4028) (xy 377.321612 -403.402358) (xy 377.302909 -403.39462)
			(xy 377.288593 -403.380312) (xy 377.280847 -403.361612) (xy 377.280424 -403.351492) (xy 377.280424 -403.194012)
			(xy 377.280002 -403.184826) (xy 377.273496 -403.167642) (xy 377.267724 -403.160484) (xy 377.245812 -403.134858)
			(xy 377.207723 -403.079218) (xy 377.176573 -403.019417) (xy 377.152811 -402.956315) (xy 377.136778 -402.890821)
			(xy 377.128705 -402.823878) (xy 347.450903 -402.823878) (xy 347.442872 -402.890633) (xy 347.426905 -402.956012)
			(xy 347.403239 -403.019015) (xy 347.372213 -403.078737) (xy 347.334272 -403.134323) (xy 347.312488 -403.159976)
			(xy 347.306675 -403.16711) (xy 347.300171 -403.184309) (xy 347.299788 -403.193504) (xy 347.299788 -403.351492)
			(xy 347.299372 -403.361647) (xy 347.291576 -403.380402) (xy 347.277178 -403.394726) (xy 347.258383 -403.402424)
			(xy 347.248226 -403.4028) (xy 346.531946 -403.4028) (xy 346.521827 -403.402237) (xy 346.503115 -403.394532)
			(xy 346.488758 -403.380269) (xy 346.48093 -403.361607) (xy 346.480384 -403.351492) (xy 346.480384 -403.193504)
			(xy 346.479975 -403.184317) (xy 346.473461 -403.167132) (xy 346.467684 -403.159976) (xy 346.445847 -403.134364)
			(xy 346.407897 -403.078772) (xy 346.376863 -403.019044) (xy 346.353191 -402.956034) (xy 346.33722 -402.890646)
			(xy 346.329179 -402.823819) (xy 343.051143 -402.823819) (xy 343.051143 -402.823874) (xy 343.043072 -402.890809)
			(xy 343.027042 -402.956296) (xy 343.003282 -403.019391) (xy 342.972137 -403.079185) (xy 342.934053 -403.134819)
			(xy 342.912192 -403.160484) (xy 342.906376 -403.167616) (xy 342.899873 -403.184817) (xy 342.899492 -403.194012)
			(xy 342.899492 -403.351492) (xy 342.899077 -403.361615) (xy 342.89133 -403.38032) (xy 342.877013 -403.394635)
			(xy 342.858307 -403.402379) (xy 342.848184 -403.4028) (xy 342.131904 -403.4028) (xy 342.121782 -403.402381)
			(xy 342.103078 -403.394634) (xy 342.088764 -403.380318) (xy 342.081019 -403.361614) (xy 342.080596 -403.351492)
			(xy 342.080596 -403.194012) (xy 342.080181 -403.184825) (xy 342.073671 -403.167641) (xy 342.067896 -403.160484)
			(xy 342.045985 -403.134858) (xy 342.007898 -403.079217) (xy 341.97675 -403.019416) (xy 341.952988 -402.956314)
			(xy 341.936956 -402.89082) (xy 341.928884 -402.823878) (xy 338.650816 -402.823878) (xy 338.642785 -402.890633)
			(xy 338.626819 -402.956012) (xy 338.603153 -403.019014) (xy 338.572128 -403.078737) (xy 338.534188 -403.134323)
			(xy 338.512404 -403.159976) (xy 338.506593 -403.167111) (xy 338.500087 -403.184309) (xy 338.499704 -403.193504)
			(xy 338.499704 -403.351492) (xy 338.499272 -403.361645) (xy 338.49148 -403.380397) (xy 338.477086 -403.39472)
			(xy 338.458297 -403.402421) (xy 338.448142 -403.4028) (xy 337.731862 -403.4028) (xy 337.721738 -403.402306)
			(xy 337.703023 -403.394573) (xy 337.68867 -403.38029) (xy 337.680845 -403.361614) (xy 337.6803 -403.351492)
			(xy 337.6803 -403.193504) (xy 337.679888 -403.184317) (xy 337.673375 -403.167133) (xy 337.6676 -403.159976)
			(xy 337.645766 -403.134362) (xy 337.607822 -403.078769) (xy 337.576793 -403.01904) (xy 337.553124 -402.956031)
			(xy 337.537156 -402.890644) (xy 337.529116 -402.823818) (xy 334.251055 -402.823818) (xy 334.251055 -402.823874)
			(xy 334.242984 -402.890809) (xy 334.226954 -402.956295) (xy 334.203196 -403.01939) (xy 334.172051 -403.079185)
			(xy 334.133969 -403.134819) (xy 334.112108 -403.160484) (xy 334.106294 -403.167617) (xy 334.09979 -403.184817)
			(xy 334.099408 -403.194012) (xy 334.099408 -403.351492) (xy 334.098978 -403.361613) (xy 334.091234 -403.380315)
			(xy 334.076922 -403.394629) (xy 334.058221 -403.402376) (xy 334.0481 -403.4028) (xy 333.33182 -403.4028)
			(xy 333.321699 -403.402368) (xy 333.302996 -403.394626) (xy 333.288681 -403.380315) (xy 333.280935 -403.361613)
			(xy 333.280512 -403.351492) (xy 333.280512 -403.194012) (xy 333.280093 -403.184826) (xy 333.273585 -403.167642)
			(xy 333.267812 -403.160484) (xy 333.2459 -403.134858) (xy 333.207812 -403.079218) (xy 333.176663 -403.019417)
			(xy 333.152901 -402.956315) (xy 333.136869 -402.890821) (xy 333.128796 -402.823878) (xy 326.525636 -402.823878)
			(xy 326.525636 -405.623648) (xy 330.929194 -405.623648) (xy 330.929195 -405.556343) (xy 330.93724 -405.489519)
			(xy 330.953214 -405.424136) (xy 330.976889 -405.361131) (xy 331.007924 -405.301408) (xy 331.045875 -405.245822)
			(xy 331.067664 -405.22017) (xy 331.073464 -405.213027) (xy 331.079975 -405.195835) (xy 331.080364 -405.186642)
			(xy 331.080364 -404.693374) (xy 331.079952 -404.684187) (xy 331.073438 -404.667004) (xy 331.067664 -404.659846)
			(xy 331.045897 -404.634176) (xy 331.007946 -404.578593) (xy 330.976911 -404.518872) (xy 330.953235 -404.45587)
			(xy 330.93726 -404.390489) (xy 330.929214 -404.323668) (xy 330.929212 -404.256365) (xy 330.937254 -404.189543)
			(xy 330.953226 -404.124162) (xy 330.976897 -404.061158) (xy 331.007929 -404.001435) (xy 331.045877 -403.94585)
			(xy 331.067664 -403.920198) (xy 331.073452 -403.913047) (xy 331.07997 -403.895861) (xy 331.080364 -403.88667)
			(xy 331.080364 -403.728682) (xy 331.08075 -403.718506) (xy 331.088546 -403.699706) (xy 331.102943 -403.685321)
			(xy 331.12175 -403.677541) (xy 331.131926 -403.67712) (xy 331.848206 -403.67712) (xy 331.858362 -403.677628)
			(xy 331.877128 -403.685401) (xy 331.891492 -403.699762) (xy 331.899269 -403.718526) (xy 331.899768 -403.728682)
			(xy 331.899768 -403.88667) (xy 331.9002 -403.895855) (xy 331.906699 -403.913039) (xy 331.912468 -403.920198)
			(xy 331.934277 -403.945832) (xy 331.972225 -404.001422) (xy 332.003257 -404.061148) (xy 332.026928 -404.124154)
			(xy 332.042899 -404.189539) (xy 332.050942 -404.256363) (xy 332.05094 -404.32367) (xy 332.042893 -404.390494)
			(xy 332.026918 -404.455877) (xy 332.003243 -404.518883) (xy 331.972208 -404.578607) (xy 331.934257 -404.634194)
			(xy 331.912468 -404.659846) (xy 331.906665 -404.666987) (xy 331.900155 -404.684181) (xy 331.899768 -404.693374)
			(xy 331.899768 -405.186642) (xy 331.900165 -405.19583) (xy 331.906689 -405.213014) (xy 331.912468 -405.22017)
			(xy 331.93425 -405.245827) (xy 331.972198 -405.301413) (xy 332.003231 -405.361136) (xy 332.026904 -405.42414)
			(xy 332.042877 -405.489521) (xy 332.050922 -405.556343) (xy 332.050923 -405.623648) (xy 332.042879 -405.69047)
			(xy 332.026907 -405.755852) (xy 332.003235 -405.818856) (xy 331.972203 -405.878579) (xy 331.934255 -405.934166)
			(xy 331.912468 -405.959818) (xy 331.906677 -405.966967) (xy 331.90016 -405.984155) (xy 331.899768 -405.993346)
			(xy 331.899768 -406.151334) (xy 331.899295 -406.161493) (xy 331.89151 -406.180262) (xy 331.877138 -406.194626)
			(xy 331.858365 -406.2024) (xy 331.848206 -406.202896) (xy 331.131926 -406.202896) (xy 331.121774 -406.202346)
			(xy 331.103012 -406.194587) (xy 331.088647 -406.180238) (xy 331.080865 -406.161485) (xy 331.080364 -406.151334)
			(xy 331.080364 -405.993346) (xy 331.079918 -405.984163) (xy 331.073428 -405.966979) (xy 331.067664 -405.959818)
			(xy 331.04587 -405.934171) (xy 331.007919 -405.878584) (xy 330.976885 -405.81886) (xy 330.953212 -405.755855)
			(xy 330.937238 -405.690472) (xy 330.929194 -405.623648) (xy 326.525636 -405.623648) (xy 326.525636 -406.723789)
			(xy 333.128808 -406.723789) (xy 333.128811 -406.656363) (xy 333.13689 -406.589422) (xy 333.152929 -406.523931)
			(xy 333.176697 -406.460833) (xy 333.207852 -406.401036) (xy 333.245946 -406.345401) (xy 333.267812 -406.319736)
			(xy 333.27362 -406.312599) (xy 333.280127 -406.295402) (xy 333.280512 -406.286208) (xy 333.280512 -405.793956)
			(xy 333.28012 -405.784767) (xy 333.273594 -405.767583) (xy 333.267812 -405.760428) (xy 333.245944 -405.734766)
			(xy 333.207854 -405.679131) (xy 333.176703 -405.619335) (xy 333.152939 -405.556238) (xy 333.136903 -405.490748)
			(xy 333.128827 -405.423809) (xy 333.128828 -405.356385) (xy 333.136904 -405.289446) (xy 333.15294 -405.223957)
			(xy 333.176706 -405.16086) (xy 333.207857 -405.101063) (xy 333.245947 -405.045429) (xy 333.267812 -405.019764)
			(xy 333.273608 -405.012618) (xy 333.280123 -404.995428) (xy 333.280512 -404.986236) (xy 333.280512 -404.828756)
			(xy 333.280949 -404.818643) (xy 333.288704 -404.799961) (xy 333.303015 -404.785668) (xy 333.321706 -404.777937)
			(xy 333.33182 -404.777448) (xy 334.0481 -404.777448) (xy 334.058202 -404.777984) (xy 334.076871 -404.785712)
			(xy 334.091163 -404.799993) (xy 334.098907 -404.818654) (xy 334.099408 -404.828756) (xy 334.099408 -404.986236)
			(xy 334.099799 -404.995425) (xy 334.106326 -405.01261) (xy 334.112108 -405.019764) (xy 334.133968 -405.045433)
			(xy 334.172056 -405.101067) (xy 334.203206 -405.160863) (xy 334.226971 -405.223959) (xy 334.243006 -405.289448)
			(xy 334.251082 -405.356385) (xy 334.251082 -405.423809) (xy 334.243007 -405.490746) (xy 334.226972 -405.556235)
			(xy 334.203209 -405.619332) (xy 334.20093 -405.623707) (xy 335.328987 -405.623707) (xy 335.328987 -405.556284)
			(xy 335.337063 -405.489346) (xy 335.353098 -405.423857) (xy 335.376861 -405.36076) (xy 335.40801 -405.300963)
			(xy 335.446097 -405.245328) (xy 335.46796 -405.219662) (xy 335.473763 -405.212521) (xy 335.480272 -405.195327)
			(xy 335.48066 -405.186134) (xy 335.48066 -404.693882) (xy 335.480245 -404.684696) (xy 335.473733 -404.667512)
			(xy 335.46796 -404.660354) (xy 335.446119 -404.63467) (xy 335.408032 -404.579037) (xy 335.376883 -404.519243)
			(xy 335.353119 -404.456149) (xy 335.337083 -404.390663) (xy 335.329006 -404.323727) (xy 335.329004 -404.256306)
			(xy 335.337078 -404.18937) (xy 335.353109 -404.123883) (xy 335.376869 -404.060787) (xy 335.408015 -404.000991)
			(xy 335.446099 -403.945356) (xy 335.46796 -403.91969) (xy 335.473751 -403.912541) (xy 335.480267 -403.895353)
			(xy 335.48066 -403.886162) (xy 335.48066 -403.728682) (xy 335.481112 -403.718552) (xy 335.48885 -403.699826)
			(xy 335.503147 -403.68547) (xy 335.52184 -403.677655) (xy 335.531968 -403.67712) (xy 336.248248 -403.67712)
			(xy 336.258408 -403.677483) (xy 336.277165 -403.685298) (xy 336.291487 -403.699713) (xy 336.299182 -403.71852)
			(xy 336.299556 -403.728682) (xy 336.299556 -403.886162) (xy 336.299995 -403.895346) (xy 336.30649 -403.91253)
			(xy 336.312256 -403.91969) (xy 336.334143 -403.945337) (xy 336.372234 -404.000973) (xy 336.403386 -404.060771)
			(xy 336.427151 -404.123871) (xy 336.443186 -404.189362) (xy 336.451261 -404.256303) (xy 336.451259 -404.32373)
			(xy 336.443181 -404.39067) (xy 336.427141 -404.456161) (xy 336.403373 -404.519259) (xy 336.372217 -404.579056)
			(xy 336.334123 -404.634689) (xy 336.312256 -404.660354) (xy 336.306449 -404.667491) (xy 336.299941 -404.684688)
			(xy 336.299556 -404.693882) (xy 336.299556 -405.186134) (xy 336.29996 -405.195322) (xy 336.306479 -405.212505)
			(xy 336.312256 -405.219662) (xy 336.334116 -405.245331) (xy 336.372207 -405.300964) (xy 336.403361 -405.360759)
			(xy 336.427127 -405.423856) (xy 336.443164 -405.489345) (xy 336.451242 -405.556283) (xy 336.451242 -405.623708)
			(xy 336.443166 -405.690646) (xy 336.42713 -405.756135) (xy 336.403365 -405.819232) (xy 336.372212 -405.879028)
			(xy 336.334121 -405.934662) (xy 336.312256 -405.960326) (xy 336.30646 -405.967472) (xy 336.299946 -405.984662)
			(xy 336.299556 -405.993854) (xy 336.299556 -406.151334) (xy 336.299101 -406.161463) (xy 336.291362 -406.180186)
			(xy 336.277066 -406.194541) (xy 336.258375 -406.202359) (xy 336.248248 -406.202896) (xy 335.531968 -406.202896)
			(xy 335.521811 -406.202505) (xy 335.503057 -406.194698) (xy 335.488735 -406.180292) (xy 335.481037 -406.161493)
			(xy 335.48066 -406.151334) (xy 335.48066 -405.993854) (xy 335.48021 -405.984671) (xy 335.473722 -405.967487)
			(xy 335.46796 -405.960326) (xy 335.446092 -405.934665) (xy 335.408006 -405.879029) (xy 335.376857 -405.819232)
			(xy 335.353095 -405.756134) (xy 335.337062 -405.690645) (xy 335.328987 -405.623707) (xy 334.20093 -405.623707)
			(xy 334.172059 -405.679128) (xy 334.133971 -405.734763) (xy 334.112108 -405.760428) (xy 334.106318 -405.767578)
			(xy 334.099799 -405.784765) (xy 334.099408 -405.793956) (xy 334.099408 -406.286208) (xy 334.099813 -406.295396)
			(xy 334.10633 -406.31258) (xy 334.112108 -406.319736) (xy 334.13394 -406.345427) (xy 334.172029 -406.401058)
			(xy 334.203181 -406.460851) (xy 334.226947 -406.523944) (xy 334.242984 -406.58943) (xy 334.251062 -406.656365)
			(xy 334.251065 -406.723729) (xy 337.529127 -406.723729) (xy 337.52913 -406.656423) (xy 337.537177 -406.589598)
			(xy 337.553152 -406.524215) (xy 337.576827 -406.461209) (xy 337.607861 -406.401484) (xy 337.645812 -406.345897)
			(xy 337.6676 -406.320244) (xy 337.673403 -406.313103) (xy 337.679914 -406.295909) (xy 337.6803 -406.286716)
			(xy 337.6803 -405.793448) (xy 337.679867 -405.784263) (xy 337.673369 -405.767079) (xy 337.6676 -405.75992)
			(xy 337.64581 -405.734271) (xy 337.607863 -405.678683) (xy 337.576832 -405.618958) (xy 337.553162 -405.555954)
			(xy 337.53719 -405.490572) (xy 337.529147 -405.423749) (xy 337.529147 -405.356445) (xy 337.537191 -405.289622)
			(xy 337.553163 -405.224241) (xy 337.576835 -405.161236) (xy 337.607866 -405.101512) (xy 337.645813 -405.045925)
			(xy 337.6676 -405.020272) (xy 337.673391 -405.013123) (xy 337.679909 -404.995935) (xy 337.6803 -404.986744)
			(xy 337.6803 -404.828756) (xy 337.680686 -404.818599) (xy 337.688496 -404.799846) (xy 337.702903 -404.785524)
			(xy 337.721703 -404.777826) (xy 337.731862 -404.777448) (xy 338.448142 -404.777448) (xy 338.458272 -404.777892)
			(xy 338.476996 -404.785635) (xy 338.491351 -404.799934) (xy 338.499167 -404.818628) (xy 338.499704 -404.828756)
			(xy 338.499704 -404.986744) (xy 338.500092 -404.995934) (xy 338.506621 -405.013118) (xy 338.512404 -405.020272)
			(xy 338.534186 -405.045928) (xy 338.572133 -405.101515) (xy 338.603164 -405.161238) (xy 338.626835 -405.224242)
			(xy 338.642807 -405.289624) (xy 338.650851 -405.356445) (xy 338.650851 -405.423749) (xy 338.642808 -405.490571)
			(xy 338.626837 -405.555952) (xy 338.603166 -405.618956) (xy 338.600728 -405.623648) (xy 339.729282 -405.623648)
			(xy 339.729282 -405.556343) (xy 339.737327 -405.489519) (xy 339.753301 -405.424137) (xy 339.776975 -405.361132)
			(xy 339.808009 -405.301408) (xy 339.845959 -405.245822) (xy 339.867748 -405.22017) (xy 339.873546 -405.213026)
			(xy 339.880058 -405.195834) (xy 339.880448 -405.186642) (xy 339.880448 -404.693374) (xy 339.88004 -404.684187)
			(xy 339.873523 -404.667003) (xy 339.867748 -404.659846) (xy 339.845982 -404.634176) (xy 339.808032 -404.578592)
			(xy 339.776997 -404.518871) (xy 339.753323 -404.455869) (xy 339.737348 -404.390489) (xy 339.729302 -404.323668)
			(xy 339.7293 -404.256365) (xy 339.737342 -404.189544) (xy 339.753313 -404.124163) (xy 339.776984 -404.061159)
			(xy 339.808015 -404.001436) (xy 339.845962 -403.94585) (xy 339.867748 -403.920198) (xy 339.873534 -403.913045)
			(xy 339.880054 -403.89586) (xy 339.880448 -403.88667) (xy 339.880448 -403.728682) (xy 339.880919 -403.718522)
			(xy 339.888701 -403.69975) (xy 339.903074 -403.685385) (xy 339.92185 -403.677613) (xy 339.93201 -403.67712)
			(xy 340.64829 -403.67712) (xy 340.658445 -403.677641) (xy 340.67721 -403.685409) (xy 340.691575 -403.699766)
			(xy 340.699353 -403.718527) (xy 340.699852 -403.728682) (xy 340.699852 -403.88667) (xy 340.700287 -403.895854)
			(xy 340.706785 -403.913038) (xy 340.712552 -403.920198) (xy 340.734362 -403.945832) (xy 340.772311 -404.001421)
			(xy 340.803343 -404.061147) (xy 340.827015 -404.124154) (xy 340.842987 -404.189538) (xy 340.85103 -404.256363)
			(xy 340.851028 -404.32367) (xy 340.842981 -404.390494) (xy 340.827006 -404.455878) (xy 340.80333 -404.518883)
			(xy 340.772294 -404.578608) (xy 340.734341 -404.634194) (xy 340.712552 -404.659846) (xy 340.706747 -404.666985)
			(xy 340.700239 -404.684181) (xy 340.699852 -404.693374) (xy 340.699852 -405.186642) (xy 340.700253 -405.19583)
			(xy 340.706774 -405.213014) (xy 340.712552 -405.22017) (xy 340.734334 -405.245827) (xy 340.772283 -405.301413)
			(xy 340.803317 -405.361135) (xy 340.826991 -405.424139) (xy 340.842965 -405.489521) (xy 340.851009 -405.556343)
			(xy 340.85101 -405.623648) (xy 340.842966 -405.69047) (xy 340.826994 -405.755852) (xy 340.803321 -405.818856)
			(xy 340.772288 -405.87858) (xy 340.734339 -405.934166) (xy 340.712552 -405.959818) (xy 340.706759 -405.966966)
			(xy 340.700244 -405.984154) (xy 340.699852 -405.993346) (xy 340.699852 -406.151334) (xy 340.699394 -406.161495)
			(xy 340.691607 -406.180267) (xy 340.67723 -406.194631) (xy 340.658452 -406.202403) (xy 340.64829 -406.202896)
			(xy 339.93201 -406.202896) (xy 339.921857 -406.202359) (xy 339.903095 -406.194594) (xy 339.88873 -406.180242)
			(xy 339.880949 -406.161487) (xy 339.880448 -406.151334) (xy 339.880448 -405.993346) (xy 339.880005 -405.984163)
			(xy 339.873513 -405.966979) (xy 339.867748 -405.959818) (xy 339.845954 -405.934171) (xy 339.808005 -405.878584)
			(xy 339.776971 -405.81886) (xy 339.753298 -405.755855) (xy 339.737325 -405.690472) (xy 339.729282 -405.623648)
			(xy 338.600728 -405.623648) (xy 338.572136 -405.67868) (xy 338.53419 -405.734267) (xy 338.512404 -405.75992)
			(xy 338.506617 -405.767072) (xy 338.500096 -405.784257) (xy 338.499704 -405.793448) (xy 338.499704 -406.286716)
			(xy 338.500106 -406.295904) (xy 338.506625 -406.313088) (xy 338.512404 -406.320244) (xy 338.534159 -406.345923)
			(xy 338.572106 -406.401506) (xy 338.603138 -406.461227) (xy 338.626811 -406.524228) (xy 338.642785 -406.589606)
			(xy 338.650831 -406.656425) (xy 338.650834 -406.723727) (xy 338.650827 -406.723789) (xy 341.928896 -406.723789)
			(xy 341.928898 -406.656363) (xy 341.936977 -406.589423) (xy 341.953016 -406.523932) (xy 341.976784 -406.460834)
			(xy 342.007938 -406.401036) (xy 342.04603 -406.345401) (xy 342.067896 -406.319736) (xy 342.073702 -406.312597)
			(xy 342.080211 -406.295402) (xy 342.080596 -406.286208) (xy 342.080596 -405.793956) (xy 342.080208 -405.784766)
			(xy 342.073679 -405.767582) (xy 342.067896 -405.760428) (xy 342.046028 -405.734766) (xy 342.00794 -405.679131)
			(xy 341.97679 -405.619334) (xy 341.953026 -405.556237) (xy 341.936991 -405.490748) (xy 341.928915 -405.423809)
			(xy 341.928916 -405.356385) (xy 341.936992 -405.289447) (xy 341.953028 -405.223957) (xy 341.976792 -405.16086)
			(xy 342.007943 -405.101064) (xy 342.046032 -405.045429) (xy 342.067896 -405.019764) (xy 342.07369 -405.012617)
			(xy 342.080206 -404.995428) (xy 342.080596 -404.986236) (xy 342.080596 -404.828756) (xy 342.081049 -404.818645)
			(xy 342.0888 -404.799967) (xy 342.103107 -404.785673) (xy 342.121793 -404.77794) (xy 342.131904 -404.777448)
			(xy 342.848184 -404.777448) (xy 342.858285 -404.777997) (xy 342.876953 -404.78572) (xy 342.891247 -404.799996)
			(xy 342.898991 -404.818655) (xy 342.899492 -404.828756) (xy 342.899492 -404.986236) (xy 342.899886 -404.995425)
			(xy 342.906411 -405.012609) (xy 342.912192 -405.019764) (xy 342.934052 -405.045432) (xy 342.972142 -405.101066)
			(xy 343.003293 -405.160862) (xy 343.027058 -405.223958) (xy 343.043094 -405.289447) (xy 343.05117 -405.356385)
			(xy 343.05117 -405.423809) (xy 343.043095 -405.490747) (xy 343.02706 -405.556236) (xy 343.003295 -405.619333)
			(xy 343.001047 -405.623648) (xy 344.129073 -405.623648) (xy 344.129073 -405.556343) (xy 344.137118 -405.48952)
			(xy 344.153091 -405.424137) (xy 344.176765 -405.361132) (xy 344.207799 -405.301409) (xy 344.245748 -405.245822)
			(xy 344.267536 -405.22017) (xy 344.273332 -405.213025) (xy 344.279846 -405.195834) (xy 344.280236 -405.186642)
			(xy 344.280236 -404.693374) (xy 344.27983 -404.684187) (xy 344.273313 -404.667003) (xy 344.267536 -404.659846)
			(xy 344.24577 -404.634176) (xy 344.207821 -404.578592) (xy 344.176787 -404.518871) (xy 344.153113 -404.455869)
			(xy 344.137139 -404.390489) (xy 344.129093 -404.323668) (xy 344.129091 -404.256365) (xy 344.137133 -404.189544)
			(xy 344.153103 -404.124163) (xy 344.176773 -404.061159) (xy 344.207804 -404.001437) (xy 344.24575 -403.94585)
			(xy 344.267536 -403.920198) (xy 344.273321 -403.913044) (xy 344.279842 -403.89586) (xy 344.280236 -403.88667)
			(xy 344.280236 -403.728682) (xy 344.280718 -403.718523) (xy 344.288498 -403.699754) (xy 344.302867 -403.685389)
			(xy 344.321639 -403.677615) (xy 344.331798 -403.67712) (xy 345.048078 -403.67712) (xy 345.058246 -403.677582)
			(xy 345.077037 -403.685356) (xy 345.091422 -403.69973) (xy 345.09921 -403.718514) (xy 345.09964 -403.728682)
			(xy 345.09964 -403.88667) (xy 345.100078 -403.895854) (xy 345.106574 -403.913038) (xy 345.11234 -403.920198)
			(xy 345.13415 -403.945832) (xy 345.1721 -404.00142) (xy 345.203133 -404.061146) (xy 345.226806 -404.124153)
			(xy 345.242778 -404.189538) (xy 345.250821 -404.256363) (xy 345.250819 -404.32367) (xy 345.242772 -404.390495)
			(xy 345.226796 -404.455878) (xy 345.20312 -404.518884) (xy 345.172083 -404.578608) (xy 345.13413 -404.634194)
			(xy 345.11234 -404.659846) (xy 345.106534 -404.666984) (xy 345.100027 -404.68418) (xy 345.09964 -404.693374)
			(xy 345.09964 -405.186642) (xy 345.100043 -405.19583) (xy 345.106563 -405.213013) (xy 345.11234 -405.22017)
			(xy 345.134122 -405.245827) (xy 345.172073 -405.301412) (xy 345.203107 -405.361135) (xy 345.226781 -405.424139)
			(xy 345.242755 -405.489521) (xy 345.2508 -405.556343) (xy 345.250801 -405.623648) (xy 345.242757 -405.69047)
			(xy 345.226784 -405.755853) (xy 345.203111 -405.818857) (xy 345.172077 -405.87858) (xy 345.134128 -405.934166)
			(xy 345.11234 -405.959818) (xy 345.106546 -405.966965) (xy 345.100031 -405.984154) (xy 345.09964 -405.993346)
			(xy 345.09964 -406.151334) (xy 345.099194 -406.161497) (xy 345.091404 -406.180271) (xy 345.077024 -406.194636)
			(xy 345.058241 -406.202405) (xy 345.048078 -406.202896) (xy 344.331798 -406.202896) (xy 344.321644 -406.202369)
			(xy 344.302882 -406.1946) (xy 344.288518 -406.180245) (xy 344.280737 -406.161487) (xy 344.280236 -406.151334)
			(xy 344.280236 -405.993346) (xy 344.279795 -405.984162) (xy 344.273302 -405.966978) (xy 344.267536 -405.959818)
			(xy 344.245742 -405.934171) (xy 344.207794 -405.878584) (xy 344.176761 -405.818859) (xy 344.153089 -405.755854)
			(xy 344.137116 -405.690471) (xy 344.129073 -405.623648) (xy 343.001047 -405.623648) (xy 342.972145 -405.679129)
			(xy 342.934056 -405.734763) (xy 342.912192 -405.760428) (xy 342.9064 -405.767576) (xy 342.899883 -405.784765)
			(xy 342.899492 -405.793956) (xy 342.899492 -406.286208) (xy 342.8999 -406.295395) (xy 342.906416 -406.312579)
			(xy 342.912192 -406.319736) (xy 342.934025 -406.345427) (xy 342.972115 -406.401058) (xy 343.003268 -406.46085)
			(xy 343.027034 -406.523944) (xy 343.043072 -406.58943) (xy 343.05115 -406.656365) (xy 343.051153 -406.72373)
			(xy 346.329191 -406.72373) (xy 346.329194 -406.656422) (xy 346.337242 -406.589596) (xy 346.35322 -406.524212)
			(xy 346.376898 -406.461206) (xy 346.407937 -406.401482) (xy 346.445893 -406.345896) (xy 346.467684 -406.320244)
			(xy 346.473485 -406.313102) (xy 346.479998 -406.295909) (xy 346.480384 -406.286716) (xy 346.480384 -405.793448)
			(xy 346.479955 -405.784263) (xy 346.473455 -405.767078) (xy 346.467684 -405.75992) (xy 346.445891 -405.734272)
			(xy 346.407939 -405.678686) (xy 346.376904 -405.618962) (xy 346.353229 -405.555957) (xy 346.337255 -405.490574)
			(xy 346.329211 -405.42375) (xy 346.329211 -405.356444) (xy 346.337256 -405.28962) (xy 346.353231 -405.224237)
			(xy 346.376906 -405.161232) (xy 346.407942 -405.101509) (xy 346.445895 -405.045924) (xy 346.467684 -405.020272)
			(xy 346.473473 -405.013121) (xy 346.479993 -404.995935) (xy 346.480384 -404.986744) (xy 346.480384 -404.828756)
			(xy 346.480785 -404.818601) (xy 346.488592 -404.799851) (xy 346.502995 -404.78553) (xy 346.521789 -404.777829)
			(xy 346.531946 -404.777448) (xy 347.248226 -404.777448) (xy 347.258355 -404.777905) (xy 347.277079 -404.785643)
			(xy 347.291434 -404.799938) (xy 347.299251 -404.818629) (xy 347.299788 -404.828756) (xy 347.299788 -404.986744)
			(xy 347.30018 -404.995933) (xy 347.306706 -405.013117) (xy 347.312488 -405.020272) (xy 347.334271 -405.045928)
			(xy 347.372218 -405.101514) (xy 347.40325 -405.161238) (xy 347.426922 -405.224242) (xy 347.442894 -405.289623)
			(xy 347.450938 -405.356445) (xy 347.450939 -405.423749) (xy 347.442895 -405.490571) (xy 347.426924 -405.555953)
			(xy 347.403253 -405.618957) (xy 347.400815 -405.623649) (xy 374.929103 -405.623649) (xy 374.929104 -405.556342)
			(xy 374.937149 -405.489519) (xy 374.953124 -405.424136) (xy 374.976799 -405.361131) (xy 375.007835 -405.301407)
			(xy 375.045787 -405.245822) (xy 375.067576 -405.22017) (xy 375.073365 -405.213019) (xy 375.079885 -405.195833)
			(xy 375.080276 -405.186642) (xy 375.080276 -404.693374) (xy 375.079884 -404.684185) (xy 375.073358 -404.667)
			(xy 375.067576 -404.659846) (xy 375.045809 -404.634177) (xy 375.007857 -404.578593) (xy 374.976821 -404.518873)
			(xy 374.953145 -404.45587) (xy 374.937169 -404.39049) (xy 374.929123 -404.323669) (xy 374.929121 -404.256365)
			(xy 374.937164 -404.189543) (xy 374.953135 -404.124161) (xy 374.976807 -404.061158) (xy 375.00784 -404.001435)
			(xy 375.045789 -403.94585) (xy 375.067576 -403.920198) (xy 375.073353 -403.913039) (xy 375.07988 -403.895859)
			(xy 375.080276 -403.88667) (xy 375.080276 -403.728682) (xy 375.08065 -403.718505) (xy 375.088448 -403.699702)
			(xy 375.102849 -403.685317) (xy 375.12166 -403.677539) (xy 375.131838 -403.67712) (xy 375.848118 -403.67712)
			(xy 375.858275 -403.677618) (xy 375.877041 -403.685395) (xy 375.891405 -403.699759) (xy 375.899182 -403.718525)
			(xy 375.89968 -403.728682) (xy 375.89968 -403.88667) (xy 375.900109 -403.895855) (xy 375.90661 -403.913039)
			(xy 375.91238 -403.920198) (xy 375.934189 -403.945833) (xy 375.972136 -404.001422) (xy 376.003167 -404.061148)
			(xy 376.026838 -404.124155) (xy 376.042809 -404.189539) (xy 376.050851 -404.256363) (xy 376.050849 -404.32367)
			(xy 376.042803 -404.390494) (xy 376.026828 -404.455877) (xy 376.003154 -404.518882) (xy 375.972119 -404.578606)
			(xy 375.934169 -404.634194) (xy 375.91238 -404.659846) (xy 375.906579 -404.666988) (xy 375.900068 -404.684181)
			(xy 375.89968 -404.693374) (xy 375.89968 -405.186642) (xy 375.900074 -405.195831) (xy 375.9066 -405.213015)
			(xy 375.91238 -405.22017) (xy 375.934161 -405.245827) (xy 375.972109 -405.301413) (xy 376.003142 -405.361136)
			(xy 376.026814 -405.42414) (xy 376.042787 -405.489522) (xy 376.050831 -405.556343) (xy 376.050832 -405.623648)
			(xy 376.042788 -405.690469) (xy 376.026817 -405.755851) (xy 376.003145 -405.818855) (xy 375.972114 -405.878579)
			(xy 375.934167 -405.934166) (xy 375.91238 -405.959818) (xy 375.906591 -405.966968) (xy 375.900072 -405.984155)
			(xy 375.89968 -405.993346) (xy 375.89968 -406.151334) (xy 375.899195 -406.161492) (xy 375.891413 -406.180258)
			(xy 375.877045 -406.194622) (xy 375.858276 -406.202398) (xy 375.848118 -406.202896) (xy 375.131838 -406.202896)
			(xy 375.121673 -406.202406) (xy 375.102886 -406.19464) (xy 375.088501 -406.180275) (xy 375.080708 -406.161498)
			(xy 375.080276 -406.151334) (xy 375.080276 -405.993346) (xy 375.079849 -405.984161) (xy 375.073347 -405.966976)
			(xy 375.067576 -405.959818) (xy 375.045781 -405.934171) (xy 375.00783 -405.878585) (xy 374.976795 -405.818861)
			(xy 374.953121 -405.755856) (xy 374.937148 -405.690472) (xy 374.929103 -405.623649) (xy 347.400815 -405.623649)
			(xy 347.372221 -405.678681) (xy 347.334275 -405.734268) (xy 347.312488 -405.75992) (xy 347.306699 -405.767071)
			(xy 347.30018 -405.784257) (xy 347.299788 -405.793448) (xy 347.299788 -406.286716) (xy 347.300193 -406.295904)
			(xy 347.30671 -406.313088) (xy 347.312488 -406.320244) (xy 347.334244 -406.345922) (xy 347.372192 -406.401506)
			(xy 347.403225 -406.461226) (xy 347.426898 -406.524227) (xy 347.442873 -406.589606) (xy 347.450919 -406.656425)
			(xy 347.450922 -406.723727) (xy 347.450915 -406.723789) (xy 377.128717 -406.723789) (xy 377.12872 -406.656363)
			(xy 377.136799 -406.589422) (xy 377.152839 -406.523931) (xy 377.176607 -406.460832) (xy 377.207763 -406.401035)
			(xy 377.245857 -406.345401) (xy 377.267724 -406.319736) (xy 377.273533 -406.3126) (xy 377.280039 -406.295402)
			(xy 377.280424 -406.286208) (xy 377.280424 -405.793956) (xy 377.28003 -405.784767) (xy 377.273504 -405.767583)
			(xy 377.267724 -405.760428) (xy 377.245855 -405.734766) (xy 377.207765 -405.679132) (xy 377.176613 -405.619335)
			(xy 377.152848 -405.556238) (xy 377.136812 -405.490748) (xy 377.128736 -405.423809) (xy 377.128737 -405.356385)
			(xy 377.136813 -405.289446) (xy 377.15285 -405.223956) (xy 377.176616 -405.160859) (xy 377.207768 -405.101063)
			(xy 377.245859 -405.045429) (xy 377.267724 -405.019764) (xy 377.273521 -405.012619) (xy 377.280035 -404.995428)
			(xy 377.280424 -404.986236) (xy 377.280424 -404.828756) (xy 377.28085 -404.818641) (xy 377.288606 -404.799958)
			(xy 377.302922 -404.785664) (xy 377.321617 -404.777935) (xy 377.331732 -404.777448) (xy 378.048012 -404.777448)
			(xy 378.058115 -404.777974) (xy 378.076783 -404.785706) (xy 378.091076 -404.79999) (xy 378.098819 -404.818653)
			(xy 378.09932 -404.828756) (xy 378.09932 -404.986236) (xy 378.099709 -404.995426) (xy 378.106237 -405.01261)
			(xy 378.11202 -405.019764) (xy 378.133879 -405.045433) (xy 378.171967 -405.101067) (xy 378.203117 -405.160863)
			(xy 378.22688 -405.22396) (xy 378.242915 -405.289448) (xy 378.250991 -405.356386) (xy 378.250992 -405.423808)
			(xy 378.242916 -405.490746) (xy 378.226882 -405.556235) (xy 378.203119 -405.619331) (xy 378.200839 -405.623707)
			(xy 379.328896 -405.623707) (xy 379.328896 -405.556284) (xy 379.336972 -405.489346) (xy 379.353008 -405.423856)
			(xy 379.376771 -405.360759) (xy 379.407921 -405.300963) (xy 379.446009 -405.245328) (xy 379.467872 -405.219662)
			(xy 379.473676 -405.212522) (xy 379.480184 -405.195327) (xy 379.480572 -405.186134) (xy 379.480572 -404.693882)
			(xy 379.480177 -404.684693) (xy 379.473653 -404.667509) (xy 379.467872 -404.660354) (xy 379.446031 -404.63467)
			(xy 379.407943 -404.579038) (xy 379.376793 -404.519244) (xy 379.353029 -404.45615) (xy 379.336993 -404.390663)
			(xy 379.328915 -404.323727) (xy 379.328913 -404.256306) (xy 379.336987 -404.18937) (xy 379.353019 -404.123882)
			(xy 379.376779 -404.060786) (xy 379.407926 -404.00099) (xy 379.44601 -403.945356) (xy 379.467872 -403.91969)
			(xy 379.473664 -403.912542) (xy 379.480179 -403.895353) (xy 379.480572 -403.886162) (xy 379.480572 -403.728682)
			(xy 379.481013 -403.71855) (xy 379.488752 -403.699822) (xy 379.503053 -403.685466) (xy 379.52175 -403.677653)
			(xy 379.53188 -403.67712) (xy 380.24816 -403.67712) (xy 380.258282 -403.677549) (xy 380.276989 -403.685288)
			(xy 380.291305 -403.699601) (xy 380.299048 -403.718306) (xy 380.299468 -403.728428) (xy 380.299468 -403.886162)
			(xy 380.299904 -403.895346) (xy 380.306401 -403.91253) (xy 380.312168 -403.91969) (xy 380.334055 -403.945337)
			(xy 380.372145 -404.000973) (xy 380.403296 -404.060772) (xy 380.427061 -404.123871) (xy 380.443096 -404.189363)
			(xy 380.45117 -404.256303) (xy 380.451168 -404.32373) (xy 380.44309 -404.39067) (xy 380.427051 -404.456161)
			(xy 380.403283 -404.519259) (xy 380.372128 -404.579055) (xy 380.334034 -404.634689) (xy 380.312168 -404.660354)
			(xy 380.306362 -404.667492) (xy 380.299854 -404.684688) (xy 380.299468 -404.693882) (xy 380.299468 -405.186134)
			(xy 380.299869 -405.195322) (xy 380.30639 -405.212506) (xy 380.312168 -405.219662) (xy 380.334027 -405.245332)
			(xy 380.372118 -405.300965) (xy 380.403271 -405.36076) (xy 380.427037 -405.423856) (xy 380.443074 -405.489345)
			(xy 380.451151 -405.556284) (xy 380.451151 -405.623707) (xy 380.443075 -405.690646) (xy 380.42704 -405.756135)
			(xy 380.403275 -405.819232) (xy 380.372123 -405.879028) (xy 380.334033 -405.934661) (xy 380.312168 -405.960326)
			(xy 380.306374 -405.967473) (xy 380.299858 -405.984662) (xy 380.299468 -405.993854) (xy 380.299468 -406.151334)
			(xy 380.299002 -406.161462) (xy 380.291264 -406.180182) (xy 380.276972 -406.194537) (xy 380.258286 -406.202357)
			(xy 380.24816 -406.202896) (xy 379.53188 -406.202896) (xy 379.521769 -406.202431) (xy 379.50309 -406.194686)
			(xy 379.488796 -406.180383) (xy 379.481062 -406.161699) (xy 379.480572 -406.151588) (xy 379.480572 -405.993854)
			(xy 379.480142 -405.984669) (xy 379.473643 -405.967484) (xy 379.467872 -405.960326) (xy 379.446003 -405.934665)
			(xy 379.407916 -405.879029) (xy 379.376768 -405.819232) (xy 379.353005 -405.756135) (xy 379.336971 -405.690646)
			(xy 379.328896 -405.623707) (xy 378.200839 -405.623707) (xy 378.17197 -405.679128) (xy 378.133883 -405.734762)
			(xy 378.11202 -405.760428) (xy 378.106231 -405.767579) (xy 378.099711 -405.784765) (xy 378.09932 -405.793956)
			(xy 378.09932 -406.286208) (xy 378.099722 -406.295396) (xy 378.106241 -406.312581) (xy 378.11202 -406.319736)
			(xy 378.133852 -406.345428) (xy 378.17194 -406.401059) (xy 378.203091 -406.460852) (xy 378.226856 -406.523945)
			(xy 378.242893 -406.589431) (xy 378.250971 -406.656366) (xy 378.250974 -406.723729) (xy 381.529036 -406.723729)
			(xy 381.529039 -406.656422) (xy 381.537086 -406.589598) (xy 381.553062 -406.524214) (xy 381.576737 -406.461209)
			(xy 381.607772 -406.401484) (xy 381.645723 -406.345897) (xy 381.667512 -406.320244) (xy 381.673316 -406.313104)
			(xy 381.679826 -406.29591) (xy 381.680212 -406.286716) (xy 381.680212 -405.793448) (xy 381.679776 -405.784264)
			(xy 381.67328 -405.767079) (xy 381.667512 -405.75992) (xy 381.645721 -405.734271) (xy 381.607774 -405.678683)
			(xy 381.576743 -405.618959) (xy 381.553071 -405.555954) (xy 381.537099 -405.490572) (xy 381.529056 -405.423749)
			(xy 381.529056 -405.356445) (xy 381.5371 -405.289622) (xy 381.553073 -405.22424) (xy 381.576745 -405.161235)
			(xy 381.607777 -405.101512) (xy 381.645725 -405.045924) (xy 381.667512 -405.020272) (xy 381.673304 -405.013124)
			(xy 381.679821 -404.995936) (xy 381.680212 -404.986744) (xy 381.680212 -404.828756) (xy 381.680649 -404.818643)
			(xy 381.688404 -404.799961) (xy 381.702715 -404.785668) (xy 381.721406 -404.777937) (xy 381.73152 -404.777448)
			(xy 382.448054 -404.777448) (xy 382.458179 -404.777965) (xy 382.4769 -404.785679) (xy 382.491258 -404.799956)
			(xy 382.499078 -404.818634) (xy 382.499616 -404.828756) (xy 382.499616 -404.986744) (xy 382.500001 -404.995934)
			(xy 382.506532 -405.013118) (xy 382.512316 -405.020272) (xy 382.534101 -405.045927) (xy 382.572053 -405.101512)
			(xy 382.603089 -405.161235) (xy 382.626764 -405.224239) (xy 382.642738 -405.289621) (xy 382.650784 -405.356444)
			(xy 382.650784 -405.42375) (xy 382.64274 -405.490573) (xy 382.626766 -405.555955) (xy 382.603091 -405.61896)
			(xy 382.600655 -405.623648) (xy 383.729191 -405.623648) (xy 383.729192 -405.556343) (xy 383.737237 -405.489519)
			(xy 383.753211 -405.424136) (xy 383.776885 -405.361132) (xy 383.807921 -405.301408) (xy 383.845871 -405.245822)
			(xy 383.86766 -405.22017) (xy 383.873459 -405.213027) (xy 383.879971 -405.195835) (xy 383.88036 -405.186642)
			(xy 383.88036 -404.693374) (xy 383.879949 -404.684187) (xy 383.873434 -404.667004) (xy 383.86766 -404.659846)
			(xy 383.845893 -404.634176) (xy 383.807943 -404.578593) (xy 383.776907 -404.518872) (xy 383.753232 -404.45587)
			(xy 383.737257 -404.390489) (xy 383.729211 -404.323668) (xy 383.729209 -404.256365) (xy 383.737251 -404.189543)
			(xy 383.753222 -404.124162) (xy 383.776894 -404.061158) (xy 383.807926 -404.001436) (xy 383.845873 -403.94585)
			(xy 383.86766 -403.920198) (xy 383.873447 -403.913047) (xy 383.879966 -403.895861) (xy 383.88036 -403.88667)
			(xy 383.88036 -403.728682) (xy 383.88075 -403.718507) (xy 383.888545 -403.699707) (xy 383.902941 -403.685322)
			(xy 383.921746 -403.677542) (xy 383.931922 -403.67712) (xy 384.648202 -403.67712) (xy 384.658358 -403.677631)
			(xy 384.677123 -403.685403) (xy 384.691488 -403.699763) (xy 384.699265 -403.718526) (xy 384.699764 -403.728682)
			(xy 384.699764 -403.88667) (xy 384.700197 -403.895855) (xy 384.706696 -403.913039) (xy 384.712464 -403.920198)
			(xy 384.734273 -403.945832) (xy 384.772221 -404.001421) (xy 384.803254 -404.061147) (xy 384.826925 -404.124154)
			(xy 384.842896 -404.189539) (xy 384.850939 -404.256363) (xy 384.850937 -404.32367) (xy 384.84289 -404.390494)
			(xy 384.826915 -404.455877) (xy 384.80324 -404.518883) (xy 384.772204 -404.578607) (xy 384.734253 -404.634194)
			(xy 384.712464 -404.659846) (xy 384.706661 -404.666986) (xy 384.700151 -404.684181) (xy 384.699764 -404.693374)
			(xy 384.699764 -405.186642) (xy 384.700162 -405.19583) (xy 384.706685 -405.213014) (xy 384.712464 -405.22017)
			(xy 384.734246 -405.245827) (xy 384.772195 -405.301413) (xy 384.803228 -405.361136) (xy 384.826901 -405.42414)
			(xy 384.842874 -405.489521) (xy 384.850919 -405.556343) (xy 384.850919 -405.623648) (xy 384.842876 -405.69047)
			(xy 384.826904 -405.755852) (xy 384.803232 -405.818856) (xy 384.772199 -405.878579) (xy 384.734251 -405.934166)
			(xy 384.712464 -405.959818) (xy 384.706673 -405.966967) (xy 384.700156 -405.984155) (xy 384.699764 -405.993346)
			(xy 384.699764 -406.151334) (xy 384.699295 -406.161494) (xy 384.691509 -406.180263) (xy 384.677136 -406.194627)
			(xy 384.658362 -406.202401) (xy 384.648202 -406.202896) (xy 383.931922 -406.202896) (xy 383.92177 -406.20235)
			(xy 383.903008 -406.194589) (xy 383.888643 -406.180239) (xy 383.880861 -406.161486) (xy 383.88036 -406.151334)
			(xy 383.88036 -405.993346) (xy 383.879914 -405.984163) (xy 383.873424 -405.966979) (xy 383.86766 -405.959818)
			(xy 383.845866 -405.934171) (xy 383.807916 -405.878584) (xy 383.776882 -405.81886) (xy 383.753208 -405.755855)
			(xy 383.737235 -405.690472) (xy 383.729191 -405.623648) (xy 382.600655 -405.623648) (xy 382.572056 -405.678683)
			(xy 382.534105 -405.734268) (xy 382.512316 -405.75992) (xy 382.50653 -405.767073) (xy 382.500009 -405.784257)
			(xy 382.499616 -405.793448) (xy 382.499616 -406.286716) (xy 382.500015 -406.295904) (xy 382.506536 -406.313089)
			(xy 382.512316 -406.320244) (xy 382.534074 -406.345921) (xy 382.572026 -406.401503) (xy 382.603063 -406.461223)
			(xy 382.62674 -406.524224) (xy 382.642717 -406.589604) (xy 382.650764 -406.656424) (xy 382.650767 -406.723728)
			(xy 382.65076 -406.723789) (xy 385.928805 -406.723789) (xy 385.928807 -406.656363) (xy 385.936887 -406.589422)
			(xy 385.952926 -406.523931) (xy 385.976694 -406.460833) (xy 386.007849 -406.401036) (xy 386.045942 -406.345401)
			(xy 386.067808 -406.319736) (xy 386.073615 -406.312598) (xy 386.080123 -406.295402) (xy 386.080508 -406.286208)
			(xy 386.080508 -405.793956) (xy 386.080117 -405.784767) (xy 386.07359 -405.767583) (xy 386.067808 -405.760428)
			(xy 386.04594 -405.734766) (xy 386.007851 -405.679131) (xy 385.9767 -405.619335) (xy 385.952935 -405.556237)
			(xy 385.9369 -405.490748) (xy 385.928824 -405.423809) (xy 385.928825 -405.356385) (xy 385.936901 -405.289446)
			(xy 385.952937 -405.223957) (xy 385.976702 -405.16086) (xy 386.007854 -405.101064) (xy 386.045944 -405.045429)
			(xy 386.067808 -405.019764) (xy 386.073603 -405.012618) (xy 386.080118 -404.995428) (xy 386.080508 -404.986236)
			(xy 386.080508 -404.828756) (xy 386.080949 -404.818643) (xy 386.088703 -404.799963) (xy 386.103013 -404.785669)
			(xy 386.121703 -404.777938) (xy 386.131816 -404.777448) (xy 386.848096 -404.777448) (xy 386.858198 -404.777987)
			(xy 386.876866 -404.785714) (xy 386.891159 -404.799993) (xy 386.898903 -404.818654) (xy 386.899404 -404.828756)
			(xy 386.899404 -404.986236) (xy 386.899796 -404.995425) (xy 386.906322 -405.012609) (xy 386.912104 -405.019764)
			(xy 386.933964 -405.045433) (xy 386.972052 -405.101067) (xy 387.003203 -405.160862) (xy 387.026967 -405.223959)
			(xy 387.043003 -405.289448) (xy 387.051079 -405.356385) (xy 387.051079 -405.423809) (xy 387.043004 -405.490747)
			(xy 387.026969 -405.556235) (xy 387.003206 -405.619332) (xy 387.000958 -405.623648) (xy 388.128982 -405.623648)
			(xy 388.128982 -405.556343) (xy 388.137027 -405.489519) (xy 388.153001 -405.424137) (xy 388.176675 -405.361132)
			(xy 388.207709 -405.301408) (xy 388.245659 -405.245822) (xy 388.267448 -405.22017) (xy 388.273246 -405.213026)
			(xy 388.279758 -405.195834) (xy 388.280148 -405.186642) (xy 388.280148 -404.693374) (xy 388.27974 -404.684187)
			(xy 388.273223 -404.667003) (xy 388.267448 -404.659846) (xy 388.245682 -404.634176) (xy 388.207732 -404.578592)
			(xy 388.176697 -404.518871) (xy 388.153023 -404.455869) (xy 388.137048 -404.390489) (xy 388.129002 -404.323668)
			(xy 388.129 -404.256365) (xy 388.137042 -404.189544) (xy 388.153013 -404.124163) (xy 388.176684 -404.061159)
			(xy 388.207715 -404.001436) (xy 388.245662 -403.94585) (xy 388.267448 -403.920198) (xy 388.273234 -403.913045)
			(xy 388.279754 -403.89586) (xy 388.280148 -403.88667) (xy 388.280148 -403.728682) (xy 388.280619 -403.718522)
			(xy 388.288401 -403.69975) (xy 388.302774 -403.685385) (xy 388.32155 -403.677613) (xy 388.33171 -403.67712)
			(xy 389.04799 -403.67712) (xy 389.058145 -403.677641) (xy 389.07691 -403.685409) (xy 389.091275 -403.699766)
			(xy 389.099053 -403.718527) (xy 389.099552 -403.728682) (xy 389.099552 -403.88667) (xy 389.099987 -403.895854)
			(xy 389.106485 -403.913038) (xy 389.112252 -403.920198) (xy 389.134062 -403.945832) (xy 389.172011 -404.001421)
			(xy 389.203043 -404.061147) (xy 389.226715 -404.124154) (xy 389.242687 -404.189538) (xy 389.25073 -404.256363)
			(xy 389.250728 -404.32367) (xy 389.242681 -404.390494) (xy 389.226706 -404.455878) (xy 389.20303 -404.518883)
			(xy 389.171994 -404.578608) (xy 389.134041 -404.634194) (xy 389.112252 -404.659846) (xy 389.106447 -404.666985)
			(xy 389.099939 -404.684181) (xy 389.099552 -404.693374) (xy 389.099552 -405.186642) (xy 389.099953 -405.19583)
			(xy 389.106474 -405.213014) (xy 389.112252 -405.22017) (xy 389.134034 -405.245827) (xy 389.171983 -405.301413)
			(xy 389.203017 -405.361135) (xy 389.226691 -405.424139) (xy 389.242665 -405.489521) (xy 389.250709 -405.556343)
			(xy 389.25071 -405.623648) (xy 389.242666 -405.69047) (xy 389.226694 -405.755852) (xy 389.203021 -405.818856)
			(xy 389.171988 -405.87858) (xy 389.134039 -405.934166) (xy 389.112252 -405.959818) (xy 389.106459 -405.966966)
			(xy 389.099944 -405.984154) (xy 389.099552 -405.993346) (xy 389.099552 -406.151334) (xy 389.099094 -406.161495)
			(xy 389.091307 -406.180267) (xy 389.07693 -406.194631) (xy 389.058152 -406.202403) (xy 389.04799 -406.202896)
			(xy 388.33171 -406.202896) (xy 388.321557 -406.202359) (xy 388.302795 -406.194594) (xy 388.28843 -406.180242)
			(xy 388.280649 -406.161487) (xy 388.280148 -406.151334) (xy 388.280148 -405.993346) (xy 388.279705 -405.984163)
			(xy 388.273213 -405.966979) (xy 388.267448 -405.959818) (xy 388.245654 -405.934171) (xy 388.207705 -405.878584)
			(xy 388.176671 -405.81886) (xy 388.152998 -405.755855) (xy 388.137025 -405.690472) (xy 388.128982 -405.623648)
			(xy 387.000958 -405.623648) (xy 386.972056 -405.679128) (xy 386.933968 -405.734763) (xy 386.912104 -405.760428)
			(xy 386.906314 -405.767578) (xy 386.899795 -405.784765) (xy 386.899404 -405.793956) (xy 386.899404 -406.286208)
			(xy 386.89981 -406.295396) (xy 386.906326 -406.31258) (xy 386.912104 -406.319736) (xy 386.933936 -406.345427)
			(xy 386.972026 -406.401058) (xy 387.003178 -406.460851) (xy 387.026943 -406.523944) (xy 387.042981 -406.58943)
			(xy 387.051059 -406.656365) (xy 387.051062 -406.723729) (xy 390.329124 -406.723729) (xy 390.329127 -406.656423)
			(xy 390.337174 -406.589599) (xy 390.353149 -406.524215) (xy 390.376823 -406.461209) (xy 390.407858 -406.401485)
			(xy 390.445808 -406.345897) (xy 390.467596 -406.320244) (xy 390.473398 -406.313103) (xy 390.47991 -406.295909)
			(xy 390.480296 -406.286716) (xy 390.480296 -405.793448) (xy 390.479864 -405.784263) (xy 390.473366 -405.767078)
			(xy 390.467596 -405.75992) (xy 390.445806 -405.73427) (xy 390.40786 -405.678683) (xy 390.376829 -405.618958)
			(xy 390.353158 -405.555954) (xy 390.337187 -405.490571) (xy 390.329144 -405.423749) (xy 390.329144 -405.356445)
			(xy 390.337188 -405.289623) (xy 390.35316 -405.224241) (xy 390.376832 -405.161236) (xy 390.407863 -405.101512)
			(xy 390.445809 -405.045925) (xy 390.467596 -405.020272) (xy 390.473386 -405.013122) (xy 390.479905 -404.995935)
			(xy 390.480296 -404.986744) (xy 390.480296 -404.828756) (xy 390.480749 -404.818645) (xy 390.4885 -404.799967)
			(xy 390.502807 -404.785673) (xy 390.521493 -404.77794) (xy 390.531604 -404.777448) (xy 391.248138 -404.777448)
			(xy 391.258268 -404.777896) (xy 391.276992 -404.785637) (xy 391.291347 -404.799935) (xy 391.299163 -404.818628)
			(xy 391.2997 -404.828756) (xy 391.2997 -404.986744) (xy 391.300089 -404.995933) (xy 391.306617 -405.013118)
			(xy 391.3124 -405.020272) (xy 391.334183 -405.045928) (xy 391.372129 -405.101515) (xy 391.40316 -405.161238)
			(xy 391.426832 -405.224242) (xy 391.442804 -405.289623) (xy 391.450848 -405.356445) (xy 391.450848 -405.423749)
			(xy 391.442805 -405.490571) (xy 391.426833 -405.555952) (xy 391.403163 -405.618956) (xy 391.372132 -405.67868)
			(xy 391.334186 -405.734267) (xy 391.3124 -405.75992) (xy 391.306612 -405.767072) (xy 391.300092 -405.784257)
			(xy 391.2997 -405.793448) (xy 391.2997 -406.286716) (xy 391.300103 -406.295904) (xy 391.306622 -406.313088)
			(xy 391.3124 -406.320244) (xy 391.334155 -406.345923) (xy 391.372102 -406.401506) (xy 391.403135 -406.461226)
			(xy 391.426808 -406.524227) (xy 391.442782 -406.589606) (xy 391.450828 -406.656425) (xy 391.450831 -406.723727)
			(xy 391.44279 -406.790547) (xy 391.426822 -406.855927) (xy 391.403154 -406.91893) (xy 391.372127 -406.978653)
			(xy 391.334185 -407.034239) (xy 391.3124 -407.059892) (xy 391.306624 -407.067052) (xy 391.300097 -407.084231)
			(xy 391.2997 -407.09342) (xy 391.2997 -407.251408) (xy 391.299221 -407.261517) (xy 391.291481 -407.280196)
			(xy 391.277182 -407.29449) (xy 391.258501 -407.302224) (xy 391.248392 -407.302716) (xy 390.531858 -407.302716)
			(xy 390.521723 -407.302307) (xy 390.502993 -407.294557) (xy 390.488636 -407.280247) (xy 390.480826 -407.261541)
			(xy 390.480296 -407.251408) (xy 390.480296 -407.09342) (xy 390.479877 -407.084234) (xy 390.47337 -407.067049)
			(xy 390.467596 -407.059892) (xy 390.445778 -407.034265) (xy 390.407833 -406.978674) (xy 390.376804 -406.918947)
			(xy 390.353135 -406.855939) (xy 390.337165 -406.790554) (xy 390.329124 -406.723729) (xy 387.051062 -406.723729)
			(xy 387.051062 -406.723787) (xy 387.04299 -406.790723) (xy 387.026958 -406.85621) (xy 387.003197 -406.919305)
			(xy 386.972051 -406.979101) (xy 386.933966 -407.034735) (xy 386.912104 -407.0604) (xy 386.906325 -407.067558)
			(xy 386.8998 -407.084739) (xy 386.899404 -407.093928) (xy 386.899404 -407.251408) (xy 386.898921 -407.261517)
			(xy 386.891182 -407.280194) (xy 386.876884 -407.294489) (xy 386.858205 -407.302224) (xy 386.848096 -407.302716)
			(xy 386.131816 -407.302716) (xy 386.121697 -407.302271) (xy 386.102996 -407.294531) (xy 386.088682 -407.280224)
			(xy 386.080933 -407.261527) (xy 386.080508 -407.251408) (xy 386.080508 -407.093928) (xy 386.080083 -407.084742)
			(xy 386.073579 -407.067558) (xy 386.067808 -407.0604) (xy 386.045912 -407.034761) (xy 386.007824 -406.979123)
			(xy 385.976674 -406.919323) (xy 385.952912 -406.856223) (xy 385.936878 -406.79073) (xy 385.928805 -406.723789)
			(xy 382.65076 -406.723789) (xy 382.642725 -406.790549) (xy 382.626754 -406.85593) (xy 382.603083 -406.918933)
			(xy 382.572051 -406.978655) (xy 382.534103 -407.03424) (xy 382.512316 -407.059892) (xy 382.506542 -407.067053)
			(xy 382.500013 -407.084231) (xy 382.499616 -407.09342) (xy 382.499616 -407.251408) (xy 382.499122 -407.261515)
			(xy 382.491384 -407.28019) (xy 382.47709 -407.294484) (xy 382.458415 -407.302222) (xy 382.448308 -407.302716)
			(xy 381.731774 -407.302716) (xy 381.72164 -407.302294) (xy 381.70291 -407.294549) (xy 381.688553 -407.280243)
			(xy 381.680743 -407.26154) (xy 381.680212 -407.251408) (xy 381.680212 -407.09342) (xy 381.679789 -407.084234)
			(xy 381.673284 -407.06705) (xy 381.667512 -407.059892) (xy 381.645694 -407.034265) (xy 381.607748 -406.978675)
			(xy 381.576717 -406.918947) (xy 381.553047 -406.855939) (xy 381.537077 -406.790554) (xy 381.529036 -406.723729)
			(xy 378.250974 -406.723729) (xy 378.250974 -406.723786) (xy 378.242902 -406.790722) (xy 378.226871 -406.856209)
			(xy 378.203111 -406.919305) (xy 378.171965 -406.9791) (xy 378.133881 -407.034734) (xy 378.11202 -407.0604)
			(xy 378.106243 -407.067559) (xy 378.099716 -407.084739) (xy 378.09932 -407.093928) (xy 378.09932 -407.251408)
			(xy 378.098822 -407.261515) (xy 378.091085 -407.280189) (xy 378.076793 -407.294483) (xy 378.058119 -407.302221)
			(xy 378.048012 -407.302716) (xy 377.331732 -407.302716) (xy 377.321614 -407.302258) (xy 377.302914 -407.294524)
			(xy 377.288599 -407.28022) (xy 377.280849 -407.261526) (xy 377.280424 -407.251408) (xy 377.280424 -407.093928)
			(xy 377.279995 -407.084743) (xy 377.273494 -407.067559) (xy 377.267724 -407.0604) (xy 377.245828 -407.034761)
			(xy 377.207738 -406.979123) (xy 377.176588 -406.919324) (xy 377.152824 -406.856223) (xy 377.13679 -406.790731)
			(xy 377.128717 -406.723789) (xy 347.450915 -406.723789) (xy 347.442881 -406.790547) (xy 347.426912 -406.855927)
			(xy 347.403244 -406.91893) (xy 347.372216 -406.978653) (xy 347.334273 -407.03424) (xy 347.312488 -407.059892)
			(xy 347.306711 -407.067051) (xy 347.300185 -407.084231) (xy 347.299788 -407.09342) (xy 347.299788 -407.251408)
			(xy 347.299385 -407.261564) (xy 347.291584 -407.280319) (xy 347.277182 -407.294642) (xy 347.258384 -407.30234)
			(xy 347.248226 -407.302716) (xy 346.531946 -407.302716) (xy 346.521817 -407.302234) (xy 346.503088 -407.294514)
			(xy 346.488729 -407.280225) (xy 346.480916 -407.261535) (xy 346.480384 -407.251408) (xy 346.480384 -407.09342)
			(xy 346.479968 -407.084233) (xy 346.473459 -407.067049) (xy 346.467684 -407.059892) (xy 346.445864 -407.034266)
			(xy 346.407913 -406.978677) (xy 346.376878 -406.91895) (xy 346.353205 -406.855942) (xy 346.337233 -406.790556)
			(xy 346.329191 -406.72373) (xy 343.051153 -406.72373) (xy 343.051153 -406.723787) (xy 343.04308 -406.790723)
			(xy 343.027048 -406.85621) (xy 343.003287 -406.919306) (xy 342.97214 -406.979101) (xy 342.934054 -407.034735)
			(xy 342.912192 -407.0604) (xy 342.906412 -407.067557) (xy 342.899888 -407.084738) (xy 342.899492 -407.093928)
			(xy 342.899492 -407.251408) (xy 342.89909 -407.261532) (xy 342.891338 -407.280237) (xy 342.877017 -407.294551)
			(xy 342.858308 -407.302295) (xy 342.848184 -407.302716) (xy 342.131904 -407.302716) (xy 342.121798 -407.302212)
			(xy 342.103122 -407.294479) (xy 342.088828 -407.280188) (xy 342.08109 -407.261514) (xy 342.080596 -407.251408)
			(xy 342.080596 -407.093928) (xy 342.080173 -407.084742) (xy 342.073668 -407.067558) (xy 342.067896 -407.0604)
			(xy 342.046001 -407.034761) (xy 342.007913 -406.979122) (xy 341.976764 -406.919322) (xy 341.953002 -406.856222)
			(xy 341.936969 -406.79073) (xy 341.928896 -406.723789) (xy 338.650827 -406.723789) (xy 338.642793 -406.790546)
			(xy 338.626825 -406.855926) (xy 338.603158 -406.918929) (xy 338.572131 -406.978652) (xy 338.534188 -407.034239)
			(xy 338.512404 -407.059892) (xy 338.506629 -407.067052) (xy 338.500101 -407.084231) (xy 338.499704 -407.09342)
			(xy 338.499704 -407.251408) (xy 338.499285 -407.261562) (xy 338.491487 -407.280314) (xy 338.47709 -407.294637)
			(xy 338.458298 -407.302337) (xy 338.448142 -407.302716) (xy 337.731862 -407.302716) (xy 337.721727 -407.302303)
			(xy 337.702997 -407.294555) (xy 337.688641 -407.280246) (xy 337.68083 -407.261541) (xy 337.6803 -407.251408)
			(xy 337.6803 -407.09342) (xy 337.67988 -407.084234) (xy 337.673373 -407.067049) (xy 337.6676 -407.059892)
			(xy 337.645782 -407.034265) (xy 337.607837 -406.978674) (xy 337.576807 -406.918947) (xy 337.553138 -406.855939)
			(xy 337.537168 -406.790554) (xy 337.529127 -406.723729) (xy 334.251065 -406.723729) (xy 334.251065 -406.723786)
			(xy 334.242993 -406.790722) (xy 334.226961 -406.85621) (xy 334.203201 -406.919305) (xy 334.172054 -406.9791)
			(xy 334.13397 -407.034735) (xy 334.112108 -407.0604) (xy 334.10633 -407.067558) (xy 334.099804 -407.084739)
			(xy 334.099408 -407.093928) (xy 334.099408 -407.251408) (xy 334.098921 -407.261516) (xy 334.091183 -407.280193)
			(xy 334.076886 -407.294487) (xy 334.058208 -407.302223) (xy 334.0481 -407.302716) (xy 333.33182 -407.302716)
			(xy 333.321701 -407.302268) (xy 333.303001 -407.29453) (xy 333.288686 -407.280223) (xy 333.280937 -407.261527)
			(xy 333.280512 -407.251408) (xy 333.280512 -407.093928) (xy 333.280086 -407.084743) (xy 333.273583 -407.067558)
			(xy 333.267812 -407.0604) (xy 333.245916 -407.034761) (xy 333.207828 -406.979123) (xy 333.176678 -406.919323)
			(xy 333.152915 -406.856223) (xy 333.136881 -406.790731) (xy 333.128808 -406.723789) (xy 326.525636 -406.723789)
			(xy 326.525636 -409.523827) (xy 330.929173 -409.523827) (xy 330.929176 -409.456519) (xy 330.937224 -409.389693)
			(xy 330.953202 -409.324309) (xy 330.976879 -409.261303) (xy 331.007918 -409.201578) (xy 331.045873 -409.145992)
			(xy 331.067664 -409.12034) (xy 331.073476 -409.113206) (xy 331.07998 -409.096007) (xy 331.080364 -409.086812)
			(xy 331.080364 -408.593544) (xy 331.079919 -408.584361) (xy 331.073428 -408.567177) (xy 331.067664 -408.560016)
			(xy 331.045868 -408.534371) (xy 331.007918 -408.478784) (xy 330.976883 -408.419059) (xy 330.95321 -408.356054)
			(xy 330.937237 -408.290671) (xy 330.929193 -408.223847) (xy 330.929194 -408.156541) (xy 330.937239 -408.089717)
			(xy 330.953213 -408.024334) (xy 330.976888 -407.96133) (xy 331.007924 -407.901606) (xy 331.045875 -407.84602)
			(xy 331.067664 -407.820368) (xy 331.073464 -407.813226) (xy 331.079975 -407.796033) (xy 331.080364 -407.78684)
			(xy 331.080364 -407.628852) (xy 331.080782 -407.618699) (xy 331.088586 -407.599953) (xy 331.102983 -407.585633)
			(xy 331.121771 -407.577928) (xy 331.131926 -407.577544) (xy 331.848206 -407.577544) (xy 331.858334 -407.578022)
			(xy 331.877056 -407.585752) (xy 331.891412 -407.600041) (xy 331.89923 -407.618727) (xy 331.899768 -407.628852)
			(xy 331.899768 -407.78684) (xy 331.900166 -407.796028) (xy 331.906689 -407.813212) (xy 331.912468 -407.820368)
			(xy 331.934248 -407.846027) (xy 331.972196 -407.901612) (xy 332.00323 -407.961335) (xy 332.026903 -408.024339)
			(xy 332.042876 -408.08972) (xy 332.050921 -408.156542) (xy 332.050921 -408.223846) (xy 332.042878 -408.290668)
			(xy 332.026906 -408.35605) (xy 332.003235 -408.419054) (xy 331.972203 -408.478777) (xy 331.934255 -408.534364)
			(xy 331.912468 -408.560016) (xy 331.906678 -408.567166) (xy 331.90016 -408.584353) (xy 331.899768 -408.593544)
			(xy 331.899768 -409.086812) (xy 331.900179 -409.095999) (xy 331.906693 -409.113183) (xy 331.912468 -409.12034)
			(xy 331.93422 -409.146022) (xy 331.972169 -409.201604) (xy 332.003204 -409.261323) (xy 332.026878 -409.324324)
			(xy 332.042853 -409.389703) (xy 332.0509 -409.456522) (xy 332.050904 -409.523824) (xy 332.042863 -409.590644)
			(xy 332.026894 -409.656024) (xy 332.003226 -409.719027) (xy 331.972197 -409.77875) (xy 331.934253 -409.834336)
			(xy 331.912468 -409.859988) (xy 331.906647 -409.867116) (xy 331.900148 -409.88432) (xy 331.899768 -409.893516)
			(xy 331.899768 -410.051504) (xy 331.899381 -410.061662) (xy 331.891578 -410.080421) (xy 331.87717 -410.094745)
			(xy 331.858367 -410.102439) (xy 331.848206 -410.102812) (xy 331.131926 -410.102812) (xy 331.121807 -410.102254)
			(xy 331.103097 -410.094544) (xy 331.088741 -410.08028) (xy 331.080912 -410.061619) (xy 331.080364 -410.051504)
			(xy 331.080364 -409.893516) (xy 331.079932 -409.884331) (xy 331.073432 -409.867148) (xy 331.067664 -409.859988)
			(xy 331.04584 -409.834365) (xy 331.007891 -409.778775) (xy 330.976857 -409.719048) (xy 330.953186 -409.656039)
			(xy 330.937214 -409.590653) (xy 330.929173 -409.523827) (xy 326.525636 -409.523827) (xy 326.525636 -410.623701)
			(xy 333.128819 -410.623701) (xy 333.12882 -410.556275) (xy 333.136898 -410.489336) (xy 333.152936 -410.423846)
			(xy 333.176702 -410.360748) (xy 333.207855 -410.300952) (xy 333.245947 -410.245317) (xy 333.267812 -410.219652)
			(xy 333.273613 -410.21251) (xy 333.280125 -410.195317) (xy 333.280512 -410.186124) (xy 333.280512 -409.693872)
			(xy 333.280113 -409.684684) (xy 333.273591 -409.6675) (xy 333.267812 -409.660344) (xy 333.245959 -409.634669)
			(xy 333.20787 -409.579036) (xy 333.176718 -409.519242) (xy 333.152952 -409.456146) (xy 333.136916 -409.390658)
			(xy 333.128839 -409.32372) (xy 333.128837 -409.256298) (xy 333.136912 -409.18936) (xy 333.152947 -409.123871)
			(xy 333.17671 -409.060775) (xy 333.20786 -409.000979) (xy 333.245948 -408.945345) (xy 333.267812 -408.91968)
			(xy 333.273601 -408.912529) (xy 333.28012 -408.895343) (xy 333.280512 -408.886152) (xy 333.280512 -408.728672)
			(xy 333.280962 -408.71856) (xy 333.288711 -408.699879) (xy 333.303019 -408.685585) (xy 333.321708 -408.677853)
			(xy 333.33182 -408.677364) (xy 334.0481 -408.677364) (xy 334.058204 -408.677884) (xy 334.076876 -408.685615)
			(xy 334.091169 -408.699901) (xy 334.09891 -408.718568) (xy 334.099408 -408.728672) (xy 334.099408 -408.886152)
			(xy 334.099839 -408.895337) (xy 334.106338 -408.912522) (xy 334.112108 -408.91968) (xy 334.133983 -408.945336)
			(xy 334.172071 -409.000972) (xy 334.203221 -409.060769) (xy 334.226984 -409.123867) (xy 334.243019 -409.189358)
			(xy 334.251093 -409.256297) (xy 334.251092 -409.323721) (xy 334.243015 -409.39066) (xy 334.226979 -409.45615)
			(xy 334.203214 -409.519247) (xy 334.200797 -409.523886) (xy 335.328966 -409.523886) (xy 335.328969 -409.45646)
			(xy 335.337048 -409.38952) (xy 335.353086 -409.32403) (xy 335.376852 -409.260931) (xy 335.408005 -409.201134)
			(xy 335.446095 -409.145498) (xy 335.46796 -409.119832) (xy 335.473775 -409.1127) (xy 335.480277 -409.095499)
			(xy 335.48066 -409.086304) (xy 335.48066 -408.594052) (xy 335.480211 -408.584869) (xy 335.473723 -408.567685)
			(xy 335.46796 -408.560524) (xy 335.44609 -408.534865) (xy 335.408004 -408.479228) (xy 335.376856 -408.419431)
			(xy 335.353094 -408.356333) (xy 335.33706 -408.290844) (xy 335.328985 -408.223906) (xy 335.328986 -408.156482)
			(xy 335.337062 -408.089544) (xy 335.353097 -408.024055) (xy 335.376861 -407.960958) (xy 335.40801 -407.901161)
			(xy 335.446097 -407.845526) (xy 335.46796 -407.81986) (xy 335.473763 -407.81272) (xy 335.480272 -407.795525)
			(xy 335.48066 -407.786332) (xy 335.48066 -407.628852) (xy 335.481145 -407.618745) (xy 335.488891 -407.600074)
			(xy 335.503187 -407.585782) (xy 335.521861 -407.578042) (xy 335.531968 -407.577544) (xy 336.248248 -407.577544)
			(xy 336.258353 -407.578045) (xy 336.277021 -407.585788) (xy 336.291312 -407.600079) (xy 336.299055 -407.618747)
			(xy 336.299556 -407.628852) (xy 336.299556 -407.786332) (xy 336.299961 -407.79552) (xy 336.306479 -407.812703)
			(xy 336.312256 -407.81986) (xy 336.334114 -407.845531) (xy 336.372205 -407.901164) (xy 336.403359 -407.960959)
			(xy 336.427126 -408.024055) (xy 336.443163 -408.089544) (xy 336.45124 -408.156482) (xy 336.451241 -408.223906)
			(xy 336.443165 -408.290844) (xy 336.427129 -408.356334) (xy 336.403364 -408.41943) (xy 336.372212 -408.479226)
			(xy 336.334121 -408.53486) (xy 336.312256 -408.560524) (xy 336.306461 -408.56767) (xy 336.299947 -408.58486)
			(xy 336.299556 -408.594052) (xy 336.299556 -409.086304) (xy 336.299974 -409.09549) (xy 336.306483 -409.112674)
			(xy 336.312256 -409.119832) (xy 336.334086 -409.145526) (xy 336.372179 -409.201155) (xy 336.403334 -409.260947)
			(xy 336.427102 -409.32404) (xy 336.443141 -409.389526) (xy 336.45122 -409.456462) (xy 336.451224 -409.523884)
			(xy 336.443151 -409.59082) (xy 336.427118 -409.656308) (xy 336.403356 -409.719404) (xy 336.372207 -409.779198)
			(xy 336.334119 -409.834832) (xy 336.312256 -409.860496) (xy 336.306473 -409.867651) (xy 336.299951 -409.884834)
			(xy 336.299556 -409.894024) (xy 336.299556 -410.051504) (xy 336.299019 -410.061606) (xy 336.291291 -410.080274)
			(xy 336.277011 -410.094566) (xy 336.25835 -410.102311) (xy 336.248248 -410.102812) (xy 335.531968 -410.102812)
			(xy 335.521859 -410.102341) (xy 335.503182 -410.094595) (xy 335.488889 -410.080294) (xy 335.481153 -410.061614)
			(xy 335.48066 -410.051504) (xy 335.48066 -409.894024) (xy 335.480225 -409.88484) (xy 335.473727 -409.867656)
			(xy 335.46796 -409.860496) (xy 335.446062 -409.834859) (xy 335.407977 -409.77922) (xy 335.37683 -409.719419)
			(xy 335.35307 -409.656319) (xy 335.337038 -409.590827) (xy 335.328966 -409.523886) (xy 334.200797 -409.523886)
			(xy 334.172062 -409.579044) (xy 334.133972 -409.634679) (xy 334.112108 -409.660344) (xy 334.106311 -409.667489)
			(xy 334.099796 -409.68468) (xy 334.099408 -409.693872) (xy 334.099408 -410.186124) (xy 334.099805 -410.195313)
			(xy 334.106328 -410.212497) (xy 334.112108 -410.219652) (xy 334.133956 -410.24533) (xy 334.172045 -410.300963)
			(xy 334.203196 -410.360758) (xy 334.22696 -410.423853) (xy 334.242997 -410.48934) (xy 334.251074 -410.556277)
			(xy 334.251075 -410.623641) (xy 337.529138 -410.623641) (xy 337.52914 -410.556335) (xy 337.537185 -410.489512)
			(xy 337.553158 -410.42413) (xy 337.576831 -410.361125) (xy 337.607864 -410.3014) (xy 337.645813 -410.245813)
			(xy 337.6676 -410.22016) (xy 337.673396 -410.213014) (xy 337.679911 -410.195824) (xy 337.6803 -410.186632)
			(xy 337.6803 -409.693364) (xy 337.679907 -409.684175) (xy 337.673382 -409.666991) (xy 337.6676 -409.659836)
			(xy 337.645825 -409.634174) (xy 337.607879 -409.578588) (xy 337.576847 -409.518865) (xy 337.553175 -409.455862)
			(xy 337.537203 -409.390482) (xy 337.529158 -409.323661) (xy 337.529157 -409.256357) (xy 337.537199 -409.189536)
			(xy 337.55317 -409.124155) (xy 337.57684 -409.061151) (xy 337.607869 -409.001428) (xy 337.645814 -408.945841)
			(xy 337.6676 -408.920188) (xy 337.673384 -408.913034) (xy 337.679906 -408.89585) (xy 337.6803 -408.88666)
			(xy 337.6803 -408.728672) (xy 337.680699 -408.718516) (xy 337.688503 -408.699763) (xy 337.702907 -408.685441)
			(xy 337.721704 -408.677742) (xy 337.731862 -408.677364) (xy 338.448142 -408.677364) (xy 338.458274 -408.677793)
			(xy 338.477001 -408.685539) (xy 338.491357 -408.699843) (xy 338.49917 -408.718542) (xy 338.499704 -408.728672)
			(xy 338.499704 -408.88666) (xy 338.500132 -408.895845) (xy 338.506633 -408.91303) (xy 338.512404 -408.920188)
			(xy 338.534202 -408.945831) (xy 338.572148 -409.00142) (xy 338.603178 -409.061145) (xy 338.626848 -409.124151)
			(xy 338.642819 -409.189534) (xy 338.650862 -409.256356) (xy 338.650861 -409.323662) (xy 338.642816 -409.390484)
			(xy 338.626843 -409.455867) (xy 338.603171 -409.518871) (xy 338.600596 -409.523827) (xy 339.729261 -409.523827)
			(xy 339.729264 -409.456519) (xy 339.737312 -409.389694) (xy 339.753289 -409.324309) (xy 339.776966 -409.261303)
			(xy 339.808004 -409.201579) (xy 339.845958 -409.145992) (xy 339.867748 -409.12034) (xy 339.873559 -409.113205)
			(xy 339.880064 -409.096006) (xy 339.880448 -409.086812) (xy 339.880448 -408.593544) (xy 339.880006 -408.58436)
			(xy 339.873513 -408.567176) (xy 339.867748 -408.560016) (xy 339.845952 -408.534371) (xy 339.808003 -408.478783)
			(xy 339.776969 -408.419059) (xy 339.753297 -408.356054) (xy 339.737324 -408.29067) (xy 339.72928 -408.223847)
			(xy 339.729281 -408.156541) (xy 339.737326 -408.089718) (xy 339.7533 -408.024335) (xy 339.776974 -407.96133)
			(xy 339.808009 -407.901606) (xy 339.845959 -407.84602) (xy 339.867748 -407.820368) (xy 339.873547 -407.813224)
			(xy 339.880059 -407.796032) (xy 339.880448 -407.78684) (xy 339.880448 -407.628852) (xy 339.880881 -407.618701)
			(xy 339.888683 -407.599958) (xy 339.903075 -407.585638) (xy 339.921857 -407.577931) (xy 339.93201 -407.577544)
			(xy 340.64829 -407.577544) (xy 340.658417 -407.578035) (xy 340.677138 -407.58576) (xy 340.691495 -407.600045)
			(xy 340.699314 -407.618728) (xy 340.699852 -407.628852) (xy 340.699852 -407.78684) (xy 340.700254 -407.796028)
			(xy 340.706775 -407.813211) (xy 340.712552 -407.820368) (xy 340.734332 -407.846027) (xy 340.772282 -407.901612)
			(xy 340.803316 -407.961335) (xy 340.826989 -408.024338) (xy 340.842963 -408.08972) (xy 340.851008 -408.156542)
			(xy 340.851009 -408.223846) (xy 340.842965 -408.290668) (xy 340.826993 -408.35605) (xy 340.803321 -408.419054)
			(xy 340.772288 -408.478778) (xy 340.734339 -408.534364) (xy 340.712552 -408.560016) (xy 340.70676 -408.567164)
			(xy 340.700244 -408.584353) (xy 340.699852 -408.593544) (xy 340.699852 -409.086812) (xy 340.700267 -409.095998)
			(xy 340.706779 -409.113182) (xy 340.712552 -409.12034) (xy 340.734304 -409.146021) (xy 340.772255 -409.201603)
			(xy 340.80329 -409.261323) (xy 340.826965 -409.324323) (xy 340.842941 -409.389702) (xy 340.850988 -409.456522)
			(xy 340.850992 -409.523824) (xy 340.842951 -409.590644) (xy 340.826981 -409.656025) (xy 340.803312 -409.719028)
			(xy 340.772283 -409.77875) (xy 340.734338 -409.834336) (xy 340.712552 -409.859988) (xy 340.70673 -409.867115)
			(xy 340.700232 -409.88432) (xy 340.699852 -409.893516) (xy 340.699852 -410.051504) (xy 340.699383 -410.061652)
			(xy 340.691595 -410.080394) (xy 340.677214 -410.094716) (xy 340.65844 -410.102424) (xy 340.64829 -410.102812)
			(xy 339.93201 -410.102812) (xy 339.92189 -410.102267) (xy 339.903179 -410.094552) (xy 339.888824 -410.080284)
			(xy 339.880996 -410.061621) (xy 339.880448 -410.051504) (xy 339.880448 -409.893516) (xy 339.88002 -409.884331)
			(xy 339.873517 -409.867147) (xy 339.867748 -409.859988) (xy 339.845924 -409.834365) (xy 339.807976 -409.778775)
			(xy 339.776944 -409.719047) (xy 339.753273 -409.656039) (xy 339.737302 -409.590653) (xy 339.729261 -409.523827)
			(xy 338.600596 -409.523827) (xy 338.572139 -409.578596) (xy 338.534191 -409.634183) (xy 338.512404 -409.659836)
			(xy 338.50661 -409.666983) (xy 338.500094 -409.684172) (xy 338.499704 -409.693364) (xy 338.499704 -410.186632)
			(xy 338.500098 -410.195821) (xy 338.506623 -410.213005) (xy 338.512404 -410.22016) (xy 338.534175 -410.245826)
			(xy 338.572121 -410.301411) (xy 338.603153 -410.361133) (xy 338.626825 -410.424136) (xy 338.642797 -410.489516)
			(xy 338.650842 -410.556336) (xy 338.650844 -410.623639) (xy 338.650837 -410.6237) (xy 341.928907 -410.6237)
			(xy 341.928908 -410.556276) (xy 341.936986 -410.489336) (xy 341.953023 -410.423846) (xy 341.976789 -410.360749)
			(xy 342.007941 -410.300952) (xy 342.046031 -410.245317) (xy 342.067896 -410.219652) (xy 342.073695 -410.212508)
			(xy 342.080208 -410.195317) (xy 342.080596 -410.186124) (xy 342.080596 -409.693872) (xy 342.0802 -409.684683)
			(xy 342.073677 -409.667499) (xy 342.067896 -409.660344) (xy 342.046044 -409.634669) (xy 342.007955 -409.579036)
			(xy 341.976804 -409.519241) (xy 341.953039 -409.456145) (xy 341.937003 -409.390657) (xy 341.928927 -409.32372)
			(xy 341.928925 -409.256298) (xy 341.937 -409.18936) (xy 341.953034 -409.123872) (xy 341.976797 -409.060776)
			(xy 342.007946 -409.00098) (xy 342.046033 -408.945345) (xy 342.067896 -408.91968) (xy 342.073683 -408.912528)
			(xy 342.080204 -408.895343) (xy 342.080596 -408.886152) (xy 342.080596 -408.728672) (xy 342.081062 -408.718562)
			(xy 342.088808 -408.699884) (xy 342.103111 -408.68559) (xy 342.121794 -408.677856) (xy 342.131904 -408.677364)
			(xy 342.848184 -408.677364) (xy 342.858287 -408.677897) (xy 342.876958 -408.685623) (xy 342.891252 -408.699905)
			(xy 342.898994 -408.718569) (xy 342.899492 -408.728672) (xy 342.899492 -408.886152) (xy 342.899927 -408.895337)
			(xy 342.906424 -408.912521) (xy 342.912192 -408.91968) (xy 342.934068 -408.945335) (xy 342.972157 -409.000971)
			(xy 343.003308 -409.060769) (xy 343.027071 -409.123867) (xy 343.043106 -409.189357) (xy 343.051181 -409.256297)
			(xy 343.05118 -409.323721) (xy 343.043103 -409.390661) (xy 343.027066 -409.45615) (xy 343.0033 -409.519248)
			(xy 343.000914 -409.523827) (xy 344.129052 -409.523827) (xy 344.129055 -409.456519) (xy 344.137102 -409.389694)
			(xy 344.153079 -409.32431) (xy 344.176756 -409.261304) (xy 344.207793 -409.201579) (xy 344.245746 -409.145992)
			(xy 344.267536 -409.12034) (xy 344.273345 -409.113204) (xy 344.279851 -409.096006) (xy 344.280236 -409.086812)
			(xy 344.280236 -408.593544) (xy 344.279796 -408.58436) (xy 344.273302 -408.567176) (xy 344.267536 -408.560016)
			(xy 344.24574 -408.53437) (xy 344.207792 -408.478783) (xy 344.176759 -408.419058) (xy 344.153087 -408.356053)
			(xy 344.137115 -408.29067) (xy 344.129071 -408.223847) (xy 344.129072 -408.156541) (xy 344.137117 -408.089718)
			(xy 344.153091 -408.024335) (xy 344.176764 -407.961331) (xy 344.207798 -407.901607) (xy 344.245748 -407.84602)
			(xy 344.267536 -407.820368) (xy 344.273333 -407.813223) (xy 344.279847 -407.796032) (xy 344.280236 -407.78684)
			(xy 344.280236 -407.628852) (xy 344.280583 -407.61869) (xy 344.288401 -407.59993) (xy 344.302821 -407.585607)
			(xy 344.321634 -407.577916) (xy 344.331798 -407.577544) (xy 345.048078 -407.577544) (xy 345.058204 -407.578045)
			(xy 345.076925 -407.585766) (xy 345.091283 -407.600048) (xy 345.099102 -407.618729) (xy 345.09964 -407.628852)
			(xy 345.09964 -407.78684) (xy 345.100044 -407.796028) (xy 345.106563 -407.813211) (xy 345.11234 -407.820368)
			(xy 345.13412 -407.846026) (xy 345.172071 -407.901611) (xy 345.203106 -407.961334) (xy 345.22678 -408.024338)
			(xy 345.242754 -408.089719) (xy 345.250799 -408.156542) (xy 345.2508 -408.223846) (xy 345.242756 -408.290669)
			(xy 345.226783 -408.356051) (xy 345.20311 -408.419055) (xy 345.172077 -408.478778) (xy 345.134128 -408.534364)
			(xy 345.11234 -408.560016) (xy 345.106547 -408.567163) (xy 345.100032 -408.584352) (xy 345.09964 -408.593544)
			(xy 345.09964 -409.086812) (xy 345.100058 -409.095998) (xy 345.106568 -409.113182) (xy 345.11234 -409.12034)
			(xy 345.134093 -409.146021) (xy 345.172044 -409.201603) (xy 345.20308 -409.261322) (xy 345.226756 -409.324323)
			(xy 345.242732 -409.389702) (xy 345.250779 -409.456522) (xy 345.250783 -409.523824) (xy 345.242742 -409.590645)
			(xy 345.226772 -409.656025) (xy 345.203102 -409.719028) (xy 345.172072 -409.778751) (xy 345.134126 -409.834336)
			(xy 345.11234 -409.859988) (xy 345.106516 -409.867114) (xy 345.100019 -409.884319) (xy 345.09964 -409.893516)
			(xy 345.09964 -410.051504) (xy 345.099182 -410.061653) (xy 345.091393 -410.080398) (xy 345.077008 -410.09472)
			(xy 345.058229 -410.102427) (xy 345.048078 -410.102812) (xy 344.331798 -410.102812) (xy 344.321678 -410.102277)
			(xy 344.302966 -410.094558) (xy 344.288612 -410.080287) (xy 344.280784 -410.061621) (xy 344.280236 -410.051504)
			(xy 344.280236 -409.893516) (xy 344.27981 -409.884331) (xy 344.273307 -409.867146) (xy 344.267536 -409.859988)
			(xy 344.245713 -409.834365) (xy 344.207765 -409.778774) (xy 344.176734 -409.719047) (xy 344.153063 -409.656038)
			(xy 344.137093 -409.590653) (xy 344.129052 -409.523827) (xy 343.000914 -409.523827) (xy 342.972148 -409.579044)
			(xy 342.934057 -409.634679) (xy 342.912192 -409.660344) (xy 342.906393 -409.667488) (xy 342.89988 -409.684679)
			(xy 342.899492 -409.693872) (xy 342.899492 -410.186124) (xy 342.899892 -410.195312) (xy 342.906413 -410.212496)
			(xy 342.912192 -410.219652) (xy 342.934041 -410.24533) (xy 342.97213 -410.300963) (xy 343.003282 -410.360757)
			(xy 343.027048 -410.423852) (xy 343.043084 -410.48934) (xy 343.051162 -410.556277) (xy 343.051163 -410.623642)
			(xy 346.329202 -410.623642) (xy 346.329204 -410.556334) (xy 346.33725 -410.48951) (xy 346.353226 -410.424126)
			(xy 346.376903 -410.361121) (xy 346.40794 -410.301397) (xy 346.445894 -410.245812) (xy 346.467684 -410.22016)
			(xy 346.473478 -410.213013) (xy 346.479995 -410.195824) (xy 346.480384 -410.186632) (xy 346.480384 -409.693364)
			(xy 346.479995 -409.684175) (xy 346.473467 -409.66699) (xy 346.467684 -409.659836) (xy 346.445907 -409.634175)
			(xy 346.407955 -409.578591) (xy 346.376918 -409.518869) (xy 346.353243 -409.455865) (xy 346.337268 -409.390484)
			(xy 346.329222 -409.323661) (xy 346.329221 -409.256357) (xy 346.337265 -409.189534) (xy 346.353238 -409.124152)
			(xy 346.376911 -409.061148) (xy 346.407945 -409.001425) (xy 346.445896 -408.94584) (xy 346.467684 -408.920188)
			(xy 346.473466 -408.913033) (xy 346.47999 -408.89585) (xy 346.480384 -408.88666) (xy 346.480384 -408.728672)
			(xy 346.480798 -408.718518) (xy 346.4886 -408.699768) (xy 346.502999 -408.685446) (xy 346.52179 -408.677745)
			(xy 346.531946 -408.677364) (xy 347.248226 -408.677364) (xy 347.258357 -408.677806) (xy 347.277084 -408.685547)
			(xy 347.29144 -408.699847) (xy 347.299254 -408.718543) (xy 347.299788 -408.728672) (xy 347.299788 -408.88666)
			(xy 347.30022 -408.895845) (xy 347.306719 -408.913029) (xy 347.312488 -408.920188) (xy 347.334287 -408.945831)
			(xy 347.372233 -409.001419) (xy 347.403265 -409.061144) (xy 347.426936 -409.12415) (xy 347.442907 -409.189533)
			(xy 347.45095 -409.256356) (xy 347.450949 -409.323662) (xy 347.442904 -409.390485) (xy 347.42693 -409.455867)
			(xy 347.403257 -409.518872) (xy 347.400682 -409.523827) (xy 374.929082 -409.523827) (xy 374.929085 -409.456519)
			(xy 374.937133 -409.389693) (xy 374.953111 -409.324308) (xy 374.97679 -409.261302) (xy 375.007829 -409.201578)
			(xy 375.045785 -409.145991) (xy 375.067576 -409.12034) (xy 375.073378 -409.113198) (xy 375.07989 -409.096005)
			(xy 375.080276 -409.086812) (xy 375.080276 -408.593544) (xy 375.07985 -408.584358) (xy 375.073348 -408.567174)
			(xy 375.067576 -408.560016) (xy 375.045779 -408.534371) (xy 375.007828 -408.478784) (xy 374.976793 -408.41906)
			(xy 374.953119 -408.356055) (xy 374.937146 -408.290671) (xy 374.929102 -408.223847) (xy 374.929103 -408.156541)
			(xy 374.937148 -408.089717) (xy 374.953123 -408.024334) (xy 374.976798 -407.961329) (xy 375.007835 -407.901605)
			(xy 375.045787 -407.84602) (xy 375.067576 -407.820368) (xy 375.073366 -407.813218) (xy 375.079885 -407.796031)
			(xy 375.080276 -407.78684) (xy 375.080276 -407.628852) (xy 375.080682 -407.618698) (xy 375.088489 -407.599949)
			(xy 375.10289 -407.585628) (xy 375.121682 -407.577926) (xy 375.131838 -407.577544) (xy 375.848118 -407.577544)
			(xy 375.858246 -407.578012) (xy 375.876969 -407.585746) (xy 375.891325 -407.600038) (xy 375.899143 -407.618726)
			(xy 375.89968 -407.628852) (xy 375.89968 -407.78684) (xy 375.900075 -407.796029) (xy 375.9066 -407.813213)
			(xy 375.91238 -407.820368) (xy 375.934159 -407.846027) (xy 375.972107 -407.901613) (xy 376.00314 -407.961336)
			(xy 376.026812 -408.024339) (xy 376.042785 -408.08972) (xy 376.05083 -408.156542) (xy 376.05083 -408.223846)
			(xy 376.042787 -408.290668) (xy 376.026816 -408.356049) (xy 376.003145 -408.419053) (xy 375.972113 -408.478777)
			(xy 375.934167 -408.534364) (xy 375.91238 -408.560016) (xy 375.906592 -408.567167) (xy 375.900073 -408.584353)
			(xy 375.89968 -408.593544) (xy 375.89968 -409.086812) (xy 375.900089 -409.095999) (xy 375.906604 -409.113183)
			(xy 375.91238 -409.12034) (xy 375.934131 -409.146022) (xy 375.97208 -409.201604) (xy 376.003114 -409.261324)
			(xy 376.026788 -409.324325) (xy 376.042763 -409.389703) (xy 376.050809 -409.456522) (xy 376.050813 -409.523824)
			(xy 376.042772 -409.590644) (xy 376.026804 -409.656024) (xy 376.003136 -409.719026) (xy 375.972108 -409.778749)
			(xy 375.934165 -409.834335) (xy 375.91238 -409.859988) (xy 375.906561 -409.867117) (xy 375.90006 -409.88432)
			(xy 375.89968 -409.893516) (xy 375.89968 -410.051504) (xy 375.899281 -410.061661) (xy 375.891481 -410.080417)
			(xy 375.877077 -410.094741) (xy 375.858277 -410.102437) (xy 375.848118 -410.102812) (xy 375.131838 -410.102812)
			(xy 375.12172 -410.102244) (xy 375.10301 -410.094538) (xy 375.088654 -410.080277) (xy 375.080824 -410.061618)
			(xy 375.080276 -410.051504) (xy 375.080276 -409.893516) (xy 375.079864 -409.884329) (xy 375.073352 -409.867144)
			(xy 375.067576 -409.859988) (xy 375.045751 -409.834366) (xy 375.007801 -409.778776) (xy 374.976768 -409.719048)
			(xy 374.953095 -409.65604) (xy 374.937124 -409.590654) (xy 374.929082 -409.523827) (xy 347.400682 -409.523827)
			(xy 347.372224 -409.578596) (xy 347.334276 -409.634184) (xy 347.312488 -409.659836) (xy 347.306692 -409.666982)
			(xy 347.300177 -409.684172) (xy 347.299788 -409.693364) (xy 347.299788 -410.186632) (xy 347.300185 -410.195821)
			(xy 347.306708 -410.213005) (xy 347.312488 -410.22016) (xy 347.334259 -410.245825) (xy 347.372207 -410.301411)
			(xy 347.403239 -410.361133) (xy 347.426912 -410.424135) (xy 347.442885 -410.489516) (xy 347.45093 -410.556336)
			(xy 347.450931 -410.62364) (xy 347.450924 -410.623701) (xy 377.128728 -410.623701) (xy 377.128729 -410.556275)
			(xy 377.136807 -410.489335) (xy 377.152845 -410.423845) (xy 377.176612 -410.360748) (xy 377.207766 -410.300951)
			(xy 377.245858 -410.245317) (xy 377.267724 -410.219652) (xy 377.273526 -410.212511) (xy 377.280037 -410.195317)
			(xy 377.280424 -410.186124) (xy 377.280424 -409.693872) (xy 377.280022 -409.684684) (xy 377.273502 -409.6675)
			(xy 377.267724 -409.660344) (xy 377.245871 -409.634669) (xy 377.20778 -409.579037) (xy 377.176628 -409.519242)
			(xy 377.152862 -409.456146) (xy 377.136825 -409.390658) (xy 377.128748 -409.323721) (xy 377.128747 -409.256297)
			(xy 377.136822 -409.18936) (xy 377.152857 -409.123871) (xy 377.17662 -409.060774) (xy 377.207771 -409.000979)
			(xy 377.24586 -408.945345) (xy 377.267724 -408.91968) (xy 377.273514 -408.912531) (xy 377.280032 -408.895343)
			(xy 377.280424 -408.886152) (xy 377.280424 -408.728672) (xy 377.280794 -408.718545) (xy 377.288555 -408.699836)
			(xy 377.302886 -408.685522) (xy 377.321604 -408.677782) (xy 377.331732 -408.677364) (xy 378.048012 -408.677364)
			(xy 378.058117 -408.677875) (xy 378.076789 -408.685609) (xy 378.091082 -408.699898) (xy 378.098822 -408.718567)
			(xy 378.09932 -408.728672) (xy 378.09932 -408.886152) (xy 378.099749 -408.895337) (xy 378.106249 -408.912522)
			(xy 378.11202 -408.91968) (xy 378.133895 -408.945336) (xy 378.171982 -409.000972) (xy 378.203131 -409.06077)
			(xy 378.226894 -409.123868) (xy 378.242928 -409.189358) (xy 378.251002 -409.256297) (xy 378.251001 -409.323721)
			(xy 378.242925 -409.39066) (xy 378.226888 -409.456149) (xy 378.203124 -409.519247) (xy 378.200707 -409.523886)
			(xy 379.328875 -409.523886) (xy 379.328878 -409.45646) (xy 379.336957 -409.38952) (xy 379.352995 -409.324029)
			(xy 379.376762 -409.260931) (xy 379.407916 -409.201133) (xy 379.446007 -409.145498) (xy 379.467872 -409.119832)
			(xy 379.473689 -409.112701) (xy 379.480189 -409.095499) (xy 379.480572 -409.086304) (xy 379.480572 -408.594052)
			(xy 379.480143 -408.584867) (xy 379.473643 -408.567682) (xy 379.467872 -408.560524) (xy 379.446001 -408.534865)
			(xy 379.407915 -408.479229) (xy 379.376766 -408.419431) (xy 379.353003 -408.356334) (xy 379.336969 -408.290844)
			(xy 379.328894 -408.223906) (xy 379.328895 -408.156482) (xy 379.336971 -408.089544) (xy 379.353007 -408.024055)
			(xy 379.376771 -407.960958) (xy 379.407921 -407.901161) (xy 379.446009 -407.845526) (xy 379.467872 -407.81986)
			(xy 379.473677 -407.812721) (xy 379.480185 -407.795525) (xy 379.480572 -407.786332) (xy 379.480572 -407.628852)
			(xy 379.481045 -407.618744) (xy 379.488793 -407.60007) (xy 379.503093 -407.585778) (xy 379.521771 -407.57804)
			(xy 379.53188 -407.577544) (xy 380.24816 -407.577544) (xy 380.258259 -407.578117) (xy 380.276926 -407.585831)
			(xy 380.29122 -407.6001) (xy 380.298966 -407.618754) (xy 380.299468 -407.628852) (xy 380.299468 -407.786332)
			(xy 380.29987 -407.79552) (xy 380.30639 -407.812704) (xy 380.312168 -407.81986) (xy 380.334025 -407.845531)
			(xy 380.372116 -407.901164) (xy 380.403269 -407.960959) (xy 380.427035 -408.024055) (xy 380.443072 -408.089544)
			(xy 380.451149 -408.156482) (xy 380.45115 -408.223906) (xy 380.443074 -408.290844) (xy 380.427039 -408.356333)
			(xy 380.403274 -408.41943) (xy 380.372122 -408.479226) (xy 380.334033 -408.534859) (xy 380.312168 -408.560524)
			(xy 380.306375 -408.567671) (xy 380.299859 -408.58486) (xy 380.299468 -408.594052) (xy 380.299468 -409.086304)
			(xy 380.299883 -409.09549) (xy 380.306394 -409.112675) (xy 380.312168 -409.119832) (xy 380.333998 -409.145526)
			(xy 380.37209 -409.201156) (xy 380.403244 -409.260947) (xy 380.427011 -409.324041) (xy 380.44305 -409.389527)
			(xy 380.451129 -409.456462) (xy 380.451133 -409.523884) (xy 380.44306 -409.59082) (xy 380.427027 -409.656308)
			(xy 380.403266 -409.719403) (xy 380.372117 -409.779198) (xy 380.334031 -409.834831) (xy 380.312168 -409.860496)
			(xy 380.306386 -409.867652) (xy 380.299864 -409.884834) (xy 380.299468 -409.894024) (xy 380.299468 -410.051504)
			(xy 380.299086 -410.061631) (xy 380.291331 -410.08034) (xy 380.277003 -410.094656) (xy 380.258287 -410.102395)
			(xy 380.24816 -410.102812) (xy 379.53188 -410.102812) (xy 379.521771 -410.102332) (xy 379.503095 -410.09459)
			(xy 379.488801 -410.080292) (xy 379.481065 -410.061613) (xy 379.480572 -410.051504) (xy 379.480572 -409.894024)
			(xy 379.480157 -409.884837) (xy 379.473647 -409.867652) (xy 379.467872 -409.860496) (xy 379.445974 -409.834859)
			(xy 379.407888 -409.77922) (xy 379.37674 -409.71942) (xy 379.352979 -409.656319) (xy 379.336947 -409.590827)
			(xy 379.328875 -409.523886) (xy 378.200707 -409.523886) (xy 378.171973 -409.579043) (xy 378.133884 -409.634678)
			(xy 378.11202 -409.660344) (xy 378.106225 -409.66749) (xy 378.099709 -409.68468) (xy 378.09932 -409.693872)
			(xy 378.09932 -410.186124) (xy 378.099714 -410.195313) (xy 378.106239 -410.212497) (xy 378.11202 -410.219652)
			(xy 378.133868 -410.245331) (xy 378.171955 -410.300964) (xy 378.203106 -410.360758) (xy 378.22687 -410.423853)
			(xy 378.242906 -410.48934) (xy 378.250983 -410.556277) (xy 378.250984 -410.623641) (xy 381.529047 -410.623641)
			(xy 381.529049 -410.556335) (xy 381.537094 -410.489512) (xy 381.553068 -410.424129) (xy 381.576742 -410.361124)
			(xy 381.607775 -410.3014) (xy 381.645724 -410.245812) (xy 381.667512 -410.22016) (xy 381.673309 -410.213015)
			(xy 381.679823 -410.195824) (xy 381.680212 -410.186632) (xy 381.680212 -409.693364) (xy 381.679817 -409.684175)
			(xy 381.673292 -409.666991) (xy 381.667512 -409.659836) (xy 381.645737 -409.634174) (xy 381.607789 -409.578588)
			(xy 381.576757 -409.518866) (xy 381.553085 -409.455863) (xy 381.537112 -409.390482) (xy 381.529067 -409.323661)
			(xy 381.529066 -409.256357) (xy 381.537109 -409.189536) (xy 381.553079 -409.124155) (xy 381.57675 -409.061151)
			(xy 381.60778 -409.001427) (xy 381.645726 -408.94584) (xy 381.667512 -408.920188) (xy 381.673298 -408.913035)
			(xy 381.679818 -408.89585) (xy 381.680212 -408.88666) (xy 381.680212 -408.728672) (xy 381.680662 -408.71856)
			(xy 381.688411 -408.699879) (xy 381.702719 -408.685585) (xy 381.721408 -408.677853) (xy 381.73152 -408.677364)
			(xy 382.448054 -408.677364) (xy 382.458181 -408.677865) (xy 382.476905 -408.685582) (xy 382.491264 -408.699865)
			(xy 382.499081 -408.718548) (xy 382.499616 -408.728672) (xy 382.499616 -408.88666) (xy 382.500042 -408.895846)
			(xy 382.506544 -408.91303) (xy 382.512316 -408.920188) (xy 382.534117 -408.94583) (xy 382.572068 -409.001417)
			(xy 382.603103 -409.061141) (xy 382.626778 -409.124147) (xy 382.642751 -409.189531) (xy 382.650795 -409.256356)
			(xy 382.650794 -409.323662) (xy 382.642748 -409.390487) (xy 382.626772 -409.45587) (xy 382.603096 -409.518875)
			(xy 382.600523 -409.523827) (xy 383.72917 -409.523827) (xy 383.729173 -409.456519) (xy 383.737221 -409.389693)
			(xy 383.753198 -409.324309) (xy 383.776876 -409.261303) (xy 383.807915 -409.201578) (xy 383.845869 -409.145992)
			(xy 383.86766 -409.12034) (xy 383.873472 -409.113206) (xy 383.879976 -409.096007) (xy 383.88036 -409.086812)
			(xy 383.88036 -408.593544) (xy 383.879915 -408.584361) (xy 383.873424 -408.567177) (xy 383.86766 -408.560016)
			(xy 383.845864 -408.53437) (xy 383.807914 -408.478784) (xy 383.77688 -408.419059) (xy 383.753207 -408.356054)
			(xy 383.737234 -408.290671) (xy 383.72919 -408.223847) (xy 383.729191 -408.156541) (xy 383.737236 -408.089717)
			(xy 383.75321 -408.024335) (xy 383.776885 -407.96133) (xy 383.80792 -407.901606) (xy 383.845871 -407.84602)
			(xy 383.86766 -407.820368) (xy 383.87346 -407.813226) (xy 383.879971 -407.796033) (xy 383.88036 -407.78684)
			(xy 383.88036 -407.628852) (xy 383.880845 -407.618745) (xy 383.888591 -407.600074) (xy 383.902887 -407.585782)
			(xy 383.921561 -407.578042) (xy 383.931668 -407.577544) (xy 384.648202 -407.577544) (xy 384.658329 -407.578025)
			(xy 384.677051 -407.585754) (xy 384.691408 -407.600042) (xy 384.699226 -407.618727) (xy 384.699764 -407.628852)
			(xy 384.699764 -407.78684) (xy 384.700163 -407.796028) (xy 384.706685 -407.813212) (xy 384.712464 -407.820368)
			(xy 384.734244 -407.846027) (xy 384.772193 -407.901612) (xy 384.803226 -407.961335) (xy 384.826899 -408.024339)
			(xy 384.842873 -408.08972) (xy 384.850918 -408.156542) (xy 384.850918 -408.223846) (xy 384.842875 -408.290668)
			(xy 384.826903 -408.35605) (xy 384.803231 -408.419054) (xy 384.772199 -408.478778) (xy 384.734251 -408.534364)
			(xy 384.712464 -408.560016) (xy 384.706674 -408.567165) (xy 384.700156 -408.584353) (xy 384.699764 -408.593544)
			(xy 384.699764 -409.086812) (xy 384.700176 -409.095999) (xy 384.706689 -409.113183) (xy 384.712464 -409.12034)
			(xy 384.734216 -409.146021) (xy 384.772166 -409.201604) (xy 384.8032 -409.261323) (xy 384.826875 -409.324324)
			(xy 384.84285 -409.389703) (xy 384.850897 -409.456522) (xy 384.850901 -409.523824) (xy 384.84286 -409.590644)
			(xy 384.826891 -409.656024) (xy 384.803222 -409.719027) (xy 384.772194 -409.77875) (xy 384.734249 -409.834336)
			(xy 384.712464 -409.859988) (xy 384.706643 -409.867116) (xy 384.700144 -409.88432) (xy 384.699764 -409.893516)
			(xy 384.699764 -410.051504) (xy 384.699386 -410.061631) (xy 384.69163 -410.080342) (xy 384.677301 -410.094657)
			(xy 384.658584 -410.102396) (xy 384.648456 -410.102812) (xy 383.931922 -410.102812) (xy 383.921803 -410.102257)
			(xy 383.903092 -410.094546) (xy 383.888737 -410.080281) (xy 383.880908 -410.06162) (xy 383.88036 -410.051504)
			(xy 383.88036 -409.893516) (xy 383.879929 -409.884331) (xy 383.873428 -409.867147) (xy 383.86766 -409.859988)
			(xy 383.845836 -409.834365) (xy 383.807887 -409.778775) (xy 383.776854 -409.719048) (xy 383.753182 -409.656039)
			(xy 383.737211 -409.590653) (xy 383.72917 -409.523827) (xy 382.600523 -409.523827) (xy 382.572059 -409.578599)
			(xy 382.534106 -409.634184) (xy 382.512316 -409.659836) (xy 382.506523 -409.666984) (xy 382.500006 -409.684172)
			(xy 382.499616 -409.693364) (xy 382.499616 -410.186632) (xy 382.500007 -410.195821) (xy 382.506534 -410.213006)
			(xy 382.512316 -410.22016) (xy 382.534089 -410.245824) (xy 382.572042 -410.301408) (xy 382.603078 -410.36113)
			(xy 382.626754 -410.424133) (xy 382.642729 -410.489514) (xy 382.650775 -410.556336) (xy 382.650777 -410.62364)
			(xy 382.65077 -410.623701) (xy 385.928816 -410.623701) (xy 385.928817 -410.556275) (xy 385.936895 -410.489336)
			(xy 385.952932 -410.423846) (xy 385.976699 -410.360748) (xy 386.007852 -410.300952) (xy 386.045943 -410.245317)
			(xy 386.067808 -410.219652) (xy 386.073608 -410.21251) (xy 386.080121 -410.195317) (xy 386.080508 -410.186124)
			(xy 386.080508 -409.693872) (xy 386.08011 -409.684684) (xy 386.073588 -409.667499) (xy 386.067808 -409.660344)
			(xy 386.045956 -409.634669) (xy 386.007866 -409.579036) (xy 385.976714 -409.519241) (xy 385.952949 -409.456146)
			(xy 385.936913 -409.390658) (xy 385.928836 -409.32372) (xy 385.928834 -409.256298) (xy 385.936909 -409.18936)
			(xy 385.952944 -409.123871) (xy 385.976707 -409.060775) (xy 386.007857 -409.000979) (xy 386.045944 -408.945345)
			(xy 386.067808 -408.91968) (xy 386.073596 -408.912529) (xy 386.080116 -408.895343) (xy 386.080508 -408.886152)
			(xy 386.080508 -408.728672) (xy 386.080962 -408.71856) (xy 386.088711 -408.69988) (xy 386.103017 -408.685586)
			(xy 386.121704 -408.677854) (xy 386.131816 -408.677364) (xy 386.848096 -408.677364) (xy 386.8582 -408.677888)
			(xy 386.876871 -408.685617) (xy 386.891165 -408.699902) (xy 386.898906 -408.718568) (xy 386.899404 -408.728672)
			(xy 386.899404 -408.886152) (xy 386.899836 -408.895337) (xy 386.906334 -408.912522) (xy 386.912104 -408.91968)
			(xy 386.93398 -408.945336) (xy 386.972068 -409.000972) (xy 387.003218 -409.060769) (xy 387.026981 -409.123867)
			(xy 387.043016 -409.189357) (xy 387.05109 -409.256297) (xy 387.051089 -409.323721) (xy 387.043012 -409.39066)
			(xy 387.026976 -409.45615) (xy 387.00321 -409.519247) (xy 387.000824 -409.523827) (xy 388.128961 -409.523827)
			(xy 388.128964 -409.456519) (xy 388.137012 -409.389694) (xy 388.152989 -409.324309) (xy 388.176666 -409.261303)
			(xy 388.207704 -409.201579) (xy 388.245658 -409.145992) (xy 388.267448 -409.12034) (xy 388.273259 -409.113205)
			(xy 388.279764 -409.096006) (xy 388.280148 -409.086812) (xy 388.280148 -408.593544) (xy 388.279706 -408.58436)
			(xy 388.273213 -408.567176) (xy 388.267448 -408.560016) (xy 388.245652 -408.534371) (xy 388.207703 -408.478783)
			(xy 388.176669 -408.419059) (xy 388.152997 -408.356054) (xy 388.137024 -408.29067) (xy 388.12898 -408.223847)
			(xy 388.128981 -408.156541) (xy 388.137026 -408.089718) (xy 388.153 -408.024335) (xy 388.176674 -407.96133)
			(xy 388.207709 -407.901606) (xy 388.245659 -407.84602) (xy 388.267448 -407.820368) (xy 388.273247 -407.813224)
			(xy 388.279759 -407.796032) (xy 388.280148 -407.78684) (xy 388.280148 -407.628852) (xy 388.280645 -407.618747)
			(xy 388.288388 -407.600077) (xy 388.302681 -407.585786) (xy 388.321351 -407.578044) (xy 388.331456 -407.577544)
			(xy 389.04799 -407.577544) (xy 389.058117 -407.578035) (xy 389.076838 -407.58576) (xy 389.091195 -407.600045)
			(xy 389.099014 -407.618728) (xy 389.099552 -407.628852) (xy 389.099552 -407.78684) (xy 389.099954 -407.796028)
			(xy 389.106475 -407.813211) (xy 389.112252 -407.820368) (xy 389.134032 -407.846027) (xy 389.171982 -407.901612)
			(xy 389.203016 -407.961335) (xy 389.226689 -408.024338) (xy 389.242663 -408.08972) (xy 389.250708 -408.156542)
			(xy 389.250709 -408.223846) (xy 389.242665 -408.290668) (xy 389.226693 -408.35605) (xy 389.203021 -408.419054)
			(xy 389.171988 -408.478778) (xy 389.134039 -408.534364) (xy 389.112252 -408.560016) (xy 389.10646 -408.567164)
			(xy 389.099944 -408.584353) (xy 389.099552 -408.593544) (xy 389.099552 -409.086812) (xy 389.099967 -409.095998)
			(xy 389.106479 -409.113182) (xy 389.112252 -409.12034) (xy 389.134004 -409.146021) (xy 389.171955 -409.201603)
			(xy 389.20299 -409.261323) (xy 389.226665 -409.324323) (xy 389.242641 -409.389702) (xy 389.250688 -409.456522)
			(xy 389.250692 -409.523824) (xy 389.242651 -409.590644) (xy 389.226681 -409.656025) (xy 389.203012 -409.719028)
			(xy 389.171983 -409.77875) (xy 389.134038 -409.834336) (xy 389.112252 -409.859988) (xy 389.10643 -409.867115)
			(xy 389.099932 -409.88432) (xy 389.099552 -409.893516) (xy 389.099552 -410.051504) (xy 389.099019 -410.061607)
			(xy 389.09129 -410.080275) (xy 389.077008 -410.094568) (xy 389.058346 -410.102311) (xy 389.048244 -410.102812)
			(xy 388.33171 -410.102812) (xy 388.32159 -410.102267) (xy 388.302879 -410.094552) (xy 388.288524 -410.080284)
			(xy 388.280696 -410.061621) (xy 388.280148 -410.051504) (xy 388.280148 -409.893516) (xy 388.27972 -409.884331)
			(xy 388.273217 -409.867147) (xy 388.267448 -409.859988) (xy 388.245624 -409.834365) (xy 388.207676 -409.778775)
			(xy 388.176644 -409.719047) (xy 388.152973 -409.656039) (xy 388.137002 -409.590653) (xy 388.128961 -409.523827)
			(xy 387.000824 -409.523827) (xy 386.972058 -409.579044) (xy 386.933969 -409.634679) (xy 386.912104 -409.660344)
			(xy 386.906307 -409.667489) (xy 386.899792 -409.68468) (xy 386.899404 -409.693872) (xy 386.899404 -410.186124)
			(xy 386.899801 -410.195313) (xy 386.906324 -410.212497) (xy 386.912104 -410.219652) (xy 386.933952 -410.24533)
			(xy 386.972041 -410.300963) (xy 387.003192 -410.360757) (xy 387.026957 -410.423853) (xy 387.042994 -410.48934)
			(xy 387.051071 -410.556277) (xy 387.051072 -410.623641) (xy 390.329135 -410.623641) (xy 390.329137 -410.556335)
			(xy 390.337182 -410.489512) (xy 390.353155 -410.42413) (xy 390.376828 -410.361125) (xy 390.407861 -410.3014)
			(xy 390.445809 -410.245813) (xy 390.467596 -410.22016) (xy 390.473392 -410.213014) (xy 390.479907 -410.195824)
			(xy 390.480296 -410.186632) (xy 390.480296 -409.693364) (xy 390.479904 -409.684175) (xy 390.473378 -409.666991)
			(xy 390.467596 -409.659836) (xy 390.445821 -409.634174) (xy 390.407875 -409.578588) (xy 390.376844 -409.518865)
			(xy 390.353172 -409.455862) (xy 390.3372 -409.390481) (xy 390.329155 -409.323661) (xy 390.329154 -409.256357)
			(xy 390.337196 -409.189536) (xy 390.353167 -409.124155) (xy 390.376836 -409.061151) (xy 390.407866 -409.001428)
			(xy 390.44581 -408.945841) (xy 390.467596 -408.920188) (xy 390.47338 -408.913034) (xy 390.479902 -408.89585)
			(xy 390.480296 -408.88666) (xy 390.480296 -408.728672) (xy 390.480762 -408.718562) (xy 390.488508 -408.699884)
			(xy 390.502811 -408.68559) (xy 390.521494 -408.677856) (xy 390.531604 -408.677364) (xy 391.248138 -408.677364)
			(xy 391.25827 -408.677796) (xy 391.276997 -408.685541) (xy 391.291352 -408.699844) (xy 391.299166 -408.718542)
			(xy 391.2997 -408.728672) (xy 391.2997 -408.88666) (xy 391.300129 -408.895845) (xy 391.30663 -408.91303)
			(xy 391.3124 -408.920188) (xy 391.334198 -408.945831) (xy 391.372144 -409.00142) (xy 391.403175 -409.061145)
			(xy 391.426845 -409.12415) (xy 391.442816 -409.189533) (xy 391.450859 -409.256356) (xy 391.450858 -409.323662)
			(xy 391.442813 -409.390484) (xy 391.42684 -409.455867) (xy 391.403167 -409.518872) (xy 391.372135 -409.578596)
			(xy 391.334187 -409.634183) (xy 391.3124 -409.659836) (xy 391.306606 -409.666983) (xy 391.30009 -409.684172)
			(xy 391.2997 -409.693364) (xy 391.2997 -410.186632) (xy 391.300095 -410.195821) (xy 391.306619 -410.213005)
			(xy 391.3124 -410.22016) (xy 391.334171 -410.245826) (xy 391.372118 -410.301411) (xy 391.403149 -410.361133)
			(xy 391.426821 -410.424136) (xy 391.442794 -410.489516) (xy 391.450839 -410.556336) (xy 391.450841 -410.623639)
			(xy 391.442799 -410.69046) (xy 391.426828 -410.755841) (xy 391.403159 -410.818845) (xy 391.37213 -410.878568)
			(xy 391.334186 -410.934155) (xy 391.3124 -410.959808) (xy 391.306618 -410.966963) (xy 391.300094 -410.984146)
			(xy 391.2997 -410.993336) (xy 391.2997 -411.151324) (xy 391.299235 -411.161434) (xy 391.291489 -411.180113)
			(xy 391.277186 -411.194407) (xy 391.258503 -411.202141) (xy 391.248392 -411.202632) (xy 390.531858 -411.202632)
			(xy 390.521725 -411.202207) (xy 390.502998 -411.19446) (xy 390.488642 -411.180155) (xy 390.480829 -411.161455)
			(xy 390.480296 -411.151324) (xy 390.480296 -410.993336) (xy 390.479869 -410.984151) (xy 390.473367 -410.966966)
			(xy 390.467596 -410.959808) (xy 390.445794 -410.934168) (xy 390.407848 -410.878579) (xy 390.376818 -410.818853)
			(xy 390.353148 -410.755847) (xy 390.337178 -410.690464) (xy 390.329135 -410.623641) (xy 387.051072 -410.623641)
			(xy 387.051072 -410.623699) (xy 387.042998 -410.690636) (xy 387.026964 -410.756124) (xy 387.003202 -410.819221)
			(xy 386.972053 -410.879016) (xy 386.933967 -410.934651) (xy 386.912104 -410.960316) (xy 386.906319 -410.967469)
			(xy 386.899797 -410.984654) (xy 386.899404 -410.993844) (xy 386.899404 -411.151324) (xy 386.898935 -411.161434)
			(xy 386.89119 -411.180112) (xy 386.876888 -411.194406) (xy 386.858206 -411.20214) (xy 386.848096 -411.202632)
			(xy 386.131816 -411.202632) (xy 386.121712 -411.202103) (xy 386.10304 -411.194376) (xy 386.088746 -411.180093)
			(xy 386.081005 -411.161427) (xy 386.080508 -411.151324) (xy 386.080508 -410.993844) (xy 386.080075 -410.984659)
			(xy 386.073577 -410.967475) (xy 386.067808 -410.960316) (xy 386.045928 -410.934664) (xy 386.007839 -410.879028)
			(xy 385.976689 -410.81923) (xy 385.952925 -410.756131) (xy 385.936891 -410.69064) (xy 385.928816 -410.623701)
			(xy 382.65077 -410.623701) (xy 382.642733 -410.690463) (xy 382.626761 -410.755844) (xy 382.603088 -410.818848)
			(xy 382.572054 -410.878571) (xy 382.534104 -410.934156) (xy 382.512316 -410.959808) (xy 382.506535 -410.966965)
			(xy 382.500011 -410.984146) (xy 382.499616 -410.993336) (xy 382.499616 -411.151324) (xy 382.499135 -411.161432)
			(xy 382.491392 -411.180108) (xy 382.477095 -411.194401) (xy 382.458416 -411.202138) (xy 382.448308 -411.202632)
			(xy 381.731774 -411.202632) (xy 381.721642 -411.202194) (xy 381.702915 -411.194453) (xy 381.688559 -411.180151)
			(xy 381.680745 -411.161454) (xy 381.680212 -411.151324) (xy 381.680212 -410.993336) (xy 381.679782 -410.984151)
			(xy 381.673282 -410.966967) (xy 381.667512 -410.959808) (xy 381.645709 -410.934168) (xy 381.607763 -410.87858)
			(xy 381.576732 -410.818854) (xy 381.553061 -410.755848) (xy 381.53709 -410.690464) (xy 381.529047 -410.623641)
			(xy 378.250984 -410.623641) (xy 378.250984 -410.623699) (xy 378.24291 -410.690636) (xy 378.226877 -410.756124)
			(xy 378.203116 -410.81922) (xy 378.171968 -410.879016) (xy 378.133882 -410.93465) (xy 378.11202 -410.960316)
			(xy 378.106236 -410.967471) (xy 378.099713 -410.984654) (xy 378.09932 -410.993844) (xy 378.09932 -411.151324)
			(xy 378.098835 -411.161432) (xy 378.091093 -411.180107) (xy 378.076797 -411.1944) (xy 378.05812 -411.202138)
			(xy 378.048012 -411.202632) (xy 377.331732 -411.202632) (xy 377.321615 -411.202159) (xy 377.302919 -411.194427)
			(xy 377.288604 -411.180128) (xy 377.280852 -411.16144) (xy 377.280424 -411.151324) (xy 377.280424 -410.993844)
			(xy 377.279987 -410.98466) (xy 377.273491 -410.967475) (xy 377.267724 -410.960316) (xy 377.245843 -410.934664)
			(xy 377.207754 -410.879028) (xy 377.176602 -410.81923) (xy 377.152838 -410.756132) (xy 377.136803 -410.690641)
			(xy 377.128728 -410.623701) (xy 347.450924 -410.623701) (xy 347.442889 -410.690461) (xy 347.426919 -410.755842)
			(xy 347.403249 -410.818845) (xy 347.372219 -410.878569) (xy 347.334274 -410.934156) (xy 347.312488 -410.959808)
			(xy 347.306704 -410.966962) (xy 347.300182 -410.984146) (xy 347.299788 -410.993336) (xy 347.299788 -411.151324)
			(xy 347.299398 -411.161481) (xy 347.291592 -411.180236) (xy 347.277186 -411.194559) (xy 347.258386 -411.202256)
			(xy 347.248226 -411.202632) (xy 346.531946 -411.202632) (xy 346.521819 -411.202135) (xy 346.503093 -411.194417)
			(xy 346.488735 -411.180133) (xy 346.480919 -411.161449) (xy 346.480384 -411.151324) (xy 346.480384 -410.993336)
			(xy 346.47996 -410.98415) (xy 346.473456 -410.966965) (xy 346.467684 -410.959808) (xy 346.445879 -410.934169)
			(xy 346.407928 -410.878582) (xy 346.376893 -410.818857) (xy 346.353219 -410.755851) (xy 346.337246 -410.690466)
			(xy 346.329202 -410.623642) (xy 343.051163 -410.623642) (xy 343.051163 -410.623699) (xy 343.043089 -410.690637)
			(xy 343.027055 -410.756125) (xy 343.003292 -410.819221) (xy 342.972143 -410.879017) (xy 342.934055 -410.934651)
			(xy 342.912192 -410.960316) (xy 342.906405 -410.967468) (xy 342.899885 -410.984653) (xy 342.899492 -410.993844)
			(xy 342.899492 -411.151324) (xy 342.899034 -411.161435) (xy 342.891287 -411.180116) (xy 342.876982 -411.19441)
			(xy 342.858296 -411.202142) (xy 342.848184 -411.202632) (xy 342.131904 -411.202632) (xy 342.121799 -411.202112)
			(xy 342.103128 -411.194382) (xy 342.088834 -411.180096) (xy 342.081093 -411.161428) (xy 342.080596 -411.151324)
			(xy 342.080596 -410.993844) (xy 342.080166 -410.984659) (xy 342.073666 -410.967474) (xy 342.067896 -410.960316)
			(xy 342.046016 -410.934664) (xy 342.007928 -410.879027) (xy 341.976779 -410.819229) (xy 341.953016 -410.756131)
			(xy 341.936981 -410.69064) (xy 341.928907 -410.6237) (xy 338.650837 -410.6237) (xy 338.642802 -410.69046)
			(xy 338.626832 -410.755841) (xy 338.603163 -410.818845) (xy 338.572134 -410.878568) (xy 338.534189 -410.934155)
			(xy 338.512404 -410.959808) (xy 338.506622 -410.966964) (xy 338.500098 -410.984146) (xy 338.499704 -410.993336)
			(xy 338.499704 -411.151324) (xy 338.499298 -411.161479) (xy 338.491495 -411.180231) (xy 338.477094 -411.194554)
			(xy 338.458299 -411.202253) (xy 338.448142 -411.202632) (xy 337.731862 -411.202632) (xy 337.721729 -411.202204)
			(xy 337.703002 -411.194458) (xy 337.688646 -411.180154) (xy 337.680833 -411.161455) (xy 337.6803 -411.151324)
			(xy 337.6803 -410.993336) (xy 337.679873 -410.984151) (xy 337.673371 -410.966966) (xy 337.6676 -410.959808)
			(xy 337.645798 -410.934168) (xy 337.607852 -410.878579) (xy 337.576822 -410.818853) (xy 337.553151 -410.755847)
			(xy 337.537181 -410.690464) (xy 337.529138 -410.623641) (xy 334.251075 -410.623641) (xy 334.251075 -410.623699)
			(xy 334.243001 -410.690636) (xy 334.226967 -410.756124) (xy 334.203205 -410.81922) (xy 334.172057 -410.879016)
			(xy 334.133971 -410.934651) (xy 334.112108 -410.960316) (xy 334.106323 -410.96747) (xy 334.099801 -410.984654)
			(xy 334.099408 -410.993844) (xy 334.099408 -411.151324) (xy 334.098935 -411.161433) (xy 334.091191 -411.180111)
			(xy 334.07689 -411.194404) (xy 334.05821 -411.20214) (xy 334.0481 -411.202632) (xy 333.33182 -411.202632)
			(xy 333.321716 -411.202099) (xy 333.303045 -411.194374) (xy 333.28875 -411.180092) (xy 333.281009 -411.161427)
			(xy 333.280512 -411.151324) (xy 333.280512 -410.993844) (xy 333.280078 -410.984659) (xy 333.273581 -410.967475)
			(xy 333.267812 -410.960316) (xy 333.245932 -410.934664) (xy 333.207843 -410.879028) (xy 333.176692 -410.81923)
			(xy 333.152928 -410.756131) (xy 333.136894 -410.69064) (xy 333.128819 -410.623701) (xy 326.525636 -410.623701)
			(xy 326.525636 -417.379404) (xy 326.525636 -417.533836) (xy 401.074128 -417.533836) (xy 401.074128 -417.366196)
			(xy 401.074128 -394.27912) (xy 414.451292 -394.27912) (xy 414.525968 -394.353542) (xy 414.525968 -397.823826)
			(xy 418.92899 -397.823826) (xy 418.928993 -397.756517) (xy 418.937042 -397.689691) (xy 418.95302 -397.624306)
			(xy 418.9767 -397.5613) (xy 419.00774 -397.501575) (xy 419.045697 -397.44599) (xy 419.067488 -397.420338)
			(xy 419.073292 -397.413198) (xy 419.079803 -397.396004) (xy 419.080188 -397.38681) (xy 419.080188 -396.893542)
			(xy 419.07976 -396.884357) (xy 419.073259 -396.867172) (xy 419.067488 -396.860014) (xy 419.045689 -396.834371)
			(xy 419.007737 -396.778784) (xy 418.976702 -396.71906) (xy 418.953027 -396.656054) (xy 418.937054 -396.59067)
			(xy 418.92901 -396.523846) (xy 418.92901 -396.456539) (xy 418.937056 -396.389715) (xy 418.953032 -396.324332)
			(xy 418.976708 -396.261327) (xy 419.007745 -396.201603) (xy 419.045698 -396.146018) (xy 419.067488 -396.120366)
			(xy 419.07328 -396.113218) (xy 419.079798 -396.09603) (xy 419.080188 -396.086838) (xy 419.080188 -395.92885)
			(xy 419.080606 -395.918675) (xy 419.088384 -395.899872) (xy 419.102772 -395.885484) (xy 419.121575 -395.877706)
			(xy 419.13175 -395.877288) (xy 419.84803 -395.877288) (xy 419.85821 -395.87764) (xy 419.877015 -395.885445)
			(xy 419.8914 -395.899852) (xy 419.899175 -395.91867) (xy 419.899592 -395.92885) (xy 419.899592 -396.086838)
			(xy 419.899986 -396.096027) (xy 419.906511 -396.113211) (xy 419.912292 -396.120366) (xy 419.934069 -396.146027)
			(xy 419.972016 -396.201613) (xy 420.003048 -396.261335) (xy 420.02672 -396.324339) (xy 420.042693 -396.389719)
			(xy 420.050737 -396.456541) (xy 420.050738 -396.523844) (xy 420.042695 -396.590666) (xy 420.026725 -396.656047)
			(xy 420.003054 -396.719051) (xy 419.972024 -396.778774) (xy 419.934078 -396.834361) (xy 419.912292 -396.860014)
			(xy 419.906506 -396.867167) (xy 419.899985 -396.884351) (xy 419.899592 -396.893542) (xy 419.899592 -397.38681)
			(xy 419.899999 -397.395998) (xy 419.906515 -397.413182) (xy 419.912292 -397.420338) (xy 419.934041 -397.446021)
			(xy 419.971989 -397.501604) (xy 420.00041 -397.556296) (xy 421.128654 -397.556296) (xy 421.13673 -397.489357)
			(xy 421.152765 -397.423869) (xy 421.17653 -397.360772) (xy 421.207681 -397.300976) (xy 421.245771 -397.245343)
			(xy 421.267636 -397.219678) (xy 421.273429 -397.21253) (xy 421.279945 -397.195342) (xy 421.280336 -397.18615)
			(xy 421.280336 -397.028924) (xy 421.280736 -397.018799) (xy 421.288483 -397.000089) (xy 421.302805 -396.985772)
			(xy 421.321518 -396.978032) (xy 421.331644 -396.977616) (xy 422.047924 -396.977616) (xy 422.058036 -396.978066)
			(xy 422.076718 -396.985814) (xy 422.091013 -397.000122) (xy 422.098744 -397.018811) (xy 422.099232 -397.028924)
			(xy 422.099232 -397.18615) (xy 422.099681 -397.195333) (xy 422.106169 -397.212517) (xy 422.111932 -397.219678)
			(xy 422.133805 -397.245336) (xy 422.171891 -397.300972) (xy 422.203039 -397.36077) (xy 422.226802 -397.423867)
			(xy 422.242835 -397.489357) (xy 422.25091 -397.556296) (xy 422.250909 -397.623719) (xy 422.242833 -397.690658)
			(xy 422.226797 -397.756147) (xy 422.203033 -397.819244) (xy 422.200615 -397.823885) (xy 423.328782 -397.823885)
			(xy 423.328786 -397.756458) (xy 423.336865 -397.689518) (xy 423.352904 -397.624027) (xy 423.376672 -397.560928)
			(xy 423.407826 -397.501131) (xy 423.445918 -397.445496) (xy 423.467784 -397.41983) (xy 423.473591 -397.412692)
			(xy 423.4801 -397.395496) (xy 423.480484 -397.386302) (xy 423.480484 -396.89405) (xy 423.480054 -396.884865)
			(xy 423.473554 -396.86768) (xy 423.467784 -396.860522) (xy 423.445911 -396.834865) (xy 423.407823 -396.779229)
			(xy 423.376674 -396.719431) (xy 423.352911 -396.656333) (xy 423.336877 -396.590843) (xy 423.328802 -396.523905)
			(xy 423.328803 -396.45648) (xy 423.33688 -396.389542) (xy 423.352916 -396.324052) (xy 423.37668 -396.260955)
			(xy 423.407831 -396.201159) (xy 423.44592 -396.145524) (xy 423.467784 -396.119858) (xy 423.473579 -396.112712)
			(xy 423.480095 -396.095522) (xy 423.480484 -396.08633) (xy 423.480484 -395.92885) (xy 423.480969 -395.918721)
			(xy 423.488688 -395.899993) (xy 423.502976 -395.885633) (xy 423.521666 -395.87782) (xy 423.531792 -395.877288)
			(xy 424.248072 -395.877288) (xy 424.258223 -395.877744) (xy 424.276972 -395.885528) (xy 424.291296 -395.899914)
			(xy 424.298999 -395.918697) (xy 424.29938 -395.92885) (xy 424.29938 -396.08633) (xy 424.29978 -396.095518)
			(xy 424.306301 -396.112702) (xy 424.31208 -396.119858) (xy 424.333935 -396.145531) (xy 424.372025 -396.201164)
			(xy 424.403177 -396.260959) (xy 424.426943 -396.324055) (xy 424.44298 -396.389543) (xy 424.451057 -396.456481)
			(xy 424.451058 -396.523904) (xy 424.442983 -396.590842) (xy 424.426948 -396.656331) (xy 424.403184 -396.719427)
			(xy 424.372033 -396.779223) (xy 424.333944 -396.834857) (xy 424.31208 -396.860522) (xy 424.306289 -396.867671)
			(xy 424.299772 -396.884859) (xy 424.29938 -396.89405) (xy 424.29938 -397.386302) (xy 424.299793 -397.395489)
			(xy 424.306305 -397.412673) (xy 424.31208 -397.41983) (xy 424.333907 -397.445526) (xy 424.371998 -397.501155)
			(xy 424.40076 -397.556356) (xy 425.528974 -397.556356) (xy 425.537017 -397.489534) (xy 425.552988 -397.424152)
			(xy 425.576659 -397.361148) (xy 425.607691 -397.301425) (xy 425.645637 -397.245838) (xy 425.667424 -397.220186)
			(xy 425.673212 -397.213035) (xy 425.679731 -397.195849) (xy 425.680124 -397.186658) (xy 425.680124 -397.028924)
			(xy 425.680542 -397.018768) (xy 425.688334 -397.000012) (xy 425.702732 -396.985687) (xy 425.721528 -396.97799)
			(xy 425.731686 -396.977616) (xy 426.447966 -396.977616) (xy 426.458088 -396.978154) (xy 426.476803 -396.985866)
			(xy 426.49116 -397.000137) (xy 426.498984 -397.018806) (xy 426.499528 -397.028924) (xy 426.499528 -397.186658)
			(xy 426.499952 -397.195844) (xy 426.506456 -397.213029) (xy 426.512228 -397.220186) (xy 426.534026 -397.24583)
			(xy 426.571977 -397.301417) (xy 426.603012 -397.361141) (xy 426.626685 -397.424147) (xy 426.642659 -397.48953)
			(xy 426.650703 -397.556354) (xy 426.650702 -397.623661) (xy 426.642656 -397.690485) (xy 426.626681 -397.755868)
			(xy 426.603006 -397.818873) (xy 426.600432 -397.823826) (xy 427.729077 -397.823826) (xy 427.729081 -397.756517)
			(xy 427.737129 -397.689691) (xy 427.753107 -397.624307) (xy 427.776786 -397.5613) (xy 427.807825 -397.501576)
			(xy 427.845781 -397.44599) (xy 427.867572 -397.420338) (xy 427.873386 -397.413206) (xy 427.879888 -397.396005)
			(xy 427.880272 -397.38681) (xy 427.880272 -396.893542) (xy 427.879848 -396.884356) (xy 427.873344 -396.867171)
			(xy 427.867572 -396.860014) (xy 427.845774 -396.83437) (xy 427.807823 -396.778783) (xy 427.776788 -396.719059)
			(xy 427.753115 -396.656053) (xy 427.737141 -396.59067) (xy 427.729097 -396.523846) (xy 427.729098 -396.456539)
			(xy 427.737144 -396.389715) (xy 427.753119 -396.324332) (xy 427.776794 -396.261327) (xy 427.807831 -396.201604)
			(xy 427.845783 -396.146018) (xy 427.867572 -396.120366) (xy 427.873374 -396.113225) (xy 427.879883 -396.096031)
			(xy 427.880272 -396.086838) (xy 427.880272 -395.92885) (xy 427.880706 -395.918677) (xy 427.88848 -395.899877)
			(xy 427.902864 -395.885489) (xy 427.921662 -395.877709) (xy 427.931834 -395.877288) (xy 428.648114 -395.877288)
			(xy 428.658293 -395.877654) (xy 428.677097 -395.885453) (xy 428.691483 -395.899857) (xy 428.699259 -395.918671)
			(xy 428.699676 -395.92885) (xy 428.699676 -396.086838) (xy 428.700073 -396.096026) (xy 428.706596 -396.11321)
			(xy 428.712376 -396.120366) (xy 428.734154 -396.146026) (xy 428.772102 -396.201612) (xy 428.803135 -396.261335)
			(xy 428.826807 -396.324338) (xy 428.84278 -396.389719) (xy 428.850825 -396.45654) (xy 428.850826 -396.523844)
			(xy 428.842783 -396.590666) (xy 428.826812 -396.656048) (xy 428.803141 -396.719052) (xy 428.772109 -396.778775)
			(xy 428.734163 -396.834362) (xy 428.712376 -396.860014) (xy 428.706588 -396.867165) (xy 428.700069 -396.884351)
			(xy 428.699676 -396.893542) (xy 428.699676 -397.38681) (xy 428.700087 -397.395997) (xy 428.7066 -397.413181)
			(xy 428.712376 -397.420338) (xy 428.734126 -397.446021) (xy 428.772075 -397.501604) (xy 428.800497 -397.556296)
			(xy 429.928742 -397.556296) (xy 429.936817 -397.489358) (xy 429.952852 -397.423869) (xy 429.976616 -397.360773)
			(xy 430.007767 -397.300977) (xy 430.045856 -397.245343) (xy 430.06772 -397.219678) (xy 430.073511 -397.212529)
			(xy 430.080028 -397.195341) (xy 430.08042 -397.18615) (xy 430.08042 -397.028924) (xy 430.080836 -397.018801)
			(xy 430.08858 -397.000094) (xy 430.102897 -396.985778) (xy 430.121605 -396.978035) (xy 430.131728 -396.977616)
			(xy 430.848008 -396.977616) (xy 430.858133 -396.97801) (xy 430.87684 -396.985764) (xy 430.891154 -397.000087)
			(xy 430.898896 -397.018799) (xy 430.899316 -397.028924) (xy 430.899316 -397.18615) (xy 430.899746 -397.195335)
			(xy 430.906246 -397.21252) (xy 430.912016 -397.219678) (xy 430.933889 -397.245335) (xy 430.971977 -397.300971)
			(xy 431.003126 -397.360769) (xy 431.026889 -397.423867) (xy 431.042923 -397.489357) (xy 431.050998 -397.556295)
			(xy 431.050997 -397.62372) (xy 431.04292 -397.690658) (xy 431.026884 -397.756148) (xy 431.00312 -397.819245)
			(xy 431.000734 -397.823826) (xy 432.128868 -397.823826) (xy 432.128872 -397.756517) (xy 432.13692 -397.689692)
			(xy 432.152898 -397.624307) (xy 432.176576 -397.561301) (xy 432.207614 -397.501576) (xy 432.245569 -397.44599)
			(xy 432.26736 -397.420338) (xy 432.273173 -397.413205) (xy 432.279676 -397.396005) (xy 432.28006 -397.38681)
			(xy 432.28006 -396.893542) (xy 432.279616 -396.884359) (xy 432.273125 -396.867175) (xy 432.26736 -396.860014)
			(xy 432.245562 -396.83437) (xy 432.207612 -396.778783) (xy 432.176578 -396.719058) (xy 432.152905 -396.656053)
			(xy 432.136932 -396.590669) (xy 432.128888 -396.523846) (xy 432.128889 -396.456539) (xy 432.136935 -396.389716)
			(xy 432.152909 -396.324333) (xy 432.176584 -396.261328) (xy 432.20762 -396.201604) (xy 432.245571 -396.146018)
			(xy 432.26736 -396.120366) (xy 432.273161 -396.113224) (xy 432.279671 -396.096031) (xy 432.28006 -396.086838)
			(xy 432.28006 -395.92885) (xy 432.280505 -395.918679) (xy 432.288278 -395.899881) (xy 432.302658 -395.885494)
			(xy 432.321451 -395.877711) (xy 432.331622 -395.877288) (xy 433.047902 -395.877288) (xy 433.05808 -395.877663)
			(xy 433.076884 -395.885458) (xy 433.091271 -395.899859) (xy 433.099047 -395.918672) (xy 433.099464 -395.92885)
			(xy 433.099464 -396.086838) (xy 433.099864 -396.096026) (xy 433.106386 -396.11321) (xy 433.112164 -396.120366)
			(xy 433.133942 -396.146026) (xy 433.171891 -396.201612) (xy 433.202924 -396.261334) (xy 433.226598 -396.324337)
			(xy 433.242571 -396.389719) (xy 433.250616 -396.45654) (xy 433.250617 -396.523845) (xy 433.242574 -396.590666)
			(xy 433.226602 -396.656048) (xy 433.202931 -396.719052) (xy 433.171899 -396.778776) (xy 433.133951 -396.834362)
			(xy 433.112164 -396.860014) (xy 433.106374 -396.867164) (xy 433.099856 -396.884351) (xy 433.099464 -396.893542)
			(xy 433.099464 -397.38681) (xy 433.099877 -397.395997) (xy 433.10639 -397.413181) (xy 433.112164 -397.420338)
			(xy 433.133914 -397.446021) (xy 433.171864 -397.501603) (xy 433.200318 -397.556356) (xy 434.329062 -397.556356)
			(xy 434.337105 -397.489534) (xy 434.353075 -397.424153) (xy 434.376746 -397.361149) (xy 434.407776 -397.301426)
			(xy 434.445722 -397.245839) (xy 434.467508 -397.220186) (xy 434.473294 -397.213033) (xy 434.479815 -397.195849)
			(xy 434.480208 -397.186658) (xy 434.480208 -397.028924) (xy 434.480641 -397.01877) (xy 434.48843 -397.000017)
			(xy 434.502824 -396.985692) (xy 434.521614 -396.977993) (xy 434.53177 -396.977616) (xy 435.24805 -396.977616)
			(xy 435.258171 -396.978167) (xy 435.276886 -396.985874) (xy 435.291243 -397.00014) (xy 435.299068 -397.018807)
			(xy 435.299612 -397.028924) (xy 435.299612 -397.186658) (xy 435.30004 -397.195843) (xy 435.306541 -397.213028)
			(xy 435.312312 -397.220186) (xy 435.334111 -397.245829) (xy 435.372063 -397.301416) (xy 435.403098 -397.36114)
			(xy 435.426773 -397.424146) (xy 435.442746 -397.48953) (xy 435.45079 -397.556354) (xy 435.45079 -397.623661)
			(xy 435.442744 -397.690485) (xy 435.426768 -397.755868) (xy 435.403092 -397.818873) (xy 435.372055 -397.878597)
			(xy 435.334102 -397.934182) (xy 435.312312 -397.959834) (xy 435.30652 -397.966982) (xy 435.300002 -397.98417)
			(xy 435.299612 -397.993362) (xy 435.299612 -398.100042) (xy 459.541382 -398.100042) (xy 459.545364 -397.972056)
			(xy 459.557296 -397.844565) (xy 459.57713 -397.718062) (xy 459.604791 -397.593037) (xy 459.640171 -397.469974)
			(xy 459.683133 -397.349348) (xy 459.733511 -397.231627) (xy 459.791111 -397.117265) (xy 459.855709 -397.006706)
			(xy 459.927056 -396.900376) (xy 460.004875 -396.798688) (xy 460.088865 -396.702034) (xy 460.178702 -396.610789)
			(xy 460.274038 -396.525306) (xy 460.374503 -396.445915) (xy 460.479711 -396.372923) (xy 460.589252 -396.306614)
			(xy 460.702704 -396.247243) (xy 460.819628 -396.195039) (xy 460.939571 -396.150206) (xy 461.062069 -396.112917)
			(xy 461.186649 -396.083315) (xy 461.312827 -396.061516) (xy 461.440117 -396.047603) (xy 461.568026 -396.041631)
			(xy 461.696059 -396.043622) (xy 461.82372 -396.05357) (xy 461.950516 -396.071434) (xy 462.075955 -396.097147)
			(xy 462.199554 -396.130609) (xy 462.320833 -396.17169) (xy 462.439324 -396.220232) (xy 462.554568 -396.276046)
			(xy 462.666118 -396.338917) (xy 462.773545 -396.408601) (xy 462.876431 -396.484829) (xy 462.974379 -396.567306)
			(xy 463.06701 -396.655713) (xy 463.153966 -396.749708) (xy 463.23491 -396.848927) (xy 463.309529 -396.952986)
			(xy 463.377534 -397.061483) (xy 463.438662 -397.173998) (xy 463.492677 -397.290096) (xy 463.53937 -397.409327)
			(xy 463.57856 -397.531231) (xy 463.610096 -397.655335) (xy 463.633855 -397.781159) (xy 463.649745 -397.908218)
			(xy 463.657706 -398.036018) (xy 463.658204 -398.100042) (xy 463.657706 -398.164066) (xy 463.649745 -398.291866)
			(xy 463.633855 -398.418925) (xy 463.610096 -398.544749) (xy 463.57856 -398.668853) (xy 463.53937 -398.790757)
			(xy 463.492677 -398.909988) (xy 463.438662 -399.026086) (xy 463.377534 -399.138601) (xy 463.309529 -399.247098)
			(xy 463.23491 -399.351157) (xy 463.153966 -399.450376) (xy 463.06701 -399.544371) (xy 462.974379 -399.632778)
			(xy 462.876431 -399.715255) (xy 462.773545 -399.791483) (xy 462.666118 -399.861167) (xy 462.554568 -399.924038)
			(xy 462.439324 -399.979852) (xy 462.320833 -400.028394) (xy 462.199554 -400.069475) (xy 462.075955 -400.102937)
			(xy 461.950516 -400.12865) (xy 461.82372 -400.146514) (xy 461.696059 -400.156462) (xy 461.568026 -400.158453)
			(xy 461.440117 -400.152481) (xy 461.312827 -400.138568) (xy 461.186649 -400.116769) (xy 461.062069 -400.087167)
			(xy 460.939571 -400.049878) (xy 460.819628 -400.005045) (xy 460.702704 -399.952841) (xy 460.589252 -399.89347)
			(xy 460.479711 -399.827161) (xy 460.374503 -399.754169) (xy 460.274038 -399.674778) (xy 460.178702 -399.589295)
			(xy 460.088865 -399.49805) (xy 460.004875 -399.401396) (xy 459.927056 -399.299708) (xy 459.855709 -399.193378)
			(xy 459.791111 -399.082819) (xy 459.733511 -398.968457) (xy 459.683133 -398.850736) (xy 459.640171 -398.73011)
			(xy 459.604791 -398.607047) (xy 459.57713 -398.482022) (xy 459.557296 -398.355519) (xy 459.545364 -398.228028)
			(xy 459.541382 -398.100042) (xy 435.299612 -398.100042) (xy 435.299612 -398.486884) (xy 435.300027 -398.496071)
			(xy 435.306537 -398.513255) (xy 435.312312 -398.520412) (xy 435.334137 -398.546034) (xy 435.372087 -398.601624)
			(xy 435.403122 -398.661351) (xy 435.426795 -398.72436) (xy 435.442767 -398.789746) (xy 435.450809 -398.856573)
			(xy 435.450805 -398.923881) (xy 435.442757 -398.990707) (xy 435.426779 -399.056092) (xy 435.4031 -399.119098)
			(xy 435.37206 -399.178823) (xy 435.334103 -399.234408) (xy 435.312312 -399.26006) (xy 435.306509 -399.267201)
			(xy 435.299998 -399.284395) (xy 435.299612 -399.293588) (xy 435.299612 -399.451576) (xy 435.299159 -399.461727)
			(xy 435.291374 -399.480477) (xy 435.276987 -399.494801) (xy 435.258203 -399.502503) (xy 435.24805 -399.502884)
			(xy 434.53177 -399.502884) (xy 434.521644 -399.502399) (xy 434.502927 -399.494666) (xy 434.488573 -399.480379)
			(xy 434.48075 -399.461699) (xy 434.480208 -399.451576) (xy 434.480208 -399.293588) (xy 434.479802 -399.2844)
			(xy 434.473285 -399.267216) (xy 434.467508 -399.26006) (xy 434.445757 -399.234378) (xy 434.407809 -399.178795)
			(xy 434.376776 -399.119076) (xy 434.353102 -399.056075) (xy 434.337128 -398.990697) (xy 434.329081 -398.923878)
			(xy 434.329078 -398.856576) (xy 434.337118 -398.789757) (xy 434.353086 -398.724377) (xy 434.376753 -398.661374)
			(xy 434.407781 -398.601651) (xy 434.445723 -398.546064) (xy 434.467508 -398.520412) (xy 434.473325 -398.513282)
			(xy 434.479827 -398.49608) (xy 434.480208 -398.486884) (xy 434.480208 -397.993362) (xy 434.479814 -397.984173)
			(xy 434.473289 -397.966989) (xy 434.467508 -397.959834) (xy 434.445731 -397.934173) (xy 434.407784 -397.878587)
			(xy 434.376752 -397.818865) (xy 434.35308 -397.755861) (xy 434.337107 -397.690481) (xy 434.329063 -397.623659)
			(xy 434.329062 -397.556356) (xy 433.200318 -397.556356) (xy 433.202899 -397.561322) (xy 433.226573 -397.624323)
			(xy 433.242549 -397.689701) (xy 433.250596 -397.75652) (xy 433.250599 -397.823822) (xy 433.242559 -397.890642)
			(xy 433.22659 -397.956022) (xy 433.202922 -398.019025) (xy 433.171893 -398.078748) (xy 433.133949 -398.134334)
			(xy 433.112164 -398.159986) (xy 433.106344 -398.167114) (xy 433.099844 -398.184318) (xy 433.099464 -398.193514)
			(xy 433.099464 -398.351502) (xy 433.098968 -398.36166) (xy 433.091194 -398.380428) (xy 433.076828 -398.394794)
			(xy 433.05806 -398.402568) (xy 433.047902 -398.403064) (xy 432.331622 -398.403064) (xy 432.321452 -398.402618)
			(xy 432.302658 -398.394841) (xy 432.288273 -398.380462) (xy 432.280487 -398.361672) (xy 432.28006 -398.351502)
			(xy 432.28006 -398.193514) (xy 432.27963 -398.184329) (xy 432.273129 -398.167145) (xy 432.26736 -398.159986)
			(xy 432.245534 -398.134365) (xy 432.207585 -398.078775) (xy 432.176552 -398.019047) (xy 432.152881 -397.956038)
			(xy 432.13691 -397.890652) (xy 432.128868 -397.823826) (xy 431.000734 -397.823826) (xy 430.971969 -397.879041)
			(xy 430.93388 -397.934676) (xy 430.912016 -397.960342) (xy 430.906221 -397.967488) (xy 430.899705 -397.984678)
			(xy 430.899316 -397.99387) (xy 430.899316 -398.486376) (xy 430.899734 -398.495562) (xy 430.906242 -398.512747)
			(xy 430.912016 -398.519904) (xy 430.933915 -398.54554) (xy 430.972001 -398.601179) (xy 431.00315 -398.66098)
			(xy 431.026911 -398.72408) (xy 431.042944 -398.789573) (xy 431.051016 -398.856514) (xy 431.051013 -398.92394)
			(xy 431.042934 -398.990881) (xy 431.026895 -399.056371) (xy 431.003128 -399.11947) (xy 430.971974 -399.179267)
			(xy 430.933882 -399.234902) (xy 430.912016 -399.260568) (xy 430.90621 -399.267707) (xy 430.8997 -399.284902)
			(xy 430.899316 -399.294096) (xy 430.899316 -399.451576) (xy 430.898865 -399.461695) (xy 430.891128 -399.480395)
			(xy 430.876822 -399.49471) (xy 430.858127 -399.502459) (xy 430.848008 -399.502884) (xy 430.131728 -399.502884)
			(xy 430.121605 -399.502461) (xy 430.102899 -399.494719) (xy 430.088583 -399.480404) (xy 430.08084 -399.461699)
			(xy 430.08042 -399.451576) (xy 430.08042 -399.294096) (xy 430.080008 -399.284909) (xy 430.073495 -399.267725)
			(xy 430.06772 -399.260568) (xy 430.045891 -399.234874) (xy 430.0078 -399.179244) (xy 429.976646 -399.119452)
			(xy 429.952879 -399.056359) (xy 429.936841 -398.990873) (xy 429.928761 -398.923938) (xy 429.928758 -398.856516)
			(xy 429.936831 -398.78958) (xy 429.952863 -398.724093) (xy 429.976624 -398.660997) (xy 430.007772 -398.601202)
			(xy 430.045857 -398.545569) (xy 430.06772 -398.519904) (xy 430.0735 -398.512747) (xy 430.080024 -398.495565)
			(xy 430.08042 -398.486376) (xy 430.08042 -397.99387) (xy 430.08002 -397.984682) (xy 430.073499 -397.967498)
			(xy 430.06772 -397.960342) (xy 430.045865 -397.934669) (xy 430.007775 -397.879036) (xy 429.976623 -397.819241)
			(xy 429.952857 -397.756145) (xy 429.93682 -397.690657) (xy 429.928743 -397.623719) (xy 429.928742 -397.556296)
			(xy 428.800497 -397.556296) (xy 428.803109 -397.561323) (xy 428.826783 -397.624323) (xy 428.842758 -397.689702)
			(xy 428.850805 -397.756521) (xy 428.850808 -397.823822) (xy 428.842768 -397.890642) (xy 428.8268 -397.956022)
			(xy 428.803132 -398.019025) (xy 428.772104 -398.078747) (xy 428.734161 -398.134333) (xy 428.712376 -398.159986)
			(xy 428.706558 -398.167116) (xy 428.700057 -398.184318) (xy 428.699676 -398.193514) (xy 428.699676 -398.351502)
			(xy 428.699169 -398.361658) (xy 428.691396 -398.380425) (xy 428.677035 -398.394789) (xy 428.65827 -398.402566)
			(xy 428.648114 -398.403064) (xy 427.931834 -398.403064) (xy 427.921665 -398.402608) (xy 427.902871 -398.394835)
			(xy 427.888485 -398.380459) (xy 427.880699 -398.361671) (xy 427.880272 -398.351502) (xy 427.880272 -398.193514)
			(xy 427.879861 -398.184327) (xy 427.873349 -398.167142) (xy 427.867572 -398.159986) (xy 427.845746 -398.134365)
			(xy 427.807796 -398.078775) (xy 427.776762 -398.019047) (xy 427.75309 -397.956039) (xy 427.737119 -397.890652)
			(xy 427.729077 -397.823826) (xy 426.600432 -397.823826) (xy 426.571969 -397.878596) (xy 426.534017 -397.934182)
			(xy 426.512228 -397.959834) (xy 426.506426 -397.966975) (xy 426.499917 -397.984169) (xy 426.499528 -397.993362)
			(xy 426.499528 -398.486884) (xy 426.499939 -398.496071) (xy 426.506451 -398.513256) (xy 426.512228 -398.520412)
			(xy 426.534052 -398.546034) (xy 426.572002 -398.601624) (xy 426.603036 -398.661352) (xy 426.626708 -398.72436)
			(xy 426.64268 -398.789746) (xy 426.650721 -398.856573) (xy 426.650718 -398.923881) (xy 426.64267 -398.990707)
			(xy 426.626692 -399.056092) (xy 426.603014 -399.119098) (xy 426.571974 -399.178822) (xy 426.534019 -399.234408)
			(xy 426.512228 -399.26006) (xy 426.506415 -399.267193) (xy 426.499912 -399.284393) (xy 426.499528 -399.293588)
			(xy 426.499528 -399.451576) (xy 426.499059 -399.461725) (xy 426.491277 -399.480472) (xy 426.476895 -399.494795)
			(xy 426.458117 -399.502501) (xy 426.447966 -399.502884) (xy 425.731686 -399.502884) (xy 425.721561 -399.502385)
			(xy 425.702845 -399.494657) (xy 425.68849 -399.480375) (xy 425.680667 -399.461698) (xy 425.680124 -399.451576)
			(xy 425.680124 -399.293588) (xy 425.679714 -399.284401) (xy 425.6732 -399.267217) (xy 425.667424 -399.26006)
			(xy 425.645672 -399.234378) (xy 425.607723 -399.178796) (xy 425.576689 -399.119076) (xy 425.553015 -399.056076)
			(xy 425.53704 -398.990697) (xy 425.528994 -398.923878) (xy 425.52899 -398.856576) (xy 425.537031 -398.789756)
			(xy 425.552999 -398.724376) (xy 425.576667 -398.661373) (xy 425.607696 -398.601651) (xy 425.645639 -398.546065)
			(xy 425.667424 -398.520412) (xy 425.673243 -398.513283) (xy 425.679744 -398.49608) (xy 425.680124 -398.486884)
			(xy 425.680124 -397.993362) (xy 425.679727 -397.984174) (xy 425.673204 -397.96699) (xy 425.667424 -397.959834)
			(xy 425.645646 -397.934174) (xy 425.607698 -397.878588) (xy 425.576665 -397.818865) (xy 425.552993 -397.755862)
			(xy 425.53702 -397.690481) (xy 425.528975 -397.62366) (xy 425.528974 -397.556356) (xy 424.40076 -397.556356)
			(xy 424.403152 -397.560947) (xy 424.426919 -397.62404) (xy 424.442958 -397.689526) (xy 424.451037 -397.756461)
			(xy 424.451041 -397.823882) (xy 424.442968 -397.890818) (xy 424.426936 -397.956305) (xy 424.403175 -398.019401)
			(xy 424.372028 -398.079196) (xy 424.333942 -398.134829) (xy 424.31208 -398.160494) (xy 424.306301 -398.167652)
			(xy 424.299777 -398.184833) (xy 424.29938 -398.194022) (xy 424.29938 -398.351502) (xy 424.298876 -398.361626)
			(xy 424.291151 -398.380344) (xy 424.27687 -398.394699) (xy 424.258194 -398.402522) (xy 424.248072 -398.403064)
			(xy 423.531792 -398.403064) (xy 423.521633 -398.402684) (xy 423.502873 -398.394879) (xy 423.488549 -398.380469)
			(xy 423.480856 -398.361663) (xy 423.480484 -398.351502) (xy 423.480484 -398.194022) (xy 423.480067 -398.184835)
			(xy 423.473558 -398.167651) (xy 423.467784 -398.160494) (xy 423.445883 -398.134859) (xy 423.407797 -398.07922)
			(xy 423.376649 -398.019419) (xy 423.352887 -397.956319) (xy 423.336855 -397.890826) (xy 423.328782 -397.823885)
			(xy 422.200615 -397.823885) (xy 422.171883 -397.879041) (xy 422.133795 -397.934676) (xy 422.111932 -397.960342)
			(xy 422.106127 -397.967481) (xy 422.099619 -397.984676) (xy 422.099232 -397.99387) (xy 422.099232 -398.486376)
			(xy 422.099669 -398.49556) (xy 422.106166 -398.512744) (xy 422.111932 -398.519904) (xy 422.13383 -398.545541)
			(xy 422.171916 -398.60118) (xy 422.203063 -398.66098) (xy 422.226824 -398.724081) (xy 422.242856 -398.789573)
			(xy 422.250928 -398.856514) (xy 422.250925 -398.92394) (xy 422.242846 -398.99088) (xy 422.226808 -399.056371)
			(xy 422.203041 -399.119469) (xy 422.171888 -399.179266) (xy 422.133797 -399.234902) (xy 422.111932 -399.260568)
			(xy 422.106116 -399.267699) (xy 422.099615 -399.284901) (xy 422.099232 -399.294096) (xy 422.099232 -399.451576)
			(xy 422.098696 -399.461679) (xy 422.090972 -399.480351) (xy 422.076691 -399.494645) (xy 422.058027 -399.502387)
			(xy 422.047924 -399.502884) (xy 421.331644 -399.502884) (xy 421.321522 -399.502447) (xy 421.302817 -399.494711)
			(xy 421.2885 -399.4804) (xy 421.280756 -399.461697) (xy 421.280336 -399.451576) (xy 421.280336 -399.294096)
			(xy 421.27992 -399.28491) (xy 421.27341 -399.267726) (xy 421.267636 -399.260568) (xy 421.245806 -399.234874)
			(xy 421.207714 -399.179245) (xy 421.17656 -399.119453) (xy 421.152792 -399.056359) (xy 421.136753 -398.990873)
			(xy 421.128674 -398.923938) (xy 421.12867 -398.856516) (xy 421.136743 -398.78958) (xy 421.152776 -398.724092)
			(xy 421.176538 -398.660997) (xy 421.207686 -398.601202) (xy 421.245773 -398.545569) (xy 421.267636 -398.519904)
			(xy 421.273418 -398.512749) (xy 421.27994 -398.495566) (xy 421.280336 -398.486376) (xy 421.280336 -397.99387)
			(xy 421.279932 -397.984682) (xy 421.273413 -397.967498) (xy 421.267636 -397.960342) (xy 421.245781 -397.934669)
			(xy 421.207689 -397.879037) (xy 421.176536 -397.819242) (xy 421.15277 -397.756146) (xy 421.136732 -397.690657)
			(xy 421.128655 -397.623719) (xy 421.128654 -397.556296) (xy 420.00041 -397.556296) (xy 420.003023 -397.561324)
			(xy 420.026696 -397.624324) (xy 420.042671 -397.689702) (xy 420.050718 -397.756521) (xy 420.050721 -397.823822)
			(xy 420.042681 -397.890642) (xy 420.026713 -397.956021) (xy 420.003046 -398.019024) (xy 419.972019 -398.078747)
			(xy 419.934077 -398.134334) (xy 419.912292 -398.159986) (xy 419.906475 -398.167117) (xy 419.899973 -398.184318)
			(xy 419.899592 -398.193514) (xy 419.899592 -398.351502) (xy 419.899069 -398.361656) (xy 419.891299 -398.38042)
			(xy 419.876943 -398.394784) (xy 419.858184 -398.402563) (xy 419.84803 -398.403064) (xy 419.13175 -398.403064)
			(xy 419.121582 -398.402595) (xy 419.102789 -398.394827) (xy 419.088402 -398.380455) (xy 419.080615 -398.36167)
			(xy 419.080188 -398.351502) (xy 419.080188 -398.193514) (xy 419.079774 -398.184327) (xy 419.073263 -398.167143)
			(xy 419.067488 -398.159986) (xy 419.045661 -398.134365) (xy 419.007711 -398.078775) (xy 418.976676 -398.019048)
			(xy 418.953004 -397.956039) (xy 418.937032 -397.890653) (xy 418.92899 -397.823826) (xy 414.525968 -397.823826)
			(xy 414.525968 -401.723737) (xy 418.929001 -401.723737) (xy 418.929003 -401.65643) (xy 418.93705 -401.589605)
			(xy 418.953027 -401.524221) (xy 418.976704 -401.461215) (xy 419.007743 -401.401491) (xy 419.045697 -401.345906)
			(xy 419.067488 -401.320254) (xy 419.073285 -401.313109) (xy 419.0798 -401.295918) (xy 419.080188 -401.286726)
			(xy 419.080188 -400.793458) (xy 419.079801 -400.784268) (xy 419.073272 -400.767084) (xy 419.067488 -400.75993)
			(xy 419.045705 -400.734274) (xy 419.007752 -400.678689) (xy 418.976716 -400.618966) (xy 418.953041 -400.555962)
			(xy 418.937066 -400.49058) (xy 418.929021 -400.423757) (xy 418.92902 -400.356452) (xy 418.937065 -400.289629)
			(xy 418.953038 -400.224246) (xy 418.976713 -400.161242) (xy 419.007748 -400.101519) (xy 419.045699 -400.045933)
			(xy 419.067488 -400.020282) (xy 419.073273 -400.013129) (xy 419.079795 -399.995944) (xy 419.080188 -399.986754)
			(xy 419.080188 -399.828766) (xy 419.080537 -399.818586) (xy 419.088343 -399.799781) (xy 419.102752 -399.785395)
			(xy 419.121569 -399.777621) (xy 419.13175 -399.777204) (xy 419.84803 -399.777204) (xy 419.858186 -399.777708)
			(xy 419.876949 -399.785486) (xy 419.891312 -399.799848) (xy 419.899091 -399.818611) (xy 419.899592 -399.828766)
			(xy 419.899592 -399.986754) (xy 419.900026 -399.995939) (xy 419.906523 -400.013123) (xy 419.912292 -400.020282)
			(xy 419.934085 -400.04593) (xy 419.972031 -400.101518) (xy 420.003063 -400.161242) (xy 420.026734 -400.224247)
			(xy 420.042705 -400.289629) (xy 420.050749 -400.356452) (xy 420.050748 -400.423757) (xy 420.042704 -400.490579)
			(xy 420.026731 -400.555962) (xy 420.003059 -400.618966) (xy 419.972027 -400.67869) (xy 419.934079 -400.734277)
			(xy 419.912292 -400.75993) (xy 419.906499 -400.767078) (xy 419.899983 -400.784266) (xy 419.899592 -400.793458)
			(xy 419.899592 -401.286726) (xy 419.899991 -401.295914) (xy 419.906513 -401.313099) (xy 419.912292 -401.320254)
			(xy 419.934057 -401.345924) (xy 419.972005 -401.401509) (xy 420.003037 -401.46123) (xy 420.02671 -401.524232)
			(xy 420.042683 -401.589612) (xy 420.050729 -401.656432) (xy 420.050731 -401.723735) (xy 420.042689 -401.790555)
			(xy 420.02672 -401.855936) (xy 420.003051 -401.918939) (xy 419.972022 -401.978663) (xy 419.934077 -402.034249)
			(xy 419.912292 -402.059902) (xy 419.906511 -402.067058) (xy 419.899987 -402.08424) (xy 419.899592 -402.09343)
			(xy 419.899592 -402.251418) (xy 419.899082 -402.261573) (xy 419.891308 -402.280337) (xy 419.876947 -402.294701)
			(xy 419.858185 -402.30248) (xy 419.84803 -402.30298) (xy 419.13175 -402.30298) (xy 419.121584 -402.302496)
			(xy 419.102794 -402.29473) (xy 419.088408 -402.280363) (xy 419.080618 -402.261584) (xy 419.080188 -402.251418)
			(xy 419.080188 -402.09343) (xy 419.079766 -402.084244) (xy 419.073261 -402.067059) (xy 419.067488 -402.059902)
			(xy 419.045677 -402.034268) (xy 419.007726 -401.97868) (xy 418.976691 -401.918955) (xy 418.953017 -401.855948)
			(xy 418.937044 -401.790563) (xy 418.929001 -401.723737) (xy 414.525968 -401.723737) (xy 414.525968 -402.823878)
			(xy 421.128614 -402.823878) (xy 421.128619 -402.75645) (xy 421.1367 -402.689508) (xy 421.152742 -402.624016)
			(xy 421.176513 -402.560916) (xy 421.207671 -402.501119) (xy 421.245768 -402.445485) (xy 421.267636 -402.41982)
			(xy 421.273454 -402.41269) (xy 421.279955 -402.395488) (xy 421.280336 -402.386292) (xy 421.280336 -401.89404)
			(xy 421.279898 -401.884856) (xy 421.273403 -401.867672) (xy 421.267636 -401.860512) (xy 421.245751 -401.834864)
			(xy 421.207661 -401.779227) (xy 421.176509 -401.719429) (xy 421.152744 -401.65633) (xy 421.136709 -401.590839)
			(xy 421.128634 -401.523898) (xy 421.128636 -401.456472) (xy 421.136714 -401.389532) (xy 421.152753 -401.324041)
			(xy 421.176521 -401.260943) (xy 421.207676 -401.201147) (xy 421.24577 -401.145513) (xy 421.267636 -401.119848)
			(xy 421.273442 -401.112709) (xy 421.27995 -401.095514) (xy 421.280336 -401.08632) (xy 421.280336 -400.92884)
			(xy 421.28075 -400.918716) (xy 421.288491 -400.900006) (xy 421.302809 -400.885689) (xy 421.32152 -400.877949)
			(xy 421.331644 -400.877532) (xy 422.047924 -400.877532) (xy 422.058052 -400.877897) (xy 422.076762 -400.885659)
			(xy 422.091077 -400.899991) (xy 422.098816 -400.918711) (xy 422.099232 -400.92884) (xy 422.099232 -401.08632)
			(xy 422.099648 -401.095506) (xy 422.106159 -401.11269) (xy 422.111932 -401.119848) (xy 422.133775 -401.14553)
			(xy 422.171862 -401.201163) (xy 422.203012 -401.260957) (xy 422.226776 -401.324052) (xy 422.242812 -401.389538)
			(xy 422.250889 -401.456474) (xy 422.250891 -401.523896) (xy 422.242817 -401.590832) (xy 422.226785 -401.65632)
			(xy 422.203024 -401.719415) (xy 422.200742 -401.723796) (xy 423.328794 -401.723796) (xy 423.328796 -401.656371)
			(xy 423.336873 -401.589431) (xy 423.352911 -401.523941) (xy 423.376677 -401.460844) (xy 423.407829 -401.401047)
			(xy 423.445919 -401.345412) (xy 423.467784 -401.319746) (xy 423.473584 -401.312603) (xy 423.480097 -401.295411)
			(xy 423.480484 -401.286218) (xy 423.480484 -400.793966) (xy 423.480094 -400.784777) (xy 423.473566 -400.767592)
			(xy 423.467784 -400.760438) (xy 423.445926 -400.734768) (xy 423.407839 -400.679133) (xy 423.376689 -400.619338)
			(xy 423.352925 -400.556242) (xy 423.336889 -400.490753) (xy 423.328813 -400.423816) (xy 423.328813 -400.356393)
			(xy 423.336888 -400.289455) (xy 423.352922 -400.223967) (xy 423.376685 -400.16087) (xy 423.407834 -400.101074)
			(xy 423.445921 -400.045439) (xy 423.467784 -400.019774) (xy 423.473572 -400.012623) (xy 423.480092 -399.995437)
			(xy 423.480484 -399.986246) (xy 423.480484 -399.828766) (xy 423.4809 -399.818632) (xy 423.488647 -399.799901)
			(xy 423.502955 -399.785545) (xy 423.521659 -399.777735) (xy 423.531792 -399.777204) (xy 424.248072 -399.777204)
			(xy 424.258225 -399.777644) (xy 424.276977 -399.785431) (xy 424.291302 -399.799823) (xy 424.299002 -399.818611)
			(xy 424.29938 -399.828766) (xy 424.29938 -399.986246) (xy 424.299821 -399.99543) (xy 424.306314 -400.012614)
			(xy 424.31208 -400.019774) (xy 424.333951 -400.045434) (xy 424.37204 -400.101069) (xy 424.403192 -400.160866)
			(xy 424.426957 -400.223963) (xy 424.442992 -400.289453) (xy 424.451068 -400.356392) (xy 424.451068 -400.423817)
			(xy 424.442991 -400.490756) (xy 424.426954 -400.556245) (xy 424.403188 -400.619343) (xy 424.372036 -400.679139)
			(xy 424.333945 -400.734773) (xy 424.31208 -400.760438) (xy 424.306282 -400.767582) (xy 424.299769 -400.784774)
			(xy 424.29938 -400.793966) (xy 424.29938 -401.286218) (xy 424.299786 -401.295406) (xy 424.306303 -401.31259)
			(xy 424.31208 -401.319746) (xy 424.333923 -401.345429) (xy 424.372014 -401.40106) (xy 424.403167 -401.460854)
			(xy 424.426933 -401.523949) (xy 424.44297 -401.589436) (xy 424.451048 -401.656372) (xy 424.45105 -401.723795)
			(xy 424.442976 -401.790732) (xy 424.426943 -401.85622) (xy 424.40318 -401.919316) (xy 424.372031 -401.979111)
			(xy 424.333943 -402.034745) (xy 424.31208 -402.06041) (xy 424.306294 -402.067563) (xy 424.299774 -402.084748)
			(xy 424.29938 -402.093938) (xy 424.29938 -402.251418) (xy 424.298889 -402.261543) (xy 424.291159 -402.280261)
			(xy 424.276874 -402.294616) (xy 424.258195 -402.302438) (xy 424.248072 -402.30298) (xy 423.531792 -402.30298)
			(xy 423.521635 -402.302584) (xy 423.502879 -402.294782) (xy 423.488555 -402.280378) (xy 423.480859 -402.261577)
			(xy 423.480484 -402.251418) (xy 423.480484 -402.093938) (xy 423.480059 -402.084752) (xy 423.473556 -402.067568)
			(xy 423.467784 -402.06041) (xy 423.445899 -402.034762) (xy 423.407812 -401.979125) (xy 423.376663 -401.919326)
			(xy 423.352901 -401.856227) (xy 423.336867 -401.790736) (xy 423.328794 -401.723796) (xy 422.200742 -401.723796)
			(xy 422.171878 -401.779211) (xy 422.133794 -401.834846) (xy 422.111932 -401.860512) (xy 422.10614 -401.86766)
			(xy 422.099624 -401.884849) (xy 422.099232 -401.89404) (xy 422.099232 -402.386292) (xy 422.099661 -402.395477)
			(xy 422.106163 -402.412661) (xy 422.111932 -402.41982) (xy 422.133748 -402.445525) (xy 422.171836 -402.501154)
			(xy 422.202987 -402.560945) (xy 422.226752 -402.624037) (xy 422.24279 -402.689521) (xy 422.250869 -402.756454)
			(xy 422.250874 -402.823818) (xy 425.528934 -402.823818) (xy 425.528938 -402.75651) (xy 425.536987 -402.689684)
			(xy 425.552965 -402.624299) (xy 425.576642 -402.561293) (xy 425.60768 -402.501568) (xy 425.645634 -402.44598)
			(xy 425.667424 -402.420328) (xy 425.673236 -402.413194) (xy 425.679741 -402.395995) (xy 425.680124 -402.3868)
			(xy 425.680124 -401.893532) (xy 425.679693 -401.884347) (xy 425.673193 -401.867163) (xy 425.667424 -401.860004)
			(xy 425.645617 -401.834368) (xy 425.60767 -401.778779) (xy 425.576638 -401.719053) (xy 425.552967 -401.656046)
			(xy 425.536996 -401.590662) (xy 425.528954 -401.523838) (xy 425.528956 -401.456532) (xy 425.537001 -401.389708)
			(xy 425.552976 -401.324325) (xy 425.57665 -401.26132) (xy 425.607685 -401.201595) (xy 425.645635 -401.146008)
			(xy 425.667424 -401.120356) (xy 425.673225 -401.113214) (xy 425.679736 -401.096021) (xy 425.680124 -401.086828)
			(xy 425.680124 -400.92884) (xy 425.680555 -400.918686) (xy 425.688342 -400.899929) (xy 425.702736 -400.885604)
			(xy 425.72153 -400.877907) (xy 425.731686 -400.877532) (xy 426.447966 -400.877532) (xy 426.45809 -400.878054)
			(xy 426.476808 -400.88577) (xy 426.491165 -400.900045) (xy 426.498987 -400.918719) (xy 426.499528 -400.92884)
			(xy 426.499528 -401.086828) (xy 426.499918 -401.096017) (xy 426.506445 -401.113202) (xy 426.512228 -401.120356)
			(xy 426.533997 -401.146024) (xy 426.571949 -401.201607) (xy 426.602985 -401.261328) (xy 426.62666 -401.324331)
			(xy 426.642635 -401.389712) (xy 426.650681 -401.456533) (xy 426.650683 -401.523837) (xy 426.642641 -401.590659)
			(xy 426.626669 -401.65604) (xy 426.602997 -401.719044) (xy 426.600558 -401.723737) (xy 427.729089 -401.723737)
			(xy 427.729091 -401.65643) (xy 427.737138 -401.589605) (xy 427.753114 -401.524221) (xy 427.776791 -401.461216)
			(xy 427.807828 -401.401492) (xy 427.845782 -401.345906) (xy 427.867572 -401.320254) (xy 427.873379 -401.313117)
			(xy 427.879886 -401.29592) (xy 427.880272 -401.286726) (xy 427.880272 -400.793458) (xy 427.879888 -400.784268)
			(xy 427.873357 -400.767084) (xy 427.867572 -400.75993) (xy 427.845789 -400.734273) (xy 427.807838 -400.678688)
			(xy 427.776803 -400.618966) (xy 427.753128 -400.555962) (xy 427.737154 -400.49058) (xy 427.729109 -400.423757)
			(xy 427.729108 -400.356452) (xy 427.737152 -400.289629) (xy 427.753126 -400.224247) (xy 427.776799 -400.161243)
			(xy 427.807833 -400.101519) (xy 427.845784 -400.045934) (xy 427.867572 -400.020282) (xy 427.873367 -400.013136)
			(xy 427.879881 -399.995946) (xy 427.880272 -399.986754) (xy 427.880272 -399.828766) (xy 427.880706 -399.818602)
			(xy 427.888498 -399.799825) (xy 427.902883 -399.78546) (xy 427.921669 -399.777693) (xy 427.931834 -399.777204)
			(xy 428.648114 -399.777204) (xy 428.658268 -399.777721) (xy 428.677031 -399.785494) (xy 428.691395 -399.799852)
			(xy 428.699175 -399.818612) (xy 428.699676 -399.828766) (xy 428.699676 -399.986754) (xy 428.700114 -399.995938)
			(xy 428.706609 -400.013122) (xy 428.712376 -400.020282) (xy 428.734169 -400.045929) (xy 428.772117 -400.101517)
			(xy 428.803149 -400.161241) (xy 428.826821 -400.224246) (xy 428.842793 -400.289629) (xy 428.850836 -400.356452)
			(xy 428.850836 -400.423757) (xy 428.842791 -400.49058) (xy 428.826818 -400.555962) (xy 428.803145 -400.618967)
			(xy 428.772112 -400.678691) (xy 428.734164 -400.734278) (xy 428.712376 -400.75993) (xy 428.706581 -400.767076)
			(xy 428.700066 -400.784266) (xy 428.699676 -400.793458) (xy 428.699676 -401.286726) (xy 428.700079 -401.295914)
			(xy 428.706598 -401.313098) (xy 428.712376 -401.320254) (xy 428.734142 -401.345924) (xy 428.77209 -401.401508)
			(xy 428.803124 -401.46123) (xy 428.826797 -401.524232) (xy 428.842771 -401.589612) (xy 428.850817 -401.656432)
			(xy 428.850819 -401.723735) (xy 428.842777 -401.790556) (xy 428.826807 -401.855937) (xy 428.803137 -401.91894)
			(xy 428.772107 -401.978663) (xy 428.734162 -402.03425) (xy 428.712376 -402.059902) (xy 428.706593 -402.067057)
			(xy 428.700071 -402.08424) (xy 428.699676 -402.09343) (xy 428.699676 -402.251418) (xy 428.699182 -402.261575)
			(xy 428.691404 -402.280342) (xy 428.677039 -402.294706) (xy 428.658271 -402.302483) (xy 428.648114 -402.30298)
			(xy 427.931834 -402.30298) (xy 427.921667 -402.302509) (xy 427.902876 -402.294738) (xy 427.888491 -402.280367)
			(xy 427.880702 -402.261585) (xy 427.880272 -402.251418) (xy 427.880272 -402.09343) (xy 427.879854 -402.084244)
			(xy 427.873347 -402.067059) (xy 427.867572 -402.059902) (xy 427.845762 -402.034268) (xy 427.807811 -401.97868)
			(xy 427.776777 -401.918954) (xy 427.753104 -401.855947) (xy 427.737132 -401.790562) (xy 427.729089 -401.723737)
			(xy 426.600558 -401.723737) (xy 426.571964 -401.778767) (xy 426.534015 -401.834352) (xy 426.512228 -401.860004)
			(xy 426.506438 -401.867154) (xy 426.499922 -401.884341) (xy 426.499528 -401.893532) (xy 426.499528 -402.3868)
			(xy 426.499932 -402.395988) (xy 426.506449 -402.413173) (xy 426.512228 -402.420328) (xy 426.53397 -402.446019)
			(xy 426.571922 -402.501599) (xy 426.602959 -402.561317) (xy 426.626636 -402.624316) (xy 426.642613 -402.689694)
			(xy 426.650662 -402.756513) (xy 426.650666 -402.823815) (xy 426.650658 -402.823878) (xy 429.928702 -402.823878)
			(xy 429.928707 -402.75645) (xy 429.936788 -402.689508) (xy 429.952829 -402.624016) (xy 429.976599 -402.560917)
			(xy 430.007757 -402.50112) (xy 430.045852 -402.445485) (xy 430.06772 -402.41982) (xy 430.073535 -402.412688)
			(xy 430.080038 -402.395487) (xy 430.08042 -402.386292) (xy 430.08042 -401.89404) (xy 430.079986 -401.884855)
			(xy 430.073488 -401.867671) (xy 430.06772 -401.860512) (xy 430.045836 -401.834863) (xy 430.007746 -401.779227)
			(xy 429.976595 -401.719429) (xy 429.952831 -401.656329) (xy 429.936797 -401.590838) (xy 429.928722 -401.523898)
			(xy 429.928724 -401.456472) (xy 429.936802 -401.389532) (xy 429.95284 -401.324042) (xy 429.976608 -401.260944)
			(xy 430.007762 -401.201147) (xy 430.045854 -401.145513) (xy 430.06772 -401.119848) (xy 430.073523 -401.112708)
			(xy 430.080033 -401.095513) (xy 430.08042 -401.08632) (xy 430.08042 -400.92884) (xy 430.080849 -400.918718)
			(xy 430.088588 -400.900011) (xy 430.102901 -400.885695) (xy 430.121606 -400.877952) (xy 430.131728 -400.877532)
			(xy 430.848008 -400.877532) (xy 430.858135 -400.87791) (xy 430.876845 -400.885667) (xy 430.89116 -400.899996)
			(xy 430.898899 -400.918713) (xy 430.899316 -400.92884) (xy 430.899316 -401.08632) (xy 430.899713 -401.095509)
			(xy 430.906236 -401.112693) (xy 430.912016 -401.119848) (xy 430.93386 -401.14553) (xy 430.971948 -401.201162)
			(xy 431.003099 -401.260956) (xy 431.026863 -401.324051) (xy 431.0429 -401.389538) (xy 431.050977 -401.456474)
			(xy 431.050979 -401.523896) (xy 431.042905 -401.590832) (xy 431.026872 -401.65632) (xy 431.003111 -401.719416)
			(xy 431.00086 -401.723737) (xy 432.128879 -401.723737) (xy 432.128881 -401.65643) (xy 432.136928 -401.589605)
			(xy 432.152904 -401.524222) (xy 432.17658 -401.461216) (xy 432.207617 -401.401492) (xy 432.24557 -401.345906)
			(xy 432.26736 -401.320254) (xy 432.273166 -401.313116) (xy 432.279673 -401.29592) (xy 432.28006 -401.286726)
			(xy 432.28006 -400.793458) (xy 432.279657 -400.78427) (xy 432.273137 -400.767087) (xy 432.26736 -400.75993)
			(xy 432.245578 -400.734273) (xy 432.207627 -400.678688) (xy 432.176593 -400.618965) (xy 432.152919 -400.555961)
			(xy 432.136945 -400.490579) (xy 432.1289 -400.423757) (xy 432.128899 -400.356452) (xy 432.136943 -400.28963)
			(xy 432.152916 -400.224247) (xy 432.176589 -400.161243) (xy 432.207623 -400.10152) (xy 432.245572 -400.045934)
			(xy 432.26736 -400.020282) (xy 432.273154 -400.013135) (xy 432.279669 -399.995946) (xy 432.28006 -399.986754)
			(xy 432.28006 -399.828766) (xy 432.280506 -399.818603) (xy 432.288296 -399.799829) (xy 432.302676 -399.785464)
			(xy 432.321459 -399.777695) (xy 432.331622 -399.777204) (xy 433.047902 -399.777204) (xy 433.058056 -399.777731)
			(xy 433.076818 -399.7855) (xy 433.091182 -399.799855) (xy 433.098963 -399.818613) (xy 433.099464 -399.828766)
			(xy 433.099464 -399.986754) (xy 433.099905 -399.995938) (xy 433.106398 -400.013122) (xy 433.112164 -400.020282)
			(xy 433.133958 -400.045929) (xy 433.171906 -400.101516) (xy 433.202939 -400.161241) (xy 433.226611 -400.224246)
			(xy 433.242584 -400.289629) (xy 433.250627 -400.356452) (xy 433.250627 -400.423757) (xy 433.242582 -400.49058)
			(xy 433.226609 -400.555963) (xy 433.202935 -400.618968) (xy 433.171901 -400.678691) (xy 433.133952 -400.734278)
			(xy 433.112164 -400.75993) (xy 433.106368 -400.767075) (xy 433.099854 -400.784266) (xy 433.099464 -400.793458)
			(xy 433.099464 -401.286726) (xy 433.09987 -401.295913) (xy 433.106387 -401.313097) (xy 433.112164 -401.320254)
			(xy 433.13393 -401.345924) (xy 433.171879 -401.401508) (xy 433.202913 -401.461229) (xy 433.226587 -401.524231)
			(xy 433.242561 -401.589611) (xy 433.250607 -401.656432) (xy 433.250609 -401.723735) (xy 433.242567 -401.790556)
			(xy 433.226597 -401.855937) (xy 433.202927 -401.918941) (xy 433.171896 -401.978663) (xy 433.13395 -402.03425)
			(xy 433.112164 -402.059902) (xy 433.106379 -402.067056) (xy 433.099858 -402.08424) (xy 433.099464 -402.09343)
			(xy 433.099464 -402.251418) (xy 433.098982 -402.261577) (xy 433.091202 -402.280346) (xy 433.076833 -402.294711)
			(xy 433.058061 -402.302485) (xy 433.047902 -402.30298) (xy 432.331622 -402.30298) (xy 432.321454 -402.302518)
			(xy 432.302663 -402.294744) (xy 432.288278 -402.28037) (xy 432.28049 -402.261586) (xy 432.28006 -402.251418)
			(xy 432.28006 -402.09343) (xy 432.279622 -402.084246) (xy 432.273126 -402.067062) (xy 432.26736 -402.059902)
			(xy 432.24555 -402.034268) (xy 432.2076 -401.97868) (xy 432.176567 -401.918954) (xy 432.152894 -401.855947)
			(xy 432.136922 -401.790562) (xy 432.128879 -401.723737) (xy 431.00086 -401.723737) (xy 430.971963 -401.779212)
			(xy 430.933878 -401.834847) (xy 430.912016 -401.860512) (xy 430.906234 -401.867667) (xy 430.89971 -401.88485)
			(xy 430.899316 -401.89404) (xy 430.899316 -402.386292) (xy 430.899726 -402.395479) (xy 430.90624 -402.412664)
			(xy 430.912016 -402.41982) (xy 430.933832 -402.445524) (xy 430.971921 -402.501154) (xy 431.003073 -402.560945)
			(xy 431.026839 -402.624036) (xy 431.042878 -402.68952) (xy 431.050957 -402.756454) (xy 431.050962 -402.823818)
			(xy 434.329022 -402.823818) (xy 434.329026 -402.75651) (xy 434.337075 -402.689684) (xy 434.353052 -402.6243)
			(xy 434.376729 -402.561294) (xy 434.407766 -402.501568) (xy 434.445718 -402.445981) (xy 434.467508 -402.420328)
			(xy 434.473319 -402.413193) (xy 434.479825 -402.395995) (xy 434.480208 -402.3868) (xy 434.480208 -401.893532)
			(xy 434.479781 -401.884347) (xy 434.473279 -401.867162) (xy 434.467508 -401.860004) (xy 434.445702 -401.834368)
			(xy 434.407755 -401.778778) (xy 434.376725 -401.719052) (xy 434.353054 -401.656046) (xy 434.337084 -401.590662)
			(xy 434.329042 -401.523838) (xy 434.329043 -401.456532) (xy 434.337089 -401.389709) (xy 434.353063 -401.324326)
			(xy 434.376737 -401.26132) (xy 434.407771 -401.201596) (xy 434.44572 -401.146009) (xy 434.467508 -401.120356)
			(xy 434.473307 -401.113212) (xy 434.47982 -401.096021) (xy 434.480208 -401.086828) (xy 434.480208 -400.92884)
			(xy 434.480655 -400.918688) (xy 434.488438 -400.899934) (xy 434.502828 -400.885609) (xy 434.521616 -400.87791)
			(xy 434.53177 -400.877532) (xy 435.24805 -400.877532) (xy 435.258173 -400.878067) (xy 435.276891 -400.885777)
			(xy 435.291249 -400.900049) (xy 435.299071 -400.918721) (xy 435.299612 -400.92884) (xy 435.299612 -401.086828)
			(xy 435.300006 -401.096017) (xy 435.306531 -401.113201) (xy 435.312312 -401.120356) (xy 435.334082 -401.146024)
			(xy 435.372034 -401.201607) (xy 435.403071 -401.261328) (xy 435.426747 -401.32433) (xy 435.442723 -401.389711)
			(xy 435.450769 -401.456533) (xy 435.450771 -401.523837) (xy 435.442728 -401.590659) (xy 435.426756 -401.656041)
			(xy 435.403083 -401.719045) (xy 435.37205 -401.778767) (xy 435.3341 -401.834353) (xy 435.312312 -401.860004)
			(xy 435.306533 -401.867161) (xy 435.300007 -401.884343) (xy 435.299612 -401.893532) (xy 435.299612 -402.3868)
			(xy 435.30002 -402.395988) (xy 435.306535 -402.413172) (xy 435.312312 -402.420328) (xy 435.334054 -402.446018)
			(xy 435.372008 -402.501598) (xy 435.403046 -402.561316) (xy 435.426723 -402.624316) (xy 435.442701 -402.689694)
			(xy 435.45075 -402.756513) (xy 435.450754 -402.823815) (xy 435.442714 -402.890635) (xy 435.426745 -402.956015)
			(xy 435.403075 -403.019018) (xy 435.372045 -403.07874) (xy 435.334098 -403.134325) (xy 435.312312 -403.159976)
			(xy 435.306502 -403.167112) (xy 435.299995 -403.184309) (xy 435.299612 -403.193504) (xy 435.299612 -403.351492)
			(xy 435.299172 -403.361644) (xy 435.291381 -403.380394) (xy 435.27699 -403.394717) (xy 435.258204 -403.402419)
			(xy 435.24805 -403.4028) (xy 434.53177 -403.4028) (xy 434.521646 -403.402299) (xy 434.502932 -403.394569)
			(xy 434.488578 -403.380288) (xy 434.480753 -403.361613) (xy 434.480208 -403.351492) (xy 434.480208 -403.193504)
			(xy 434.479794 -403.184317) (xy 434.473283 -403.167133) (xy 434.467508 -403.159976) (xy 434.445674 -403.134362)
			(xy 434.407729 -403.07877) (xy 434.376699 -403.01904) (xy 434.353031 -402.956031) (xy 434.337062 -402.890644)
			(xy 434.329022 -402.823818) (xy 431.050962 -402.823818) (xy 431.050962 -402.823874) (xy 431.042891 -402.890808)
			(xy 431.026861 -402.956295) (xy 431.003103 -403.019389) (xy 430.971958 -403.079184) (xy 430.933877 -403.134819)
			(xy 430.912016 -403.160484) (xy 430.906203 -403.167618) (xy 430.899698 -403.184817) (xy 430.899316 -403.194012)
			(xy 430.899316 -403.351492) (xy 430.898809 -403.361598) (xy 430.891077 -403.380273) (xy 430.876787 -403.394568)
			(xy 430.858114 -403.402306) (xy 430.848008 -403.4028) (xy 430.131728 -403.4028) (xy 430.121607 -403.402361)
			(xy 430.102904 -403.394622) (xy 430.088589 -403.380313) (xy 430.080843 -403.361613) (xy 430.08042 -403.351492)
			(xy 430.08042 -403.194012) (xy 430.079999 -403.184826) (xy 430.073492 -403.167642) (xy 430.06772 -403.160484)
			(xy 430.045808 -403.134858) (xy 430.00772 -403.079218) (xy 429.97657 -403.019417) (xy 429.952807 -402.956315)
			(xy 429.936775 -402.890821) (xy 429.928702 -402.823878) (xy 426.650658 -402.823878) (xy 426.642626 -402.890635)
			(xy 426.626657 -402.956015) (xy 426.602989 -403.019017) (xy 426.571959 -403.078739) (xy 426.534014 -403.134324)
			(xy 426.512228 -403.159976) (xy 426.506408 -403.167104) (xy 426.499909 -403.184308) (xy 426.499528 -403.193504)
			(xy 426.499528 -403.351492) (xy 426.499072 -403.361642) (xy 426.491285 -403.380389) (xy 426.476899 -403.394712)
			(xy 426.458118 -403.402417) (xy 426.447966 -403.4028) (xy 425.731686 -403.4028) (xy 425.721563 -403.402286)
			(xy 425.70285 -403.394561) (xy 425.688495 -403.380284) (xy 425.68067 -403.361612) (xy 425.680124 -403.351492)
			(xy 425.680124 -403.193504) (xy 425.679707 -403.184318) (xy 425.673198 -403.167133) (xy 425.667424 -403.159976)
			(xy 425.64559 -403.134362) (xy 425.607643 -403.07877) (xy 425.576613 -403.019041) (xy 425.552943 -402.956032)
			(xy 425.536974 -402.890645) (xy 425.528934 -402.823818) (xy 422.250874 -402.823818) (xy 422.250874 -402.823874)
			(xy 422.242803 -402.890808) (xy 422.226774 -402.956294) (xy 422.203016 -403.019389) (xy 422.171873 -403.079184)
			(xy 422.133792 -403.134818) (xy 422.111932 -403.160484) (xy 422.106109 -403.16761) (xy 422.099612 -403.184816)
			(xy 422.099232 -403.194012) (xy 422.099232 -403.351492) (xy 422.098709 -403.361596) (xy 422.09098 -403.380268)
			(xy 422.076695 -403.394562) (xy 422.058028 -403.402303) (xy 422.047924 -403.4028) (xy 421.331644 -403.4028)
			(xy 421.321524 -403.402348) (xy 421.302822 -403.394614) (xy 421.288506 -403.380308) (xy 421.280759 -403.361611)
			(xy 421.280336 -403.351492) (xy 421.280336 -403.194012) (xy 421.279912 -403.184826) (xy 421.273407 -403.167642)
			(xy 421.267636 -403.160484) (xy 421.245724 -403.134858) (xy 421.207634 -403.079219) (xy 421.176483 -403.019418)
			(xy 421.15272 -402.956315) (xy 421.136687 -402.890821) (xy 421.128614 -402.823878) (xy 414.525968 -402.823878)
			(xy 414.525968 -405.623649) (xy 418.929012 -405.623649) (xy 418.929013 -405.556342) (xy 418.937058 -405.489518)
			(xy 418.953033 -405.424135) (xy 418.976709 -405.36113) (xy 419.007746 -405.301407) (xy 419.045698 -405.245822)
			(xy 419.067488 -405.22017) (xy 419.073278 -405.21302) (xy 419.079797 -405.195833) (xy 419.080188 -405.186642)
			(xy 419.080188 -404.693374) (xy 419.079793 -404.684185) (xy 419.073269 -404.667001) (xy 419.067488 -404.659846)
			(xy 419.04572 -404.634177) (xy 419.007768 -404.578594) (xy 418.976731 -404.518873) (xy 418.953055 -404.455871)
			(xy 418.937079 -404.39049) (xy 418.929032 -404.323669) (xy 418.92903 -404.256364) (xy 418.937073 -404.189542)
			(xy 418.953045 -404.124161) (xy 418.976717 -404.061157) (xy 419.007751 -404.001435) (xy 419.0457 -403.945849)
			(xy 419.067488 -403.920198) (xy 419.073267 -403.91304) (xy 419.079792 -403.895859) (xy 419.080188 -403.88667)
			(xy 419.080188 -403.728682) (xy 419.08055 -403.718503) (xy 419.088351 -403.699698) (xy 419.102756 -403.685313)
			(xy 419.12157 -403.677537) (xy 419.13175 -403.67712) (xy 419.84803 -403.67712) (xy 419.858187 -403.677608)
			(xy 419.876954 -403.685389) (xy 419.891317 -403.699756) (xy 419.899094 -403.718524) (xy 419.899592 -403.728682)
			(xy 419.899592 -403.88667) (xy 419.900018 -403.895855) (xy 419.906521 -403.91304) (xy 419.912292 -403.920198)
			(xy 419.9341 -403.945833) (xy 419.972047 -404.001422) (xy 420.003077 -404.061149) (xy 420.026747 -404.124155)
			(xy 420.042718 -404.189539) (xy 420.05076 -404.256363) (xy 420.050758 -404.32367) (xy 420.042712 -404.390493)
			(xy 420.026738 -404.455876) (xy 420.003064 -404.518882) (xy 419.97203 -404.578606) (xy 419.93408 -404.634193)
			(xy 419.912292 -404.659846) (xy 419.906492 -404.666989) (xy 419.89998 -404.684181) (xy 419.899592 -404.693374)
			(xy 419.899592 -405.186642) (xy 419.899984 -405.195831) (xy 419.90651 -405.213015) (xy 419.912292 -405.22017)
			(xy 419.934073 -405.245827) (xy 419.97202 -405.301414) (xy 420.003052 -405.361137) (xy 420.026723 -405.424141)
			(xy 420.042696 -405.489522) (xy 420.05074 -405.556343) (xy 420.050741 -405.623647) (xy 420.042698 -405.690469)
			(xy 420.026726 -405.755851) (xy 420.003055 -405.818855) (xy 419.972025 -405.878578) (xy 419.934078 -405.934165)
			(xy 419.912292 -405.959818) (xy 419.906504 -405.96697) (xy 419.899985 -405.984155) (xy 419.899592 -405.993346)
			(xy 419.899592 -406.151334) (xy 419.899095 -406.16149) (xy 419.891315 -406.180254) (xy 419.876951 -406.194617)
			(xy 419.858186 -406.202396) (xy 419.84803 -406.202896) (xy 419.13175 -406.202896) (xy 419.121586 -406.202396)
			(xy 419.102799 -406.194634) (xy 419.088413 -406.180272) (xy 419.08062 -406.161497) (xy 419.080188 -406.151334)
			(xy 419.080188 -405.993346) (xy 419.079759 -405.984161) (xy 419.073259 -405.966976) (xy 419.067488 -405.959818)
			(xy 419.045693 -405.934171) (xy 419.007741 -405.878585) (xy 418.976705 -405.818861) (xy 418.953031 -405.755856)
			(xy 418.937057 -405.690473) (xy 418.929012 -405.623649) (xy 414.525968 -405.623649) (xy 414.525968 -406.723789)
			(xy 421.128626 -406.723789) (xy 421.128629 -406.656363) (xy 421.136708 -406.589421) (xy 421.152748 -406.52393)
			(xy 421.176518 -406.460832) (xy 421.207674 -406.401035) (xy 421.245769 -406.345401) (xy 421.267636 -406.319736)
			(xy 421.273447 -406.312601) (xy 421.279952 -406.295403) (xy 421.280336 -406.286208) (xy 421.280336 -405.793956)
			(xy 421.279939 -405.784768) (xy 421.273415 -405.767584) (xy 421.267636 -405.760428) (xy 421.245767 -405.734767)
			(xy 421.207676 -405.679132) (xy 421.176523 -405.619336) (xy 421.152758 -405.556239) (xy 421.136722 -405.490749)
			(xy 421.128645 -405.423809) (xy 421.128646 -405.356385) (xy 421.136723 -405.289445) (xy 421.15276 -405.223956)
			(xy 421.176526 -405.160859) (xy 421.207679 -405.101062) (xy 421.245771 -405.045429) (xy 421.267636 -405.019764)
			(xy 421.273435 -405.012621) (xy 421.279947 -404.995429) (xy 421.280336 -404.986236) (xy 421.280336 -404.828756)
			(xy 421.28075 -404.81864) (xy 421.288509 -404.799954) (xy 421.302828 -404.785659) (xy 421.321527 -404.777933)
			(xy 421.331644 -404.777448) (xy 422.047924 -404.777448) (xy 422.058028 -404.777964) (xy 422.076697 -404.7857)
			(xy 422.090989 -404.799986) (xy 422.098732 -404.818652) (xy 422.099232 -404.828756) (xy 422.099232 -404.986236)
			(xy 422.09964 -404.995423) (xy 422.106157 -405.012607) (xy 422.111932 -405.019764) (xy 422.133791 -405.045433)
			(xy 422.171878 -405.101068) (xy 422.203027 -405.160864) (xy 422.22679 -405.22396) (xy 422.242825 -405.289448)
			(xy 422.2509 -405.356386) (xy 422.250901 -405.423808) (xy 422.242826 -405.490746) (xy 422.226792 -405.556234)
			(xy 422.203029 -405.619331) (xy 422.20075 -405.623707) (xy 423.328805 -405.623707) (xy 423.328805 -405.556284)
			(xy 423.336882 -405.489345) (xy 423.352917 -405.423856) (xy 423.376681 -405.360759) (xy 423.407832 -405.300962)
			(xy 423.44592 -405.245328) (xy 423.467784 -405.219662) (xy 423.473577 -405.212514) (xy 423.480094 -405.195326)
			(xy 423.480484 -405.186134) (xy 423.480484 -404.693882) (xy 423.480086 -404.684693) (xy 423.473564 -404.667509)
			(xy 423.467784 -404.660354) (xy 423.445942 -404.634671) (xy 423.407854 -404.579038) (xy 423.376703 -404.519245)
			(xy 423.352938 -404.45615) (xy 423.336902 -404.390663) (xy 423.328825 -404.323727) (xy 423.328823 -404.256306)
			(xy 423.336896 -404.189369) (xy 423.352929 -404.123882) (xy 423.37669 -404.060786) (xy 423.407837 -404.00099)
			(xy 423.445922 -403.945355) (xy 423.467784 -403.91969) (xy 423.473565 -403.912534) (xy 423.48009 -403.895352)
			(xy 423.480484 -403.886162) (xy 423.480484 -403.728682) (xy 423.480913 -403.718549) (xy 423.488655 -403.699819)
			(xy 423.502959 -403.685461) (xy 423.521661 -403.677651) (xy 423.531792 -403.67712) (xy 424.248072 -403.67712)
			(xy 424.258227 -403.677545) (xy 424.276983 -403.685335) (xy 424.291308 -403.699731) (xy 424.299005 -403.718525)
			(xy 424.29938 -403.728682) (xy 424.29938 -403.886162) (xy 424.299813 -403.895347) (xy 424.306311 -403.912531)
			(xy 424.31208 -403.91969) (xy 424.333966 -403.945337) (xy 424.372056 -404.000974) (xy 424.403207 -404.060772)
			(xy 424.42697 -404.123872) (xy 424.443005 -404.189363) (xy 424.451079 -404.256304) (xy 424.451077 -404.323729)
			(xy 424.442999 -404.39067) (xy 424.426961 -404.45616) (xy 424.403193 -404.519258) (xy 424.372039 -404.579055)
			(xy 424.333946 -404.634689) (xy 424.31208 -404.660354) (xy 424.306276 -404.667494) (xy 424.299766 -404.684688)
			(xy 424.29938 -404.693882) (xy 424.29938 -405.186134) (xy 424.299778 -405.195322) (xy 424.306301 -405.212506)
			(xy 424.31208 -405.219662) (xy 424.333939 -405.245332) (xy 424.372029 -405.300965) (xy 424.403181 -405.360761)
			(xy 424.426946 -405.423857) (xy 424.442983 -405.489346) (xy 424.45106 -405.556284) (xy 424.45106 -405.623707)
			(xy 424.442985 -405.690646) (xy 424.426949 -405.756134) (xy 424.403185 -405.819231) (xy 424.372034 -405.879027)
			(xy 424.333944 -405.934661) (xy 424.31208 -405.960326) (xy 424.306288 -405.967474) (xy 424.299771 -405.984662)
			(xy 424.29938 -405.993854) (xy 424.29938 -406.151334) (xy 424.298902 -406.16146) (xy 424.291167 -406.180179)
			(xy 424.276878 -406.194533) (xy 424.258196 -406.202355) (xy 424.248072 -406.202896) (xy 423.531792 -406.202896)
			(xy 423.521637 -406.202485) (xy 423.502884 -406.194686) (xy 423.48856 -406.180286) (xy 423.480862 -406.161491)
			(xy 423.480484 -406.151334) (xy 423.480484 -405.993854) (xy 423.480051 -405.984669) (xy 423.473553 -405.967484)
			(xy 423.467784 -405.960326) (xy 423.445915 -405.934665) (xy 423.407827 -405.87903) (xy 423.376678 -405.819233)
			(xy 423.352915 -405.756135) (xy 423.33688 -405.690646) (xy 423.328805 -405.623707) (xy 422.20075 -405.623707)
			(xy 422.171881 -405.679127) (xy 422.133795 -405.734762) (xy 422.111932 -405.760428) (xy 422.106133 -405.767571)
			(xy 422.099622 -405.784763) (xy 422.099232 -405.793956) (xy 422.099232 -406.286208) (xy 422.099654 -406.295394)
			(xy 422.106161 -406.312577) (xy 422.111932 -406.319736) (xy 422.133763 -406.345428) (xy 422.171851 -406.401059)
			(xy 422.203001 -406.460852) (xy 422.226766 -406.523945) (xy 422.242803 -406.589431) (xy 422.250881 -406.656366)
			(xy 422.250883 -406.72373) (xy 425.528945 -406.72373) (xy 425.528948 -406.656422) (xy 425.536995 -406.589598)
			(xy 425.552971 -406.524214) (xy 425.576647 -406.461208) (xy 425.607683 -406.401484) (xy 425.645635 -406.345896)
			(xy 425.667424 -406.320244) (xy 425.67323 -406.313105) (xy 425.679738 -406.29591) (xy 425.680124 -406.286716)
			(xy 425.680124 -405.793448) (xy 425.679685 -405.784264) (xy 425.673191 -405.76708) (xy 425.667424 -405.75992)
			(xy 425.645633 -405.734271) (xy 425.607685 -405.678684) (xy 425.576653 -405.61896) (xy 425.552981 -405.555955)
			(xy 425.537009 -405.490572) (xy 425.528965 -405.42375) (xy 425.528965 -405.356444) (xy 425.53701 -405.289622)
			(xy 425.552983 -405.22424) (xy 425.576655 -405.161235) (xy 425.607688 -405.101511) (xy 425.645636 -405.045924)
			(xy 425.667424 -405.020272) (xy 425.673218 -405.013125) (xy 425.679733 -404.995936) (xy 425.680124 -404.986744)
			(xy 425.680124 -404.828756) (xy 425.680486 -404.818596) (xy 425.688301 -404.799838) (xy 425.702716 -404.785515)
			(xy 425.721523 -404.777822) (xy 425.731686 -404.777448) (xy 426.447966 -404.777448) (xy 426.458091 -404.777955)
			(xy 426.476813 -404.785673) (xy 426.491171 -404.799953) (xy 426.49899 -404.818633) (xy 426.499528 -404.828756)
			(xy 426.499528 -404.986744) (xy 426.499911 -404.995934) (xy 426.506443 -405.013119) (xy 426.512228 -405.020272)
			(xy 426.534013 -405.045927) (xy 426.571964 -405.101512) (xy 426.602999 -405.161235) (xy 426.626674 -405.224239)
			(xy 426.642648 -405.289622) (xy 426.650693 -405.356444) (xy 426.650693 -405.42375) (xy 426.642649 -405.490573)
			(xy 426.626675 -405.555955) (xy 426.603002 -405.618959) (xy 426.600565 -405.623649) (xy 427.7291 -405.623649)
			(xy 427.729101 -405.556342) (xy 427.737146 -405.489519) (xy 427.753121 -405.424136) (xy 427.776796 -405.361131)
			(xy 427.807831 -405.301408) (xy 427.845783 -405.245822) (xy 427.867572 -405.22017) (xy 427.873373 -405.213028)
			(xy 427.879883 -405.195835) (xy 427.880272 -405.186642) (xy 427.880272 -404.693374) (xy 427.879881 -404.684185)
			(xy 427.873355 -404.667) (xy 427.867572 -404.659846) (xy 427.845805 -404.634176) (xy 427.807853 -404.578593)
			(xy 427.776817 -404.518872) (xy 427.753142 -404.45587) (xy 427.737166 -404.39049) (xy 427.72912 -404.323668)
			(xy 427.729118 -404.256365) (xy 427.73716 -404.189543) (xy 427.753132 -404.124162) (xy 427.776804 -404.061158)
			(xy 427.807836 -404.001435) (xy 427.845785 -403.94585) (xy 427.867572 -403.920198) (xy 427.873361 -403.913048)
			(xy 427.879878 -403.895861) (xy 427.880272 -403.88667) (xy 427.880272 -403.728682) (xy 427.88065 -403.718505)
			(xy 427.888447 -403.699703) (xy 427.902847 -403.685318) (xy 427.921657 -403.67754) (xy 427.931834 -403.67712)
			(xy 428.648114 -403.67712) (xy 428.65827 -403.677622) (xy 428.677036 -403.685397) (xy 428.6914 -403.69976)
			(xy 428.699178 -403.718526) (xy 428.699676 -403.728682) (xy 428.699676 -403.88667) (xy 428.700106 -403.895855)
			(xy 428.706607 -403.913039) (xy 428.712376 -403.920198) (xy 428.734185 -403.945833) (xy 428.772132 -404.001422)
			(xy 428.803164 -404.061148) (xy 428.826835 -404.124155) (xy 428.842806 -404.189539) (xy 428.850848 -404.256363)
			(xy 428.850846 -404.32367) (xy 428.8428 -404.390494) (xy 428.826825 -404.455877) (xy 428.80315 -404.518882)
			(xy 428.772115 -404.578607) (xy 428.734165 -404.634194) (xy 428.712376 -404.659846) (xy 428.706575 -404.666988)
			(xy 428.700064 -404.684181) (xy 428.699676 -404.693374) (xy 428.699676 -405.186642) (xy 428.700071 -405.195831)
			(xy 428.706596 -405.213015) (xy 428.712376 -405.22017) (xy 428.734157 -405.245827) (xy 428.772106 -405.301413)
			(xy 428.803138 -405.361136) (xy 428.826811 -405.42414) (xy 428.842784 -405.489522) (xy 428.850828 -405.556343)
			(xy 428.850829 -405.623648) (xy 428.842785 -405.69047) (xy 428.826813 -405.755851) (xy 428.803142 -405.818856)
			(xy 428.77211 -405.878579) (xy 428.734163 -405.934166) (xy 428.712376 -405.959818) (xy 428.706587 -405.966968)
			(xy 428.700068 -405.984155) (xy 428.699676 -405.993346) (xy 428.699676 -406.151334) (xy 428.699195 -406.161492)
			(xy 428.691412 -406.180259) (xy 428.677043 -406.194623) (xy 428.658272 -406.202399) (xy 428.648114 -406.202896)
			(xy 427.931834 -406.202896) (xy 427.921683 -406.202339) (xy 427.902921 -406.194583) (xy 427.888556 -406.180236)
			(xy 427.880774 -406.161485) (xy 427.880272 -406.151334) (xy 427.880272 -405.993346) (xy 427.879846 -405.98416)
			(xy 427.873344 -405.966976) (xy 427.867572 -405.959818) (xy 427.845777 -405.934171) (xy 427.807827 -405.878585)
			(xy 427.776792 -405.818861) (xy 427.753118 -405.755855) (xy 427.737144 -405.690472) (xy 427.7291 -405.623649)
			(xy 426.600565 -405.623649) (xy 426.571967 -405.678683) (xy 426.534016 -405.734268) (xy 426.512228 -405.75992)
			(xy 426.506432 -405.767065) (xy 426.499919 -405.784256) (xy 426.499528 -405.793448) (xy 426.499528 -406.286716)
			(xy 426.499924 -406.295905) (xy 426.506447 -406.313089) (xy 426.512228 -406.320244) (xy 426.533985 -406.345922)
			(xy 426.571937 -406.401504) (xy 426.602974 -406.461223) (xy 426.62665 -406.524225) (xy 426.642626 -406.589604)
			(xy 426.650673 -406.656424) (xy 426.650676 -406.723728) (xy 426.650669 -406.723789) (xy 429.928714 -406.723789)
			(xy 429.928717 -406.656363) (xy 429.936796 -406.589422) (xy 429.952835 -406.523931) (xy 429.976604 -406.460832)
			(xy 430.00776 -406.401036) (xy 430.045853 -406.345401) (xy 430.06772 -406.319736) (xy 430.073529 -406.312599)
			(xy 430.080035 -406.295402) (xy 430.08042 -406.286208) (xy 430.08042 -405.793956) (xy 430.080027 -405.784767)
			(xy 430.073501 -405.767583) (xy 430.06772 -405.760428) (xy 430.045851 -405.734766) (xy 430.007761 -405.679132)
			(xy 429.97661 -405.619335) (xy 429.952845 -405.556238) (xy 429.936809 -405.490748) (xy 429.928733 -405.423809)
			(xy 429.928734 -405.356385) (xy 429.93681 -405.289446) (xy 429.952847 -405.223956) (xy 429.976612 -405.160859)
			(xy 430.007765 -405.101063) (xy 430.045855 -405.045429) (xy 430.06772 -405.019764) (xy 430.073517 -405.012619)
			(xy 430.080031 -404.995428) (xy 430.08042 -404.986236) (xy 430.08042 -404.828756) (xy 430.08085 -404.818642)
			(xy 430.088605 -404.799959) (xy 430.102919 -404.785665) (xy 430.121613 -404.777935) (xy 430.131728 -404.777448)
			(xy 430.848008 -404.777448) (xy 430.858111 -404.777977) (xy 430.876779 -404.785708) (xy 430.891072 -404.799991)
			(xy 430.898815 -404.818654) (xy 430.899316 -404.828756) (xy 430.899316 -404.986236) (xy 430.899705 -404.995425)
			(xy 430.906233 -405.01261) (xy 430.912016 -405.019764) (xy 430.933875 -405.045433) (xy 430.971963 -405.101067)
			(xy 431.003113 -405.160863) (xy 431.026877 -405.223959) (xy 431.042912 -405.289448) (xy 431.050988 -405.356385)
			(xy 431.050989 -405.423809) (xy 431.042913 -405.490746) (xy 431.026879 -405.556235) (xy 431.003116 -405.619331)
			(xy 431.000867 -405.623648) (xy 432.128891 -405.623648) (xy 432.128892 -405.556343) (xy 432.136937 -405.489519)
			(xy 432.152911 -405.424136) (xy 432.176585 -405.361132) (xy 432.207621 -405.301408) (xy 432.245571 -405.245822)
			(xy 432.26736 -405.22017) (xy 432.273159 -405.213027) (xy 432.279671 -405.195835) (xy 432.28006 -405.186642)
			(xy 432.28006 -404.693374) (xy 432.279649 -404.684187) (xy 432.273134 -404.667004) (xy 432.26736 -404.659846)
			(xy 432.245593 -404.634176) (xy 432.207643 -404.578593) (xy 432.176607 -404.518872) (xy 432.152932 -404.45587)
			(xy 432.136957 -404.390489) (xy 432.128911 -404.323668) (xy 432.128909 -404.256365) (xy 432.136951 -404.189543)
			(xy 432.152922 -404.124162) (xy 432.176594 -404.061158) (xy 432.207626 -404.001436) (xy 432.245573 -403.94585)
			(xy 432.26736 -403.920198) (xy 432.273147 -403.913047) (xy 432.279666 -403.895861) (xy 432.28006 -403.88667)
			(xy 432.28006 -403.728682) (xy 432.28045 -403.718507) (xy 432.288245 -403.699707) (xy 432.302641 -403.685322)
			(xy 432.321446 -403.677542) (xy 432.331622 -403.67712) (xy 433.047902 -403.67712) (xy 433.058058 -403.677631)
			(xy 433.076823 -403.685403) (xy 433.091188 -403.699763) (xy 433.098965 -403.718526) (xy 433.099464 -403.728682)
			(xy 433.099464 -403.88667) (xy 433.099897 -403.895855) (xy 433.106396 -403.913039) (xy 433.112164 -403.920198)
			(xy 433.133973 -403.945832) (xy 433.171921 -404.001421) (xy 433.202954 -404.061147) (xy 433.226625 -404.124154)
			(xy 433.242596 -404.189539) (xy 433.250639 -404.256363) (xy 433.250637 -404.32367) (xy 433.24259 -404.390494)
			(xy 433.226615 -404.455877) (xy 433.20294 -404.518883) (xy 433.171904 -404.578607) (xy 433.133953 -404.634194)
			(xy 433.112164 -404.659846) (xy 433.106361 -404.666986) (xy 433.099851 -404.684181) (xy 433.099464 -404.693374)
			(xy 433.099464 -405.186642) (xy 433.099862 -405.19583) (xy 433.106385 -405.213014) (xy 433.112164 -405.22017)
			(xy 433.133946 -405.245827) (xy 433.171895 -405.301413) (xy 433.202928 -405.361136) (xy 433.226601 -405.42414)
			(xy 433.242574 -405.489521) (xy 433.250619 -405.556343) (xy 433.250619 -405.623648) (xy 433.242576 -405.69047)
			(xy 433.226604 -405.755852) (xy 433.202932 -405.818856) (xy 433.171899 -405.878579) (xy 433.133951 -405.934166)
			(xy 433.112164 -405.959818) (xy 433.106373 -405.966967) (xy 433.099856 -405.984155) (xy 433.099464 -405.993346)
			(xy 433.099464 -406.151334) (xy 433.098995 -406.161494) (xy 433.091209 -406.180263) (xy 433.076836 -406.194627)
			(xy 433.058062 -406.202401) (xy 433.047902 -406.202896) (xy 432.331622 -406.202896) (xy 432.32147 -406.20235)
			(xy 432.302708 -406.194589) (xy 432.288343 -406.180239) (xy 432.280561 -406.161486) (xy 432.28006 -406.151334)
			(xy 432.28006 -405.993346) (xy 432.279614 -405.984163) (xy 432.273124 -405.966979) (xy 432.26736 -405.959818)
			(xy 432.245566 -405.934171) (xy 432.207616 -405.878584) (xy 432.176582 -405.81886) (xy 432.152908 -405.755855)
			(xy 432.136935 -405.690472) (xy 432.128891 -405.623648) (xy 431.000867 -405.623648) (xy 430.971966 -405.679128)
			(xy 430.933879 -405.734762) (xy 430.912016 -405.760428) (xy 430.906227 -405.767579) (xy 430.899707 -405.784765)
			(xy 430.899316 -405.793956) (xy 430.899316 -406.286208) (xy 430.899719 -406.295396) (xy 430.906237 -406.31258)
			(xy 430.912016 -406.319736) (xy 430.933848 -406.345427) (xy 430.971937 -406.401059) (xy 431.003088 -406.460851)
			(xy 431.026853 -406.523945) (xy 431.04289 -406.58943) (xy 431.050968 -406.656366) (xy 431.050971 -406.723729)
			(xy 434.329033 -406.723729) (xy 434.329036 -406.656422) (xy 434.337083 -406.589598) (xy 434.353058 -406.524215)
			(xy 434.376733 -406.461209) (xy 434.407769 -406.401484) (xy 434.445719 -406.345897) (xy 434.467508 -406.320244)
			(xy 434.473312 -406.313104) (xy 434.479822 -406.295909) (xy 434.480208 -406.286716) (xy 434.480208 -405.793448)
			(xy 434.479773 -405.784263) (xy 434.473276 -405.767079) (xy 434.467508 -405.75992) (xy 434.445717 -405.734271)
			(xy 434.407771 -405.678683) (xy 434.376739 -405.618959) (xy 434.353068 -405.555954) (xy 434.337096 -405.490572)
			(xy 434.329053 -405.423749) (xy 434.329053 -405.356445) (xy 434.337097 -405.289622) (xy 434.35307 -405.22424)
			(xy 434.376742 -405.161236) (xy 434.407774 -405.101512) (xy 434.445721 -405.045925) (xy 434.467508 -405.020272)
			(xy 434.4733 -405.013124) (xy 434.479817 -404.995935) (xy 434.480208 -404.986744) (xy 434.480208 -404.828756)
			(xy 434.480586 -404.818598) (xy 434.488397 -404.799843) (xy 434.502807 -404.785521) (xy 434.52161 -404.777824)
			(xy 434.53177 -404.777448) (xy 435.24805 -404.777448) (xy 435.258175 -404.777968) (xy 435.276896 -404.785681)
			(xy 435.291254 -404.799957) (xy 435.299074 -404.818634) (xy 435.299612 -404.828756) (xy 435.299612 -404.986744)
			(xy 435.299998 -404.995934) (xy 435.306528 -405.013118) (xy 435.312312 -405.020272) (xy 435.334097 -405.045927)
			(xy 435.372049 -405.101512) (xy 435.403086 -405.161234) (xy 435.426761 -405.224239) (xy 435.442735 -405.289621)
			(xy 435.450781 -405.356444) (xy 435.450781 -405.42375) (xy 435.442736 -405.490573) (xy 435.426762 -405.555956)
			(xy 435.403088 -405.61896) (xy 435.372052 -405.678683) (xy 435.334101 -405.734269) (xy 435.312312 -405.75992)
			(xy 435.306526 -405.767073) (xy 435.300005 -405.784257) (xy 435.299612 -405.793448) (xy 435.299612 -406.286716)
			(xy 435.300012 -406.295904) (xy 435.306532 -406.313089) (xy 435.312312 -406.320244) (xy 435.33407 -406.345921)
			(xy 435.372023 -406.401503) (xy 435.40306 -406.461223) (xy 435.426737 -406.524224) (xy 435.442713 -406.589604)
			(xy 435.450761 -406.656424) (xy 435.450764 -406.723728) (xy 435.442722 -406.790549) (xy 435.426751 -406.85593)
			(xy 435.40308 -406.918933) (xy 435.372048 -406.978656) (xy 435.334099 -407.034241) (xy 435.312312 -407.059892)
			(xy 435.306538 -407.067053) (xy 435.300009 -407.084231) (xy 435.299612 -407.09342) (xy 435.299612 -407.251408)
			(xy 435.299185 -407.261561) (xy 435.291389 -407.280311) (xy 435.276994 -407.294634) (xy 435.258205 -407.302335)
			(xy 435.24805 -407.302716) (xy 434.53177 -407.302716) (xy 434.521636 -407.302297) (xy 434.502906 -407.294551)
			(xy 434.488549 -407.280244) (xy 434.480739 -407.26154) (xy 434.480208 -407.251408) (xy 434.480208 -407.09342)
			(xy 434.479786 -407.084234) (xy 434.47328 -407.06705) (xy 434.467508 -407.059892) (xy 434.44569 -407.034265)
			(xy 434.407744 -406.978674) (xy 434.376714 -406.918947) (xy 434.353044 -406.855939) (xy 434.337074 -406.790554)
			(xy 434.329033 -406.723729) (xy 431.050971 -406.723729) (xy 431.050971 -406.723786) (xy 431.042899 -406.790722)
			(xy 431.026867 -406.856209) (xy 431.003107 -406.919305) (xy 430.971961 -406.9791) (xy 430.933877 -407.034735)
			(xy 430.912016 -407.0604) (xy 430.906239 -407.067559) (xy 430.899712 -407.084739) (xy 430.899316 -407.093928)
			(xy 430.899316 -407.251408) (xy 430.898822 -407.261515) (xy 430.891084 -407.28019) (xy 430.87679 -407.294484)
			(xy 430.858115 -407.302222) (xy 430.848008 -407.302716) (xy 430.131728 -407.302716) (xy 430.121609 -407.302262)
			(xy 430.102909 -407.294526) (xy 430.088595 -407.280221) (xy 430.080845 -407.261526) (xy 430.08042 -407.251408)
			(xy 430.08042 -407.093928) (xy 430.079992 -407.084743) (xy 430.07349 -407.067559) (xy 430.06772 -407.0604)
			(xy 430.045824 -407.034761) (xy 430.007735 -406.979123) (xy 429.976584 -406.919324) (xy 429.952821 -406.856223)
			(xy 429.936787 -406.790731) (xy 429.928714 -406.723789) (xy 426.650669 -406.723789) (xy 426.642634 -406.790548)
			(xy 426.626664 -406.855929) (xy 426.602993 -406.918933) (xy 426.571962 -406.978655) (xy 426.534015 -407.03424)
			(xy 426.512228 -407.059892) (xy 426.506444 -407.067045) (xy 426.499924 -407.08423) (xy 426.499528 -407.09342)
			(xy 426.499528 -407.251408) (xy 426.499085 -407.261559) (xy 426.491292 -407.280306) (xy 426.476903 -407.294628)
			(xy 426.458119 -407.302333) (xy 426.447966 -407.302716) (xy 425.731686 -407.302716) (xy 425.721553 -407.302283)
			(xy 425.702823 -407.294543) (xy 425.688466 -407.28024) (xy 425.680655 -407.261539) (xy 425.680124 -407.251408)
			(xy 425.680124 -407.09342) (xy 425.679699 -407.084235) (xy 425.673195 -407.06705) (xy 425.667424 -407.059892)
			(xy 425.645605 -407.034266) (xy 425.607658 -406.978675) (xy 425.576627 -406.918948) (xy 425.552957 -406.85594)
			(xy 425.536987 -406.790555) (xy 425.528945 -406.72373) (xy 422.250883 -406.72373) (xy 422.250883 -406.723786)
			(xy 422.242811 -406.790722) (xy 422.22678 -406.856209) (xy 422.203021 -406.919304) (xy 422.171876 -406.9791)
			(xy 422.133793 -407.034734) (xy 422.111932 -407.0604) (xy 422.106145 -407.067551) (xy 422.099626 -407.084737)
			(xy 422.099232 -407.093928) (xy 422.099232 -407.251408) (xy 422.098722 -407.261513) (xy 422.090988 -407.280185)
			(xy 422.076699 -407.294479) (xy 422.058029 -407.302219) (xy 422.047924 -407.302716) (xy 421.331644 -407.302716)
			(xy 421.321526 -407.302248) (xy 421.302827 -407.294518) (xy 421.288512 -407.280217) (xy 421.280762 -407.261525)
			(xy 421.280336 -407.251408) (xy 421.280336 -407.093928) (xy 421.279904 -407.084743) (xy 421.273405 -407.067559)
			(xy 421.267636 -407.0604) (xy 421.245739 -407.034761) (xy 421.207649 -406.979124) (xy 421.176498 -406.919324)
			(xy 421.152734 -406.856224) (xy 421.1367 -406.790731) (xy 421.128626 -406.723789) (xy 414.525968 -406.723789)
			(xy 414.525968 -409.523827) (xy 418.928991 -409.523827) (xy 418.928995 -409.456519) (xy 418.937043 -409.389693)
			(xy 418.953021 -409.324308) (xy 418.9767 -409.261302) (xy 419.00774 -409.201577) (xy 419.045697 -409.145992)
			(xy 419.067488 -409.12034) (xy 419.073291 -409.113199) (xy 419.079802 -409.096005) (xy 419.080188 -409.086812)
			(xy 419.080188 -408.593544) (xy 419.079759 -408.584359) (xy 419.073259 -408.567174) (xy 419.067488 -408.560016)
			(xy 419.045691 -408.534371) (xy 419.007739 -408.478785) (xy 418.976704 -408.419061) (xy 418.953029 -408.356055)
			(xy 418.937055 -408.290671) (xy 418.929011 -408.223847) (xy 418.929012 -408.156541) (xy 418.937057 -408.089717)
			(xy 418.953033 -408.024333) (xy 418.976708 -407.961328) (xy 419.007745 -407.901605) (xy 419.045698 -407.84602)
			(xy 419.067488 -407.820368) (xy 419.073279 -407.813219) (xy 419.079797 -407.796031) (xy 419.080188 -407.78684)
			(xy 419.080188 -407.628852) (xy 419.080582 -407.618696) (xy 419.088391 -407.599945) (xy 419.102796 -407.585624)
			(xy 419.121592 -407.577924) (xy 419.13175 -407.577544) (xy 419.84803 -407.577544) (xy 419.858159 -407.578002)
			(xy 419.876882 -407.58574) (xy 419.891237 -407.600035) (xy 419.899055 -407.618725) (xy 419.899592 -407.628852)
			(xy 419.899592 -407.78684) (xy 419.899985 -407.796029) (xy 419.906511 -407.813213) (xy 419.912292 -407.820368)
			(xy 419.934071 -407.846027) (xy 419.972018 -407.901613) (xy 420.00305 -407.961336) (xy 420.026722 -408.02434)
			(xy 420.042694 -408.089721) (xy 420.050739 -408.156542) (xy 420.050739 -408.223846) (xy 420.042697 -408.290667)
			(xy 420.026725 -408.356049) (xy 420.003055 -408.419053) (xy 419.972024 -408.478776) (xy 419.934078 -408.534363)
			(xy 419.912292 -408.560016) (xy 419.906505 -408.567168) (xy 419.899985 -408.584353) (xy 419.899592 -408.593544)
			(xy 419.899592 -409.086812) (xy 419.899998 -409.096) (xy 419.906515 -409.113184) (xy 419.912292 -409.12034)
			(xy 419.934043 -409.146022) (xy 419.971991 -409.201605) (xy 420.003024 -409.261324) (xy 420.026698 -409.324325)
			(xy 420.042672 -409.389703) (xy 420.050719 -409.456522) (xy 420.050722 -409.523824) (xy 420.042682 -409.590643)
			(xy 420.026714 -409.656023) (xy 420.003047 -409.719026) (xy 419.972019 -409.778749) (xy 419.934077 -409.834336)
			(xy 419.912292 -409.859988) (xy 419.906475 -409.867118) (xy 419.899973 -409.88432) (xy 419.899592 -409.893516)
			(xy 419.899592 -410.051504) (xy 419.899181 -410.061659) (xy 419.891383 -410.080413) (xy 419.876983 -410.094737)
			(xy 419.858187 -410.102435) (xy 419.84803 -410.102812) (xy 419.13175 -410.102812) (xy 419.121633 -410.102234)
			(xy 419.102923 -410.094532) (xy 419.088567 -410.080274) (xy 419.080736 -410.061618) (xy 419.080188 -410.051504)
			(xy 419.080188 -409.893516) (xy 419.079773 -409.884329) (xy 419.073263 -409.867145) (xy 419.067488 -409.859988)
			(xy 419.045663 -409.834366) (xy 419.007713 -409.778776) (xy 418.976678 -409.719049) (xy 418.953005 -409.65604)
			(xy 418.937033 -409.590654) (xy 418.928991 -409.523827) (xy 414.525968 -409.523827) (xy 414.525968 -410.623701)
			(xy 421.128637 -410.623701) (xy 421.128638 -410.556275) (xy 421.136716 -410.489335) (xy 421.152755 -410.423845)
			(xy 421.176522 -410.360747) (xy 421.207677 -410.300951) (xy 421.24577 -410.245317) (xy 421.267636 -410.219652)
			(xy 421.27344 -410.212512) (xy 421.279949 -410.195317) (xy 421.280336 -410.186124) (xy 421.280336 -409.693872)
			(xy 421.279931 -409.684684) (xy 421.273413 -409.667501) (xy 421.267636 -409.660344) (xy 421.245783 -409.63467)
			(xy 421.207691 -409.579037) (xy 421.176538 -409.519243) (xy 421.152771 -409.456147) (xy 421.136734 -409.390659)
			(xy 421.128657 -409.323721) (xy 421.128656 -409.256297) (xy 421.136731 -409.189359) (xy 421.152766 -409.12387)
			(xy 421.176531 -409.060774) (xy 421.207682 -409.000978) (xy 421.245771 -408.945345) (xy 421.267636 -408.91968)
			(xy 421.273428 -408.912532) (xy 421.279945 -408.895343) (xy 421.280336 -408.886152) (xy 421.280336 -408.728672)
			(xy 421.280694 -408.718543) (xy 421.288458 -408.699832) (xy 421.302793 -408.685517) (xy 421.321515 -408.67778)
			(xy 421.331644 -408.677364) (xy 422.047924 -408.677364) (xy 422.05803 -408.677864) (xy 422.076702 -408.685603)
			(xy 422.090994 -408.699895) (xy 422.098735 -408.718566) (xy 422.099232 -408.728672) (xy 422.099232 -408.886152)
			(xy 422.09968 -408.895335) (xy 422.106169 -408.912519) (xy 422.111932 -408.91968) (xy 422.133807 -408.945336)
			(xy 422.171893 -409.000973) (xy 422.203041 -409.06077) (xy 422.226803 -409.123868) (xy 422.242837 -409.189358)
			(xy 422.250911 -409.256297) (xy 422.25091 -409.323721) (xy 422.242834 -409.39066) (xy 422.226798 -409.456149)
			(xy 422.203034 -409.519246) (xy 422.200617 -409.523886) (xy 423.328784 -409.523886) (xy 423.328787 -409.45646)
			(xy 423.336866 -409.389519) (xy 423.352905 -409.324029) (xy 423.376672 -409.26093) (xy 423.407826 -409.201133)
			(xy 423.445918 -409.145498) (xy 423.467784 -409.119832) (xy 423.47359 -409.112693) (xy 423.4801 -409.095498)
			(xy 423.480484 -409.086304) (xy 423.480484 -408.594052) (xy 423.480052 -408.584867) (xy 423.473554 -408.567682)
			(xy 423.467784 -408.560524) (xy 423.445913 -408.534865) (xy 423.407825 -408.479229) (xy 423.376676 -408.419432)
			(xy 423.352913 -408.356334) (xy 423.336878 -408.290845) (xy 423.328803 -408.223906) (xy 423.328804 -408.156482)
			(xy 423.336881 -408.089543) (xy 423.352916 -408.024054) (xy 423.376681 -407.960957) (xy 423.407832 -407.901161)
			(xy 423.44592 -407.845526) (xy 423.467784 -407.81986) (xy 423.473578 -407.812713) (xy 423.480095 -407.795524)
			(xy 423.480484 -407.786332) (xy 423.480484 -407.628852) (xy 423.480946 -407.618742) (xy 423.488696 -407.600066)
			(xy 423.503 -407.585774) (xy 423.521682 -407.578038) (xy 423.531792 -407.577544) (xy 424.248072 -407.577544)
			(xy 424.258172 -407.578106) (xy 424.276839 -407.585825) (xy 424.291133 -407.600097) (xy 424.298879 -407.618753)
			(xy 424.29938 -407.628852) (xy 424.29938 -407.786332) (xy 424.299779 -407.79552) (xy 424.306301 -407.812704)
			(xy 424.31208 -407.81986) (xy 424.333937 -407.845531) (xy 424.372027 -407.901165) (xy 424.403179 -407.96096)
			(xy 424.426945 -408.024056) (xy 424.442981 -408.089544) (xy 424.451058 -408.156482) (xy 424.451059 -408.223906)
			(xy 424.442984 -408.290844) (xy 424.426948 -408.356333) (xy 424.403184 -408.419429) (xy 424.372033 -408.479225)
			(xy 424.333944 -408.534859) (xy 424.31208 -408.560524) (xy 424.306288 -408.567673) (xy 424.299771 -408.584861)
			(xy 424.29938 -408.594052) (xy 424.29938 -409.086304) (xy 424.299792 -409.095491) (xy 424.306305 -409.112675)
			(xy 424.31208 -409.119832) (xy 424.333909 -409.145526) (xy 424.372 -409.201156) (xy 424.403154 -409.260948)
			(xy 424.426921 -409.324041) (xy 424.442959 -409.389527) (xy 424.451039 -409.456462) (xy 424.451042 -409.523884)
			(xy 424.442969 -409.59082) (xy 424.426937 -409.656307) (xy 424.403176 -409.719403) (xy 424.372028 -409.779198)
			(xy 424.333943 -409.834831) (xy 424.31208 -409.860496) (xy 424.3063 -409.867653) (xy 424.299776 -409.884835)
			(xy 424.29938 -409.894024) (xy 424.29938 -410.051504) (xy 424.298987 -410.061629) (xy 424.291234 -410.080337)
			(xy 424.27691 -410.094651) (xy 424.258197 -410.102393) (xy 424.248072 -410.102812) (xy 423.531792 -410.102812)
			(xy 423.521684 -410.102322) (xy 423.503008 -410.094584) (xy 423.488714 -410.080288) (xy 423.480978 -410.061612)
			(xy 423.480484 -410.051504) (xy 423.480484 -409.894024) (xy 423.480066 -409.884838) (xy 423.473558 -409.867653)
			(xy 423.467784 -409.860496) (xy 423.445885 -409.83486) (xy 423.407799 -409.779221) (xy 423.37665 -409.71942)
			(xy 423.352889 -409.65632) (xy 423.336856 -409.590827) (xy 423.328784 -409.523886) (xy 422.200617 -409.523886)
			(xy 422.171884 -409.579043) (xy 422.133796 -409.634678) (xy 422.111932 -409.660344) (xy 422.106126 -409.667482)
			(xy 422.099619 -409.684678) (xy 422.099232 -409.693872) (xy 422.099232 -410.186124) (xy 422.099646 -410.19531)
			(xy 422.106159 -410.212494) (xy 422.111932 -410.219652) (xy 422.133779 -410.245331) (xy 422.171866 -410.300964)
			(xy 422.203016 -410.360759) (xy 422.22678 -410.423854) (xy 422.242815 -410.489341) (xy 422.250892 -410.556277)
			(xy 422.250893 -410.623641) (xy 425.528957 -410.623641) (xy 425.528958 -410.556335) (xy 425.537003 -410.489512)
			(xy 425.552978 -410.424129) (xy 425.576652 -410.361123) (xy 425.607686 -410.301399) (xy 425.645636 -410.245812)
			(xy 425.667424 -410.22016) (xy 425.673223 -410.213017) (xy 425.679735 -410.195825) (xy 425.680124 -410.186632)
			(xy 425.680124 -409.693364) (xy 425.679726 -409.684176) (xy 425.673203 -409.666992) (xy 425.667424 -409.659836)
			(xy 425.645648 -409.634174) (xy 425.6077 -409.578589) (xy 425.576667 -409.518866) (xy 425.552994 -409.455863)
			(xy 425.537021 -409.390482) (xy 425.528976 -409.323661) (xy 425.528975 -409.256357) (xy 425.537018 -409.189536)
			(xy 425.552989 -409.124154) (xy 425.57666 -409.06115) (xy 425.607691 -409.001427) (xy 425.645637 -408.94584)
			(xy 425.667424 -408.920188) (xy 425.673211 -408.913036) (xy 425.679731 -408.895851) (xy 425.680124 -408.88666)
			(xy 425.680124 -408.728672) (xy 425.680499 -408.718513) (xy 425.688308 -408.699755) (xy 425.70272 -408.685432)
			(xy 425.721525 -408.677738) (xy 425.731686 -408.677364) (xy 426.447966 -408.677364) (xy 426.458093 -408.677855)
			(xy 426.476818 -408.685576) (xy 426.491177 -408.699862) (xy 426.498993 -408.718547) (xy 426.499528 -408.728672)
			(xy 426.499528 -408.88666) (xy 426.499951 -408.895846) (xy 426.506455 -408.913031) (xy 426.512228 -408.920188)
			(xy 426.534028 -408.94583) (xy 426.571979 -409.001417) (xy 426.603014 -409.061142) (xy 426.626687 -409.124148)
			(xy 426.64266 -409.189532) (xy 426.650704 -409.256356) (xy 426.650703 -409.323662) (xy 426.642657 -409.390486)
			(xy 426.626682 -409.45587) (xy 426.603006 -409.518875) (xy 426.600433 -409.523827) (xy 427.729079 -409.523827)
			(xy 427.729082 -409.456519) (xy 427.73713 -409.389693) (xy 427.753108 -409.324308) (xy 427.776786 -409.261302)
			(xy 427.807826 -409.201578) (xy 427.845781 -409.145992) (xy 427.867572 -409.12034) (xy 427.873385 -409.113207)
			(xy 427.879888 -409.096007) (xy 427.880272 -409.086812) (xy 427.880272 -408.593544) (xy 427.879847 -408.584358)
			(xy 427.873344 -408.567174) (xy 427.867572 -408.560016) (xy 427.845776 -408.534371) (xy 427.807825 -408.478784)
			(xy 427.77679 -408.41906) (xy 427.753116 -408.356054) (xy 427.737143 -408.290671) (xy 427.729099 -408.223847)
			(xy 427.7291 -408.156541) (xy 427.737145 -408.089717) (xy 427.75312 -408.024334) (xy 427.776795 -407.961329)
			(xy 427.807831 -407.901606) (xy 427.845783 -407.84602) (xy 427.867572 -407.820368) (xy 427.873373 -407.813227)
			(xy 427.879883 -407.796033) (xy 427.880272 -407.78684) (xy 427.880272 -407.628852) (xy 427.880682 -407.618698)
			(xy 427.888488 -407.59995) (xy 427.902887 -407.58563) (xy 427.921678 -407.577927) (xy 427.931834 -407.577544)
			(xy 428.648114 -407.577544) (xy 428.658242 -407.578015) (xy 428.676964 -407.585749) (xy 428.69132 -407.600039)
			(xy 428.699138 -407.618726) (xy 428.699676 -407.628852) (xy 428.699676 -407.78684) (xy 428.700072 -407.796029)
			(xy 428.706596 -407.813212) (xy 428.712376 -407.820368) (xy 428.734155 -407.846027) (xy 428.772104 -407.901613)
			(xy 428.803136 -407.961335) (xy 428.826809 -408.024339) (xy 428.842782 -408.08972) (xy 428.850827 -408.156542)
			(xy 428.850827 -408.223846) (xy 428.842784 -408.290668) (xy 428.826813 -408.356049) (xy 428.803141 -408.419054)
			(xy 428.77211 -408.478777) (xy 428.734163 -408.534364) (xy 428.712376 -408.560016) (xy 428.706587 -408.567167)
			(xy 428.700069 -408.584353) (xy 428.699676 -408.593544) (xy 428.699676 -409.086812) (xy 428.700086 -409.095999)
			(xy 428.7066 -409.113183) (xy 428.712376 -409.12034) (xy 428.734128 -409.146022) (xy 428.772077 -409.201604)
			(xy 428.803111 -409.261324) (xy 428.826785 -409.324324) (xy 428.84276 -409.389703) (xy 428.850806 -409.456522)
			(xy 428.85081 -409.523824) (xy 428.842769 -409.590644) (xy 428.826801 -409.656024) (xy 428.803133 -409.719027)
			(xy 428.772104 -409.778749) (xy 428.734161 -409.834335) (xy 428.712376 -409.859988) (xy 428.706557 -409.867117)
			(xy 428.700056 -409.88432) (xy 428.699676 -409.893516) (xy 428.699676 -410.051504) (xy 428.699281 -410.061661)
			(xy 428.69148 -410.080418) (xy 428.677074 -410.094742) (xy 428.658274 -410.102438) (xy 428.648114 -410.102812)
			(xy 427.931834 -410.102812) (xy 427.921716 -410.102247) (xy 427.903005 -410.09454) (xy 427.88865 -410.080278)
			(xy 427.88082 -410.061619) (xy 427.880272 -410.051504) (xy 427.880272 -409.893516) (xy 427.879861 -409.884329)
			(xy 427.873349 -409.867144) (xy 427.867572 -409.859988) (xy 427.845748 -409.834366) (xy 427.807798 -409.778776)
			(xy 427.776764 -409.719048) (xy 427.753092 -409.65604) (xy 427.73712 -409.590654) (xy 427.729079 -409.523827)
			(xy 426.600433 -409.523827) (xy 426.57197 -409.578598) (xy 426.534017 -409.634184) (xy 426.512228 -409.659836)
			(xy 426.506425 -409.666976) (xy 426.499916 -409.684171) (xy 426.499528 -409.693364) (xy 426.499528 -410.186632)
			(xy 426.499917 -410.195822) (xy 426.506445 -410.213006) (xy 426.512228 -410.22016) (xy 426.534001 -410.245825)
			(xy 426.571952 -410.301409) (xy 426.602988 -410.36113) (xy 426.626663 -410.424133) (xy 426.642638 -410.489514)
			(xy 426.650684 -410.556336) (xy 426.650686 -410.62364) (xy 426.650679 -410.623701) (xy 429.928725 -410.623701)
			(xy 429.928726 -410.556275) (xy 429.936804 -410.489336) (xy 429.952842 -410.423845) (xy 429.976609 -410.360748)
			(xy 430.007762 -410.300951) (xy 430.045854 -410.245317) (xy 430.06772 -410.219652) (xy 430.073522 -410.212511)
			(xy 430.080033 -410.195317) (xy 430.08042 -410.186124) (xy 430.08042 -409.693872) (xy 430.080019 -409.684684)
			(xy 430.073498 -409.6675) (xy 430.06772 -409.660344) (xy 430.045867 -409.634669) (xy 430.007777 -409.579037)
			(xy 429.976624 -409.519242) (xy 429.952859 -409.456146) (xy 429.936822 -409.390658) (xy 429.928745 -409.323721)
			(xy 429.928744 -409.256297) (xy 429.936819 -409.18936) (xy 429.952853 -409.123871) (xy 429.976617 -409.060775)
			(xy 430.007767 -409.000979) (xy 430.045856 -408.945345) (xy 430.06772 -408.91968) (xy 430.07351 -408.91253)
			(xy 430.080028 -408.895343) (xy 430.08042 -408.886152) (xy 430.08042 -408.728672) (xy 430.080863 -408.718559)
			(xy 430.088613 -408.699876) (xy 430.102923 -408.685582) (xy 430.121614 -408.677852) (xy 430.131728 -408.677364)
			(xy 430.848008 -408.677364) (xy 430.858113 -408.677878) (xy 430.876784 -408.685611) (xy 430.891077 -408.699899)
			(xy 430.898818 -408.718567) (xy 430.899316 -408.728672) (xy 430.899316 -408.886152) (xy 430.899745 -408.895337)
			(xy 430.906245 -408.912522) (xy 430.912016 -408.91968) (xy 430.933891 -408.945336) (xy 430.971979 -409.000972)
			(xy 431.003128 -409.06077) (xy 431.026891 -409.123868) (xy 431.042925 -409.189358) (xy 431.050999 -409.256297)
			(xy 431.050998 -409.323721) (xy 431.042922 -409.39066) (xy 431.026885 -409.456149) (xy 431.00312 -409.519247)
			(xy 431.000734 -409.523827) (xy 432.12887 -409.523827) (xy 432.128873 -409.456519) (xy 432.136921 -409.389693)
			(xy 432.152898 -409.324309) (xy 432.176576 -409.261303) (xy 432.207615 -409.201578) (xy 432.245569 -409.145992)
			(xy 432.26736 -409.12034) (xy 432.273172 -409.113206) (xy 432.279676 -409.096007) (xy 432.28006 -409.086812)
			(xy 432.28006 -408.593544) (xy 432.279615 -408.584361) (xy 432.273124 -408.567177) (xy 432.26736 -408.560016)
			(xy 432.245564 -408.53437) (xy 432.207614 -408.478784) (xy 432.17658 -408.419059) (xy 432.152907 -408.356054)
			(xy 432.136934 -408.290671) (xy 432.12889 -408.223847) (xy 432.128891 -408.156541) (xy 432.136936 -408.089717)
			(xy 432.15291 -408.024335) (xy 432.176585 -407.96133) (xy 432.20762 -407.901606) (xy 432.245571 -407.84602)
			(xy 432.26736 -407.820368) (xy 432.27316 -407.813226) (xy 432.279671 -407.796033) (xy 432.28006 -407.78684)
			(xy 432.28006 -407.628852) (xy 432.280482 -407.6187) (xy 432.288286 -407.599954) (xy 432.302681 -407.585634)
			(xy 432.321468 -407.577929) (xy 432.331622 -407.577544) (xy 433.047902 -407.577544) (xy 433.058029 -407.578025)
			(xy 433.076751 -407.585754) (xy 433.091108 -407.600042) (xy 433.098926 -407.618727) (xy 433.099464 -407.628852)
			(xy 433.099464 -407.78684) (xy 433.099863 -407.796028) (xy 433.106385 -407.813212) (xy 433.112164 -407.820368)
			(xy 433.133944 -407.846027) (xy 433.171893 -407.901612) (xy 433.202926 -407.961335) (xy 433.226599 -408.024339)
			(xy 433.242573 -408.08972) (xy 433.250618 -408.156542) (xy 433.250618 -408.223846) (xy 433.242575 -408.290668)
			(xy 433.226603 -408.35605) (xy 433.202931 -408.419054) (xy 433.171899 -408.478778) (xy 433.133951 -408.534364)
			(xy 433.112164 -408.560016) (xy 433.106374 -408.567165) (xy 433.099856 -408.584353) (xy 433.099464 -408.593544)
			(xy 433.099464 -409.086812) (xy 433.099876 -409.095999) (xy 433.106389 -409.113183) (xy 433.112164 -409.12034)
			(xy 433.133916 -409.146021) (xy 433.171866 -409.201604) (xy 433.2029 -409.261323) (xy 433.226575 -409.324324)
			(xy 433.24255 -409.389703) (xy 433.250597 -409.456522) (xy 433.250601 -409.523824) (xy 433.24256 -409.590644)
			(xy 433.226591 -409.656024) (xy 433.202922 -409.719027) (xy 433.171894 -409.77875) (xy 433.133949 -409.834336)
			(xy 433.112164 -409.859988) (xy 433.106343 -409.867116) (xy 433.099844 -409.88432) (xy 433.099464 -409.893516)
			(xy 433.099464 -410.051504) (xy 433.099081 -410.061663) (xy 433.091277 -410.080422) (xy 433.076868 -410.094747)
			(xy 433.058063 -410.10244) (xy 433.047902 -410.102812) (xy 432.331622 -410.102812) (xy 432.321503 -410.102257)
			(xy 432.302792 -410.094546) (xy 432.288437 -410.080281) (xy 432.280608 -410.06162) (xy 432.28006 -410.051504)
			(xy 432.28006 -409.893516) (xy 432.279629 -409.884331) (xy 432.273128 -409.867147) (xy 432.26736 -409.859988)
			(xy 432.245536 -409.834365) (xy 432.207587 -409.778775) (xy 432.176554 -409.719048) (xy 432.152882 -409.656039)
			(xy 432.136911 -409.590653) (xy 432.12887 -409.523827) (xy 431.000734 -409.523827) (xy 430.971969 -409.579043)
			(xy 430.93388 -409.634678) (xy 430.912016 -409.660344) (xy 430.90622 -409.66749) (xy 430.899705 -409.68468)
			(xy 430.899316 -409.693872) (xy 430.899316 -410.186124) (xy 430.899711 -410.195313) (xy 430.906235 -410.212497)
			(xy 430.912016 -410.219652) (xy 430.933864 -410.24533) (xy 430.971952 -410.300963) (xy 431.003102 -410.360758)
			(xy 431.026867 -410.423853) (xy 431.042903 -410.48934) (xy 431.05098 -410.556277) (xy 431.050981 -410.623641)
			(xy 434.329044 -410.623641) (xy 434.329046 -410.556335) (xy 434.337091 -410.489512) (xy 434.353065 -410.424129)
			(xy 434.376738 -410.361124) (xy 434.407772 -410.3014) (xy 434.44572 -410.245813) (xy 434.467508 -410.22016)
			(xy 434.473305 -410.213015) (xy 434.479819 -410.195824) (xy 434.480208 -410.186632) (xy 434.480208 -409.693364)
			(xy 434.479814 -409.684175) (xy 434.473289 -409.666991) (xy 434.467508 -409.659836) (xy 434.445733 -409.634174)
			(xy 434.407786 -409.578588) (xy 434.376754 -409.518866) (xy 434.353082 -409.455862) (xy 434.337109 -409.390482)
			(xy 434.329064 -409.323661) (xy 434.329063 -409.256357) (xy 434.337106 -409.189536) (xy 434.353076 -409.124155)
			(xy 434.376746 -409.061151) (xy 434.407777 -409.001427) (xy 434.445722 -408.945841) (xy 434.467508 -408.920188)
			(xy 434.473293 -408.913035) (xy 434.479814 -408.89585) (xy 434.480208 -408.88666) (xy 434.480208 -408.728672)
			(xy 434.480599 -408.718515) (xy 434.488405 -408.69976) (xy 434.502811 -408.685438) (xy 434.521611 -408.67774)
			(xy 434.53177 -408.677364) (xy 435.24805 -408.677364) (xy 435.258176 -408.677868) (xy 435.276901 -408.685584)
			(xy 435.29126 -408.699866) (xy 435.299077 -408.718548) (xy 435.299612 -408.728672) (xy 435.299612 -408.88666)
			(xy 435.300039 -408.895846) (xy 435.30654 -408.91303) (xy 435.312312 -408.920188) (xy 435.334113 -408.94583)
			(xy 435.372065 -409.001417) (xy 435.4031 -409.061141) (xy 435.426774 -409.124147) (xy 435.442748 -409.189531)
			(xy 435.450792 -409.256356) (xy 435.450791 -409.323662) (xy 435.442745 -409.390487) (xy 435.426769 -409.45587)
			(xy 435.403093 -409.518875) (xy 435.372055 -409.578599) (xy 435.334102 -409.634184) (xy 435.312312 -409.659836)
			(xy 435.306519 -409.666984) (xy 435.300002 -409.684172) (xy 435.299612 -409.693364) (xy 435.299612 -410.186632)
			(xy 435.300004 -410.195821) (xy 435.30653 -410.213006) (xy 435.312312 -410.22016) (xy 435.334085 -410.245824)
			(xy 435.372038 -410.301408) (xy 435.403075 -410.361129) (xy 435.42675 -410.424132) (xy 435.442726 -410.489514)
			(xy 435.450772 -410.556336) (xy 435.450774 -410.62364) (xy 435.44273 -410.690463) (xy 435.426758 -410.755845)
			(xy 435.403084 -410.818849) (xy 435.37205 -410.878571) (xy 435.3341 -410.934157) (xy 435.312312 -410.959808)
			(xy 435.306531 -410.966964) (xy 435.300007 -410.984146) (xy 435.299612 -410.993336) (xy 435.299612 -411.151324)
			(xy 435.299198 -411.161478) (xy 435.291397 -411.180229) (xy 435.276998 -411.194551) (xy 435.258206 -411.202252)
			(xy 435.24805 -411.202632) (xy 434.53177 -411.202632) (xy 434.521638 -411.202197) (xy 434.502911 -411.194454)
			(xy 434.488554 -411.180152) (xy 434.480741 -411.161454) (xy 434.480208 -411.151324) (xy 434.480208 -410.993336)
			(xy 434.479779 -410.984151) (xy 434.473278 -410.966966) (xy 434.467508 -410.959808) (xy 434.445706 -410.934168)
			(xy 434.407759 -410.878579) (xy 434.376728 -410.818854) (xy 434.353058 -410.755848) (xy 434.337087 -410.690464)
			(xy 434.329044 -410.623641) (xy 431.050981 -410.623641) (xy 431.050981 -410.623699) (xy 431.042907 -410.690636)
			(xy 431.026874 -410.756124) (xy 431.003112 -410.81922) (xy 430.971964 -410.879016) (xy 430.933878 -410.934651)
			(xy 430.912016 -410.960316) (xy 430.906232 -410.96747) (xy 430.899709 -410.984654) (xy 430.899316 -410.993844)
			(xy 430.899316 -411.151324) (xy 430.898835 -411.161432) (xy 430.891092 -411.180108) (xy 430.876795 -411.194401)
			(xy 430.858116 -411.202138) (xy 430.848008 -411.202632) (xy 430.131728 -411.202632) (xy 430.121611 -411.202162)
			(xy 430.102914 -411.194429) (xy 430.0886 -411.180129) (xy 430.080848 -411.16144) (xy 430.08042 -411.151324)
			(xy 430.08042 -410.993844) (xy 430.079984 -410.98466) (xy 430.073488 -410.967475) (xy 430.06772 -410.960316)
			(xy 430.04584 -410.934664) (xy 430.00775 -410.879028) (xy 429.976599 -410.81923) (xy 429.952835 -410.756132)
			(xy 429.9368 -410.690641) (xy 429.928725 -410.623701) (xy 426.650679 -410.623701) (xy 426.642643 -410.690462)
			(xy 426.62667 -410.755844) (xy 426.602998 -410.818848) (xy 426.571965 -410.878571) (xy 426.534016 -410.934156)
			(xy 426.512228 -410.959808) (xy 426.506437 -410.966957) (xy 426.499921 -410.984145) (xy 426.499528 -410.993336)
			(xy 426.499528 -411.151324) (xy 426.499099 -411.161476) (xy 426.4913 -411.180224) (xy 426.476907 -411.194545)
			(xy 426.45812 -411.202249) (xy 426.447966 -411.202632) (xy 425.731686 -411.202632) (xy 425.721555 -411.202184)
			(xy 425.702828 -411.194446) (xy 425.688472 -411.180148) (xy 425.680658 -411.161453) (xy 425.680124 -411.151324)
			(xy 425.680124 -410.993336) (xy 425.679691 -410.984151) (xy 425.673193 -410.966967) (xy 425.667424 -410.959808)
			(xy 425.645621 -410.934169) (xy 425.607674 -410.87858) (xy 425.576642 -410.818855) (xy 425.552971 -410.755848)
			(xy 425.536999 -410.690465) (xy 425.528957 -410.623641) (xy 422.250893 -410.623641) (xy 422.250893 -410.623699)
			(xy 422.242819 -410.690635) (xy 422.226787 -410.756123) (xy 422.203026 -410.819219) (xy 422.171879 -410.879015)
			(xy 422.133794 -410.93465) (xy 422.111932 -410.960316) (xy 422.106138 -410.967463) (xy 422.099624 -410.984652)
			(xy 422.099232 -410.993844) (xy 422.099232 -411.151324) (xy 422.098735 -411.16143) (xy 422.090996 -411.180103)
			(xy 422.076703 -411.194396) (xy 422.05803 -411.202135) (xy 422.047924 -411.202632) (xy 421.331644 -411.202632)
			(xy 421.321528 -411.202149) (xy 421.302832 -411.194421) (xy 421.288517 -411.180125) (xy 421.280765 -411.161439)
			(xy 421.280336 -411.151324) (xy 421.280336 -410.993844) (xy 421.279896 -410.98466) (xy 421.273402 -410.967476)
			(xy 421.267636 -410.960316) (xy 421.245755 -410.934664) (xy 421.207664 -410.879029) (xy 421.176512 -410.819231)
			(xy 421.152748 -410.756132) (xy 421.136712 -410.690641) (xy 421.128637 -410.623701) (xy 414.525968 -410.623701)
			(xy 414.525968 -417.366196) (xy 414.52546 -417.366196) (xy 414.52546 -417.533836) (xy 414.525117 -417.545925)
			(xy 414.517634 -417.568917) (xy 414.503411 -417.588471) (xy 414.483842 -417.602672) (xy 414.460842 -417.61013)
			(xy 414.448752 -417.610544) (xy 401.15109 -417.610544) (xy 401.138998 -417.610101) (xy 401.115995 -417.602639)
			(xy 401.096414 -417.588447) (xy 401.082164 -417.568908) (xy 401.074635 -417.545926) (xy 401.074128 -417.533836)
			(xy 326.525636 -417.533836) (xy 326.525172 -417.545885) (xy 326.517733 -417.568805) (xy 326.503592 -417.588317)
			(xy 326.484126 -417.602521) (xy 326.461229 -417.610032) (xy 326.449182 -417.610544) (xy 313.151012 -417.610544)
			(xy 313.138942 -417.610026) (xy 313.115981 -417.602571) (xy 313.096447 -417.588387) (xy 313.082251 -417.568862)
			(xy 313.074781 -417.545906) (xy 313.074304 -417.533836) (xy 313.074304 -417.379404) (xy 313.073796 -417.379404)
			(xy 273.434939 -417.379404) (xy 273.506495 -417.442585) (xy 273.605798 -417.540617) (xy 273.652996 -417.592002)
			(xy 273.691387 -417.633573) (xy 273.773525 -417.71142) (xy 273.861325 -417.782821) (xy 273.954282 -417.847364)
			(xy 274.051862 -417.90468) (xy 274.153504 -417.954438) (xy 274.258623 -417.996352) (xy 274.366616 -418.030181)
			(xy 274.476862 -418.055732) (xy 274.588726 -418.072856) (xy 274.701566 -418.081457) (xy 274.75815 -418.081968)
			(xy 465.600034 -418.081968) (xy 465.65584 -418.081445) (xy 465.767139 -418.073102) (xy 465.877504 -418.056464)
			(xy 465.986317 -418.031626) (xy 466.092969 -417.998726) (xy 466.196865 -417.957947) (xy 466.297422 -417.909518)
			(xy 466.39408 -417.85371) (xy 466.486296 -417.790835) (xy 466.573556 -417.721245) (xy 466.655372 -417.645328)
			(xy 466.731285 -417.563509) (xy 466.800872 -417.476246) (xy 466.863743 -417.384027) (xy 466.919547 -417.287367)
			(xy 466.967972 -417.186808) (xy 467.008746 -417.082911) (xy 467.041642 -416.976257) (xy 467.066476 -416.867443)
			(xy 467.083109 -416.757078) (xy 467.091447 -416.645778) (xy 467.09203 -416.589972) (xy 467.09203 -246.48795)
			(xy 467.091546 -246.4347) (xy 467.083933 -246.328473) (xy 467.068764 -246.223059) (xy 467.046116 -246.118995)
			(xy 467.016104 -246.016811) (xy 466.978881 -245.917028) (xy 466.934637 -245.820154) (xy 466.883597 -245.726681)
			(xy 466.82602 -245.637087) (xy 466.762201 -245.551827) (xy 466.692464 -245.471335) (xy 466.65515 -245.433342)
			(xy 464.026504 -242.80495) (xy 463.9771 -242.754859) (xy 463.883341 -242.649941) (xy 463.795613 -242.53993)
			(xy 463.714192 -242.425173) (xy 463.639333 -242.306031) (xy 463.571273 -242.182879) (xy 463.510225 -242.056105)
			(xy 463.456381 -241.926107) (xy 463.409911 -241.793295) (xy 463.370962 -241.658086) (xy 463.339655 -241.520905)
			(xy 463.31609 -241.382185) (xy 463.300339 -241.242362) (xy 463.292454 -241.101876) (xy 463.291936 -241.031522)
			(xy 463.291936 -87.588344) (xy 463.292417 -87.517998) (xy 463.3003 -87.377526) (xy 463.316048 -87.237717)
			(xy 463.339614 -87.099011) (xy 463.370921 -86.961846) (xy 463.409872 -86.826652) (xy 463.456344 -86.693856)
			(xy 463.510191 -86.563875) (xy 463.571243 -86.437119) (xy 463.639308 -86.313987) (xy 463.714172 -86.194865)
			(xy 463.7956 -86.08013) (xy 463.883333 -85.970143) (xy 463.977098 -85.865249) (xy 464.026504 -85.81517)
			(xy 466.65515 -83.186524) (xy 466.692477 -83.148543) (xy 466.762224 -83.068056) (xy 466.826051 -82.982799)
			(xy 466.883632 -82.893206) (xy 466.934676 -82.799733) (xy 466.978921 -82.702856) (xy 467.016141 -82.60307)
			(xy 467.046149 -82.500883) (xy 467.068789 -82.396815) (xy 467.083947 -82.291397) (xy 467.091547 -82.185167)
			(xy 467.09203 -82.131916) (xy 467.09203 -1.999996) (xy 467.091508 -1.944189) (xy 467.083167 -1.832886)
			(xy 467.066532 -1.722518) (xy 467.041695 -1.613701) (xy 467.008796 -1.507045) (xy 466.968019 -1.403146)
			(xy 466.919592 -1.302584) (xy 466.863785 -1.205923) (xy 466.800911 -1.113702) (xy 466.731321 -1.026437)
			(xy 466.655404 -0.944617) (xy 466.573586 -0.868699) (xy 466.486322 -0.799107) (xy 466.394103 -0.736231)
			(xy 466.297442 -0.680422) (xy 466.196882 -0.631993) (xy 466.092983 -0.591214) (xy 465.986328 -0.558313)
			(xy 465.877512 -0.533474) (xy 465.767144 -0.516836) (xy 465.655841 -0.508493) (xy 465.600034 -0.508)
			(xy 446.265046 -0.508) (xy 446.209237 -0.508508) (xy 446.097932 -0.516845) (xy 445.987561 -0.533478)
			(xy 445.878741 -0.558312) (xy 445.772082 -0.591209) (xy 445.668179 -0.631985) (xy 445.567615 -0.680412)
			(xy 445.47095 -0.736218) (xy 445.378726 -0.799093) (xy 445.291459 -0.868683) (xy 445.209636 -0.944601)
			(xy 445.133716 -1.026421) (xy 445.064123 -1.113686) (xy 445.001245 -1.205908) (xy 444.945435 -1.30257)
			(xy 444.897005 -1.403134) (xy 444.856226 -1.507035) (xy 444.823325 -1.613693) (xy 444.798487 -1.722512)
			(xy 444.781851 -1.832882) (xy 444.773509 -1.944187) (xy 444.77305 -1.999996) (xy 444.77305 -11.850116)
			(xy 444.77258 -11.903957) (xy 444.764897 -12.011363) (xy 444.749571 -12.117948) (xy 444.726681 -12.223168)
			(xy 444.696342 -12.326487) (xy 444.65871 -12.427378) (xy 444.613976 -12.525327) (xy 444.562368 -12.619836)
			(xy 444.504149 -12.710422) (xy 444.439617 -12.796624) (xy 444.369099 -12.878002) (xy 444.292955 -12.954143)
			(xy 444.211574 -13.024657) (xy 444.125369 -13.089186) (xy 444.034781 -13.147401) (xy 443.94027 -13.199004)
			(xy 443.842319 -13.243734) (xy 443.741426 -13.281362) (xy 443.638106 -13.311696) (xy 443.532885 -13.334583)
			(xy 443.4263 -13.349904) (xy 443.318893 -13.357583) (xy 443.265052 -13.358114) (xy 435.265068 -13.358114)
			(xy 435.211227 -13.357632) (xy 435.103821 -13.349948) (xy 434.997236 -13.334622) (xy 434.892016 -13.311731)
			(xy 434.788697 -13.281392) (xy 434.687806 -13.24376) (xy 434.589856 -13.199026) (xy 434.495347 -13.147419)
			(xy 434.40476 -13.089201) (xy 434.318558 -13.024669) (xy 434.237178 -12.954153) (xy 434.161036 -12.87801)
			(xy 434.090521 -12.79663) (xy 434.02599 -12.710426) (xy 433.967773 -12.619839) (xy 433.916167 -12.52533)
			(xy 433.871434 -12.42738) (xy 433.833803 -12.326488) (xy 433.803465 -12.223169) (xy 433.780576 -12.117948)
			(xy 433.76525 -12.011363) (xy 433.757567 -11.903957) (xy 433.75707 -11.850116) (xy 433.75707 -1.999996)
			(xy 433.756561 -1.944189) (xy 433.748219 -1.832887) (xy 433.731584 -1.72252) (xy 433.706747 -1.613704)
			(xy 433.673847 -1.507049) (xy 433.633069 -1.40315) (xy 433.584641 -1.30259) (xy 433.528833 -1.20593)
			(xy 433.465958 -1.11371) (xy 433.396367 -1.026448) (xy 433.320449 -0.944629) (xy 433.23863 -0.868713)
			(xy 433.151366 -0.799124) (xy 433.059145 -0.736251) (xy 432.962484 -0.680445) (xy 432.861922 -0.632019)
			(xy 432.758023 -0.591243) (xy 432.651367 -0.558346) (xy 432.542551 -0.533511) (xy 432.432183 -0.516877)
			(xy 432.320881 -0.508538) (xy 432.265074 -0.508) (xy 420.265098 -0.508) (xy 420.209291 -0.508522)
			(xy 420.097989 -0.516863) (xy 419.987622 -0.533498) (xy 419.878806 -0.558335) (xy 419.772151 -0.591234)
			(xy 419.668252 -0.632011) (xy 419.567691 -0.680438) (xy 419.471031 -0.736245) (xy 419.378811 -0.79912)
			(xy 419.291547 -0.86871) (xy 419.209728 -0.944627) (xy 419.133811 -1.026446) (xy 419.064221 -1.113709)
			(xy 419.001346 -1.205929) (xy 418.945539 -1.302589) (xy 418.897112 -1.40315) (xy 418.856334 -1.507049)
			(xy 418.823435 -1.613704) (xy 418.798599 -1.72252) (xy 418.781963 -1.832887) (xy 418.773622 -1.944189)
			(xy 418.773102 -1.999996) (xy 418.773102 -11.850116) (xy 418.772621 -11.903957) (xy 418.764938 -12.011364)
			(xy 418.749612 -12.117949) (xy 418.726722 -12.22317) (xy 418.696384 -12.326489) (xy 418.658752 -12.427381)
			(xy 418.614019 -12.525332) (xy 418.562412 -12.619841) (xy 418.504194 -12.710429) (xy 418.439663 -12.796632)
			(xy 418.369146 -12.878012) (xy 418.293003 -12.954154) (xy 418.211622 -13.02467) (xy 418.125419 -13.089201)
			(xy 418.034831 -13.147418) (xy 417.940321 -13.199024) (xy 417.84237 -13.243756) (xy 417.741478 -13.281387)
			(xy 417.638158 -13.311725) (xy 417.532938 -13.334614) (xy 417.426352 -13.349939) (xy 417.318945 -13.357621)
			(xy 417.265104 -13.358114) (xy 409.26512 -13.358114) (xy 409.211278 -13.357646) (xy 409.103868 -13.349965)
			(xy 408.997279 -13.334641) (xy 408.892055 -13.311753) (xy 408.788733 -13.281416) (xy 408.687837 -13.243785)
			(xy 408.589884 -13.199053) (xy 408.495371 -13.147446) (xy 408.40478 -13.089229) (xy 408.318573 -13.024697)
			(xy 408.23719 -12.95418) (xy 408.161045 -12.878036) (xy 408.090526 -12.796655) (xy 408.025992 -12.71045)
			(xy 407.967772 -12.61986) (xy 407.916164 -12.525349) (xy 407.871429 -12.427396) (xy 407.833796 -12.326502)
			(xy 407.803456 -12.223179) (xy 407.780565 -12.117956) (xy 407.765239 -12.011368) (xy 407.757556 -11.903958)
			(xy 407.757122 -11.850116) (xy 407.757122 -1.999996) (xy 407.7566 -1.944189) (xy 407.748259 -1.832886)
			(xy 407.731624 -1.722518) (xy 407.706787 -1.613702) (xy 407.673888 -1.507046) (xy 407.633111 -1.403147)
			(xy 407.584684 -1.302586) (xy 407.528877 -1.205924) (xy 407.466002 -1.113704) (xy 407.396412 -1.02644)
			(xy 407.320496 -0.94462) (xy 407.238677 -0.868702) (xy 407.151414 -0.799111) (xy 407.059194 -0.736235)
			(xy 406.962534 -0.680427) (xy 406.861973 -0.631998) (xy 406.758075 -0.591219) (xy 406.651419 -0.558319)
			(xy 406.542603 -0.53348) (xy 406.432236 -0.516843) (xy 406.320933 -0.508501) (xy 406.265126 -0.508)
			(xy 394.264896 -0.508) (xy 394.209089 -0.508522) (xy 394.097787 -0.516863) (xy 393.98742 -0.533498)
			(xy 393.878604 -0.558335) (xy 393.771949 -0.591234) (xy 393.668051 -0.632011) (xy 393.56749 -0.680439)
			(xy 393.470829 -0.736246) (xy 393.37861 -0.799121) (xy 393.291346 -0.868711) (xy 393.209528 -0.944628)
			(xy 393.133611 -1.026446) (xy 393.064021 -1.11371) (xy 393.001146 -1.205929) (xy 392.945339 -1.30259)
			(xy 392.896911 -1.403151) (xy 392.856134 -1.507049) (xy 392.823235 -1.613704) (xy 392.798398 -1.72252)
			(xy 392.781763 -1.832887) (xy 392.773422 -1.944189) (xy 392.7729 -1.999996) (xy 392.7729 -11.850116)
			(xy 392.772419 -11.903957) (xy 392.764736 -12.011364) (xy 392.74941 -12.117949) (xy 392.72652 -12.22317)
			(xy 392.696182 -12.326489) (xy 392.65855 -12.427381) (xy 392.613817 -12.525331) (xy 392.56221 -12.619841)
			(xy 392.503992 -12.710428) (xy 392.43946 -12.796631) (xy 392.368944 -12.878011) (xy 392.292801 -12.954153)
			(xy 392.21142 -13.024669) (xy 392.125217 -13.0892) (xy 392.034629 -13.147417) (xy 391.940119 -13.199023)
			(xy 391.842168 -13.243755) (xy 391.741276 -13.281386) (xy 391.637956 -13.311723) (xy 391.532735 -13.334613)
			(xy 391.42615 -13.349937) (xy 391.318743 -13.357619) (xy 391.264902 -13.358114) (xy 383.264918 -13.358114)
			(xy 383.211076 -13.357645) (xy 383.103666 -13.349965) (xy 382.997077 -13.334641) (xy 382.891854 -13.311752)
			(xy 382.788531 -13.281415) (xy 382.687636 -13.243785) (xy 382.589682 -13.199052) (xy 382.495169 -13.147445)
			(xy 382.404579 -13.089228) (xy 382.318373 -13.024696) (xy 382.236989 -12.954179) (xy 382.160844 -12.878035)
			(xy 382.090325 -12.796654) (xy 382.025791 -12.710449) (xy 381.967572 -12.61986) (xy 381.915963 -12.525348)
			(xy 381.871228 -12.427396) (xy 381.833596 -12.326501) (xy 381.803256 -12.223179) (xy 381.780365 -12.117956)
			(xy 381.765039 -12.011368) (xy 381.757356 -11.903958) (xy 381.75692 -11.850116) (xy 381.75692 -1.999996)
			(xy 381.756398 -1.944189) (xy 381.748057 -1.832886) (xy 381.731422 -1.722518) (xy 381.706585 -1.613702)
			(xy 381.673686 -1.507047) (xy 381.632909 -1.403147) (xy 381.584482 -1.302586) (xy 381.528675 -1.205925)
			(xy 381.4658 -1.113704) (xy 381.39621 -1.02644) (xy 381.320294 -0.944621) (xy 381.238475 -0.868703)
			(xy 381.151212 -0.799112) (xy 381.058992 -0.736236) (xy 380.962332 -0.680428) (xy 380.861771 -0.631999)
			(xy 380.757872 -0.59122) (xy 380.651217 -0.55832) (xy 380.542401 -0.533482) (xy 380.432034 -0.516845)
			(xy 380.320731 -0.508503) (xy 380.264924 -0.508) (xy 368.264948 -0.508) (xy 368.209139 -0.508507)
			(xy 368.097834 -0.516845) (xy 367.987463 -0.533478) (xy 367.878643 -0.558312) (xy 367.771984 -0.591209)
			(xy 367.668081 -0.631985) (xy 367.567516 -0.680411) (xy 367.470851 -0.736218) (xy 367.378627 -0.799092)
			(xy 367.29136 -0.868683) (xy 367.209537 -0.9446) (xy 367.133617 -1.02642) (xy 367.064023 -1.113685)
			(xy 367.001145 -1.205907) (xy 366.945336 -1.30257) (xy 366.896905 -1.403133) (xy 366.856126 -1.507034)
			(xy 366.823225 -1.613693) (xy 366.798387 -1.722511) (xy 366.781751 -1.832882) (xy 366.773409 -1.944187)
			(xy 366.772952 -1.999996) (xy 366.772952 -11.850116) (xy 366.772482 -11.903957) (xy 366.764799 -12.011363)
			(xy 366.749473 -12.117948) (xy 366.726583 -12.223168) (xy 366.696244 -12.326487) (xy 366.658612 -12.427378)
			(xy 366.613878 -12.525328) (xy 366.56227 -12.619836) (xy 366.504051 -12.710422) (xy 366.439519 -12.796624)
			(xy 366.369001 -12.878003) (xy 366.292858 -12.954143) (xy 366.211476 -13.024658) (xy 366.125271 -13.089187)
			(xy 366.034683 -13.147402) (xy 365.940172 -13.199005) (xy 365.842221 -13.243735) (xy 365.741328 -13.281363)
			(xy 365.638008 -13.311698) (xy 365.532787 -13.334584) (xy 365.426202 -13.349906) (xy 365.318795 -13.357584)
			(xy 365.264954 -13.358114) (xy 357.26497 -13.358114) (xy 357.211129 -13.357632) (xy 357.103723 -13.349948)
			(xy 356.997138 -13.334622) (xy 356.891918 -13.311731) (xy 356.788599 -13.281392) (xy 356.687707 -13.24376)
			(xy 356.589757 -13.199027) (xy 356.495248 -13.147419) (xy 356.404661 -13.089202) (xy 356.318459 -13.02467)
			(xy 356.237079 -12.954153) (xy 356.160937 -12.878011) (xy 356.090421 -12.796631) (xy 356.02589 -12.710427)
			(xy 355.967673 -12.61984) (xy 355.916067 -12.52533) (xy 355.871335 -12.42738) (xy 355.833703 -12.326488)
			(xy 355.803366 -12.223169) (xy 355.780476 -12.117949) (xy 355.76515 -12.011363) (xy 355.757467 -11.903957)
			(xy 355.756972 -11.850116) (xy 355.756972 -1.999996) (xy 355.756463 -1.944189) (xy 355.748121 -1.832887)
			(xy 355.731486 -1.722519) (xy 355.706649 -1.613704) (xy 355.673749 -1.507049) (xy 355.632971 -1.40315)
			(xy 355.584543 -1.30259) (xy 355.528735 -1.205929) (xy 355.46586 -1.11371) (xy 355.396269 -1.026447)
			(xy 355.320352 -0.944629) (xy 355.238532 -0.868713) (xy 355.151268 -0.799123) (xy 355.059047 -0.73625)
			(xy 354.962386 -0.680444) (xy 354.861824 -0.632017) (xy 354.757925 -0.591241) (xy 354.651269 -0.558344)
			(xy 354.542453 -0.533509) (xy 354.432085 -0.516876) (xy 354.320783 -0.508536) (xy 354.264976 -0.508)
			(xy 330.164948 -0.508) (xy 330.109139 -0.508507) (xy 329.997834 -0.516845) (xy 329.887463 -0.533478)
			(xy 329.778643 -0.558312) (xy 329.671984 -0.591209) (xy 329.568081 -0.631985) (xy 329.467516 -0.680411)
			(xy 329.370851 -0.736218) (xy 329.278627 -0.799092) (xy 329.19136 -0.868683) (xy 329.109537 -0.9446)
			(xy 329.033617 -1.02642) (xy 328.964023 -1.113685) (xy 328.901145 -1.205907) (xy 328.845336 -1.30257)
			(xy 328.796905 -1.403133) (xy 328.756126 -1.507034) (xy 328.723225 -1.613693) (xy 328.698387 -1.722511)
			(xy 328.681751 -1.832882) (xy 328.673409 -1.944187) (xy 328.672952 -1.999996) (xy 328.672952 -11.850116)
			(xy 328.672482 -11.903957) (xy 328.664799 -12.011363) (xy 328.649473 -12.117948) (xy 328.626583 -12.223168)
			(xy 328.596244 -12.326487) (xy 328.558612 -12.427378) (xy 328.513878 -12.525328) (xy 328.46227 -12.619836)
			(xy 328.404051 -12.710422) (xy 328.339519 -12.796624) (xy 328.269001 -12.878003) (xy 328.192858 -12.954143)
			(xy 328.111476 -13.024658) (xy 328.025271 -13.089187) (xy 327.934683 -13.147402) (xy 327.840172 -13.199005)
			(xy 327.742221 -13.243735) (xy 327.641328 -13.281363) (xy 327.538008 -13.311698) (xy 327.432787 -13.334584)
			(xy 327.326202 -13.349906) (xy 327.218795 -13.357584) (xy 327.164954 -13.358114) (xy 319.16497 -13.358114)
			(xy 319.111129 -13.357632) (xy 319.003723 -13.349948) (xy 318.897138 -13.334622) (xy 318.791918 -13.311731)
			(xy 318.688599 -13.281392) (xy 318.587707 -13.24376) (xy 318.489757 -13.199027) (xy 318.395248 -13.147419)
			(xy 318.304661 -13.089202) (xy 318.218459 -13.02467) (xy 318.137079 -12.954153) (xy 318.060937 -12.878011)
			(xy 317.990421 -12.796631) (xy 317.92589 -12.710427) (xy 317.867673 -12.61984) (xy 317.816067 -12.52533)
			(xy 317.771335 -12.42738) (xy 317.733703 -12.326488) (xy 317.703366 -12.223169) (xy 317.680476 -12.117949)
			(xy 317.66515 -12.011363) (xy 317.657467 -11.903957) (xy 317.656972 -11.850116) (xy 317.656972 -1.999996)
			(xy 317.656463 -1.944189) (xy 317.648121 -1.832887) (xy 317.631486 -1.722519) (xy 317.606649 -1.613704)
			(xy 317.573749 -1.507049) (xy 317.532971 -1.40315) (xy 317.484543 -1.30259) (xy 317.428735 -1.205929)
			(xy 317.36586 -1.11371) (xy 317.296269 -1.026447) (xy 317.220352 -0.944629) (xy 317.138532 -0.868713)
			(xy 317.051268 -0.799123) (xy 316.959047 -0.73625) (xy 316.862386 -0.680444) (xy 316.761824 -0.632017)
			(xy 316.657925 -0.591241) (xy 316.551269 -0.558344) (xy 316.442453 -0.533509) (xy 316.332085 -0.516876)
			(xy 316.220783 -0.508536) (xy 316.164976 -0.508) (xy 304.165 -0.508) (xy 304.109193 -0.508522) (xy 303.997891 -0.516863)
			(xy 303.887523 -0.533498) (xy 303.778708 -0.558334) (xy 303.672052 -0.591233) (xy 303.568153 -0.63201)
			(xy 303.467592 -0.680438) (xy 303.370932 -0.736245) (xy 303.278712 -0.799119) (xy 303.191448 -0.868709)
			(xy 303.109629 -0.944626) (xy 303.033712 -1.026445) (xy 302.964122 -1.113708) (xy 302.901247 -1.205928)
			(xy 302.84544 -1.302589) (xy 302.797012 -1.40315) (xy 302.756234 -1.507048) (xy 302.723335 -1.613704)
			(xy 302.698499 -1.722519) (xy 302.681863 -1.832887) (xy 302.673522 -1.944189) (xy 302.673004 -1.999996)
			(xy 302.673004 -11.850116) (xy 302.672523 -11.903957) (xy 302.66484 -12.011364) (xy 302.649514 -12.11795)
			(xy 302.626624 -12.22317) (xy 302.596286 -12.32649) (xy 302.558654 -12.427382) (xy 302.513921 -12.525332)
			(xy 302.462314 -12.619842) (xy 302.404096 -12.710429) (xy 302.339565 -12.796632) (xy 302.269048 -12.878012)
			(xy 302.192905 -12.954155) (xy 302.111525 -13.024671) (xy 302.025321 -13.089202) (xy 301.934733 -13.147419)
			(xy 301.840223 -13.199025) (xy 301.742272 -13.243758) (xy 301.64138 -13.281389) (xy 301.53806 -13.311726)
			(xy 301.43284 -13.334616) (xy 301.326254 -13.349941) (xy 301.218847 -13.357623) (xy 301.165006 -13.358114)
			(xy 293.165022 -13.358114) (xy 293.11118 -13.357646) (xy 293.00377 -13.349965) (xy 292.897181 -13.334641)
			(xy 292.791957 -13.311753) (xy 292.688634 -13.281416) (xy 292.587739 -13.243786) (xy 292.489785 -13.199053)
			(xy 292.395272 -13.147447) (xy 292.304681 -13.089229) (xy 292.218474 -13.024698) (xy 292.137091 -12.95418)
			(xy 292.060946 -12.878037) (xy 291.990426 -12.796655) (xy 291.925892 -12.71045) (xy 291.867673 -12.619861)
			(xy 291.816064 -12.525349) (xy 291.771329 -12.427396) (xy 291.733696 -12.326502) (xy 291.703356 -12.22318)
			(xy 291.680465 -12.117956) (xy 291.665139 -12.011368) (xy 291.657456 -11.903958) (xy 291.657024 -11.850116)
			(xy 291.657024 -1.999996) (xy 291.656502 -1.944189) (xy 291.648161 -1.832886) (xy 291.631526 -1.722518)
			(xy 291.606689 -1.613702) (xy 291.57379 -1.507046) (xy 291.533013 -1.403147) (xy 291.484586 -1.302585)
			(xy 291.428779 -1.205924) (xy 291.365905 -1.113703) (xy 291.296314 -1.026439) (xy 291.220398 -0.944619)
			(xy 291.138579 -0.868701) (xy 291.051316 -0.79911) (xy 290.959096 -0.736234) (xy 290.862436 -0.680426)
			(xy 290.761875 -0.631997) (xy 290.657977 -0.591218) (xy 290.551321 -0.558317) (xy 290.442505 -0.533479)
			(xy 290.332138 -0.516842) (xy 290.220835 -0.508499) (xy 290.165028 -0.508) (xy 278.165052 -0.508)
			(xy 278.109246 -0.508523) (xy 277.997947 -0.516868) (xy 277.887582 -0.533506) (xy 277.778769 -0.558345)
			(xy 277.672116 -0.591246) (xy 277.568221 -0.632024) (xy 277.467663 -0.680453) (xy 277.371005 -0.736261)
			(xy 277.278789 -0.799136) (xy 277.191528 -0.868726) (xy 277.109712 -0.944643) (xy 277.033798 -1.026461)
			(xy 276.96421 -1.113724) (xy 276.901338 -1.205943) (xy 276.845533 -1.302602) (xy 276.797107 -1.403161)
			(xy 276.756331 -1.507058) (xy 276.723433 -1.613711) (xy 276.698598 -1.722525) (xy 276.681963 -1.83289)
			(xy 276.673622 -1.94419) (xy 276.673056 -1.999996) (xy 276.673056 -11.850116) (xy 276.672586 -11.903957)
			(xy 276.664903 -12.011363) (xy 276.649577 -12.117948) (xy 276.626687 -12.223169) (xy 276.596348 -12.326487)
			(xy 276.558716 -12.427379) (xy 276.513982 -12.525328) (xy 276.462374 -12.619837) (xy 276.404156 -12.710423)
			(xy 276.339623 -12.796626) (xy 276.269105 -12.878004) (xy 276.192962 -12.954145) (xy 276.11158 -13.02466)
			(xy 276.025376 -13.089189) (xy 275.934787 -13.147404) (xy 275.840277 -13.199008) (xy 275.742325 -13.243738)
			(xy 275.641432 -13.281366) (xy 275.538112 -13.311701) (xy 275.432891 -13.334588) (xy 275.326306 -13.349909)
			(xy 275.218899 -13.357588) (xy 275.165058 -13.358114) (xy 267.165074 -13.358114) (xy 267.111233 -13.357632)
			(xy 267.003826 -13.349949) (xy 266.897241 -13.334623) (xy 266.792021 -13.311732) (xy 266.688702 -13.281393)
			(xy 266.58781 -13.243761) (xy 266.48986 -13.199028) (xy 266.39535 -13.147421) (xy 266.304763 -13.089203)
			(xy 266.21856 -13.024672) (xy 266.13718 -12.954155) (xy 266.061038 -12.878012) (xy 265.990522 -12.796632)
			(xy 265.925991 -12.710428) (xy 265.867774 -12.619841) (xy 265.816168 -12.525331) (xy 265.771435 -12.427381)
			(xy 265.733804 -12.326489) (xy 265.703466 -12.22317) (xy 265.680576 -12.117949) (xy 265.66525 -12.011364)
			(xy 265.657567 -11.903957) (xy 265.657076 -11.850116) (xy 265.657076 -1.999996) (xy 265.656567 -1.944189)
			(xy 265.648225 -1.832887) (xy 265.63159 -1.722519) (xy 265.606753 -1.613703) (xy 265.573853 -1.507048)
			(xy 265.533076 -1.403149) (xy 265.484647 -1.302589) (xy 265.42884 -1.205928) (xy 265.365964 -1.113709)
			(xy 265.296373 -1.026446) (xy 265.220456 -0.944627) (xy 265.138636 -0.868711) (xy 265.051372 -0.799121)
			(xy 264.959151 -0.736248) (xy 264.86249 -0.680441) (xy 264.761929 -0.632015) (xy 264.658029 -0.591239)
			(xy 264.551373 -0.558341) (xy 264.442557 -0.533506) (xy 264.332189 -0.516872) (xy 264.220887 -0.508532)
			(xy 264.16508 -0.508) (xy 252.165104 -0.508) (xy 252.109297 -0.508522) (xy 251.997995 -0.516862)
			(xy 251.887627 -0.533497) (xy 251.778811 -0.558333) (xy 251.672155 -0.591232) (xy 251.568256 -0.632009)
			(xy 251.467695 -0.680436) (xy 251.371034 -0.736243) (xy 251.278814 -0.799118) (xy 251.19155 -0.868708)
			(xy 251.10973 -0.944625) (xy 251.033813 -1.026444) (xy 250.964222 -1.113707) (xy 250.901348 -1.205927)
			(xy 250.84554 -1.302588) (xy 250.797112 -1.403149) (xy 250.756335 -1.507047) (xy 250.723435 -1.613703)
			(xy 250.698599 -1.722519) (xy 250.681963 -1.832887) (xy 250.673622 -1.944189) (xy 250.673108 -1.999996)
			(xy 250.673108 -11.850116) (xy 250.672627 -11.903957) (xy 250.664944 -12.011364) (xy 250.649618 -12.11795)
			(xy 250.626728 -12.223171) (xy 250.59639 -12.32649) (xy 250.558758 -12.427382) (xy 250.514025 -12.525333)
			(xy 250.462418 -12.619843) (xy 250.4042 -12.71043) (xy 250.339669 -12.796633) (xy 250.269152 -12.878014)
			(xy 250.193009 -12.954156) (xy 250.111629 -13.024673) (xy 250.025425 -13.089204) (xy 249.934837 -13.147421)
			(xy 249.840327 -13.199027) (xy 249.742377 -13.24376) (xy 249.641484 -13.281392) (xy 249.538165 -13.311729)
			(xy 249.432944 -13.334619) (xy 249.326358 -13.349944) (xy 249.218951 -13.357627) (xy 249.16511 -13.358114)
			(xy 241.164872 -13.358114) (xy 241.111035 -13.357619) (xy 241.003638 -13.34991) (xy 240.897064 -13.334562)
			(xy 240.791856 -13.311652) (xy 240.688549 -13.281298) (xy 240.58767 -13.243654) (xy 240.489733 -13.198912)
			(xy 240.395235 -13.1473) (xy 240.304659 -13.08908) (xy 240.218466 -13.024548) (xy 240.137093 -12.954035)
			(xy 240.060957 -12.877898) (xy 239.990444 -12.796525) (xy 239.925914 -12.710331) (xy 239.867694 -12.619754)
			(xy 239.816083 -12.525256) (xy 239.771341 -12.427319) (xy 239.733698 -12.326439) (xy 239.703345 -12.223133)
			(xy 239.680436 -12.117924) (xy 239.665089 -12.01135) (xy 239.657381 -11.903953) (xy 239.656874 -11.850116)
			(xy 239.656874 -1.999996) (xy 239.656365 -1.944189) (xy 239.648023 -1.832887) (xy 239.631388 -1.722519)
			(xy 239.606551 -1.613704) (xy 239.573651 -1.507048) (xy 239.532873 -1.40315) (xy 239.484445 -1.302589)
			(xy 239.428638 -1.205929) (xy 239.365762 -1.113709) (xy 239.296171 -1.026446) (xy 239.220254 -0.944628)
			(xy 239.138434 -0.868712) (xy 239.05117 -0.799122) (xy 238.958949 -0.736249) (xy 238.862288 -0.680443)
			(xy 238.761726 -0.632016) (xy 238.657827 -0.59124) (xy 238.551171 -0.558343) (xy 238.442355 -0.533507)
			(xy 238.331987 -0.516874) (xy 238.220685 -0.508534) (xy 238.164878 -0.508) (xy 214.065104 -0.508)
			(xy 214.009297 -0.508522) (xy 213.897995 -0.516862) (xy 213.787627 -0.533497) (xy 213.678811 -0.558333)
			(xy 213.572155 -0.591232) (xy 213.468256 -0.632009) (xy 213.367695 -0.680436) (xy 213.271034 -0.736243)
			(xy 213.178814 -0.799118) (xy 213.09155 -0.868708) (xy 213.00973 -0.944625) (xy 212.933813 -1.026444)
			(xy 212.864222 -1.113707) (xy 212.801348 -1.205927) (xy 212.74554 -1.302588) (xy 212.697112 -1.403149)
			(xy 212.656335 -1.507047) (xy 212.623435 -1.613703) (xy 212.598599 -1.722519) (xy 212.581963 -1.832887)
			(xy 212.573622 -1.944189) (xy 212.573108 -1.999996) (xy 212.573108 -11.850116) (xy 212.572627 -11.903957)
			(xy 212.564944 -12.011364) (xy 212.549618 -12.11795) (xy 212.526728 -12.223171) (xy 212.49639 -12.32649)
			(xy 212.458758 -12.427382) (xy 212.414025 -12.525333) (xy 212.362418 -12.619843) (xy 212.3042 -12.71043)
			(xy 212.239669 -12.796633) (xy 212.169152 -12.878014) (xy 212.093009 -12.954156) (xy 212.011629 -13.024673)
			(xy 211.925425 -13.089204) (xy 211.834837 -13.147421) (xy 211.740327 -13.199027) (xy 211.642377 -13.24376)
			(xy 211.541484 -13.281392) (xy 211.438165 -13.311729) (xy 211.332944 -13.334619) (xy 211.226358 -13.349944)
			(xy 211.118951 -13.357627) (xy 211.06511 -13.358114) (xy 203.064872 -13.358114) (xy 203.011035 -13.357619)
			(xy 202.903638 -13.34991) (xy 202.797064 -13.334562) (xy 202.691856 -13.311652) (xy 202.588549 -13.281298)
			(xy 202.48767 -13.243654) (xy 202.389733 -13.198912) (xy 202.295235 -13.1473) (xy 202.204659 -13.08908)
			(xy 202.118466 -13.024548) (xy 202.037093 -12.954035) (xy 201.960957 -12.877898) (xy 201.890444 -12.796525)
			(xy 201.825914 -12.710331) (xy 201.767694 -12.619754) (xy 201.716083 -12.525256) (xy 201.671341 -12.427319)
			(xy 201.633698 -12.326439) (xy 201.603345 -12.223133) (xy 201.580436 -12.117924) (xy 201.565089 -12.01135)
			(xy 201.557381 -11.903953) (xy 201.556874 -11.850116) (xy 201.556874 -1.999996) (xy 201.556365 -1.944189)
			(xy 201.548023 -1.832887) (xy 201.531388 -1.722519) (xy 201.506551 -1.613704) (xy 201.473651 -1.507048)
			(xy 201.432873 -1.40315) (xy 201.384445 -1.302589) (xy 201.328638 -1.205929) (xy 201.265762 -1.113709)
			(xy 201.196171 -1.026446) (xy 201.120254 -0.944628) (xy 201.038434 -0.868712) (xy 200.95117 -0.799122)
			(xy 200.858949 -0.736249) (xy 200.762288 -0.680443) (xy 200.661726 -0.632016) (xy 200.557827 -0.59124)
			(xy 200.451171 -0.558343) (xy 200.342355 -0.533507) (xy 200.231987 -0.516874) (xy 200.120685 -0.508534)
			(xy 200.064878 -0.508) (xy 188.064902 -0.508) (xy 188.009095 -0.508522) (xy 187.897793 -0.516862)
			(xy 187.787425 -0.533498) (xy 187.678609 -0.558334) (xy 187.571954 -0.591233) (xy 187.468055 -0.63201)
			(xy 187.367494 -0.680437) (xy 187.270833 -0.736244) (xy 187.178613 -0.799118) (xy 187.091349 -0.868709)
			(xy 187.00953 -0.944625) (xy 186.933613 -1.026444) (xy 186.864022 -1.113708) (xy 186.801147 -1.205928)
			(xy 186.74534 -1.302588) (xy 186.696912 -1.403149) (xy 186.656135 -1.507048) (xy 186.623235 -1.613703)
			(xy 186.598399 -1.722519) (xy 186.581763 -1.832887) (xy 186.573422 -1.944189) (xy 186.572906 -1.999996)
			(xy 186.572906 -11.850116) (xy 186.572425 -11.903957) (xy 186.564742 -12.011364) (xy 186.549416 -12.11795)
			(xy 186.526526 -12.22317) (xy 186.496188 -12.32649) (xy 186.458556 -12.427382) (xy 186.413823 -12.525332)
			(xy 186.362216 -12.619842) (xy 186.303998 -12.71043) (xy 186.239467 -12.796633) (xy 186.16895 -12.878013)
			(xy 186.092807 -12.954155) (xy 186.011427 -13.024672) (xy 185.925223 -13.089203) (xy 185.834635 -13.14742)
			(xy 185.740125 -13.199026) (xy 185.642175 -13.243759) (xy 185.541282 -13.28139) (xy 185.437963 -13.311728)
			(xy 185.332742 -13.334618) (xy 185.226156 -13.349943) (xy 185.118749 -13.357625) (xy 185.064908 -13.358114)
			(xy 177.064924 -13.358114) (xy 177.011082 -13.357646) (xy 176.903671 -13.349965) (xy 176.797083 -13.334642)
			(xy 176.691859 -13.311753) (xy 176.588536 -13.281417) (xy 176.48764 -13.243786) (xy 176.389686 -13.199054)
			(xy 176.295173 -13.147447) (xy 176.204582 -13.08923) (xy 176.118375 -13.024698) (xy 176.036992 -12.954181)
			(xy 175.960846 -12.878038) (xy 175.890327 -12.796656) (xy 175.825793 -12.710451) (xy 175.767573 -12.619862)
			(xy 175.715964 -12.52535) (xy 175.671229 -12.427397) (xy 175.633596 -12.326502) (xy 175.603257 -12.22318)
			(xy 175.580365 -12.117957) (xy 175.565039 -12.011368) (xy 175.557356 -11.903958) (xy 175.556926 -11.850116)
			(xy 175.556926 -1.999996) (xy 175.556404 -1.944189) (xy 175.548063 -1.832886) (xy 175.531428 -1.722518)
			(xy 175.506591 -1.613702) (xy 175.473692 -1.507046) (xy 175.432915 -1.403146) (xy 175.384488 -1.302585)
			(xy 175.328681 -1.205923) (xy 175.265807 -1.113703) (xy 175.196217 -1.026438) (xy 175.1203 -0.944618)
			(xy 175.038481 -0.8687) (xy 174.951218 -0.799109) (xy 174.858999 -0.736233) (xy 174.762338 -0.680424)
			(xy 174.661777 -0.631995) (xy 174.557879 -0.591216) (xy 174.451223 -0.558316) (xy 174.342408 -0.533477)
			(xy 174.23204 -0.51684) (xy 174.120737 -0.508497) (xy 174.06493 -0.508) (xy 162.064954 -0.508) (xy 162.009148 -0.508523)
			(xy 161.897848 -0.516867) (xy 161.787483 -0.533505) (xy 161.67867 -0.558344) (xy 161.572018 -0.591245)
			(xy 161.468122 -0.632024) (xy 161.367564 -0.680453) (xy 161.270907 -0.73626) (xy 161.17869 -0.799135)
			(xy 161.091429 -0.868726) (xy 161.009613 -0.944642) (xy 160.933698 -1.026461) (xy 160.86411 -1.113723)
			(xy 160.801238 -1.205942) (xy 160.745433 -1.302601) (xy 160.697007 -1.403161) (xy 160.656231 -1.507058)
			(xy 160.623333 -1.613711) (xy 160.598498 -1.722525) (xy 160.581863 -1.83289) (xy 160.573522 -1.94419)
			(xy 160.572958 -1.999996) (xy 160.572958 -11.850116) (xy 160.572488 -11.903957) (xy 160.564805 -12.011363)
			(xy 160.549479 -12.117949) (xy 160.526589 -12.223169) (xy 160.49625 -12.326488) (xy 160.458618 -12.427379)
			(xy 160.413884 -12.525329) (xy 160.362276 -12.619838) (xy 160.304058 -12.710424) (xy 160.239525 -12.796626)
			(xy 160.169008 -12.878005) (xy 160.092864 -12.954146) (xy 160.011483 -13.02466) (xy 159.925278 -13.08919)
			(xy 159.834689 -13.147405) (xy 159.740179 -13.199009) (xy 159.642227 -13.243739) (xy 159.541335 -13.281368)
			(xy 159.438014 -13.311702) (xy 159.332793 -13.334589) (xy 159.226208 -13.349911) (xy 159.118801 -13.35759)
			(xy 159.06496 -13.358114) (xy 151.064976 -13.358114) (xy 151.011135 -13.357633) (xy 150.903728 -13.349949)
			(xy 150.797143 -13.334623) (xy 150.691922 -13.311732) (xy 150.588603 -13.281394) (xy 150.487711 -13.243762)
			(xy 150.389761 -13.199028) (xy 150.295252 -13.147421) (xy 150.204664 -13.089204) (xy 150.118461 -13.024672)
			(xy 150.037081 -12.954156) (xy 149.960939 -12.878013) (xy 149.890423 -12.796633) (xy 149.825892 -12.710429)
			(xy 149.767674 -12.619842) (xy 149.716068 -12.525332) (xy 149.671335 -12.427381) (xy 149.633704 -12.326489)
			(xy 149.603366 -12.22317) (xy 149.580476 -12.117949) (xy 149.56515 -12.011364) (xy 149.557467 -11.903957)
			(xy 149.556978 -11.850116) (xy 149.556978 -1.999996) (xy 149.556469 -1.944189) (xy 149.548127 -1.832887)
			(xy 149.531492 -1.722519) (xy 149.506655 -1.613703) (xy 149.473755 -1.507048) (xy 149.432978 -1.403149)
			(xy 149.384549 -1.302588) (xy 149.328742 -1.205928) (xy 149.265867 -1.113708) (xy 149.196276 -1.026445)
			(xy 149.120358 -0.944627) (xy 149.038538 -0.86871) (xy 148.951274 -0.79912) (xy 148.859054 -0.736247)
			(xy 148.762392 -0.68044) (xy 148.661831 -0.632014) (xy 148.557931 -0.591237) (xy 148.451276 -0.55834)
			(xy 148.342459 -0.533504) (xy 148.232091 -0.51687) (xy 148.120789 -0.508531) (xy 148.064982 -0.508)
			(xy 136.065006 -0.508) (xy 136.009198 -0.508509) (xy 135.897895 -0.51685) (xy 135.787526 -0.533485)
			(xy 135.678709 -0.558321) (xy 135.572052 -0.59122) (xy 135.468152 -0.631997) (xy 135.36759 -0.680425)
			(xy 135.270928 -0.736232) (xy 135.178707 -0.799107) (xy 135.091442 -0.868698) (xy 135.009622 -0.944615)
			(xy 134.933704 -1.026435) (xy 134.864113 -1.113699) (xy 134.801237 -1.20592) (xy 134.745429 -1.302581)
			(xy 134.697001 -1.403143) (xy 134.656223 -1.507043) (xy 134.623324 -1.613699) (xy 134.598486 -1.722516)
			(xy 134.581851 -1.832885) (xy 134.573509 -1.944188) (xy 134.57301 -1.999996) (xy 134.57301 -11.850116)
			(xy 134.572529 -11.903957) (xy 134.564846 -12.011364) (xy 134.54952 -12.11795) (xy 134.52663 -12.223171)
			(xy 134.496292 -12.32649) (xy 134.45866 -12.427383) (xy 134.413927 -12.525333) (xy 134.36232 -12.619843)
			(xy 134.304102 -12.710431) (xy 134.239571 -12.796634) (xy 134.169054 -12.878014) (xy 134.092911 -12.954157)
			(xy 134.011531 -13.024673) (xy 133.925327 -13.089205) (xy 133.83474 -13.147422) (xy 133.74023 -13.199029)
			(xy 133.642279 -13.243762) (xy 133.541387 -13.281393) (xy 133.438067 -13.311731) (xy 133.332846 -13.334621)
			(xy 133.22626 -13.349946) (xy 133.118853 -13.357629) (xy 133.065012 -13.358114) (xy 125.065028 -13.358114)
			(xy 125.011186 -13.357646) (xy 124.903775 -13.349966) (xy 124.797186 -13.334642) (xy 124.691962 -13.311754)
			(xy 124.588639 -13.281418) (xy 124.487743 -13.243787) (xy 124.389789 -13.199055) (xy 124.295275 -13.147449)
			(xy 124.204684 -13.089231) (xy 124.118477 -13.0247) (xy 124.037093 -12.954182) (xy 123.960948 -12.878039)
			(xy 123.890428 -12.796657) (xy 123.825894 -12.710452) (xy 123.767674 -12.619863) (xy 123.716065 -12.525351)
			(xy 123.671329 -12.427398) (xy 123.633696 -12.326503) (xy 123.603357 -12.223181) (xy 123.580465 -12.117957)
			(xy 123.565139 -12.011369) (xy 123.557456 -11.903958) (xy 123.55703 -11.850116) (xy 123.55703 -1.999996)
			(xy 123.556508 -1.944189) (xy 123.548167 -1.832886) (xy 123.531532 -1.722518) (xy 123.506695 -1.613701)
			(xy 123.473796 -1.507045) (xy 123.433019 -1.403146) (xy 123.384592 -1.302584) (xy 123.328785 -1.205923)
			(xy 123.265911 -1.113702) (xy 123.196321 -1.026437) (xy 123.120404 -0.944617) (xy 123.038586 -0.868699)
			(xy 122.951322 -0.799107) (xy 122.859103 -0.736231) (xy 122.762442 -0.680422) (xy 122.661882 -0.631993)
			(xy 122.557983 -0.591214) (xy 122.451328 -0.558313) (xy 122.342512 -0.533474) (xy 122.232144 -0.516836)
			(xy 122.120841 -0.508493) (xy 122.065034 -0.508) (xy 97.965006 -0.508) (xy 97.909198 -0.508509) (xy 97.797895 -0.51685)
			(xy 97.687526 -0.533485) (xy 97.578709 -0.558321) (xy 97.472052 -0.59122) (xy 97.368152 -0.631997)
			(xy 97.26759 -0.680425) (xy 97.170928 -0.736232) (xy 97.078707 -0.799107) (xy 96.991442 -0.868698)
			(xy 96.909622 -0.944615) (xy 96.833704 -1.026435) (xy 96.764113 -1.113699) (xy 96.701237 -1.20592)
			(xy 96.645429 -1.302581) (xy 96.597001 -1.403143) (xy 96.556223 -1.507043) (xy 96.523324 -1.613699)
			(xy 96.498486 -1.722516) (xy 96.481851 -1.832885) (xy 96.473509 -1.944188) (xy 96.47301 -1.999996)
			(xy 96.47301 -11.850116) (xy 96.472529 -11.903957) (xy 96.464846 -12.011364) (xy 96.44952 -12.11795)
			(xy 96.42663 -12.223171) (xy 96.396292 -12.32649) (xy 96.35866 -12.427383) (xy 96.313927 -12.525333)
			(xy 96.26232 -12.619843) (xy 96.204102 -12.710431) (xy 96.139571 -12.796634) (xy 96.069054 -12.878014)
			(xy 95.992911 -12.954157) (xy 95.911531 -13.024673) (xy 95.825327 -13.089205) (xy 95.73474 -13.147422)
			(xy 95.64023 -13.199029) (xy 95.542279 -13.243762) (xy 95.441387 -13.281393) (xy 95.338067 -13.311731)
			(xy 95.232846 -13.334621) (xy 95.12626 -13.349946) (xy 95.018853 -13.357629) (xy 94.965012 -13.358114)
			(xy 86.965028 -13.358114) (xy 86.911186 -13.357646) (xy 86.803775 -13.349966) (xy 86.697186 -13.334642)
			(xy 86.591962 -13.311754) (xy 86.488639 -13.281418) (xy 86.387743 -13.243787) (xy 86.289789 -13.199055)
			(xy 86.195275 -13.147449) (xy 86.104684 -13.089231) (xy 86.018477 -13.0247) (xy 85.937093 -12.954182)
			(xy 85.860948 -12.878039) (xy 85.790428 -12.796657) (xy 85.725894 -12.710452) (xy 85.667674 -12.619863)
			(xy 85.616065 -12.525351) (xy 85.571329 -12.427398) (xy 85.533696 -12.326503) (xy 85.503357 -12.223181)
			(xy 85.480465 -12.117957) (xy 85.465139 -12.011369) (xy 85.457456 -11.903958) (xy 85.45703 -11.850116)
			(xy 85.45703 -1.999996) (xy 85.456508 -1.944189) (xy 85.448167 -1.832886) (xy 85.431532 -1.722518)
			(xy 85.406695 -1.613701) (xy 85.373796 -1.507045) (xy 85.333019 -1.403146) (xy 85.284592 -1.302584)
			(xy 85.228785 -1.205923) (xy 85.165911 -1.113702) (xy 85.096321 -1.026437) (xy 85.020404 -0.944617)
			(xy 84.938586 -0.868699) (xy 84.851322 -0.799107) (xy 84.759103 -0.736231) (xy 84.662442 -0.680422)
			(xy 84.561882 -0.631993) (xy 84.457983 -0.591214) (xy 84.351328 -0.558313) (xy 84.242512 -0.533474)
			(xy 84.132144 -0.516836) (xy 84.020841 -0.508493) (xy 83.965034 -0.508) (xy 71.965058 -0.508) (xy 71.909252 -0.508523)
			(xy 71.797952 -0.516867) (xy 71.687587 -0.533505) (xy 71.578774 -0.558343) (xy 71.472121 -0.591244)
			(xy 71.368225 -0.632023) (xy 71.267667 -0.680451) (xy 71.171009 -0.736259) (xy 71.078791 -0.799134)
			(xy 70.991531 -0.868724) (xy 70.909714 -0.944641) (xy 70.8338 -1.026459) (xy 70.764211 -1.113722)
			(xy 70.701339 -1.205941) (xy 70.645534 -1.3026) (xy 70.597107 -1.40316) (xy 70.556331 -1.507057)
			(xy 70.523434 -1.61371) (xy 70.498598 -1.722524) (xy 70.481963 -1.83289) (xy 70.473622 -1.94419)
			(xy 70.473062 -1.999996) (xy 70.473062 -11.850116) (xy 70.472592 -11.903957) (xy 70.464909 -12.011364)
			(xy 70.449583 -12.117949) (xy 70.426693 -12.223169) (xy 70.396354 -12.326488) (xy 70.358722 -12.42738)
			(xy 70.313988 -12.52533) (xy 70.26238 -12.619839) (xy 70.204162 -12.710425) (xy 70.139629 -12.796627)
			(xy 70.069112 -12.878006) (xy 69.992968 -12.954147) (xy 69.911587 -13.024662) (xy 69.825382 -13.089192)
			(xy 69.734794 -13.147407) (xy 69.640283 -13.199011) (xy 69.542332 -13.243742) (xy 69.441439 -13.28137)
			(xy 69.338119 -13.311705) (xy 69.232898 -13.334592) (xy 69.126312 -13.349915) (xy 69.018905 -13.357594)
			(xy 68.965064 -13.358114) (xy 60.96508 -13.358114) (xy 60.911239 -13.357633) (xy 60.803832 -13.349949)
			(xy 60.697246 -13.334624) (xy 60.592026 -13.311733) (xy 60.488706 -13.281395) (xy 60.387814 -13.243763)
			(xy 60.289864 -13.19903) (xy 60.195354 -13.147423) (xy 60.104766 -13.089205) (xy 60.018563 -13.024674)
			(xy 59.937183 -12.954157) (xy 59.86104 -12.878014) (xy 59.790524 -12.796634) (xy 59.725992 -12.71043)
			(xy 59.667775 -12.619843) (xy 59.616169 -12.525333) (xy 59.571435 -12.427382) (xy 59.533804 -12.32649)
			(xy 59.503466 -12.22317) (xy 59.480576 -12.11795) (xy 59.46525 -12.011364) (xy 59.457567 -11.903957)
			(xy 59.457082 -11.850116) (xy 59.457082 -1.999996) (xy 59.456573 -1.944189) (xy 59.448231 -1.832886)
			(xy 59.431596 -1.722519) (xy 59.406759 -1.613703) (xy 59.373859 -1.507047) (xy 59.333082 -1.403148)
			(xy 59.284653 -1.302588) (xy 59.228846 -1.205927) (xy 59.165971 -1.113707) (xy 59.09638 -1.026444)
			(xy 59.020462 -0.944625) (xy 58.938643 -0.868709) (xy 58.851378 -0.799119) (xy 58.759158 -0.736245)
			(xy 58.662496 -0.680438) (xy 58.561935 -0.632011) (xy 58.458036 -0.591235) (xy 58.35138 -0.558337)
			(xy 58.242564 -0.533501) (xy 58.132196 -0.516867) (xy 58.020893 -0.508527) (xy 57.965086 -0.508)
			(xy 45.96511 -0.508) (xy 45.909302 -0.508509) (xy 45.797999 -0.516849) (xy 45.68763 -0.533484) (xy 45.578812 -0.55832)
			(xy 45.472155 -0.591219) (xy 45.368255 -0.631996) (xy 45.267693 -0.680423) (xy 45.17103 -0.736231)
			(xy 45.078809 -0.799106) (xy 44.991544 -0.868696) (xy 44.909724 -0.944614) (xy 44.833805 -1.026433)
			(xy 44.764214 -1.113698) (xy 44.701338 -1.205919) (xy 44.64553 -1.30258) (xy 44.597101 -1.403142)
			(xy 44.556323 -1.507042) (xy 44.523424 -1.613699) (xy 44.498587 -1.722516) (xy 44.481951 -1.832885)
			(xy 44.473609 -1.944188) (xy 44.473114 -1.999996) (xy 44.473114 -11.850116) (xy 44.472633 -11.903957)
			(xy 44.46495 -12.011364) (xy 44.449624 -12.11795) (xy 44.426734 -12.223171) (xy 44.396396 -12.326491)
			(xy 44.358764 -12.427383) (xy 44.314031 -12.525334) (xy 44.262424 -12.619844) (xy 44.204207 -12.710432)
			(xy 44.139675 -12.796635) (xy 44.069158 -12.878016) (xy 43.993016 -12.954158) (xy 43.911635 -13.024675)
			(xy 43.825432 -13.089207) (xy 43.734844 -13.147424) (xy 43.640334 -13.199031) (xy 43.542383 -13.243764)
			(xy 43.441491 -13.281396) (xy 43.338171 -13.311734) (xy 43.23295 -13.334624) (xy 43.126364 -13.34995)
			(xy 43.018957 -13.357633) (xy 42.965116 -13.358114) (xy 34.964878 -13.358114) (xy 34.911037 -13.357633)
			(xy 34.80363 -13.349949) (xy 34.697045 -13.334623) (xy 34.591824 -13.311733) (xy 34.488505 -13.281394)
			(xy 34.387613 -13.243762) (xy 34.289662 -13.199029) (xy 34.195153 -13.147422) (xy 34.104565 -13.089205)
			(xy 34.018362 -13.024673) (xy 33.936982 -12.954156) (xy 33.86084 -12.878014) (xy 33.790323 -12.796633)
			(xy 33.725792 -12.71043) (xy 33.667575 -12.619842) (xy 33.615968 -12.525332) (xy 33.571235 -12.427382)
			(xy 33.533604 -12.32649) (xy 33.503266 -12.22317) (xy 33.480376 -12.11795) (xy 33.46505 -12.011364)
			(xy 33.457367 -11.903957) (xy 33.45688 -11.850116) (xy 33.45688 -1.999996) (xy 33.456371 -1.944189)
			(xy 33.448029 -1.832887) (xy 33.431394 -1.722519) (xy 33.406557 -1.613703) (xy 33.373657 -1.507048)
			(xy 33.33288 -1.403149) (xy 33.284451 -1.302588) (xy 33.228644 -1.205927) (xy 33.165769 -1.113708)
			(xy 33.096178 -1.026444) (xy 33.02026 -0.944626) (xy 32.93844 -0.868709) (xy 32.851176 -0.79912)
			(xy 32.758956 -0.736246) (xy 32.662294 -0.680439) (xy 32.561733 -0.632012) (xy 32.457834 -0.591236)
			(xy 32.351178 -0.558338) (xy 32.242361 -0.533503) (xy 32.131994 -0.516868) (xy 32.020691 -0.508529)
			(xy 31.964884 -0.508) (xy 19.964908 -0.508) (xy 19.9091 -0.508509) (xy 19.797797 -0.516849) (xy 19.687428 -0.533484)
			(xy 19.578611 -0.55832) (xy 19.471954 -0.591219) (xy 19.368054 -0.631996) (xy 19.267491 -0.680424)
			(xy 19.170829 -0.736231) (xy 19.078608 -0.799106) (xy 18.991343 -0.868697) (xy 18.909523 -0.944614)
			(xy 18.833605 -1.026434) (xy 18.764013 -1.113698) (xy 18.701138 -1.205919) (xy 18.64533 -1.302581)
			(xy 18.596901 -1.403143) (xy 18.556123 -1.507043) (xy 18.523224 -1.613699) (xy 18.498386 -1.722516)
			(xy 18.481751 -1.832885) (xy 18.473409 -1.944188) (xy 18.472912 -1.999996) (xy 18.472912 -11.850116)
			(xy 18.472443 -11.903958) (xy 18.464761 -12.011366) (xy 18.449437 -12.117953) (xy 18.426547 -12.223176)
			(xy 18.396209 -12.326497) (xy 18.358578 -12.42739) (xy 18.313845 -12.525342) (xy 18.262238 -12.619854)
			(xy 18.20402 -12.710442) (xy 18.139488 -12.796647) (xy 18.068971 -12.878029) (xy 17.992827 -12.954172)
			(xy 17.911446 -13.024689) (xy 17.825241 -13.089221) (xy 17.734652 -13.147439) (xy 17.640141 -13.199046)
			(xy 17.542189 -13.243779) (xy 17.441295 -13.28141) (xy 17.337974 -13.311748) (xy 17.232751 -13.334637)
			(xy 17.126164 -13.349961) (xy 17.018756 -13.357643) (xy 16.964914 -13.358114) (xy 8.96493 -13.358114)
			(xy 8.911089 -13.357645) (xy 8.80368 -13.349963) (xy 8.697093 -13.334638) (xy 8.591871 -13.311748)
			(xy 8.48855 -13.28141) (xy 8.387656 -13.243779) (xy 8.289705 -13.199046) (xy 8.195194 -13.147439)
			(xy 8.104605 -13.089221) (xy 8.0184 -13.024689) (xy 7.937019 -12.954171) (xy 7.860876 -12.878028)
			(xy 7.790359 -12.796646) (xy 7.725827 -12.710442) (xy 7.667609 -12.619853) (xy 7.616002 -12.525342)
			(xy 7.57127 -12.42739) (xy 7.533638 -12.326496) (xy 7.503301 -12.223175) (xy 7.480411 -12.117953)
			(xy 7.465087 -12.011366) (xy 7.457405 -11.903957) (xy 7.456932 -11.850116) (xy 7.456932 -1.999996)
			(xy 7.45641 -1.944189) (xy 7.448069 -1.832887) (xy 7.431434 -1.72252) (xy 7.406597 -1.613704) (xy 7.373698 -1.507049)
			(xy 7.332921 -1.40315) (xy 7.284493 -1.30259) (xy 7.228686 -1.205929) (xy 7.165812 -1.113709) (xy 7.096221 -1.026446)
			(xy 7.020305 -0.944627) (xy 6.938486 -0.86871) (xy 6.851222 -0.79912) (xy 6.759003 -0.736245) (xy 6.662342 -0.680438)
			(xy 6.561782 -0.63201) (xy 6.457883 -0.591233) (xy 6.351228 -0.558334) (xy 6.242412 -0.533497) (xy 6.132045 -0.516861)
			(xy 6.020743 -0.50852) (xy 5.964936 -0.508) (xy 1.999996 -0.508) (xy 1.944189 -0.508522) (xy 1.832887 -0.516863)
			(xy 1.72252 -0.533498) (xy 1.613704 -0.558335) (xy 1.507049 -0.591234) (xy 1.403151 -0.632011) (xy 1.30259 -0.680439)
			(xy 1.205929 -0.736246) (xy 1.11371 -0.799121) (xy 1.026446 -0.868711) (xy 0.944628 -0.944628) (xy 0.868711 -1.026446)
			(xy 0.799121 -1.11371) (xy 0.736246 -1.205929) (xy 0.680439 -1.30259) (xy 0.632011 -1.403151) (xy 0.591234 -1.507049)
			(xy 0.558335 -1.613704) (xy 0.533498 -1.72252) (xy 0.516863 -1.832887) (xy 0.508522 -1.944189) (xy 0.508 -1.999996)
			(xy 0.508 -15.200122) (xy 459.541372 -15.200122) (xy 459.541372 -13.599922) (xy 459.54188 -13.535242)
			(xy 459.550003 -13.406136) (xy 459.566216 -13.277796) (xy 459.590456 -13.150726) (xy 459.622626 -13.02543)
			(xy 459.662601 -12.9024) (xy 459.710222 -12.782124) (xy 459.765301 -12.665075) (xy 459.827621 -12.551715)
			(xy 459.896936 -12.442492) (xy 459.972972 -12.337837) (xy 460.05543 -12.238163) (xy 460.143983 -12.143863)
			(xy 460.238283 -12.05531) (xy 460.337957 -11.972852) (xy 460.442612 -11.896816) (xy 460.551835 -11.827501)
			(xy 460.665195 -11.765181) (xy 460.782244 -11.710102) (xy 460.90252 -11.662481) (xy 461.02555 -11.622506)
			(xy 461.150846 -11.590336) (xy 461.277916 -11.566096) (xy 461.406256 -11.549883) (xy 461.535362 -11.54176)
			(xy 461.664722 -11.54176) (xy 461.793828 -11.549883) (xy 461.922168 -11.566096) (xy 462.049238 -11.590336)
			(xy 462.174534 -11.622506) (xy 462.297564 -11.662481) (xy 462.41784 -11.710102) (xy 462.534889 -11.765181)
			(xy 462.648249 -11.827501) (xy 462.757472 -11.896816) (xy 462.862127 -11.972852) (xy 462.961801 -12.05531)
			(xy 463.056101 -12.143863) (xy 463.144654 -12.238163) (xy 463.227112 -12.337837) (xy 463.303148 -12.442492)
			(xy 463.372463 -12.551715) (xy 463.434783 -12.665075) (xy 463.489862 -12.782124) (xy 463.537483 -12.9024)
			(xy 463.577458 -13.02543) (xy 463.609628 -13.150726) (xy 463.633868 -13.277796) (xy 463.650081 -13.406136)
			(xy 463.658204 -13.535242) (xy 463.658712 -13.599922) (xy 463.658712 -15.200122) (xy 463.658204 -15.264802)
			(xy 463.650081 -15.393908) (xy 463.633868 -15.522248) (xy 463.609628 -15.649318) (xy 463.577458 -15.774614)
			(xy 463.537483 -15.897644) (xy 463.489862 -16.01792) (xy 463.434783 -16.134969) (xy 463.372463 -16.248329)
			(xy 463.303148 -16.357552) (xy 463.227112 -16.462207) (xy 463.144654 -16.561881) (xy 463.056101 -16.656181)
			(xy 462.961801 -16.744734) (xy 462.862127 -16.827192) (xy 462.757472 -16.903228) (xy 462.648249 -16.972543)
			(xy 462.534889 -17.034863) (xy 462.41784 -17.089942) (xy 462.297564 -17.137563) (xy 462.174534 -17.177538)
			(xy 462.049238 -17.209708) (xy 461.922168 -17.233948) (xy 461.793828 -17.250161) (xy 461.664722 -17.258284)
			(xy 461.535362 -17.258284) (xy 461.406256 -17.250161) (xy 461.277916 -17.233948) (xy 461.150846 -17.209708)
			(xy 461.02555 -17.177538) (xy 460.90252 -17.137563) (xy 460.782244 -17.089942) (xy 460.665195 -17.034863)
			(xy 460.551835 -16.972543) (xy 460.442612 -16.903228) (xy 460.337957 -16.827192) (xy 460.238283 -16.744734)
			(xy 460.143983 -16.656181) (xy 460.05543 -16.561881) (xy 459.972972 -16.462207) (xy 459.896936 -16.357552)
			(xy 459.827621 -16.248329) (xy 459.765301 -16.134969) (xy 459.710222 -16.01792) (xy 459.662601 -15.897644)
			(xy 459.622626 -15.774614) (xy 459.590456 -15.649318) (xy 459.566216 -15.522248) (xy 459.550003 -15.393908)
			(xy 459.54188 -15.264802) (xy 459.541372 -15.200122) (xy 0.508 -15.200122) (xy 0.508 -16.969994)
			(xy 13.748265 -16.969994) (xy 13.75227 -16.882086) (xy 13.764253 -16.794906) (xy 13.784113 -16.709177)
			(xy 13.811688 -16.625609) (xy 13.846747 -16.544895) (xy 13.889 -16.467703) (xy 13.938098 -16.394674)
			(xy 13.993634 -16.326412) (xy 14.055146 -16.263482) (xy 14.122127 -16.206408) (xy 14.19402 -16.15566)
			(xy 14.270229 -16.11166) (xy 14.350124 -16.074773) (xy 14.433043 -16.045304) (xy 14.518298 -16.023497)
			(xy 14.605182 -16.009533) (xy 14.692976 -16.003527) (xy 14.780953 -16.005531) (xy 14.868383 -16.015526)
			(xy 14.954542 -16.03343) (xy 15.038716 -16.059094) (xy 15.120207 -16.092307) (xy 15.198341 -16.132793)
			(xy 15.272469 -16.180215) (xy 15.341977 -16.234182) (xy 15.406291 -16.294247) (xy 15.464875 -16.359911)
			(xy 15.517246 -16.43063) (xy 15.562969 -16.505818) (xy 15.601666 -16.584853) (xy 15.633015 -16.667079)
			(xy 15.656757 -16.751815) (xy 15.672695 -16.838359) (xy 15.680697 -16.925994) (xy 15.681198 -16.969994)
			(xy 39.748213 -16.969994) (xy 39.752218 -16.882086) (xy 39.764201 -16.794906) (xy 39.784061 -16.709177)
			(xy 39.811636 -16.625609) (xy 39.846695 -16.544895) (xy 39.888948 -16.467703) (xy 39.938046 -16.394674)
			(xy 39.993582 -16.326412) (xy 40.055094 -16.263482) (xy 40.122075 -16.206408) (xy 40.193968 -16.15566)
			(xy 40.270177 -16.11166) (xy 40.350072 -16.074773) (xy 40.432991 -16.045304) (xy 40.518246 -16.023497)
			(xy 40.60513 -16.009533) (xy 40.692924 -16.003527) (xy 40.780901 -16.005531) (xy 40.868331 -16.015526)
			(xy 40.95449 -16.03343) (xy 41.038664 -16.059094) (xy 41.120155 -16.092307) (xy 41.198289 -16.132793)
			(xy 41.272417 -16.180215) (xy 41.341925 -16.234182) (xy 41.406239 -16.294247) (xy 41.464823 -16.359911)
			(xy 41.517194 -16.43063) (xy 41.562917 -16.505818) (xy 41.601614 -16.584853) (xy 41.632963 -16.667079)
			(xy 41.656705 -16.751815) (xy 41.672643 -16.838359) (xy 41.680645 -16.925994) (xy 41.681146 -16.969994)
			(xy 65.748161 -16.969994) (xy 65.752166 -16.882086) (xy 65.764149 -16.794906) (xy 65.784009 -16.709177)
			(xy 65.811584 -16.625609) (xy 65.846643 -16.544895) (xy 65.888896 -16.467703) (xy 65.937994 -16.394674)
			(xy 65.99353 -16.326412) (xy 66.055042 -16.263482) (xy 66.122023 -16.206408) (xy 66.193916 -16.15566)
			(xy 66.270125 -16.11166) (xy 66.35002 -16.074773) (xy 66.432939 -16.045304) (xy 66.518194 -16.023497)
			(xy 66.605078 -16.009533) (xy 66.692872 -16.003527) (xy 66.780849 -16.005531) (xy 66.868279 -16.015526)
			(xy 66.954438 -16.03343) (xy 67.038612 -16.059094) (xy 67.120103 -16.092307) (xy 67.198237 -16.132793)
			(xy 67.272365 -16.180215) (xy 67.341873 -16.234182) (xy 67.406187 -16.294247) (xy 67.464771 -16.359911)
			(xy 67.517142 -16.43063) (xy 67.562865 -16.505818) (xy 67.601562 -16.584853) (xy 67.632911 -16.667079)
			(xy 67.656653 -16.751815) (xy 67.672591 -16.838359) (xy 67.680593 -16.925994) (xy 67.681094 -16.969994)
			(xy 91.748109 -16.969994) (xy 91.752114 -16.882086) (xy 91.764097 -16.794906) (xy 91.783957 -16.709177)
			(xy 91.811532 -16.625609) (xy 91.846591 -16.544895) (xy 91.888844 -16.467703) (xy 91.937942 -16.394674)
			(xy 91.993478 -16.326412) (xy 92.05499 -16.263482) (xy 92.121971 -16.206408) (xy 92.193864 -16.15566)
			(xy 92.270073 -16.11166) (xy 92.349968 -16.074773) (xy 92.432887 -16.045304) (xy 92.518142 -16.023497)
			(xy 92.605026 -16.009533) (xy 92.69282 -16.003527) (xy 92.780797 -16.005531) (xy 92.868227 -16.015526)
			(xy 92.954386 -16.03343) (xy 93.03856 -16.059094) (xy 93.120051 -16.092307) (xy 93.198185 -16.132793)
			(xy 93.272313 -16.180215) (xy 93.341821 -16.234182) (xy 93.406135 -16.294247) (xy 93.464719 -16.359911)
			(xy 93.51709 -16.43063) (xy 93.562813 -16.505818) (xy 93.60151 -16.584853) (xy 93.632859 -16.667079)
			(xy 93.656601 -16.751815) (xy 93.672539 -16.838359) (xy 93.680541 -16.925994) (xy 93.681042 -16.969994)
			(xy 129.848363 -16.969994) (xy 129.852368 -16.882086) (xy 129.864351 -16.794906) (xy 129.884211 -16.709177)
			(xy 129.911786 -16.625609) (xy 129.946845 -16.544895) (xy 129.989098 -16.467703) (xy 130.038196 -16.394674)
			(xy 130.093732 -16.326412) (xy 130.155244 -16.263482) (xy 130.222225 -16.206408) (xy 130.294118 -16.15566)
			(xy 130.370327 -16.11166) (xy 130.450222 -16.074773) (xy 130.533141 -16.045304) (xy 130.618396 -16.023497)
			(xy 130.70528 -16.009533) (xy 130.793074 -16.003527) (xy 130.881051 -16.005531) (xy 130.968481 -16.015526)
			(xy 131.05464 -16.03343) (xy 131.138814 -16.059094) (xy 131.220305 -16.092307) (xy 131.298439 -16.132793)
			(xy 131.372567 -16.180215) (xy 131.442075 -16.234182) (xy 131.506389 -16.294247) (xy 131.564973 -16.359911)
			(xy 131.617344 -16.43063) (xy 131.663067 -16.505818) (xy 131.701764 -16.584853) (xy 131.733113 -16.667079)
			(xy 131.756855 -16.751815) (xy 131.772793 -16.838359) (xy 131.780795 -16.925994) (xy 131.781296 -16.969994)
			(xy 155.848311 -16.969994) (xy 155.852316 -16.882086) (xy 155.864299 -16.794906) (xy 155.884159 -16.709177)
			(xy 155.911734 -16.625609) (xy 155.946793 -16.544895) (xy 155.989046 -16.467703) (xy 156.038144 -16.394674)
			(xy 156.09368 -16.326412) (xy 156.155192 -16.263482) (xy 156.222173 -16.206408) (xy 156.294066 -16.15566)
			(xy 156.370275 -16.11166) (xy 156.45017 -16.074773) (xy 156.533089 -16.045304) (xy 156.618344 -16.023497)
			(xy 156.705228 -16.009533) (xy 156.793022 -16.003527) (xy 156.880999 -16.005531) (xy 156.968429 -16.015526)
			(xy 157.054588 -16.03343) (xy 157.138762 -16.059094) (xy 157.220253 -16.092307) (xy 157.298387 -16.132793)
			(xy 157.372515 -16.180215) (xy 157.442023 -16.234182) (xy 157.506337 -16.294247) (xy 157.564921 -16.359911)
			(xy 157.617292 -16.43063) (xy 157.663015 -16.505818) (xy 157.701712 -16.584853) (xy 157.733061 -16.667079)
			(xy 157.756803 -16.751815) (xy 157.772741 -16.838359) (xy 157.780743 -16.925994) (xy 157.781244 -16.969994)
			(xy 181.848259 -16.969994) (xy 181.852264 -16.882086) (xy 181.864247 -16.794906) (xy 181.884107 -16.709177)
			(xy 181.911682 -16.625609) (xy 181.946741 -16.544895) (xy 181.988994 -16.467703) (xy 182.038092 -16.394674)
			(xy 182.093628 -16.326412) (xy 182.15514 -16.263482) (xy 182.222121 -16.206408) (xy 182.294014 -16.15566)
			(xy 182.370223 -16.11166) (xy 182.450118 -16.074773) (xy 182.533037 -16.045304) (xy 182.618292 -16.023497)
			(xy 182.705176 -16.009533) (xy 182.79297 -16.003527) (xy 182.880947 -16.005531) (xy 182.968377 -16.015526)
			(xy 183.054536 -16.03343) (xy 183.13871 -16.059094) (xy 183.220201 -16.092307) (xy 183.298335 -16.132793)
			(xy 183.372463 -16.180215) (xy 183.441971 -16.234182) (xy 183.506285 -16.294247) (xy 183.564869 -16.359911)
			(xy 183.61724 -16.43063) (xy 183.662963 -16.505818) (xy 183.70166 -16.584853) (xy 183.733009 -16.667079)
			(xy 183.756751 -16.751815) (xy 183.772689 -16.838359) (xy 183.780691 -16.925994) (xy 183.781192 -16.969994)
			(xy 207.848207 -16.969994) (xy 207.852212 -16.882086) (xy 207.864195 -16.794906) (xy 207.884055 -16.709177)
			(xy 207.91163 -16.625609) (xy 207.946689 -16.544895) (xy 207.988942 -16.467703) (xy 208.03804 -16.394674)
			(xy 208.093576 -16.326412) (xy 208.155088 -16.263482) (xy 208.222069 -16.206408) (xy 208.293962 -16.15566)
			(xy 208.370171 -16.11166) (xy 208.450066 -16.074773) (xy 208.532985 -16.045304) (xy 208.61824 -16.023497)
			(xy 208.705124 -16.009533) (xy 208.792918 -16.003527) (xy 208.880895 -16.005531) (xy 208.968325 -16.015526)
			(xy 209.054484 -16.03343) (xy 209.138658 -16.059094) (xy 209.220149 -16.092307) (xy 209.298283 -16.132793)
			(xy 209.372411 -16.180215) (xy 209.441919 -16.234182) (xy 209.506233 -16.294247) (xy 209.564817 -16.359911)
			(xy 209.617188 -16.43063) (xy 209.662911 -16.505818) (xy 209.701608 -16.584853) (xy 209.732957 -16.667079)
			(xy 209.756699 -16.751815) (xy 209.772637 -16.838359) (xy 209.780639 -16.925994) (xy 209.78114 -16.969994)
			(xy 245.948207 -16.969994) (xy 245.952212 -16.882086) (xy 245.964195 -16.794906) (xy 245.984055 -16.709177)
			(xy 246.01163 -16.625609) (xy 246.046689 -16.544895) (xy 246.088942 -16.467703) (xy 246.13804 -16.394674)
			(xy 246.193576 -16.326412) (xy 246.255088 -16.263482) (xy 246.322069 -16.206408) (xy 246.393962 -16.15566)
			(xy 246.470171 -16.11166) (xy 246.550066 -16.074773) (xy 246.632985 -16.045304) (xy 246.71824 -16.023497)
			(xy 246.805124 -16.009533) (xy 246.892918 -16.003527) (xy 246.980895 -16.005531) (xy 247.068325 -16.015526)
			(xy 247.154484 -16.03343) (xy 247.238658 -16.059094) (xy 247.320149 -16.092307) (xy 247.398283 -16.132793)
			(xy 247.472411 -16.180215) (xy 247.541919 -16.234182) (xy 247.606233 -16.294247) (xy 247.664817 -16.359911)
			(xy 247.717188 -16.43063) (xy 247.762911 -16.505818) (xy 247.801608 -16.584853) (xy 247.832957 -16.667079)
			(xy 247.856699 -16.751815) (xy 247.872637 -16.838359) (xy 247.880639 -16.925994) (xy 247.88114 -16.969994)
			(xy 271.948155 -16.969994) (xy 271.95216 -16.882086) (xy 271.964143 -16.794906) (xy 271.984003 -16.709177)
			(xy 272.011578 -16.625609) (xy 272.046637 -16.544895) (xy 272.08889 -16.467703) (xy 272.137988 -16.394674)
			(xy 272.193524 -16.326412) (xy 272.255036 -16.263482) (xy 272.322017 -16.206408) (xy 272.39391 -16.15566)
			(xy 272.470119 -16.11166) (xy 272.550014 -16.074773) (xy 272.632933 -16.045304) (xy 272.718188 -16.023497)
			(xy 272.805072 -16.009533) (xy 272.892866 -16.003527) (xy 272.980843 -16.005531) (xy 273.068273 -16.015526)
			(xy 273.154432 -16.03343) (xy 273.238606 -16.059094) (xy 273.320097 -16.092307) (xy 273.398231 -16.132793)
			(xy 273.472359 -16.180215) (xy 273.541867 -16.234182) (xy 273.606181 -16.294247) (xy 273.664765 -16.359911)
			(xy 273.717136 -16.43063) (xy 273.762859 -16.505818) (xy 273.801556 -16.584853) (xy 273.832905 -16.667079)
			(xy 273.856647 -16.751815) (xy 273.872585 -16.838359) (xy 273.880587 -16.925994) (xy 273.881088 -16.969994)
			(xy 297.948103 -16.969994) (xy 297.952108 -16.882086) (xy 297.964091 -16.794906) (xy 297.983951 -16.709177)
			(xy 298.011526 -16.625609) (xy 298.046585 -16.544895) (xy 298.088838 -16.467703) (xy 298.137936 -16.394674)
			(xy 298.193472 -16.326412) (xy 298.254984 -16.263482) (xy 298.321965 -16.206408) (xy 298.393858 -16.15566)
			(xy 298.470067 -16.11166) (xy 298.549962 -16.074773) (xy 298.632881 -16.045304) (xy 298.718136 -16.023497)
			(xy 298.80502 -16.009533) (xy 298.892814 -16.003527) (xy 298.980791 -16.005531) (xy 299.068221 -16.015526)
			(xy 299.15438 -16.03343) (xy 299.238554 -16.059094) (xy 299.320045 -16.092307) (xy 299.398179 -16.132793)
			(xy 299.472307 -16.180215) (xy 299.541815 -16.234182) (xy 299.606129 -16.294247) (xy 299.664713 -16.359911)
			(xy 299.717084 -16.43063) (xy 299.762807 -16.505818) (xy 299.801504 -16.584853) (xy 299.832853 -16.667079)
			(xy 299.856595 -16.751815) (xy 299.872533 -16.838359) (xy 299.880535 -16.925994) (xy 299.881036 -16.969994)
			(xy 323.948051 -16.969994) (xy 323.952056 -16.882086) (xy 323.964039 -16.794906) (xy 323.983899 -16.709177)
			(xy 324.011474 -16.625609) (xy 324.046533 -16.544895) (xy 324.088786 -16.467703) (xy 324.137884 -16.394674)
			(xy 324.19342 -16.326412) (xy 324.254932 -16.263482) (xy 324.321913 -16.206408) (xy 324.393806 -16.15566)
			(xy 324.470015 -16.11166) (xy 324.54991 -16.074773) (xy 324.632829 -16.045304) (xy 324.718084 -16.023497)
			(xy 324.804968 -16.009533) (xy 324.892762 -16.003527) (xy 324.980739 -16.005531) (xy 325.068169 -16.015526)
			(xy 325.154328 -16.03343) (xy 325.238502 -16.059094) (xy 325.319993 -16.092307) (xy 325.398127 -16.132793)
			(xy 325.472255 -16.180215) (xy 325.541763 -16.234182) (xy 325.606077 -16.294247) (xy 325.664661 -16.359911)
			(xy 325.717032 -16.43063) (xy 325.762755 -16.505818) (xy 325.801452 -16.584853) (xy 325.832801 -16.667079)
			(xy 325.856543 -16.751815) (xy 325.872481 -16.838359) (xy 325.880483 -16.925994) (xy 325.880984 -16.969994)
			(xy 362.048305 -16.969994) (xy 362.05231 -16.882086) (xy 362.064293 -16.794906) (xy 362.084153 -16.709177)
			(xy 362.111728 -16.625609) (xy 362.146787 -16.544895) (xy 362.18904 -16.467703) (xy 362.238138 -16.394674)
			(xy 362.293674 -16.326412) (xy 362.355186 -16.263482) (xy 362.422167 -16.206408) (xy 362.49406 -16.15566)
			(xy 362.570269 -16.11166) (xy 362.650164 -16.074773) (xy 362.733083 -16.045304) (xy 362.818338 -16.023497)
			(xy 362.905222 -16.009533) (xy 362.993016 -16.003527) (xy 363.080993 -16.005531) (xy 363.168423 -16.015526)
			(xy 363.254582 -16.03343) (xy 363.338756 -16.059094) (xy 363.420247 -16.092307) (xy 363.498381 -16.132793)
			(xy 363.572509 -16.180215) (xy 363.642017 -16.234182) (xy 363.706331 -16.294247) (xy 363.764915 -16.359911)
			(xy 363.817286 -16.43063) (xy 363.863009 -16.505818) (xy 363.901706 -16.584853) (xy 363.933055 -16.667079)
			(xy 363.956797 -16.751815) (xy 363.972735 -16.838359) (xy 363.980737 -16.925994) (xy 363.981238 -16.969994)
			(xy 388.048253 -16.969994) (xy 388.052258 -16.882086) (xy 388.064241 -16.794906) (xy 388.084101 -16.709177)
			(xy 388.111676 -16.625609) (xy 388.146735 -16.544895) (xy 388.188988 -16.467703) (xy 388.238086 -16.394674)
			(xy 388.293622 -16.326412) (xy 388.355134 -16.263482) (xy 388.422115 -16.206408) (xy 388.494008 -16.15566)
			(xy 388.570217 -16.11166) (xy 388.650112 -16.074773) (xy 388.733031 -16.045304) (xy 388.818286 -16.023497)
			(xy 388.90517 -16.009533) (xy 388.992964 -16.003527) (xy 389.080941 -16.005531) (xy 389.168371 -16.015526)
			(xy 389.25453 -16.03343) (xy 389.338704 -16.059094) (xy 389.420195 -16.092307) (xy 389.498329 -16.132793)
			(xy 389.572457 -16.180215) (xy 389.641965 -16.234182) (xy 389.706279 -16.294247) (xy 389.764863 -16.359911)
			(xy 389.817234 -16.43063) (xy 389.862957 -16.505818) (xy 389.901654 -16.584853) (xy 389.933003 -16.667079)
			(xy 389.956745 -16.751815) (xy 389.972683 -16.838359) (xy 389.980685 -16.925994) (xy 389.981186 -16.969994)
			(xy 414.048201 -16.969994) (xy 414.052206 -16.882086) (xy 414.064189 -16.794906) (xy 414.084049 -16.709177)
			(xy 414.111624 -16.625609) (xy 414.146683 -16.544895) (xy 414.188936 -16.467703) (xy 414.238034 -16.394674)
			(xy 414.29357 -16.326412) (xy 414.355082 -16.263482) (xy 414.422063 -16.206408) (xy 414.493956 -16.15566)
			(xy 414.570165 -16.11166) (xy 414.65006 -16.074773) (xy 414.732979 -16.045304) (xy 414.818234 -16.023497)
			(xy 414.905118 -16.009533) (xy 414.992912 -16.003527) (xy 415.080889 -16.005531) (xy 415.168319 -16.015526)
			(xy 415.254478 -16.03343) (xy 415.338652 -16.059094) (xy 415.420143 -16.092307) (xy 415.498277 -16.132793)
			(xy 415.572405 -16.180215) (xy 415.641913 -16.234182) (xy 415.706227 -16.294247) (xy 415.764811 -16.359911)
			(xy 415.817182 -16.43063) (xy 415.862905 -16.505818) (xy 415.901602 -16.584853) (xy 415.932951 -16.667079)
			(xy 415.956693 -16.751815) (xy 415.972631 -16.838359) (xy 415.980633 -16.925994) (xy 415.981134 -16.969994)
			(xy 440.048149 -16.969994) (xy 440.052154 -16.882086) (xy 440.064137 -16.794906) (xy 440.083997 -16.709177)
			(xy 440.111572 -16.625609) (xy 440.146631 -16.544895) (xy 440.188884 -16.467703) (xy 440.237982 -16.394674)
			(xy 440.293518 -16.326412) (xy 440.35503 -16.263482) (xy 440.422011 -16.206408) (xy 440.493904 -16.15566)
			(xy 440.570113 -16.11166) (xy 440.650008 -16.074773) (xy 440.732927 -16.045304) (xy 440.818182 -16.023497)
			(xy 440.905066 -16.009533) (xy 440.99286 -16.003527) (xy 441.080837 -16.005531) (xy 441.168267 -16.015526)
			(xy 441.254426 -16.03343) (xy 441.3386 -16.059094) (xy 441.420091 -16.092307) (xy 441.498225 -16.132793)
			(xy 441.572353 -16.180215) (xy 441.641861 -16.234182) (xy 441.706175 -16.294247) (xy 441.764759 -16.359911)
			(xy 441.81713 -16.43063) (xy 441.862853 -16.505818) (xy 441.90155 -16.584853) (xy 441.932899 -16.667079)
			(xy 441.956641 -16.751815) (xy 441.972579 -16.838359) (xy 441.980581 -16.925994) (xy 441.981082 -16.969994)
			(xy 441.980581 -17.013994) (xy 441.972579 -17.101629) (xy 441.956641 -17.188173) (xy 441.932899 -17.272909)
			(xy 441.90155 -17.355135) (xy 441.862853 -17.43417) (xy 441.81713 -17.509358) (xy 441.764759 -17.580077)
			(xy 441.706175 -17.645741) (xy 441.641861 -17.705806) (xy 441.572353 -17.759773) (xy 441.498225 -17.807195)
			(xy 441.420091 -17.847681) (xy 441.3386 -17.880894) (xy 441.254426 -17.906558) (xy 441.168267 -17.924462)
			(xy 441.080837 -17.934457) (xy 440.99286 -17.936461) (xy 440.905066 -17.930455) (xy 440.818182 -17.916491)
			(xy 440.732927 -17.894684) (xy 440.650008 -17.865215) (xy 440.570113 -17.828328) (xy 440.493904 -17.784328)
			(xy 440.422011 -17.73358) (xy 440.35503 -17.676506) (xy 440.293518 -17.613576) (xy 440.237982 -17.545314)
			(xy 440.188884 -17.472285) (xy 440.146631 -17.395093) (xy 440.111572 -17.314379) (xy 440.083997 -17.230811)
			(xy 440.064137 -17.145082) (xy 440.052154 -17.057902) (xy 440.048149 -16.969994) (xy 415.981134 -16.969994)
			(xy 415.980633 -17.013994) (xy 415.972631 -17.101629) (xy 415.956693 -17.188173) (xy 415.932951 -17.272909)
			(xy 415.901602 -17.355135) (xy 415.862905 -17.43417) (xy 415.817182 -17.509358) (xy 415.764811 -17.580077)
			(xy 415.706227 -17.645741) (xy 415.641913 -17.705806) (xy 415.572405 -17.759773) (xy 415.498277 -17.807195)
			(xy 415.420143 -17.847681) (xy 415.338652 -17.880894) (xy 415.254478 -17.906558) (xy 415.168319 -17.924462)
			(xy 415.080889 -17.934457) (xy 414.992912 -17.936461) (xy 414.905118 -17.930455) (xy 414.818234 -17.916491)
			(xy 414.732979 -17.894684) (xy 414.65006 -17.865215) (xy 414.570165 -17.828328) (xy 414.493956 -17.784328)
			(xy 414.422063 -17.73358) (xy 414.355082 -17.676506) (xy 414.29357 -17.613576) (xy 414.238034 -17.545314)
			(xy 414.188936 -17.472285) (xy 414.146683 -17.395093) (xy 414.111624 -17.314379) (xy 414.084049 -17.230811)
			(xy 414.064189 -17.145082) (xy 414.052206 -17.057902) (xy 414.048201 -16.969994) (xy 389.981186 -16.969994)
			(xy 389.980685 -17.013994) (xy 389.972683 -17.101629) (xy 389.956745 -17.188173) (xy 389.933003 -17.272909)
			(xy 389.901654 -17.355135) (xy 389.862957 -17.43417) (xy 389.817234 -17.509358) (xy 389.764863 -17.580077)
			(xy 389.706279 -17.645741) (xy 389.641965 -17.705806) (xy 389.572457 -17.759773) (xy 389.498329 -17.807195)
			(xy 389.420195 -17.847681) (xy 389.338704 -17.880894) (xy 389.25453 -17.906558) (xy 389.168371 -17.924462)
			(xy 389.080941 -17.934457) (xy 388.992964 -17.936461) (xy 388.90517 -17.930455) (xy 388.818286 -17.916491)
			(xy 388.733031 -17.894684) (xy 388.650112 -17.865215) (xy 388.570217 -17.828328) (xy 388.494008 -17.784328)
			(xy 388.422115 -17.73358) (xy 388.355134 -17.676506) (xy 388.293622 -17.613576) (xy 388.238086 -17.545314)
			(xy 388.188988 -17.472285) (xy 388.146735 -17.395093) (xy 388.111676 -17.314379) (xy 388.084101 -17.230811)
			(xy 388.064241 -17.145082) (xy 388.052258 -17.057902) (xy 388.048253 -16.969994) (xy 363.981238 -16.969994)
			(xy 363.980737 -17.013994) (xy 363.972735 -17.101629) (xy 363.956797 -17.188173) (xy 363.933055 -17.272909)
			(xy 363.901706 -17.355135) (xy 363.863009 -17.43417) (xy 363.817286 -17.509358) (xy 363.764915 -17.580077)
			(xy 363.706331 -17.645741) (xy 363.642017 -17.705806) (xy 363.572509 -17.759773) (xy 363.498381 -17.807195)
			(xy 363.420247 -17.847681) (xy 363.338756 -17.880894) (xy 363.254582 -17.906558) (xy 363.168423 -17.924462)
			(xy 363.080993 -17.934457) (xy 362.993016 -17.936461) (xy 362.905222 -17.930455) (xy 362.818338 -17.916491)
			(xy 362.733083 -17.894684) (xy 362.650164 -17.865215) (xy 362.570269 -17.828328) (xy 362.49406 -17.784328)
			(xy 362.422167 -17.73358) (xy 362.355186 -17.676506) (xy 362.293674 -17.613576) (xy 362.238138 -17.545314)
			(xy 362.18904 -17.472285) (xy 362.146787 -17.395093) (xy 362.111728 -17.314379) (xy 362.084153 -17.230811)
			(xy 362.064293 -17.145082) (xy 362.05231 -17.057902) (xy 362.048305 -16.969994) (xy 325.880984 -16.969994)
			(xy 325.880483 -17.013994) (xy 325.872481 -17.101629) (xy 325.856543 -17.188173) (xy 325.832801 -17.272909)
			(xy 325.801452 -17.355135) (xy 325.762755 -17.43417) (xy 325.717032 -17.509358) (xy 325.664661 -17.580077)
			(xy 325.606077 -17.645741) (xy 325.541763 -17.705806) (xy 325.472255 -17.759773) (xy 325.398127 -17.807195)
			(xy 325.319993 -17.847681) (xy 325.238502 -17.880894) (xy 325.154328 -17.906558) (xy 325.068169 -17.924462)
			(xy 324.980739 -17.934457) (xy 324.892762 -17.936461) (xy 324.804968 -17.930455) (xy 324.718084 -17.916491)
			(xy 324.632829 -17.894684) (xy 324.54991 -17.865215) (xy 324.470015 -17.828328) (xy 324.393806 -17.784328)
			(xy 324.321913 -17.73358) (xy 324.254932 -17.676506) (xy 324.19342 -17.613576) (xy 324.137884 -17.545314)
			(xy 324.088786 -17.472285) (xy 324.046533 -17.395093) (xy 324.011474 -17.314379) (xy 323.983899 -17.230811)
			(xy 323.964039 -17.145082) (xy 323.952056 -17.057902) (xy 323.948051 -16.969994) (xy 299.881036 -16.969994)
			(xy 299.880535 -17.013994) (xy 299.872533 -17.101629) (xy 299.856595 -17.188173) (xy 299.832853 -17.272909)
			(xy 299.801504 -17.355135) (xy 299.762807 -17.43417) (xy 299.717084 -17.509358) (xy 299.664713 -17.580077)
			(xy 299.606129 -17.645741) (xy 299.541815 -17.705806) (xy 299.472307 -17.759773) (xy 299.398179 -17.807195)
			(xy 299.320045 -17.847681) (xy 299.238554 -17.880894) (xy 299.15438 -17.906558) (xy 299.068221 -17.924462)
			(xy 298.980791 -17.934457) (xy 298.892814 -17.936461) (xy 298.80502 -17.930455) (xy 298.718136 -17.916491)
			(xy 298.632881 -17.894684) (xy 298.549962 -17.865215) (xy 298.470067 -17.828328) (xy 298.393858 -17.784328)
			(xy 298.321965 -17.73358) (xy 298.254984 -17.676506) (xy 298.193472 -17.613576) (xy 298.137936 -17.545314)
			(xy 298.088838 -17.472285) (xy 298.046585 -17.395093) (xy 298.011526 -17.314379) (xy 297.983951 -17.230811)
			(xy 297.964091 -17.145082) (xy 297.952108 -17.057902) (xy 297.948103 -16.969994) (xy 273.881088 -16.969994)
			(xy 273.880587 -17.013994) (xy 273.872585 -17.101629) (xy 273.856647 -17.188173) (xy 273.832905 -17.272909)
			(xy 273.801556 -17.355135) (xy 273.762859 -17.43417) (xy 273.717136 -17.509358) (xy 273.664765 -17.580077)
			(xy 273.606181 -17.645741) (xy 273.541867 -17.705806) (xy 273.472359 -17.759773) (xy 273.398231 -17.807195)
			(xy 273.320097 -17.847681) (xy 273.238606 -17.880894) (xy 273.154432 -17.906558) (xy 273.068273 -17.924462)
			(xy 272.980843 -17.934457) (xy 272.892866 -17.936461) (xy 272.805072 -17.930455) (xy 272.718188 -17.916491)
			(xy 272.632933 -17.894684) (xy 272.550014 -17.865215) (xy 272.470119 -17.828328) (xy 272.39391 -17.784328)
			(xy 272.322017 -17.73358) (xy 272.255036 -17.676506) (xy 272.193524 -17.613576) (xy 272.137988 -17.545314)
			(xy 272.08889 -17.472285) (xy 272.046637 -17.395093) (xy 272.011578 -17.314379) (xy 271.984003 -17.230811)
			(xy 271.964143 -17.145082) (xy 271.95216 -17.057902) (xy 271.948155 -16.969994) (xy 247.88114 -16.969994)
			(xy 247.880639 -17.013994) (xy 247.872637 -17.101629) (xy 247.856699 -17.188173) (xy 247.832957 -17.272909)
			(xy 247.801608 -17.355135) (xy 247.762911 -17.43417) (xy 247.717188 -17.509358) (xy 247.664817 -17.580077)
			(xy 247.606233 -17.645741) (xy 247.541919 -17.705806) (xy 247.472411 -17.759773) (xy 247.398283 -17.807195)
			(xy 247.320149 -17.847681) (xy 247.238658 -17.880894) (xy 247.154484 -17.906558) (xy 247.068325 -17.924462)
			(xy 246.980895 -17.934457) (xy 246.892918 -17.936461) (xy 246.805124 -17.930455) (xy 246.71824 -17.916491)
			(xy 246.632985 -17.894684) (xy 246.550066 -17.865215) (xy 246.470171 -17.828328) (xy 246.393962 -17.784328)
			(xy 246.322069 -17.73358) (xy 246.255088 -17.676506) (xy 246.193576 -17.613576) (xy 246.13804 -17.545314)
			(xy 246.088942 -17.472285) (xy 246.046689 -17.395093) (xy 246.01163 -17.314379) (xy 245.984055 -17.230811)
			(xy 245.964195 -17.145082) (xy 245.952212 -17.057902) (xy 245.948207 -16.969994) (xy 209.78114 -16.969994)
			(xy 209.780639 -17.013994) (xy 209.772637 -17.101629) (xy 209.756699 -17.188173) (xy 209.732957 -17.272909)
			(xy 209.701608 -17.355135) (xy 209.662911 -17.43417) (xy 209.617188 -17.509358) (xy 209.564817 -17.580077)
			(xy 209.506233 -17.645741) (xy 209.441919 -17.705806) (xy 209.372411 -17.759773) (xy 209.298283 -17.807195)
			(xy 209.220149 -17.847681) (xy 209.138658 -17.880894) (xy 209.054484 -17.906558) (xy 208.968325 -17.924462)
			(xy 208.880895 -17.934457) (xy 208.792918 -17.936461) (xy 208.705124 -17.930455) (xy 208.61824 -17.916491)
			(xy 208.532985 -17.894684) (xy 208.450066 -17.865215) (xy 208.370171 -17.828328) (xy 208.293962 -17.784328)
			(xy 208.222069 -17.73358) (xy 208.155088 -17.676506) (xy 208.093576 -17.613576) (xy 208.03804 -17.545314)
			(xy 207.988942 -17.472285) (xy 207.946689 -17.395093) (xy 207.91163 -17.314379) (xy 207.884055 -17.230811)
			(xy 207.864195 -17.145082) (xy 207.852212 -17.057902) (xy 207.848207 -16.969994) (xy 183.781192 -16.969994)
			(xy 183.780691 -17.013994) (xy 183.772689 -17.101629) (xy 183.756751 -17.188173) (xy 183.733009 -17.272909)
			(xy 183.70166 -17.355135) (xy 183.662963 -17.43417) (xy 183.61724 -17.509358) (xy 183.564869 -17.580077)
			(xy 183.506285 -17.645741) (xy 183.441971 -17.705806) (xy 183.372463 -17.759773) (xy 183.298335 -17.807195)
			(xy 183.220201 -17.847681) (xy 183.13871 -17.880894) (xy 183.054536 -17.906558) (xy 182.968377 -17.924462)
			(xy 182.880947 -17.934457) (xy 182.79297 -17.936461) (xy 182.705176 -17.930455) (xy 182.618292 -17.916491)
			(xy 182.533037 -17.894684) (xy 182.450118 -17.865215) (xy 182.370223 -17.828328) (xy 182.294014 -17.784328)
			(xy 182.222121 -17.73358) (xy 182.15514 -17.676506) (xy 182.093628 -17.613576) (xy 182.038092 -17.545314)
			(xy 181.988994 -17.472285) (xy 181.946741 -17.395093) (xy 181.911682 -17.314379) (xy 181.884107 -17.230811)
			(xy 181.864247 -17.145082) (xy 181.852264 -17.057902) (xy 181.848259 -16.969994) (xy 157.781244 -16.969994)
			(xy 157.780743 -17.013994) (xy 157.772741 -17.101629) (xy 157.756803 -17.188173) (xy 157.733061 -17.272909)
			(xy 157.701712 -17.355135) (xy 157.663015 -17.43417) (xy 157.617292 -17.509358) (xy 157.564921 -17.580077)
			(xy 157.506337 -17.645741) (xy 157.442023 -17.705806) (xy 157.372515 -17.759773) (xy 157.298387 -17.807195)
			(xy 157.220253 -17.847681) (xy 157.138762 -17.880894) (xy 157.054588 -17.906558) (xy 156.968429 -17.924462)
			(xy 156.880999 -17.934457) (xy 156.793022 -17.936461) (xy 156.705228 -17.930455) (xy 156.618344 -17.916491)
			(xy 156.533089 -17.894684) (xy 156.45017 -17.865215) (xy 156.370275 -17.828328) (xy 156.294066 -17.784328)
			(xy 156.222173 -17.73358) (xy 156.155192 -17.676506) (xy 156.09368 -17.613576) (xy 156.038144 -17.545314)
			(xy 155.989046 -17.472285) (xy 155.946793 -17.395093) (xy 155.911734 -17.314379) (xy 155.884159 -17.230811)
			(xy 155.864299 -17.145082) (xy 155.852316 -17.057902) (xy 155.848311 -16.969994) (xy 131.781296 -16.969994)
			(xy 131.780795 -17.013994) (xy 131.772793 -17.101629) (xy 131.756855 -17.188173) (xy 131.733113 -17.272909)
			(xy 131.701764 -17.355135) (xy 131.663067 -17.43417) (xy 131.617344 -17.509358) (xy 131.564973 -17.580077)
			(xy 131.506389 -17.645741) (xy 131.442075 -17.705806) (xy 131.372567 -17.759773) (xy 131.298439 -17.807195)
			(xy 131.220305 -17.847681) (xy 131.138814 -17.880894) (xy 131.05464 -17.906558) (xy 130.968481 -17.924462)
			(xy 130.881051 -17.934457) (xy 130.793074 -17.936461) (xy 130.70528 -17.930455) (xy 130.618396 -17.916491)
			(xy 130.533141 -17.894684) (xy 130.450222 -17.865215) (xy 130.370327 -17.828328) (xy 130.294118 -17.784328)
			(xy 130.222225 -17.73358) (xy 130.155244 -17.676506) (xy 130.093732 -17.613576) (xy 130.038196 -17.545314)
			(xy 129.989098 -17.472285) (xy 129.946845 -17.395093) (xy 129.911786 -17.314379) (xy 129.884211 -17.230811)
			(xy 129.864351 -17.145082) (xy 129.852368 -17.057902) (xy 129.848363 -16.969994) (xy 93.681042 -16.969994)
			(xy 93.680541 -17.013994) (xy 93.672539 -17.101629) (xy 93.656601 -17.188173) (xy 93.632859 -17.272909)
			(xy 93.60151 -17.355135) (xy 93.562813 -17.43417) (xy 93.51709 -17.509358) (xy 93.464719 -17.580077)
			(xy 93.406135 -17.645741) (xy 93.341821 -17.705806) (xy 93.272313 -17.759773) (xy 93.198185 -17.807195)
			(xy 93.120051 -17.847681) (xy 93.03856 -17.880894) (xy 92.954386 -17.906558) (xy 92.868227 -17.924462)
			(xy 92.780797 -17.934457) (xy 92.69282 -17.936461) (xy 92.605026 -17.930455) (xy 92.518142 -17.916491)
			(xy 92.432887 -17.894684) (xy 92.349968 -17.865215) (xy 92.270073 -17.828328) (xy 92.193864 -17.784328)
			(xy 92.121971 -17.73358) (xy 92.05499 -17.676506) (xy 91.993478 -17.613576) (xy 91.937942 -17.545314)
			(xy 91.888844 -17.472285) (xy 91.846591 -17.395093) (xy 91.811532 -17.314379) (xy 91.783957 -17.230811)
			(xy 91.764097 -17.145082) (xy 91.752114 -17.057902) (xy 91.748109 -16.969994) (xy 67.681094 -16.969994)
			(xy 67.680593 -17.013994) (xy 67.672591 -17.101629) (xy 67.656653 -17.188173) (xy 67.632911 -17.272909)
			(xy 67.601562 -17.355135) (xy 67.562865 -17.43417) (xy 67.517142 -17.509358) (xy 67.464771 -17.580077)
			(xy 67.406187 -17.645741) (xy 67.341873 -17.705806) (xy 67.272365 -17.759773) (xy 67.198237 -17.807195)
			(xy 67.120103 -17.847681) (xy 67.038612 -17.880894) (xy 66.954438 -17.906558) (xy 66.868279 -17.924462)
			(xy 66.780849 -17.934457) (xy 66.692872 -17.936461) (xy 66.605078 -17.930455) (xy 66.518194 -17.916491)
			(xy 66.432939 -17.894684) (xy 66.35002 -17.865215) (xy 66.270125 -17.828328) (xy 66.193916 -17.784328)
			(xy 66.122023 -17.73358) (xy 66.055042 -17.676506) (xy 65.99353 -17.613576) (xy 65.937994 -17.545314)
			(xy 65.888896 -17.472285) (xy 65.846643 -17.395093) (xy 65.811584 -17.314379) (xy 65.784009 -17.230811)
			(xy 65.764149 -17.145082) (xy 65.752166 -17.057902) (xy 65.748161 -16.969994) (xy 41.681146 -16.969994)
			(xy 41.680645 -17.013994) (xy 41.672643 -17.101629) (xy 41.656705 -17.188173) (xy 41.632963 -17.272909)
			(xy 41.601614 -17.355135) (xy 41.562917 -17.43417) (xy 41.517194 -17.509358) (xy 41.464823 -17.580077)
			(xy 41.406239 -17.645741) (xy 41.341925 -17.705806) (xy 41.272417 -17.759773) (xy 41.198289 -17.807195)
			(xy 41.120155 -17.847681) (xy 41.038664 -17.880894) (xy 40.95449 -17.906558) (xy 40.868331 -17.924462)
			(xy 40.780901 -17.934457) (xy 40.692924 -17.936461) (xy 40.60513 -17.930455) (xy 40.518246 -17.916491)
			(xy 40.432991 -17.894684) (xy 40.350072 -17.865215) (xy 40.270177 -17.828328) (xy 40.193968 -17.784328)
			(xy 40.122075 -17.73358) (xy 40.055094 -17.676506) (xy 39.993582 -17.613576) (xy 39.938046 -17.545314)
			(xy 39.888948 -17.472285) (xy 39.846695 -17.395093) (xy 39.811636 -17.314379) (xy 39.784061 -17.230811)
			(xy 39.764201 -17.145082) (xy 39.752218 -17.057902) (xy 39.748213 -16.969994) (xy 15.681198 -16.969994)
			(xy 15.680697 -17.013994) (xy 15.672695 -17.101629) (xy 15.656757 -17.188173) (xy 15.633015 -17.272909)
			(xy 15.601666 -17.355135) (xy 15.562969 -17.43417) (xy 15.517246 -17.509358) (xy 15.464875 -17.580077)
			(xy 15.406291 -17.645741) (xy 15.341977 -17.705806) (xy 15.272469 -17.759773) (xy 15.198341 -17.807195)
			(xy 15.120207 -17.847681) (xy 15.038716 -17.880894) (xy 14.954542 -17.906558) (xy 14.868383 -17.924462)
			(xy 14.780953 -17.934457) (xy 14.692976 -17.936461) (xy 14.605182 -17.930455) (xy 14.518298 -17.916491)
			(xy 14.433043 -17.894684) (xy 14.350124 -17.865215) (xy 14.270229 -17.828328) (xy 14.19402 -17.784328)
			(xy 14.122127 -17.73358) (xy 14.055146 -17.676506) (xy 13.993634 -17.613576) (xy 13.938098 -17.545314)
			(xy 13.889 -17.472285) (xy 13.846747 -17.395093) (xy 13.811688 -17.314379) (xy 13.784113 -17.230811)
			(xy 13.764253 -17.145082) (xy 13.75227 -17.057902) (xy 13.748265 -16.969994) (xy 0.508 -16.969994)
			(xy 0.508 -27.342846) (xy 16.523716 -27.342846) (xy 16.523716 -26.479246) (xy 16.524206 -26.449278)
			(xy 16.532029 -26.389856) (xy 16.547542 -26.331963) (xy 16.570478 -26.27659) (xy 16.600445 -26.224684)
			(xy 16.636932 -26.177134) (xy 16.679312 -26.134754) (xy 16.726862 -26.098267) (xy 16.778768 -26.0683)
			(xy 16.834141 -26.045364) (xy 16.892034 -26.029851) (xy 16.951456 -26.022028) (xy 17.011392 -26.022028)
			(xy 17.070814 -26.029851) (xy 17.128707 -26.045364) (xy 17.18408 -26.0683) (xy 17.235986 -26.098267)
			(xy 17.283536 -26.134754) (xy 17.325916 -26.177134) (xy 17.362403 -26.224684) (xy 17.39237 -26.27659)
			(xy 17.415306 -26.331963) (xy 17.430819 -26.389856) (xy 17.438642 -26.449278) (xy 17.439132 -26.479246)
			(xy 17.439132 -27.342846) (xy 42.523664 -27.342846) (xy 42.523664 -26.479246) (xy 42.524154 -26.449278)
			(xy 42.531977 -26.389856) (xy 42.54749 -26.331963) (xy 42.570426 -26.27659) (xy 42.600393 -26.224684)
			(xy 42.63688 -26.177134) (xy 42.67926 -26.134754) (xy 42.72681 -26.098267) (xy 42.778716 -26.0683)
			(xy 42.834089 -26.045364) (xy 42.891982 -26.029851) (xy 42.951404 -26.022028) (xy 43.01134 -26.022028)
			(xy 43.070762 -26.029851) (xy 43.128655 -26.045364) (xy 43.184028 -26.0683) (xy 43.235934 -26.098267)
			(xy 43.283484 -26.134754) (xy 43.325864 -26.177134) (xy 43.362351 -26.224684) (xy 43.392318 -26.27659)
			(xy 43.415254 -26.331963) (xy 43.430767 -26.389856) (xy 43.43859 -26.449278) (xy 43.43908 -26.479246)
			(xy 43.43908 -27.342846) (xy 68.523612 -27.342846) (xy 68.523612 -26.479246) (xy 68.524102 -26.449278)
			(xy 68.531925 -26.389856) (xy 68.547438 -26.331963) (xy 68.570374 -26.27659) (xy 68.600341 -26.224684)
			(xy 68.636828 -26.177134) (xy 68.679208 -26.134754) (xy 68.726758 -26.098267) (xy 68.778664 -26.0683)
			(xy 68.834037 -26.045364) (xy 68.89193 -26.029851) (xy 68.951352 -26.022028) (xy 69.011288 -26.022028)
			(xy 69.07071 -26.029851) (xy 69.128603 -26.045364) (xy 69.183976 -26.0683) (xy 69.235882 -26.098267)
			(xy 69.283432 -26.134754) (xy 69.325812 -26.177134) (xy 69.362299 -26.224684) (xy 69.392266 -26.27659)
			(xy 69.415202 -26.331963) (xy 69.430715 -26.389856) (xy 69.438538 -26.449278) (xy 69.439028 -26.479246)
			(xy 69.439028 -27.342846) (xy 94.52356 -27.342846) (xy 94.52356 -26.479246) (xy 94.52405 -26.449278)
			(xy 94.531873 -26.389856) (xy 94.547386 -26.331963) (xy 94.570322 -26.27659) (xy 94.600289 -26.224684)
			(xy 94.636776 -26.177134) (xy 94.679156 -26.134754) (xy 94.726706 -26.098267) (xy 94.778612 -26.0683)
			(xy 94.833985 -26.045364) (xy 94.891878 -26.029851) (xy 94.9513 -26.022028) (xy 95.011236 -26.022028)
			(xy 95.070658 -26.029851) (xy 95.128551 -26.045364) (xy 95.183924 -26.0683) (xy 95.23583 -26.098267)
			(xy 95.28338 -26.134754) (xy 95.32576 -26.177134) (xy 95.362247 -26.224684) (xy 95.392214 -26.27659)
			(xy 95.41515 -26.331963) (xy 95.430663 -26.389856) (xy 95.438486 -26.449278) (xy 95.438976 -26.479246)
			(xy 95.438976 -27.342846) (xy 132.62356 -27.342846) (xy 132.62356 -26.479246) (xy 132.62405 -26.449262)
			(xy 132.631878 -26.389806) (xy 132.647399 -26.331881) (xy 132.670348 -26.276477) (xy 132.700332 -26.224543)
			(xy 132.736838 -26.176967) (xy 132.779243 -26.134562) (xy 132.826819 -26.098056) (xy 132.878753 -26.068072)
			(xy 132.934157 -26.045123) (xy 132.992082 -26.029602) (xy 133.051538 -26.021774) (xy 133.111506 -26.021774)
			(xy 133.170962 -26.029602) (xy 133.228887 -26.045123) (xy 133.284291 -26.068072) (xy 133.336225 -26.098056)
			(xy 133.383801 -26.134562) (xy 133.426206 -26.176967) (xy 133.462712 -26.224543) (xy 133.492696 -26.276477)
			(xy 133.515645 -26.331881) (xy 133.531166 -26.389806) (xy 133.538994 -26.449262) (xy 133.539484 -26.479246)
			(xy 133.539484 -27.342846) (xy 158.623508 -27.342846) (xy 158.623508 -26.479246) (xy 158.623998 -26.449262)
			(xy 158.631826 -26.389806) (xy 158.647347 -26.331881) (xy 158.670296 -26.276477) (xy 158.70028 -26.224543)
			(xy 158.736786 -26.176967) (xy 158.779191 -26.134562) (xy 158.826767 -26.098056) (xy 158.878701 -26.068072)
			(xy 158.934105 -26.045123) (xy 158.99203 -26.029602) (xy 159.051486 -26.021774) (xy 159.111454 -26.021774)
			(xy 159.17091 -26.029602) (xy 159.228835 -26.045123) (xy 159.284239 -26.068072) (xy 159.336173 -26.098056)
			(xy 159.383749 -26.134562) (xy 159.426154 -26.176967) (xy 159.46266 -26.224543) (xy 159.492644 -26.276477)
			(xy 159.515593 -26.331881) (xy 159.531114 -26.389806) (xy 159.538942 -26.449262) (xy 159.539432 -26.479246)
			(xy 159.539432 -27.342846) (xy 184.623456 -27.342846) (xy 184.623456 -26.479246) (xy 184.623946 -26.449262)
			(xy 184.631774 -26.389806) (xy 184.647295 -26.331881) (xy 184.670244 -26.276477) (xy 184.700228 -26.224543)
			(xy 184.736734 -26.176967) (xy 184.779139 -26.134562) (xy 184.826715 -26.098056) (xy 184.878649 -26.068072)
			(xy 184.934053 -26.045123) (xy 184.991978 -26.029602) (xy 185.051434 -26.021774) (xy 185.111402 -26.021774)
			(xy 185.170858 -26.029602) (xy 185.228783 -26.045123) (xy 185.284187 -26.068072) (xy 185.336121 -26.098056)
			(xy 185.383697 -26.134562) (xy 185.426102 -26.176967) (xy 185.462608 -26.224543) (xy 185.492592 -26.276477)
			(xy 185.515541 -26.331881) (xy 185.531062 -26.389806) (xy 185.53889 -26.449262) (xy 185.53938 -26.479246)
			(xy 185.53938 -27.342846) (xy 210.623404 -27.342846) (xy 210.623404 -26.479246) (xy 210.623894 -26.449262)
			(xy 210.631722 -26.389806) (xy 210.647243 -26.331881) (xy 210.670192 -26.276477) (xy 210.700176 -26.224543)
			(xy 210.736682 -26.176967) (xy 210.779087 -26.134562) (xy 210.826663 -26.098056) (xy 210.878597 -26.068072)
			(xy 210.934001 -26.045123) (xy 210.991926 -26.029602) (xy 211.051382 -26.021774) (xy 211.11135 -26.021774)
			(xy 211.170806 -26.029602) (xy 211.228731 -26.045123) (xy 211.284135 -26.068072) (xy 211.336069 -26.098056)
			(xy 211.383645 -26.134562) (xy 211.42605 -26.176967) (xy 211.462556 -26.224543) (xy 211.49254 -26.276477)
			(xy 211.515489 -26.331881) (xy 211.53101 -26.389806) (xy 211.538838 -26.449262) (xy 211.539328 -26.479246)
			(xy 211.539328 -27.342846) (xy 248.723404 -27.342846) (xy 248.723404 -26.479246) (xy 248.723894 -26.449262)
			(xy 248.731722 -26.389806) (xy 248.747243 -26.331881) (xy 248.770192 -26.276477) (xy 248.800176 -26.224543)
			(xy 248.836682 -26.176967) (xy 248.879087 -26.134562) (xy 248.926663 -26.098056) (xy 248.978597 -26.068072)
			(xy 249.034001 -26.045123) (xy 249.091926 -26.029602) (xy 249.151382 -26.021774) (xy 249.21135 -26.021774)
			(xy 249.270806 -26.029602) (xy 249.328731 -26.045123) (xy 249.384135 -26.068072) (xy 249.436069 -26.098056)
			(xy 249.483645 -26.134562) (xy 249.52605 -26.176967) (xy 249.562556 -26.224543) (xy 249.59254 -26.276477)
			(xy 249.615489 -26.331881) (xy 249.63101 -26.389806) (xy 249.638838 -26.449262) (xy 249.639328 -26.479246)
			(xy 249.639328 -27.342846) (xy 274.723352 -27.342846) (xy 274.723352 -26.479246) (xy 274.723842 -26.449262)
			(xy 274.73167 -26.389806) (xy 274.747191 -26.331881) (xy 274.77014 -26.276477) (xy 274.800124 -26.224543)
			(xy 274.83663 -26.176967) (xy 274.879035 -26.134562) (xy 274.926611 -26.098056) (xy 274.978545 -26.068072)
			(xy 275.033949 -26.045123) (xy 275.091874 -26.029602) (xy 275.15133 -26.021774) (xy 275.211298 -26.021774)
			(xy 275.270754 -26.029602) (xy 275.328679 -26.045123) (xy 275.384083 -26.068072) (xy 275.436017 -26.098056)
			(xy 275.483593 -26.134562) (xy 275.525998 -26.176967) (xy 275.562504 -26.224543) (xy 275.592488 -26.276477)
			(xy 275.615437 -26.331881) (xy 275.630958 -26.389806) (xy 275.638786 -26.449262) (xy 275.639276 -26.479246)
			(xy 275.639276 -27.342846) (xy 300.7233 -27.342846) (xy 300.7233 -26.479246) (xy 300.72379 -26.449262)
			(xy 300.731618 -26.389806) (xy 300.747139 -26.331881) (xy 300.770088 -26.276477) (xy 300.800072 -26.224543)
			(xy 300.836578 -26.176967) (xy 300.878983 -26.134562) (xy 300.926559 -26.098056) (xy 300.978493 -26.068072)
			(xy 301.033897 -26.045123) (xy 301.091822 -26.029602) (xy 301.151278 -26.021774) (xy 301.211246 -26.021774)
			(xy 301.270702 -26.029602) (xy 301.328627 -26.045123) (xy 301.384031 -26.068072) (xy 301.435965 -26.098056)
			(xy 301.483541 -26.134562) (xy 301.525946 -26.176967) (xy 301.562452 -26.224543) (xy 301.592436 -26.276477)
			(xy 301.615385 -26.331881) (xy 301.630906 -26.389806) (xy 301.638734 -26.449262) (xy 301.639224 -26.479246)
			(xy 301.639224 -27.342846) (xy 326.723248 -27.342846) (xy 326.723248 -26.479246) (xy 326.723738 -26.449262)
			(xy 326.731566 -26.389806) (xy 326.747087 -26.331881) (xy 326.770036 -26.276477) (xy 326.80002 -26.224543)
			(xy 326.836526 -26.176967) (xy 326.878931 -26.134562) (xy 326.926507 -26.098056) (xy 326.978441 -26.068072)
			(xy 327.033845 -26.045123) (xy 327.09177 -26.029602) (xy 327.151226 -26.021774) (xy 327.211194 -26.021774)
			(xy 327.27065 -26.029602) (xy 327.328575 -26.045123) (xy 327.383979 -26.068072) (xy 327.435913 -26.098056)
			(xy 327.483489 -26.134562) (xy 327.525894 -26.176967) (xy 327.5624 -26.224543) (xy 327.592384 -26.276477)
			(xy 327.615333 -26.331881) (xy 327.630854 -26.389806) (xy 327.638682 -26.449262) (xy 327.639172 -26.479246)
			(xy 327.639172 -27.342846) (xy 364.823756 -27.342846) (xy 364.823756 -26.479246) (xy 364.824246 -26.449278)
			(xy 364.832069 -26.389856) (xy 364.847582 -26.331963) (xy 364.870518 -26.27659) (xy 364.900485 -26.224684)
			(xy 364.936972 -26.177134) (xy 364.979352 -26.134754) (xy 365.026902 -26.098267) (xy 365.078808 -26.0683)
			(xy 365.134181 -26.045364) (xy 365.192074 -26.029851) (xy 365.251496 -26.022028) (xy 365.311432 -26.022028)
			(xy 365.370854 -26.029851) (xy 365.428747 -26.045364) (xy 365.48412 -26.0683) (xy 365.536026 -26.098267)
			(xy 365.583576 -26.134754) (xy 365.625956 -26.177134) (xy 365.662443 -26.224684) (xy 365.69241 -26.27659)
			(xy 365.715346 -26.331963) (xy 365.730859 -26.389856) (xy 365.738682 -26.449278) (xy 365.739172 -26.479246)
			(xy 365.739172 -27.342846) (xy 390.823704 -27.342846) (xy 390.823704 -26.479246) (xy 390.824194 -26.449278)
			(xy 390.832017 -26.389856) (xy 390.84753 -26.331963) (xy 390.870466 -26.27659) (xy 390.900433 -26.224684)
			(xy 390.93692 -26.177134) (xy 390.9793 -26.134754) (xy 391.02685 -26.098267) (xy 391.078756 -26.0683)
			(xy 391.134129 -26.045364) (xy 391.192022 -26.029851) (xy 391.251444 -26.022028) (xy 391.31138 -26.022028)
			(xy 391.370802 -26.029851) (xy 391.428695 -26.045364) (xy 391.484068 -26.0683) (xy 391.535974 -26.098267)
			(xy 391.583524 -26.134754) (xy 391.625904 -26.177134) (xy 391.662391 -26.224684) (xy 391.692358 -26.27659)
			(xy 391.715294 -26.331963) (xy 391.730807 -26.389856) (xy 391.73863 -26.449278) (xy 391.73912 -26.479246)
			(xy 391.73912 -27.342846) (xy 416.823652 -27.342846) (xy 416.823652 -26.479246) (xy 416.824142 -26.449278)
			(xy 416.831965 -26.389856) (xy 416.847478 -26.331963) (xy 416.870414 -26.27659) (xy 416.900381 -26.224684)
			(xy 416.936868 -26.177134) (xy 416.979248 -26.134754) (xy 417.026798 -26.098267) (xy 417.078704 -26.0683)
			(xy 417.134077 -26.045364) (xy 417.19197 -26.029851) (xy 417.251392 -26.022028) (xy 417.311328 -26.022028)
			(xy 417.37075 -26.029851) (xy 417.428643 -26.045364) (xy 417.484016 -26.0683) (xy 417.535922 -26.098267)
			(xy 417.583472 -26.134754) (xy 417.625852 -26.177134) (xy 417.662339 -26.224684) (xy 417.692306 -26.27659)
			(xy 417.715242 -26.331963) (xy 417.730755 -26.389856) (xy 417.738578 -26.449278) (xy 417.739068 -26.479246)
			(xy 417.739068 -27.342846) (xy 442.8236 -27.342846) (xy 442.8236 -26.479246) (xy 442.82409 -26.449278)
			(xy 442.831913 -26.389856) (xy 442.847426 -26.331963) (xy 442.870362 -26.27659) (xy 442.900329 -26.224684)
			(xy 442.936816 -26.177134) (xy 442.979196 -26.134754) (xy 443.026746 -26.098267) (xy 443.078652 -26.0683)
			(xy 443.134025 -26.045364) (xy 443.191918 -26.029851) (xy 443.25134 -26.022028) (xy 443.311276 -26.022028)
			(xy 443.370698 -26.029851) (xy 443.428591 -26.045364) (xy 443.483964 -26.0683) (xy 443.53587 -26.098267)
			(xy 443.58342 -26.134754) (xy 443.6258 -26.177134) (xy 443.662287 -26.224684) (xy 443.692254 -26.27659)
			(xy 443.71519 -26.331963) (xy 443.730703 -26.389856) (xy 443.738526 -26.449278) (xy 443.739016 -26.479246)
			(xy 443.739016 -27.342846) (xy 443.738526 -27.372814) (xy 443.730703 -27.432236) (xy 443.71519 -27.490129)
			(xy 443.692254 -27.545502) (xy 443.662287 -27.597408) (xy 443.6258 -27.644958) (xy 443.58342 -27.687338)
			(xy 443.53587 -27.723825) (xy 443.483964 -27.753792) (xy 443.428591 -27.776728) (xy 443.370698 -27.792241)
			(xy 443.311276 -27.800064) (xy 443.25134 -27.800064) (xy 443.191918 -27.792241) (xy 443.134025 -27.776728)
			(xy 443.078652 -27.753792) (xy 443.026746 -27.723825) (xy 442.979196 -27.687338) (xy 442.936816 -27.644958)
			(xy 442.900329 -27.597408) (xy 442.870362 -27.545502) (xy 442.847426 -27.490129) (xy 442.831913 -27.432236)
			(xy 442.82409 -27.372814) (xy 442.8236 -27.342846) (xy 417.739068 -27.342846) (xy 417.738578 -27.372814)
			(xy 417.730755 -27.432236) (xy 417.715242 -27.490129) (xy 417.692306 -27.545502) (xy 417.662339 -27.597408)
			(xy 417.625852 -27.644958) (xy 417.583472 -27.687338) (xy 417.535922 -27.723825) (xy 417.484016 -27.753792)
			(xy 417.428643 -27.776728) (xy 417.37075 -27.792241) (xy 417.311328 -27.800064) (xy 417.251392 -27.800064)
			(xy 417.19197 -27.792241) (xy 417.134077 -27.776728) (xy 417.078704 -27.753792) (xy 417.026798 -27.723825)
			(xy 416.979248 -27.687338) (xy 416.936868 -27.644958) (xy 416.900381 -27.597408) (xy 416.870414 -27.545502)
			(xy 416.847478 -27.490129) (xy 416.831965 -27.432236) (xy 416.824142 -27.372814) (xy 416.823652 -27.342846)
			(xy 391.73912 -27.342846) (xy 391.73863 -27.372814) (xy 391.730807 -27.432236) (xy 391.715294 -27.490129)
			(xy 391.692358 -27.545502) (xy 391.662391 -27.597408) (xy 391.625904 -27.644958) (xy 391.583524 -27.687338)
			(xy 391.535974 -27.723825) (xy 391.484068 -27.753792) (xy 391.428695 -27.776728) (xy 391.370802 -27.792241)
			(xy 391.31138 -27.800064) (xy 391.251444 -27.800064) (xy 391.192022 -27.792241) (xy 391.134129 -27.776728)
			(xy 391.078756 -27.753792) (xy 391.02685 -27.723825) (xy 390.9793 -27.687338) (xy 390.93692 -27.644958)
			(xy 390.900433 -27.597408) (xy 390.870466 -27.545502) (xy 390.84753 -27.490129) (xy 390.832017 -27.432236)
			(xy 390.824194 -27.372814) (xy 390.823704 -27.342846) (xy 365.739172 -27.342846) (xy 365.738682 -27.372814)
			(xy 365.730859 -27.432236) (xy 365.715346 -27.490129) (xy 365.69241 -27.545502) (xy 365.662443 -27.597408)
			(xy 365.625956 -27.644958) (xy 365.583576 -27.687338) (xy 365.536026 -27.723825) (xy 365.48412 -27.753792)
			(xy 365.428747 -27.776728) (xy 365.370854 -27.792241) (xy 365.311432 -27.800064) (xy 365.251496 -27.800064)
			(xy 365.192074 -27.792241) (xy 365.134181 -27.776728) (xy 365.078808 -27.753792) (xy 365.026902 -27.723825)
			(xy 364.979352 -27.687338) (xy 364.936972 -27.644958) (xy 364.900485 -27.597408) (xy 364.870518 -27.545502)
			(xy 364.847582 -27.490129) (xy 364.832069 -27.432236) (xy 364.824246 -27.372814) (xy 364.823756 -27.342846)
			(xy 327.639172 -27.342846) (xy 327.638682 -27.37283) (xy 327.630854 -27.432286) (xy 327.615333 -27.490211)
			(xy 327.592384 -27.545615) (xy 327.5624 -27.597549) (xy 327.525894 -27.645125) (xy 327.483489 -27.68753)
			(xy 327.435913 -27.724036) (xy 327.383979 -27.75402) (xy 327.328575 -27.776969) (xy 327.27065 -27.79249)
			(xy 327.211194 -27.800318) (xy 327.151226 -27.800318) (xy 327.09177 -27.79249) (xy 327.033845 -27.776969)
			(xy 326.978441 -27.75402) (xy 326.926507 -27.724036) (xy 326.878931 -27.68753) (xy 326.836526 -27.645125)
			(xy 326.80002 -27.597549) (xy 326.770036 -27.545615) (xy 326.747087 -27.490211) (xy 326.731566 -27.432286)
			(xy 326.723738 -27.37283) (xy 326.723248 -27.342846) (xy 301.639224 -27.342846) (xy 301.638734 -27.37283)
			(xy 301.630906 -27.432286) (xy 301.615385 -27.490211) (xy 301.592436 -27.545615) (xy 301.562452 -27.597549)
			(xy 301.525946 -27.645125) (xy 301.483541 -27.68753) (xy 301.435965 -27.724036) (xy 301.384031 -27.75402)
			(xy 301.328627 -27.776969) (xy 301.270702 -27.79249) (xy 301.211246 -27.800318) (xy 301.151278 -27.800318)
			(xy 301.091822 -27.79249) (xy 301.033897 -27.776969) (xy 300.978493 -27.75402) (xy 300.926559 -27.724036)
			(xy 300.878983 -27.68753) (xy 300.836578 -27.645125) (xy 300.800072 -27.597549) (xy 300.770088 -27.545615)
			(xy 300.747139 -27.490211) (xy 300.731618 -27.432286) (xy 300.72379 -27.37283) (xy 300.7233 -27.342846)
			(xy 275.639276 -27.342846) (xy 275.638786 -27.37283) (xy 275.630958 -27.432286) (xy 275.615437 -27.490211)
			(xy 275.592488 -27.545615) (xy 275.562504 -27.597549) (xy 275.525998 -27.645125) (xy 275.483593 -27.68753)
			(xy 275.436017 -27.724036) (xy 275.384083 -27.75402) (xy 275.328679 -27.776969) (xy 275.270754 -27.79249)
			(xy 275.211298 -27.800318) (xy 275.15133 -27.800318) (xy 275.091874 -27.79249) (xy 275.033949 -27.776969)
			(xy 274.978545 -27.75402) (xy 274.926611 -27.724036) (xy 274.879035 -27.68753) (xy 274.83663 -27.645125)
			(xy 274.800124 -27.597549) (xy 274.77014 -27.545615) (xy 274.747191 -27.490211) (xy 274.73167 -27.432286)
			(xy 274.723842 -27.37283) (xy 274.723352 -27.342846) (xy 249.639328 -27.342846) (xy 249.638838 -27.37283)
			(xy 249.63101 -27.432286) (xy 249.615489 -27.490211) (xy 249.59254 -27.545615) (xy 249.562556 -27.597549)
			(xy 249.52605 -27.645125) (xy 249.483645 -27.68753) (xy 249.436069 -27.724036) (xy 249.384135 -27.75402)
			(xy 249.328731 -27.776969) (xy 249.270806 -27.79249) (xy 249.21135 -27.800318) (xy 249.151382 -27.800318)
			(xy 249.091926 -27.79249) (xy 249.034001 -27.776969) (xy 248.978597 -27.75402) (xy 248.926663 -27.724036)
			(xy 248.879087 -27.68753) (xy 248.836682 -27.645125) (xy 248.800176 -27.597549) (xy 248.770192 -27.545615)
			(xy 248.747243 -27.490211) (xy 248.731722 -27.432286) (xy 248.723894 -27.37283) (xy 248.723404 -27.342846)
			(xy 211.539328 -27.342846) (xy 211.538838 -27.37283) (xy 211.53101 -27.432286) (xy 211.515489 -27.490211)
			(xy 211.49254 -27.545615) (xy 211.462556 -27.597549) (xy 211.42605 -27.645125) (xy 211.383645 -27.68753)
			(xy 211.336069 -27.724036) (xy 211.284135 -27.75402) (xy 211.228731 -27.776969) (xy 211.170806 -27.79249)
			(xy 211.11135 -27.800318) (xy 211.051382 -27.800318) (xy 210.991926 -27.79249) (xy 210.934001 -27.776969)
			(xy 210.878597 -27.75402) (xy 210.826663 -27.724036) (xy 210.779087 -27.68753) (xy 210.736682 -27.645125)
			(xy 210.700176 -27.597549) (xy 210.670192 -27.545615) (xy 210.647243 -27.490211) (xy 210.631722 -27.432286)
			(xy 210.623894 -27.37283) (xy 210.623404 -27.342846) (xy 185.53938 -27.342846) (xy 185.53889 -27.37283)
			(xy 185.531062 -27.432286) (xy 185.515541 -27.490211) (xy 185.492592 -27.545615) (xy 185.462608 -27.597549)
			(xy 185.426102 -27.645125) (xy 185.383697 -27.68753) (xy 185.336121 -27.724036) (xy 185.284187 -27.75402)
			(xy 185.228783 -27.776969) (xy 185.170858 -27.79249) (xy 185.111402 -27.800318) (xy 185.051434 -27.800318)
			(xy 184.991978 -27.79249) (xy 184.934053 -27.776969) (xy 184.878649 -27.75402) (xy 184.826715 -27.724036)
			(xy 184.779139 -27.68753) (xy 184.736734 -27.645125) (xy 184.700228 -27.597549) (xy 184.670244 -27.545615)
			(xy 184.647295 -27.490211) (xy 184.631774 -27.432286) (xy 184.623946 -27.37283) (xy 184.623456 -27.342846)
			(xy 159.539432 -27.342846) (xy 159.538942 -27.37283) (xy 159.531114 -27.432286) (xy 159.515593 -27.490211)
			(xy 159.492644 -27.545615) (xy 159.46266 -27.597549) (xy 159.426154 -27.645125) (xy 159.383749 -27.68753)
			(xy 159.336173 -27.724036) (xy 159.284239 -27.75402) (xy 159.228835 -27.776969) (xy 159.17091 -27.79249)
			(xy 159.111454 -27.800318) (xy 159.051486 -27.800318) (xy 158.99203 -27.79249) (xy 158.934105 -27.776969)
			(xy 158.878701 -27.75402) (xy 158.826767 -27.724036) (xy 158.779191 -27.68753) (xy 158.736786 -27.645125)
			(xy 158.70028 -27.597549) (xy 158.670296 -27.545615) (xy 158.647347 -27.490211) (xy 158.631826 -27.432286)
			(xy 158.623998 -27.37283) (xy 158.623508 -27.342846) (xy 133.539484 -27.342846) (xy 133.538994 -27.37283)
			(xy 133.531166 -27.432286) (xy 133.515645 -27.490211) (xy 133.492696 -27.545615) (xy 133.462712 -27.597549)
			(xy 133.426206 -27.645125) (xy 133.383801 -27.68753) (xy 133.336225 -27.724036) (xy 133.284291 -27.75402)
			(xy 133.228887 -27.776969) (xy 133.170962 -27.79249) (xy 133.111506 -27.800318) (xy 133.051538 -27.800318)
			(xy 132.992082 -27.79249) (xy 132.934157 -27.776969) (xy 132.878753 -27.75402) (xy 132.826819 -27.724036)
			(xy 132.779243 -27.68753) (xy 132.736838 -27.645125) (xy 132.700332 -27.597549) (xy 132.670348 -27.545615)
			(xy 132.647399 -27.490211) (xy 132.631878 -27.432286) (xy 132.62405 -27.37283) (xy 132.62356 -27.342846)
			(xy 95.438976 -27.342846) (xy 95.438486 -27.372814) (xy 95.430663 -27.432236) (xy 95.41515 -27.490129)
			(xy 95.392214 -27.545502) (xy 95.362247 -27.597408) (xy 95.32576 -27.644958) (xy 95.28338 -27.687338)
			(xy 95.23583 -27.723825) (xy 95.183924 -27.753792) (xy 95.128551 -27.776728) (xy 95.070658 -27.792241)
			(xy 95.011236 -27.800064) (xy 94.9513 -27.800064) (xy 94.891878 -27.792241) (xy 94.833985 -27.776728)
			(xy 94.778612 -27.753792) (xy 94.726706 -27.723825) (xy 94.679156 -27.687338) (xy 94.636776 -27.644958)
			(xy 94.600289 -27.597408) (xy 94.570322 -27.545502) (xy 94.547386 -27.490129) (xy 94.531873 -27.432236)
			(xy 94.52405 -27.372814) (xy 94.52356 -27.342846) (xy 69.439028 -27.342846) (xy 69.438538 -27.372814)
			(xy 69.430715 -27.432236) (xy 69.415202 -27.490129) (xy 69.392266 -27.545502) (xy 69.362299 -27.597408)
			(xy 69.325812 -27.644958) (xy 69.283432 -27.687338) (xy 69.235882 -27.723825) (xy 69.183976 -27.753792)
			(xy 69.128603 -27.776728) (xy 69.07071 -27.792241) (xy 69.011288 -27.800064) (xy 68.951352 -27.800064)
			(xy 68.89193 -27.792241) (xy 68.834037 -27.776728) (xy 68.778664 -27.753792) (xy 68.726758 -27.723825)
			(xy 68.679208 -27.687338) (xy 68.636828 -27.644958) (xy 68.600341 -27.597408) (xy 68.570374 -27.545502)
			(xy 68.547438 -27.490129) (xy 68.531925 -27.432236) (xy 68.524102 -27.372814) (xy 68.523612 -27.342846)
			(xy 43.43908 -27.342846) (xy 43.43859 -27.372814) (xy 43.430767 -27.432236) (xy 43.415254 -27.490129)
			(xy 43.392318 -27.545502) (xy 43.362351 -27.597408) (xy 43.325864 -27.644958) (xy 43.283484 -27.687338)
			(xy 43.235934 -27.723825) (xy 43.184028 -27.753792) (xy 43.128655 -27.776728) (xy 43.070762 -27.792241)
			(xy 43.01134 -27.800064) (xy 42.951404 -27.800064) (xy 42.891982 -27.792241) (xy 42.834089 -27.776728)
			(xy 42.778716 -27.753792) (xy 42.72681 -27.723825) (xy 42.67926 -27.687338) (xy 42.63688 -27.644958)
			(xy 42.600393 -27.597408) (xy 42.570426 -27.545502) (xy 42.54749 -27.490129) (xy 42.531977 -27.432236)
			(xy 42.524154 -27.372814) (xy 42.523664 -27.342846) (xy 17.439132 -27.342846) (xy 17.438642 -27.372814)
			(xy 17.430819 -27.432236) (xy 17.415306 -27.490129) (xy 17.39237 -27.545502) (xy 17.362403 -27.597408)
			(xy 17.325916 -27.644958) (xy 17.283536 -27.687338) (xy 17.235986 -27.723825) (xy 17.18408 -27.753792)
			(xy 17.128707 -27.776728) (xy 17.070814 -27.792241) (xy 17.011392 -27.800064) (xy 16.951456 -27.800064)
			(xy 16.892034 -27.792241) (xy 16.834141 -27.776728) (xy 16.778768 -27.753792) (xy 16.726862 -27.723825)
			(xy 16.679312 -27.687338) (xy 16.636932 -27.644958) (xy 16.600445 -27.597408) (xy 16.570478 -27.545502)
			(xy 16.547542 -27.490129) (xy 16.532029 -27.432236) (xy 16.524206 -27.372814) (xy 16.523716 -27.342846)
			(xy 0.508 -27.342846) (xy 0.508 -29.12237) (xy 8.607044 -29.12237) (xy 8.607044 -28.25877) (xy 8.607534 -28.228802)
			(xy 8.615357 -28.16938) (xy 8.63087 -28.111487) (xy 8.653806 -28.056114) (xy 8.683773 -28.004208)
			(xy 8.72026 -27.956658) (xy 8.76264 -27.914278) (xy 8.81019 -27.877791) (xy 8.862096 -27.847824)
			(xy 8.917469 -27.824888) (xy 8.975362 -27.809375) (xy 9.034784 -27.801552) (xy 9.09472 -27.801552)
			(xy 9.154142 -27.809375) (xy 9.212035 -27.824888) (xy 9.267408 -27.847824) (xy 9.319314 -27.877791)
			(xy 9.366864 -27.914278) (xy 9.409244 -27.956658) (xy 9.445731 -28.004208) (xy 9.475698 -28.056114)
			(xy 9.498634 -28.111487) (xy 9.514147 -28.16938) (xy 9.52197 -28.228802) (xy 9.52246 -28.25877) (xy 9.52246 -29.114242)
			(xy 18.847308 -29.114242) (xy 18.847308 -28.250642) (xy 18.847798 -28.220658) (xy 18.855626 -28.161202)
			(xy 18.871147 -28.103277) (xy 18.894096 -28.047873) (xy 18.92408 -27.995939) (xy 18.960586 -27.948363)
			(xy 19.002991 -27.905958) (xy 19.050567 -27.869452) (xy 19.102501 -27.839468) (xy 19.157905 -27.816519)
			(xy 19.21583 -27.800998) (xy 19.275286 -27.79317) (xy 19.335254 -27.79317) (xy 19.39471 -27.800998)
			(xy 19.452635 -27.816519) (xy 19.508039 -27.839468) (xy 19.559973 -27.869452) (xy 19.607549 -27.905958)
			(xy 19.649954 -27.948363) (xy 19.68646 -27.995939) (xy 19.716444 -28.047873) (xy 19.739393 -28.103277)
			(xy 19.754914 -28.161202) (xy 19.762742 -28.220658) (xy 19.763232 -28.250642) (xy 19.763232 -29.114242)
			(xy 19.763099 -29.12237) (xy 34.606992 -29.12237) (xy 34.606992 -28.25877) (xy 34.607482 -28.228802)
			(xy 34.615305 -28.16938) (xy 34.630818 -28.111487) (xy 34.653754 -28.056114) (xy 34.683721 -28.004208)
			(xy 34.720208 -27.956658) (xy 34.762588 -27.914278) (xy 34.810138 -27.877791) (xy 34.862044 -27.847824)
			(xy 34.917417 -27.824888) (xy 34.97531 -27.809375) (xy 35.034732 -27.801552) (xy 35.094668 -27.801552)
			(xy 35.15409 -27.809375) (xy 35.211983 -27.824888) (xy 35.267356 -27.847824) (xy 35.319262 -27.877791)
			(xy 35.366812 -27.914278) (xy 35.409192 -27.956658) (xy 35.445679 -28.004208) (xy 35.475646 -28.056114)
			(xy 35.498582 -28.111487) (xy 35.514095 -28.16938) (xy 35.521918 -28.228802) (xy 35.522408 -28.25877)
			(xy 35.522408 -29.114242) (xy 44.847256 -29.114242) (xy 44.847256 -28.250642) (xy 44.847746 -28.220658)
			(xy 44.855574 -28.161202) (xy 44.871095 -28.103277) (xy 44.894044 -28.047873) (xy 44.924028 -27.995939)
			(xy 44.960534 -27.948363) (xy 45.002939 -27.905958) (xy 45.050515 -27.869452) (xy 45.102449 -27.839468)
			(xy 45.157853 -27.816519) (xy 45.215778 -27.800998) (xy 45.275234 -27.79317) (xy 45.335202 -27.79317)
			(xy 45.394658 -27.800998) (xy 45.452583 -27.816519) (xy 45.507987 -27.839468) (xy 45.559921 -27.869452)
			(xy 45.607497 -27.905958) (xy 45.649902 -27.948363) (xy 45.686408 -27.995939) (xy 45.716392 -28.047873)
			(xy 45.739341 -28.103277) (xy 45.754862 -28.161202) (xy 45.76269 -28.220658) (xy 45.76318 -28.250642)
			(xy 45.76318 -29.114242) (xy 45.763047 -29.12237) (xy 60.60694 -29.12237) (xy 60.60694 -28.25877)
			(xy 60.60743 -28.228802) (xy 60.615253 -28.16938) (xy 60.630766 -28.111487) (xy 60.653702 -28.056114)
			(xy 60.683669 -28.004208) (xy 60.720156 -27.956658) (xy 60.762536 -27.914278) (xy 60.810086 -27.877791)
			(xy 60.861992 -27.847824) (xy 60.917365 -27.824888) (xy 60.975258 -27.809375) (xy 61.03468 -27.801552)
			(xy 61.094616 -27.801552) (xy 61.154038 -27.809375) (xy 61.211931 -27.824888) (xy 61.267304 -27.847824)
			(xy 61.31921 -27.877791) (xy 61.36676 -27.914278) (xy 61.40914 -27.956658) (xy 61.445627 -28.004208)
			(xy 61.475594 -28.056114) (xy 61.49853 -28.111487) (xy 61.514043 -28.16938) (xy 61.521866 -28.228802)
			(xy 61.522356 -28.25877) (xy 61.522356 -29.114242) (xy 70.847204 -29.114242) (xy 70.847204 -28.250642)
			(xy 70.847694 -28.220658) (xy 70.855522 -28.161202) (xy 70.871043 -28.103277) (xy 70.893992 -28.047873)
			(xy 70.923976 -27.995939) (xy 70.960482 -27.948363) (xy 71.002887 -27.905958) (xy 71.050463 -27.869452)
			(xy 71.102397 -27.839468) (xy 71.157801 -27.816519) (xy 71.215726 -27.800998) (xy 71.275182 -27.79317)
			(xy 71.33515 -27.79317) (xy 71.394606 -27.800998) (xy 71.452531 -27.816519) (xy 71.507935 -27.839468)
			(xy 71.559869 -27.869452) (xy 71.607445 -27.905958) (xy 71.64985 -27.948363) (xy 71.686356 -27.995939)
			(xy 71.71634 -28.047873) (xy 71.739289 -28.103277) (xy 71.75481 -28.161202) (xy 71.762638 -28.220658)
			(xy 71.763128 -28.250642) (xy 71.763128 -29.114242) (xy 71.762995 -29.12237) (xy 86.606888 -29.12237)
			(xy 86.606888 -28.25877) (xy 86.607378 -28.228802) (xy 86.615201 -28.16938) (xy 86.630714 -28.111487)
			(xy 86.65365 -28.056114) (xy 86.683617 -28.004208) (xy 86.720104 -27.956658) (xy 86.762484 -27.914278)
			(xy 86.810034 -27.877791) (xy 86.86194 -27.847824) (xy 86.917313 -27.824888) (xy 86.975206 -27.809375)
			(xy 87.034628 -27.801552) (xy 87.094564 -27.801552) (xy 87.153986 -27.809375) (xy 87.211879 -27.824888)
			(xy 87.267252 -27.847824) (xy 87.319158 -27.877791) (xy 87.366708 -27.914278) (xy 87.409088 -27.956658)
			(xy 87.445575 -28.004208) (xy 87.475542 -28.056114) (xy 87.498478 -28.111487) (xy 87.513991 -28.16938)
			(xy 87.521814 -28.228802) (xy 87.522304 -28.25877) (xy 87.522304 -29.114242) (xy 96.847152 -29.114242)
			(xy 96.847152 -28.250642) (xy 96.847642 -28.220658) (xy 96.85547 -28.161202) (xy 96.870991 -28.103277)
			(xy 96.89394 -28.047873) (xy 96.923924 -27.995939) (xy 96.96043 -27.948363) (xy 97.002835 -27.905958)
			(xy 97.050411 -27.869452) (xy 97.102345 -27.839468) (xy 97.157749 -27.816519) (xy 97.215674 -27.800998)
			(xy 97.27513 -27.79317) (xy 97.335098 -27.79317) (xy 97.394554 -27.800998) (xy 97.452479 -27.816519)
			(xy 97.507883 -27.839468) (xy 97.559817 -27.869452) (xy 97.607393 -27.905958) (xy 97.649798 -27.948363)
			(xy 97.686304 -27.995939) (xy 97.716288 -28.047873) (xy 97.739237 -28.103277) (xy 97.754758 -28.161202)
			(xy 97.762586 -28.220658) (xy 97.763076 -28.250642) (xy 97.763076 -29.114242) (xy 97.762943 -29.12237)
			(xy 124.706888 -29.12237) (xy 124.706888 -28.25877) (xy 124.707378 -28.228786) (xy 124.715206 -28.16933)
			(xy 124.730727 -28.111405) (xy 124.753676 -28.056001) (xy 124.78366 -28.004067) (xy 124.820166 -27.956491)
			(xy 124.862571 -27.914086) (xy 124.910147 -27.87758) (xy 124.962081 -27.847596) (xy 125.017485 -27.824647)
			(xy 125.07541 -27.809126) (xy 125.134866 -27.801298) (xy 125.194834 -27.801298) (xy 125.25429 -27.809126)
			(xy 125.312215 -27.824647) (xy 125.367619 -27.847596) (xy 125.419553 -27.87758) (xy 125.467129 -27.914086)
			(xy 125.509534 -27.956491) (xy 125.54604 -28.004067) (xy 125.576024 -28.056001) (xy 125.598973 -28.111405)
			(xy 125.614494 -28.16933) (xy 125.622322 -28.228786) (xy 125.622812 -28.25877) (xy 125.622812 -29.114242)
			(xy 134.94766 -29.114242) (xy 134.94766 -28.250642) (xy 134.94815 -28.220674) (xy 134.955973 -28.161252)
			(xy 134.971486 -28.103359) (xy 134.994422 -28.047986) (xy 135.024389 -27.99608) (xy 135.060876 -27.94853)
			(xy 135.103256 -27.90615) (xy 135.150806 -27.869663) (xy 135.202712 -27.839696) (xy 135.258085 -27.81676)
			(xy 135.315978 -27.801247) (xy 135.3754 -27.793424) (xy 135.435336 -27.793424) (xy 135.494758 -27.801247)
			(xy 135.552651 -27.81676) (xy 135.608024 -27.839696) (xy 135.65993 -27.869663) (xy 135.70748 -27.90615)
			(xy 135.74986 -27.94853) (xy 135.786347 -27.99608) (xy 135.816314 -28.047986) (xy 135.83925 -28.103359)
			(xy 135.854763 -28.161252) (xy 135.862586 -28.220674) (xy 135.863076 -28.250642) (xy 135.863076 -29.114242)
			(xy 135.862943 -29.12237) (xy 150.706836 -29.12237) (xy 150.706836 -28.25877) (xy 150.707326 -28.228786)
			(xy 150.715154 -28.16933) (xy 150.730675 -28.111405) (xy 150.753624 -28.056001) (xy 150.783608 -28.004067)
			(xy 150.820114 -27.956491) (xy 150.862519 -27.914086) (xy 150.910095 -27.87758) (xy 150.962029 -27.847596)
			(xy 151.017433 -27.824647) (xy 151.075358 -27.809126) (xy 151.134814 -27.801298) (xy 151.194782 -27.801298)
			(xy 151.254238 -27.809126) (xy 151.312163 -27.824647) (xy 151.367567 -27.847596) (xy 151.419501 -27.87758)
			(xy 151.467077 -27.914086) (xy 151.509482 -27.956491) (xy 151.545988 -28.004067) (xy 151.575972 -28.056001)
			(xy 151.598921 -28.111405) (xy 151.614442 -28.16933) (xy 151.62227 -28.228786) (xy 151.62276 -28.25877)
			(xy 151.62276 -29.114242) (xy 160.947608 -29.114242) (xy 160.947608 -28.250642) (xy 160.948098 -28.220674)
			(xy 160.955921 -28.161252) (xy 160.971434 -28.103359) (xy 160.99437 -28.047986) (xy 161.024337 -27.99608)
			(xy 161.060824 -27.94853) (xy 161.103204 -27.90615) (xy 161.150754 -27.869663) (xy 161.20266 -27.839696)
			(xy 161.258033 -27.81676) (xy 161.315926 -27.801247) (xy 161.375348 -27.793424) (xy 161.435284 -27.793424)
			(xy 161.494706 -27.801247) (xy 161.552599 -27.81676) (xy 161.607972 -27.839696) (xy 161.659878 -27.869663)
			(xy 161.707428 -27.90615) (xy 161.749808 -27.94853) (xy 161.786295 -27.99608) (xy 161.816262 -28.047986)
			(xy 161.839198 -28.103359) (xy 161.854711 -28.161252) (xy 161.862534 -28.220674) (xy 161.863024 -28.250642)
			(xy 161.863024 -29.114242) (xy 161.862891 -29.12237) (xy 176.706784 -29.12237) (xy 176.706784 -28.25877)
			(xy 176.707274 -28.228786) (xy 176.715102 -28.16933) (xy 176.730623 -28.111405) (xy 176.753572 -28.056001)
			(xy 176.783556 -28.004067) (xy 176.820062 -27.956491) (xy 176.862467 -27.914086) (xy 176.910043 -27.87758)
			(xy 176.961977 -27.847596) (xy 177.017381 -27.824647) (xy 177.075306 -27.809126) (xy 177.134762 -27.801298)
			(xy 177.19473 -27.801298) (xy 177.254186 -27.809126) (xy 177.312111 -27.824647) (xy 177.367515 -27.847596)
			(xy 177.419449 -27.87758) (xy 177.467025 -27.914086) (xy 177.50943 -27.956491) (xy 177.545936 -28.004067)
			(xy 177.57592 -28.056001) (xy 177.598869 -28.111405) (xy 177.61439 -28.16933) (xy 177.622218 -28.228786)
			(xy 177.622708 -28.25877) (xy 177.622708 -29.114242) (xy 186.947556 -29.114242) (xy 186.947556 -28.250642)
			(xy 186.948046 -28.220674) (xy 186.955869 -28.161252) (xy 186.971382 -28.103359) (xy 186.994318 -28.047986)
			(xy 187.024285 -27.99608) (xy 187.060772 -27.94853) (xy 187.103152 -27.90615) (xy 187.150702 -27.869663)
			(xy 187.202608 -27.839696) (xy 187.257981 -27.81676) (xy 187.315874 -27.801247) (xy 187.375296 -27.793424)
			(xy 187.435232 -27.793424) (xy 187.494654 -27.801247) (xy 187.552547 -27.81676) (xy 187.60792 -27.839696)
			(xy 187.659826 -27.869663) (xy 187.707376 -27.90615) (xy 187.749756 -27.94853) (xy 187.786243 -27.99608)
			(xy 187.81621 -28.047986) (xy 187.839146 -28.103359) (xy 187.854659 -28.161252) (xy 187.862482 -28.220674)
			(xy 187.862972 -28.250642) (xy 187.862972 -29.114242) (xy 187.862839 -29.12237) (xy 202.706732 -29.12237)
			(xy 202.706732 -28.25877) (xy 202.707222 -28.228786) (xy 202.71505 -28.16933) (xy 202.730571 -28.111405)
			(xy 202.75352 -28.056001) (xy 202.783504 -28.004067) (xy 202.82001 -27.956491) (xy 202.862415 -27.914086)
			(xy 202.909991 -27.87758) (xy 202.961925 -27.847596) (xy 203.017329 -27.824647) (xy 203.075254 -27.809126)
			(xy 203.13471 -27.801298) (xy 203.194678 -27.801298) (xy 203.254134 -27.809126) (xy 203.312059 -27.824647)
			(xy 203.367463 -27.847596) (xy 203.419397 -27.87758) (xy 203.466973 -27.914086) (xy 203.509378 -27.956491)
			(xy 203.545884 -28.004067) (xy 203.575868 -28.056001) (xy 203.598817 -28.111405) (xy 203.614338 -28.16933)
			(xy 203.622166 -28.228786) (xy 203.622656 -28.25877) (xy 203.622656 -29.114242) (xy 212.947504 -29.114242)
			(xy 212.947504 -28.250642) (xy 212.947994 -28.220674) (xy 212.955817 -28.161252) (xy 212.97133 -28.103359)
			(xy 212.994266 -28.047986) (xy 213.024233 -27.99608) (xy 213.06072 -27.94853) (xy 213.1031 -27.90615)
			(xy 213.15065 -27.869663) (xy 213.202556 -27.839696) (xy 213.257929 -27.81676) (xy 213.315822 -27.801247)
			(xy 213.375244 -27.793424) (xy 213.43518 -27.793424) (xy 213.494602 -27.801247) (xy 213.552495 -27.81676)
			(xy 213.607868 -27.839696) (xy 213.659774 -27.869663) (xy 213.707324 -27.90615) (xy 213.749704 -27.94853)
			(xy 213.786191 -27.99608) (xy 213.816158 -28.047986) (xy 213.839094 -28.103359) (xy 213.854607 -28.161252)
			(xy 213.86243 -28.220674) (xy 213.86292 -28.250642) (xy 213.86292 -29.114242) (xy 213.862787 -29.12237)
			(xy 240.806732 -29.12237) (xy 240.806732 -28.25877) (xy 240.807222 -28.228786) (xy 240.81505 -28.16933)
			(xy 240.830571 -28.111405) (xy 240.85352 -28.056001) (xy 240.883504 -28.004067) (xy 240.92001 -27.956491)
			(xy 240.962415 -27.914086) (xy 241.009991 -27.87758) (xy 241.061925 -27.847596) (xy 241.117329 -27.824647)
			(xy 241.175254 -27.809126) (xy 241.23471 -27.801298) (xy 241.294678 -27.801298) (xy 241.354134 -27.809126)
			(xy 241.412059 -27.824647) (xy 241.467463 -27.847596) (xy 241.519397 -27.87758) (xy 241.566973 -27.914086)
			(xy 241.609378 -27.956491) (xy 241.645884 -28.004067) (xy 241.675868 -28.056001) (xy 241.698817 -28.111405)
			(xy 241.714338 -28.16933) (xy 241.722166 -28.228786) (xy 241.722656 -28.25877) (xy 241.722656 -29.114242)
			(xy 251.047504 -29.114242) (xy 251.047504 -28.250642) (xy 251.047994 -28.220674) (xy 251.055817 -28.161252)
			(xy 251.07133 -28.103359) (xy 251.094266 -28.047986) (xy 251.124233 -27.99608) (xy 251.16072 -27.94853)
			(xy 251.2031 -27.90615) (xy 251.25065 -27.869663) (xy 251.302556 -27.839696) (xy 251.357929 -27.81676)
			(xy 251.415822 -27.801247) (xy 251.475244 -27.793424) (xy 251.53518 -27.793424) (xy 251.594602 -27.801247)
			(xy 251.652495 -27.81676) (xy 251.707868 -27.839696) (xy 251.759774 -27.869663) (xy 251.807324 -27.90615)
			(xy 251.849704 -27.94853) (xy 251.886191 -27.99608) (xy 251.916158 -28.047986) (xy 251.939094 -28.103359)
			(xy 251.954607 -28.161252) (xy 251.96243 -28.220674) (xy 251.96292 -28.250642) (xy 251.96292 -29.114242)
			(xy 251.962787 -29.12237) (xy 266.80668 -29.12237) (xy 266.80668 -28.25877) (xy 266.80717 -28.228786)
			(xy 266.814998 -28.16933) (xy 266.830519 -28.111405) (xy 266.853468 -28.056001) (xy 266.883452 -28.004067)
			(xy 266.919958 -27.956491) (xy 266.962363 -27.914086) (xy 267.009939 -27.87758) (xy 267.061873 -27.847596)
			(xy 267.117277 -27.824647) (xy 267.175202 -27.809126) (xy 267.234658 -27.801298) (xy 267.294626 -27.801298)
			(xy 267.354082 -27.809126) (xy 267.412007 -27.824647) (xy 267.467411 -27.847596) (xy 267.519345 -27.87758)
			(xy 267.566921 -27.914086) (xy 267.609326 -27.956491) (xy 267.645832 -28.004067) (xy 267.675816 -28.056001)
			(xy 267.698765 -28.111405) (xy 267.714286 -28.16933) (xy 267.722114 -28.228786) (xy 267.722604 -28.25877)
			(xy 267.722604 -29.114242) (xy 277.047452 -29.114242) (xy 277.047452 -28.250642) (xy 277.047942 -28.220674)
			(xy 277.055765 -28.161252) (xy 277.071278 -28.103359) (xy 277.094214 -28.047986) (xy 277.124181 -27.99608)
			(xy 277.160668 -27.94853) (xy 277.203048 -27.90615) (xy 277.250598 -27.869663) (xy 277.302504 -27.839696)
			(xy 277.357877 -27.81676) (xy 277.41577 -27.801247) (xy 277.475192 -27.793424) (xy 277.535128 -27.793424)
			(xy 277.59455 -27.801247) (xy 277.652443 -27.81676) (xy 277.707816 -27.839696) (xy 277.759722 -27.869663)
			(xy 277.807272 -27.90615) (xy 277.849652 -27.94853) (xy 277.886139 -27.99608) (xy 277.916106 -28.047986)
			(xy 277.939042 -28.103359) (xy 277.954555 -28.161252) (xy 277.962378 -28.220674) (xy 277.962868 -28.250642)
			(xy 277.962868 -29.114242) (xy 277.962735 -29.12237) (xy 292.806628 -29.12237) (xy 292.806628 -28.25877)
			(xy 292.807118 -28.228786) (xy 292.814946 -28.16933) (xy 292.830467 -28.111405) (xy 292.853416 -28.056001)
			(xy 292.8834 -28.004067) (xy 292.919906 -27.956491) (xy 292.962311 -27.914086) (xy 293.009887 -27.87758)
			(xy 293.061821 -27.847596) (xy 293.117225 -27.824647) (xy 293.17515 -27.809126) (xy 293.234606 -27.801298)
			(xy 293.294574 -27.801298) (xy 293.35403 -27.809126) (xy 293.411955 -27.824647) (xy 293.467359 -27.847596)
			(xy 293.519293 -27.87758) (xy 293.566869 -27.914086) (xy 293.609274 -27.956491) (xy 293.64578 -28.004067)
			(xy 293.675764 -28.056001) (xy 293.698713 -28.111405) (xy 293.714234 -28.16933) (xy 293.722062 -28.228786)
			(xy 293.722552 -28.25877) (xy 293.722552 -29.114242) (xy 303.0474 -29.114242) (xy 303.0474 -28.250642)
			(xy 303.04789 -28.220674) (xy 303.055713 -28.161252) (xy 303.071226 -28.103359) (xy 303.094162 -28.047986)
			(xy 303.124129 -27.99608) (xy 303.160616 -27.94853) (xy 303.202996 -27.90615) (xy 303.250546 -27.869663)
			(xy 303.302452 -27.839696) (xy 303.357825 -27.81676) (xy 303.415718 -27.801247) (xy 303.47514 -27.793424)
			(xy 303.535076 -27.793424) (xy 303.594498 -27.801247) (xy 303.652391 -27.81676) (xy 303.707764 -27.839696)
			(xy 303.75967 -27.869663) (xy 303.80722 -27.90615) (xy 303.8496 -27.94853) (xy 303.886087 -27.99608)
			(xy 303.916054 -28.047986) (xy 303.93899 -28.103359) (xy 303.954503 -28.161252) (xy 303.962326 -28.220674)
			(xy 303.962816 -28.250642) (xy 303.962816 -29.114242) (xy 303.962683 -29.12237) (xy 318.806576 -29.12237)
			(xy 318.806576 -28.25877) (xy 318.807066 -28.228786) (xy 318.814894 -28.16933) (xy 318.830415 -28.111405)
			(xy 318.853364 -28.056001) (xy 318.883348 -28.004067) (xy 318.919854 -27.956491) (xy 318.962259 -27.914086)
			(xy 319.009835 -27.87758) (xy 319.061769 -27.847596) (xy 319.117173 -27.824647) (xy 319.175098 -27.809126)
			(xy 319.234554 -27.801298) (xy 319.294522 -27.801298) (xy 319.353978 -27.809126) (xy 319.411903 -27.824647)
			(xy 319.467307 -27.847596) (xy 319.519241 -27.87758) (xy 319.566817 -27.914086) (xy 319.609222 -27.956491)
			(xy 319.645728 -28.004067) (xy 319.675712 -28.056001) (xy 319.698661 -28.111405) (xy 319.714182 -28.16933)
			(xy 319.72201 -28.228786) (xy 319.7225 -28.25877) (xy 319.7225 -29.114242) (xy 329.047348 -29.114242)
			(xy 329.047348 -28.250642) (xy 329.047838 -28.220674) (xy 329.055661 -28.161252) (xy 329.071174 -28.103359)
			(xy 329.09411 -28.047986) (xy 329.124077 -27.99608) (xy 329.160564 -27.94853) (xy 329.202944 -27.90615)
			(xy 329.250494 -27.869663) (xy 329.3024 -27.839696) (xy 329.357773 -27.81676) (xy 329.415666 -27.801247)
			(xy 329.475088 -27.793424) (xy 329.535024 -27.793424) (xy 329.594446 -27.801247) (xy 329.652339 -27.81676)
			(xy 329.707712 -27.839696) (xy 329.759618 -27.869663) (xy 329.807168 -27.90615) (xy 329.849548 -27.94853)
			(xy 329.886035 -27.99608) (xy 329.916002 -28.047986) (xy 329.938938 -28.103359) (xy 329.954451 -28.161252)
			(xy 329.962274 -28.220674) (xy 329.962764 -28.250642) (xy 329.962764 -29.114242) (xy 329.962631 -29.12237)
			(xy 356.907084 -29.12237) (xy 356.907084 -28.25877) (xy 356.907574 -28.228802) (xy 356.915397 -28.16938)
			(xy 356.93091 -28.111487) (xy 356.953846 -28.056114) (xy 356.983813 -28.004208) (xy 357.0203 -27.956658)
			(xy 357.06268 -27.914278) (xy 357.11023 -27.877791) (xy 357.162136 -27.847824) (xy 357.217509 -27.824888)
			(xy 357.275402 -27.809375) (xy 357.334824 -27.801552) (xy 357.39476 -27.801552) (xy 357.454182 -27.809375)
			(xy 357.512075 -27.824888) (xy 357.567448 -27.847824) (xy 357.619354 -27.877791) (xy 357.666904 -27.914278)
			(xy 357.709284 -27.956658) (xy 357.745771 -28.004208) (xy 357.775738 -28.056114) (xy 357.798674 -28.111487)
			(xy 357.814187 -28.16938) (xy 357.82201 -28.228802) (xy 357.8225 -28.25877) (xy 357.8225 -29.114242)
			(xy 367.147348 -29.114242) (xy 367.147348 -28.250642) (xy 367.147838 -28.220658) (xy 367.155666 -28.161202)
			(xy 367.171187 -28.103277) (xy 367.194136 -28.047873) (xy 367.22412 -27.995939) (xy 367.260626 -27.948363)
			(xy 367.303031 -27.905958) (xy 367.350607 -27.869452) (xy 367.402541 -27.839468) (xy 367.457945 -27.816519)
			(xy 367.51587 -27.800998) (xy 367.575326 -27.79317) (xy 367.635294 -27.79317) (xy 367.69475 -27.800998)
			(xy 367.752675 -27.816519) (xy 367.808079 -27.839468) (xy 367.860013 -27.869452) (xy 367.907589 -27.905958)
			(xy 367.949994 -27.948363) (xy 367.9865 -27.995939) (xy 368.016484 -28.047873) (xy 368.039433 -28.103277)
			(xy 368.054954 -28.161202) (xy 368.062782 -28.220658) (xy 368.063272 -28.250642) (xy 368.063272 -29.114242)
			(xy 368.063139 -29.12237) (xy 382.907032 -29.12237) (xy 382.907032 -28.25877) (xy 382.907522 -28.228802)
			(xy 382.915345 -28.16938) (xy 382.930858 -28.111487) (xy 382.953794 -28.056114) (xy 382.983761 -28.004208)
			(xy 383.020248 -27.956658) (xy 383.062628 -27.914278) (xy 383.110178 -27.877791) (xy 383.162084 -27.847824)
			(xy 383.217457 -27.824888) (xy 383.27535 -27.809375) (xy 383.334772 -27.801552) (xy 383.394708 -27.801552)
			(xy 383.45413 -27.809375) (xy 383.512023 -27.824888) (xy 383.567396 -27.847824) (xy 383.619302 -27.877791)
			(xy 383.666852 -27.914278) (xy 383.709232 -27.956658) (xy 383.745719 -28.004208) (xy 383.775686 -28.056114)
			(xy 383.798622 -28.111487) (xy 383.814135 -28.16938) (xy 383.821958 -28.228802) (xy 383.822448 -28.25877)
			(xy 383.822448 -29.114242) (xy 393.147296 -29.114242) (xy 393.147296 -28.250642) (xy 393.147786 -28.220658)
			(xy 393.155614 -28.161202) (xy 393.171135 -28.103277) (xy 393.194084 -28.047873) (xy 393.224068 -27.995939)
			(xy 393.260574 -27.948363) (xy 393.302979 -27.905958) (xy 393.350555 -27.869452) (xy 393.402489 -27.839468)
			(xy 393.457893 -27.816519) (xy 393.515818 -27.800998) (xy 393.575274 -27.79317) (xy 393.635242 -27.79317)
			(xy 393.694698 -27.800998) (xy 393.752623 -27.816519) (xy 393.808027 -27.839468) (xy 393.859961 -27.869452)
			(xy 393.907537 -27.905958) (xy 393.949942 -27.948363) (xy 393.986448 -27.995939) (xy 394.016432 -28.047873)
			(xy 394.039381 -28.103277) (xy 394.054902 -28.161202) (xy 394.06273 -28.220658) (xy 394.06322 -28.250642)
			(xy 394.06322 -29.114242) (xy 394.063087 -29.12237) (xy 408.90698 -29.12237) (xy 408.90698 -28.25877)
			(xy 408.90747 -28.228802) (xy 408.915293 -28.16938) (xy 408.930806 -28.111487) (xy 408.953742 -28.056114)
			(xy 408.983709 -28.004208) (xy 409.020196 -27.956658) (xy 409.062576 -27.914278) (xy 409.110126 -27.877791)
			(xy 409.162032 -27.847824) (xy 409.217405 -27.824888) (xy 409.275298 -27.809375) (xy 409.33472 -27.801552)
			(xy 409.394656 -27.801552) (xy 409.454078 -27.809375) (xy 409.511971 -27.824888) (xy 409.567344 -27.847824)
			(xy 409.61925 -27.877791) (xy 409.6668 -27.914278) (xy 409.70918 -27.956658) (xy 409.745667 -28.004208)
			(xy 409.775634 -28.056114) (xy 409.79857 -28.111487) (xy 409.814083 -28.16938) (xy 409.821906 -28.228802)
			(xy 409.822396 -28.25877) (xy 409.822396 -29.114242) (xy 419.147244 -29.114242) (xy 419.147244 -28.250642)
			(xy 419.147734 -28.220658) (xy 419.155562 -28.161202) (xy 419.171083 -28.103277) (xy 419.194032 -28.047873)
			(xy 419.224016 -27.995939) (xy 419.260522 -27.948363) (xy 419.302927 -27.905958) (xy 419.350503 -27.869452)
			(xy 419.402437 -27.839468) (xy 419.457841 -27.816519) (xy 419.515766 -27.800998) (xy 419.575222 -27.79317)
			(xy 419.63519 -27.79317) (xy 419.694646 -27.800998) (xy 419.752571 -27.816519) (xy 419.807975 -27.839468)
			(xy 419.859909 -27.869452) (xy 419.907485 -27.905958) (xy 419.94989 -27.948363) (xy 419.986396 -27.995939)
			(xy 420.01638 -28.047873) (xy 420.039329 -28.103277) (xy 420.05485 -28.161202) (xy 420.062678 -28.220658)
			(xy 420.063168 -28.250642) (xy 420.063168 -29.114242) (xy 420.063035 -29.12237) (xy 434.906928 -29.12237)
			(xy 434.906928 -28.25877) (xy 434.907418 -28.228802) (xy 434.915241 -28.16938) (xy 434.930754 -28.111487)
			(xy 434.95369 -28.056114) (xy 434.983657 -28.004208) (xy 435.020144 -27.956658) (xy 435.062524 -27.914278)
			(xy 435.110074 -27.877791) (xy 435.16198 -27.847824) (xy 435.217353 -27.824888) (xy 435.275246 -27.809375)
			(xy 435.334668 -27.801552) (xy 435.394604 -27.801552) (xy 435.454026 -27.809375) (xy 435.511919 -27.824888)
			(xy 435.567292 -27.847824) (xy 435.619198 -27.877791) (xy 435.666748 -27.914278) (xy 435.709128 -27.956658)
			(xy 435.745615 -28.004208) (xy 435.775582 -28.056114) (xy 435.798518 -28.111487) (xy 435.814031 -28.16938)
			(xy 435.821854 -28.228802) (xy 435.822344 -28.25877) (xy 435.822344 -29.114242) (xy 445.147192 -29.114242)
			(xy 445.147192 -28.250642) (xy 445.147682 -28.220658) (xy 445.15551 -28.161202) (xy 445.171031 -28.103277)
			(xy 445.19398 -28.047873) (xy 445.223964 -27.995939) (xy 445.26047 -27.948363) (xy 445.302875 -27.905958)
			(xy 445.350451 -27.869452) (xy 445.402385 -27.839468) (xy 445.457789 -27.816519) (xy 445.515714 -27.800998)
			(xy 445.57517 -27.79317) (xy 445.635138 -27.79317) (xy 445.694594 -27.800998) (xy 445.752519 -27.816519)
			(xy 445.807923 -27.839468) (xy 445.859857 -27.869452) (xy 445.907433 -27.905958) (xy 445.949838 -27.948363)
			(xy 445.986344 -27.995939) (xy 446.016328 -28.047873) (xy 446.039277 -28.103277) (xy 446.054798 -28.161202)
			(xy 446.062626 -28.220658) (xy 446.063116 -28.250642) (xy 446.063116 -29.114242) (xy 446.062626 -29.144226)
			(xy 446.054798 -29.203682) (xy 446.039277 -29.261607) (xy 446.016328 -29.317011) (xy 445.986344 -29.368945)
			(xy 445.949838 -29.416521) (xy 445.907433 -29.458926) (xy 445.859857 -29.495432) (xy 445.807923 -29.525416)
			(xy 445.752519 -29.548365) (xy 445.694594 -29.563886) (xy 445.635138 -29.571714) (xy 445.57517 -29.571714)
			(xy 445.515714 -29.563886) (xy 445.457789 -29.548365) (xy 445.402385 -29.525416) (xy 445.350451 -29.495432)
			(xy 445.302875 -29.458926) (xy 445.26047 -29.416521) (xy 445.223964 -29.368945) (xy 445.19398 -29.317011)
			(xy 445.171031 -29.261607) (xy 445.15551 -29.203682) (xy 445.147682 -29.144226) (xy 445.147192 -29.114242)
			(xy 435.822344 -29.114242) (xy 435.822344 -29.12237) (xy 435.821854 -29.152338) (xy 435.814031 -29.21176)
			(xy 435.798518 -29.269653) (xy 435.775582 -29.325026) (xy 435.745615 -29.376932) (xy 435.709128 -29.424482)
			(xy 435.666748 -29.466862) (xy 435.619198 -29.503349) (xy 435.567292 -29.533316) (xy 435.511919 -29.556252)
			(xy 435.454026 -29.571765) (xy 435.394604 -29.579588) (xy 435.334668 -29.579588) (xy 435.275246 -29.571765)
			(xy 435.217353 -29.556252) (xy 435.16198 -29.533316) (xy 435.110074 -29.503349) (xy 435.062524 -29.466862)
			(xy 435.020144 -29.424482) (xy 434.983657 -29.376932) (xy 434.95369 -29.325026) (xy 434.930754 -29.269653)
			(xy 434.915241 -29.21176) (xy 434.907418 -29.152338) (xy 434.906928 -29.12237) (xy 420.063035 -29.12237)
			(xy 420.062678 -29.144226) (xy 420.05485 -29.203682) (xy 420.039329 -29.261607) (xy 420.01638 -29.317011)
			(xy 419.986396 -29.368945) (xy 419.94989 -29.416521) (xy 419.907485 -29.458926) (xy 419.859909 -29.495432)
			(xy 419.807975 -29.525416) (xy 419.752571 -29.548365) (xy 419.694646 -29.563886) (xy 419.63519 -29.571714)
			(xy 419.575222 -29.571714) (xy 419.515766 -29.563886) (xy 419.457841 -29.548365) (xy 419.402437 -29.525416)
			(xy 419.350503 -29.495432) (xy 419.302927 -29.458926) (xy 419.260522 -29.416521) (xy 419.224016 -29.368945)
			(xy 419.194032 -29.317011) (xy 419.171083 -29.261607) (xy 419.155562 -29.203682) (xy 419.147734 -29.144226)
			(xy 419.147244 -29.114242) (xy 409.822396 -29.114242) (xy 409.822396 -29.12237) (xy 409.821906 -29.152338)
			(xy 409.814083 -29.21176) (xy 409.79857 -29.269653) (xy 409.775634 -29.325026) (xy 409.745667 -29.376932)
			(xy 409.70918 -29.424482) (xy 409.6668 -29.466862) (xy 409.61925 -29.503349) (xy 409.567344 -29.533316)
			(xy 409.511971 -29.556252) (xy 409.454078 -29.571765) (xy 409.394656 -29.579588) (xy 409.33472 -29.579588)
			(xy 409.275298 -29.571765) (xy 409.217405 -29.556252) (xy 409.162032 -29.533316) (xy 409.110126 -29.503349)
			(xy 409.062576 -29.466862) (xy 409.020196 -29.424482) (xy 408.983709 -29.376932) (xy 408.953742 -29.325026)
			(xy 408.930806 -29.269653) (xy 408.915293 -29.21176) (xy 408.90747 -29.152338) (xy 408.90698 -29.12237)
			(xy 394.063087 -29.12237) (xy 394.06273 -29.144226) (xy 394.054902 -29.203682) (xy 394.039381 -29.261607)
			(xy 394.016432 -29.317011) (xy 393.986448 -29.368945) (xy 393.949942 -29.416521) (xy 393.907537 -29.458926)
			(xy 393.859961 -29.495432) (xy 393.808027 -29.525416) (xy 393.752623 -29.548365) (xy 393.694698 -29.563886)
			(xy 393.635242 -29.571714) (xy 393.575274 -29.571714) (xy 393.515818 -29.563886) (xy 393.457893 -29.548365)
			(xy 393.402489 -29.525416) (xy 393.350555 -29.495432) (xy 393.302979 -29.458926) (xy 393.260574 -29.416521)
			(xy 393.224068 -29.368945) (xy 393.194084 -29.317011) (xy 393.171135 -29.261607) (xy 393.155614 -29.203682)
			(xy 393.147786 -29.144226) (xy 393.147296 -29.114242) (xy 383.822448 -29.114242) (xy 383.822448 -29.12237)
			(xy 383.821958 -29.152338) (xy 383.814135 -29.21176) (xy 383.798622 -29.269653) (xy 383.775686 -29.325026)
			(xy 383.745719 -29.376932) (xy 383.709232 -29.424482) (xy 383.666852 -29.466862) (xy 383.619302 -29.503349)
			(xy 383.567396 -29.533316) (xy 383.512023 -29.556252) (xy 383.45413 -29.571765) (xy 383.394708 -29.579588)
			(xy 383.334772 -29.579588) (xy 383.27535 -29.571765) (xy 383.217457 -29.556252) (xy 383.162084 -29.533316)
			(xy 383.110178 -29.503349) (xy 383.062628 -29.466862) (xy 383.020248 -29.424482) (xy 382.983761 -29.376932)
			(xy 382.953794 -29.325026) (xy 382.930858 -29.269653) (xy 382.915345 -29.21176) (xy 382.907522 -29.152338)
			(xy 382.907032 -29.12237) (xy 368.063139 -29.12237) (xy 368.062782 -29.144226) (xy 368.054954 -29.203682)
			(xy 368.039433 -29.261607) (xy 368.016484 -29.317011) (xy 367.9865 -29.368945) (xy 367.949994 -29.416521)
			(xy 367.907589 -29.458926) (xy 367.860013 -29.495432) (xy 367.808079 -29.525416) (xy 367.752675 -29.548365)
			(xy 367.69475 -29.563886) (xy 367.635294 -29.571714) (xy 367.575326 -29.571714) (xy 367.51587 -29.563886)
			(xy 367.457945 -29.548365) (xy 367.402541 -29.525416) (xy 367.350607 -29.495432) (xy 367.303031 -29.458926)
			(xy 367.260626 -29.416521) (xy 367.22412 -29.368945) (xy 367.194136 -29.317011) (xy 367.171187 -29.261607)
			(xy 367.155666 -29.203682) (xy 367.147838 -29.144226) (xy 367.147348 -29.114242) (xy 357.8225 -29.114242)
			(xy 357.8225 -29.12237) (xy 357.82201 -29.152338) (xy 357.814187 -29.21176) (xy 357.798674 -29.269653)
			(xy 357.775738 -29.325026) (xy 357.745771 -29.376932) (xy 357.709284 -29.424482) (xy 357.666904 -29.466862)
			(xy 357.619354 -29.503349) (xy 357.567448 -29.533316) (xy 357.512075 -29.556252) (xy 357.454182 -29.571765)
			(xy 357.39476 -29.579588) (xy 357.334824 -29.579588) (xy 357.275402 -29.571765) (xy 357.217509 -29.556252)
			(xy 357.162136 -29.533316) (xy 357.11023 -29.503349) (xy 357.06268 -29.466862) (xy 357.0203 -29.424482)
			(xy 356.983813 -29.376932) (xy 356.953846 -29.325026) (xy 356.93091 -29.269653) (xy 356.915397 -29.21176)
			(xy 356.907574 -29.152338) (xy 356.907084 -29.12237) (xy 329.962631 -29.12237) (xy 329.962274 -29.14421)
			(xy 329.954451 -29.203632) (xy 329.938938 -29.261525) (xy 329.916002 -29.316898) (xy 329.886035 -29.368804)
			(xy 329.849548 -29.416354) (xy 329.807168 -29.458734) (xy 329.759618 -29.495221) (xy 329.707712 -29.525188)
			(xy 329.652339 -29.548124) (xy 329.594446 -29.563637) (xy 329.535024 -29.57146) (xy 329.475088 -29.57146)
			(xy 329.415666 -29.563637) (xy 329.357773 -29.548124) (xy 329.3024 -29.525188) (xy 329.250494 -29.495221)
			(xy 329.202944 -29.458734) (xy 329.160564 -29.416354) (xy 329.124077 -29.368804) (xy 329.09411 -29.316898)
			(xy 329.071174 -29.261525) (xy 329.055661 -29.203632) (xy 329.047838 -29.14421) (xy 329.047348 -29.114242)
			(xy 319.7225 -29.114242) (xy 319.7225 -29.12237) (xy 319.72201 -29.152354) (xy 319.714182 -29.21181)
			(xy 319.698661 -29.269735) (xy 319.675712 -29.325139) (xy 319.645728 -29.377073) (xy 319.609222 -29.424649)
			(xy 319.566817 -29.467054) (xy 319.519241 -29.50356) (xy 319.467307 -29.533544) (xy 319.411903 -29.556493)
			(xy 319.353978 -29.572014) (xy 319.294522 -29.579842) (xy 319.234554 -29.579842) (xy 319.175098 -29.572014)
			(xy 319.117173 -29.556493) (xy 319.061769 -29.533544) (xy 319.009835 -29.50356) (xy 318.962259 -29.467054)
			(xy 318.919854 -29.424649) (xy 318.883348 -29.377073) (xy 318.853364 -29.325139) (xy 318.830415 -29.269735)
			(xy 318.814894 -29.21181) (xy 318.807066 -29.152354) (xy 318.806576 -29.12237) (xy 303.962683 -29.12237)
			(xy 303.962326 -29.14421) (xy 303.954503 -29.203632) (xy 303.93899 -29.261525) (xy 303.916054 -29.316898)
			(xy 303.886087 -29.368804) (xy 303.8496 -29.416354) (xy 303.80722 -29.458734) (xy 303.75967 -29.495221)
			(xy 303.707764 -29.525188) (xy 303.652391 -29.548124) (xy 303.594498 -29.563637) (xy 303.535076 -29.57146)
			(xy 303.47514 -29.57146) (xy 303.415718 -29.563637) (xy 303.357825 -29.548124) (xy 303.302452 -29.525188)
			(xy 303.250546 -29.495221) (xy 303.202996 -29.458734) (xy 303.160616 -29.416354) (xy 303.124129 -29.368804)
			(xy 303.094162 -29.316898) (xy 303.071226 -29.261525) (xy 303.055713 -29.203632) (xy 303.04789 -29.14421)
			(xy 303.0474 -29.114242) (xy 293.722552 -29.114242) (xy 293.722552 -29.12237) (xy 293.722062 -29.152354)
			(xy 293.714234 -29.21181) (xy 293.698713 -29.269735) (xy 293.675764 -29.325139) (xy 293.64578 -29.377073)
			(xy 293.609274 -29.424649) (xy 293.566869 -29.467054) (xy 293.519293 -29.50356) (xy 293.467359 -29.533544)
			(xy 293.411955 -29.556493) (xy 293.35403 -29.572014) (xy 293.294574 -29.579842) (xy 293.234606 -29.579842)
			(xy 293.17515 -29.572014) (xy 293.117225 -29.556493) (xy 293.061821 -29.533544) (xy 293.009887 -29.50356)
			(xy 292.962311 -29.467054) (xy 292.919906 -29.424649) (xy 292.8834 -29.377073) (xy 292.853416 -29.325139)
			(xy 292.830467 -29.269735) (xy 292.814946 -29.21181) (xy 292.807118 -29.152354) (xy 292.806628 -29.12237)
			(xy 277.962735 -29.12237) (xy 277.962378 -29.14421) (xy 277.954555 -29.203632) (xy 277.939042 -29.261525)
			(xy 277.916106 -29.316898) (xy 277.886139 -29.368804) (xy 277.849652 -29.416354) (xy 277.807272 -29.458734)
			(xy 277.759722 -29.495221) (xy 277.707816 -29.525188) (xy 277.652443 -29.548124) (xy 277.59455 -29.563637)
			(xy 277.535128 -29.57146) (xy 277.475192 -29.57146) (xy 277.41577 -29.563637) (xy 277.357877 -29.548124)
			(xy 277.302504 -29.525188) (xy 277.250598 -29.495221) (xy 277.203048 -29.458734) (xy 277.160668 -29.416354)
			(xy 277.124181 -29.368804) (xy 277.094214 -29.316898) (xy 277.071278 -29.261525) (xy 277.055765 -29.203632)
			(xy 277.047942 -29.14421) (xy 277.047452 -29.114242) (xy 267.722604 -29.114242) (xy 267.722604 -29.12237)
			(xy 267.722114 -29.152354) (xy 267.714286 -29.21181) (xy 267.698765 -29.269735) (xy 267.675816 -29.325139)
			(xy 267.645832 -29.377073) (xy 267.609326 -29.424649) (xy 267.566921 -29.467054) (xy 267.519345 -29.50356)
			(xy 267.467411 -29.533544) (xy 267.412007 -29.556493) (xy 267.354082 -29.572014) (xy 267.294626 -29.579842)
			(xy 267.234658 -29.579842) (xy 267.175202 -29.572014) (xy 267.117277 -29.556493) (xy 267.061873 -29.533544)
			(xy 267.009939 -29.50356) (xy 266.962363 -29.467054) (xy 266.919958 -29.424649) (xy 266.883452 -29.377073)
			(xy 266.853468 -29.325139) (xy 266.830519 -29.269735) (xy 266.814998 -29.21181) (xy 266.80717 -29.152354)
			(xy 266.80668 -29.12237) (xy 251.962787 -29.12237) (xy 251.96243 -29.14421) (xy 251.954607 -29.203632)
			(xy 251.939094 -29.261525) (xy 251.916158 -29.316898) (xy 251.886191 -29.368804) (xy 251.849704 -29.416354)
			(xy 251.807324 -29.458734) (xy 251.759774 -29.495221) (xy 251.707868 -29.525188) (xy 251.652495 -29.548124)
			(xy 251.594602 -29.563637) (xy 251.53518 -29.57146) (xy 251.475244 -29.57146) (xy 251.415822 -29.563637)
			(xy 251.357929 -29.548124) (xy 251.302556 -29.525188) (xy 251.25065 -29.495221) (xy 251.2031 -29.458734)
			(xy 251.16072 -29.416354) (xy 251.124233 -29.368804) (xy 251.094266 -29.316898) (xy 251.07133 -29.261525)
			(xy 251.055817 -29.203632) (xy 251.047994 -29.14421) (xy 251.047504 -29.114242) (xy 241.722656 -29.114242)
			(xy 241.722656 -29.12237) (xy 241.722166 -29.152354) (xy 241.714338 -29.21181) (xy 241.698817 -29.269735)
			(xy 241.675868 -29.325139) (xy 241.645884 -29.377073) (xy 241.609378 -29.424649) (xy 241.566973 -29.467054)
			(xy 241.519397 -29.50356) (xy 241.467463 -29.533544) (xy 241.412059 -29.556493) (xy 241.354134 -29.572014)
			(xy 241.294678 -29.579842) (xy 241.23471 -29.579842) (xy 241.175254 -29.572014) (xy 241.117329 -29.556493)
			(xy 241.061925 -29.533544) (xy 241.009991 -29.50356) (xy 240.962415 -29.467054) (xy 240.92001 -29.424649)
			(xy 240.883504 -29.377073) (xy 240.85352 -29.325139) (xy 240.830571 -29.269735) (xy 240.81505 -29.21181)
			(xy 240.807222 -29.152354) (xy 240.806732 -29.12237) (xy 213.862787 -29.12237) (xy 213.86243 -29.14421)
			(xy 213.854607 -29.203632) (xy 213.839094 -29.261525) (xy 213.816158 -29.316898) (xy 213.786191 -29.368804)
			(xy 213.749704 -29.416354) (xy 213.707324 -29.458734) (xy 213.659774 -29.495221) (xy 213.607868 -29.525188)
			(xy 213.552495 -29.548124) (xy 213.494602 -29.563637) (xy 213.43518 -29.57146) (xy 213.375244 -29.57146)
			(xy 213.315822 -29.563637) (xy 213.257929 -29.548124) (xy 213.202556 -29.525188) (xy 213.15065 -29.495221)
			(xy 213.1031 -29.458734) (xy 213.06072 -29.416354) (xy 213.024233 -29.368804) (xy 212.994266 -29.316898)
			(xy 212.97133 -29.261525) (xy 212.955817 -29.203632) (xy 212.947994 -29.14421) (xy 212.947504 -29.114242)
			(xy 203.622656 -29.114242) (xy 203.622656 -29.12237) (xy 203.622166 -29.152354) (xy 203.614338 -29.21181)
			(xy 203.598817 -29.269735) (xy 203.575868 -29.325139) (xy 203.545884 -29.377073) (xy 203.509378 -29.424649)
			(xy 203.466973 -29.467054) (xy 203.419397 -29.50356) (xy 203.367463 -29.533544) (xy 203.312059 -29.556493)
			(xy 203.254134 -29.572014) (xy 203.194678 -29.579842) (xy 203.13471 -29.579842) (xy 203.075254 -29.572014)
			(xy 203.017329 -29.556493) (xy 202.961925 -29.533544) (xy 202.909991 -29.50356) (xy 202.862415 -29.467054)
			(xy 202.82001 -29.424649) (xy 202.783504 -29.377073) (xy 202.75352 -29.325139) (xy 202.730571 -29.269735)
			(xy 202.71505 -29.21181) (xy 202.707222 -29.152354) (xy 202.706732 -29.12237) (xy 187.862839 -29.12237)
			(xy 187.862482 -29.14421) (xy 187.854659 -29.203632) (xy 187.839146 -29.261525) (xy 187.81621 -29.316898)
			(xy 187.786243 -29.368804) (xy 187.749756 -29.416354) (xy 187.707376 -29.458734) (xy 187.659826 -29.495221)
			(xy 187.60792 -29.525188) (xy 187.552547 -29.548124) (xy 187.494654 -29.563637) (xy 187.435232 -29.57146)
			(xy 187.375296 -29.57146) (xy 187.315874 -29.563637) (xy 187.257981 -29.548124) (xy 187.202608 -29.525188)
			(xy 187.150702 -29.495221) (xy 187.103152 -29.458734) (xy 187.060772 -29.416354) (xy 187.024285 -29.368804)
			(xy 186.994318 -29.316898) (xy 186.971382 -29.261525) (xy 186.955869 -29.203632) (xy 186.948046 -29.14421)
			(xy 186.947556 -29.114242) (xy 177.622708 -29.114242) (xy 177.622708 -29.12237) (xy 177.622218 -29.152354)
			(xy 177.61439 -29.21181) (xy 177.598869 -29.269735) (xy 177.57592 -29.325139) (xy 177.545936 -29.377073)
			(xy 177.50943 -29.424649) (xy 177.467025 -29.467054) (xy 177.419449 -29.50356) (xy 177.367515 -29.533544)
			(xy 177.312111 -29.556493) (xy 177.254186 -29.572014) (xy 177.19473 -29.579842) (xy 177.134762 -29.579842)
			(xy 177.075306 -29.572014) (xy 177.017381 -29.556493) (xy 176.961977 -29.533544) (xy 176.910043 -29.50356)
			(xy 176.862467 -29.467054) (xy 176.820062 -29.424649) (xy 176.783556 -29.377073) (xy 176.753572 -29.325139)
			(xy 176.730623 -29.269735) (xy 176.715102 -29.21181) (xy 176.707274 -29.152354) (xy 176.706784 -29.12237)
			(xy 161.862891 -29.12237) (xy 161.862534 -29.14421) (xy 161.854711 -29.203632) (xy 161.839198 -29.261525)
			(xy 161.816262 -29.316898) (xy 161.786295 -29.368804) (xy 161.749808 -29.416354) (xy 161.707428 -29.458734)
			(xy 161.659878 -29.495221) (xy 161.607972 -29.525188) (xy 161.552599 -29.548124) (xy 161.494706 -29.563637)
			(xy 161.435284 -29.57146) (xy 161.375348 -29.57146) (xy 161.315926 -29.563637) (xy 161.258033 -29.548124)
			(xy 161.20266 -29.525188) (xy 161.150754 -29.495221) (xy 161.103204 -29.458734) (xy 161.060824 -29.416354)
			(xy 161.024337 -29.368804) (xy 160.99437 -29.316898) (xy 160.971434 -29.261525) (xy 160.955921 -29.203632)
			(xy 160.948098 -29.14421) (xy 160.947608 -29.114242) (xy 151.62276 -29.114242) (xy 151.62276 -29.12237)
			(xy 151.62227 -29.152354) (xy 151.614442 -29.21181) (xy 151.598921 -29.269735) (xy 151.575972 -29.325139)
			(xy 151.545988 -29.377073) (xy 151.509482 -29.424649) (xy 151.467077 -29.467054) (xy 151.419501 -29.50356)
			(xy 151.367567 -29.533544) (xy 151.312163 -29.556493) (xy 151.254238 -29.572014) (xy 151.194782 -29.579842)
			(xy 151.134814 -29.579842) (xy 151.075358 -29.572014) (xy 151.017433 -29.556493) (xy 150.962029 -29.533544)
			(xy 150.910095 -29.50356) (xy 150.862519 -29.467054) (xy 150.820114 -29.424649) (xy 150.783608 -29.377073)
			(xy 150.753624 -29.325139) (xy 150.730675 -29.269735) (xy 150.715154 -29.21181) (xy 150.707326 -29.152354)
			(xy 150.706836 -29.12237) (xy 135.862943 -29.12237) (xy 135.862586 -29.14421) (xy 135.854763 -29.203632)
			(xy 135.83925 -29.261525) (xy 135.816314 -29.316898) (xy 135.786347 -29.368804) (xy 135.74986 -29.416354)
			(xy 135.70748 -29.458734) (xy 135.65993 -29.495221) (xy 135.608024 -29.525188) (xy 135.552651 -29.548124)
			(xy 135.494758 -29.563637) (xy 135.435336 -29.57146) (xy 135.3754 -29.57146) (xy 135.315978 -29.563637)
			(xy 135.258085 -29.548124) (xy 135.202712 -29.525188) (xy 135.150806 -29.495221) (xy 135.103256 -29.458734)
			(xy 135.060876 -29.416354) (xy 135.024389 -29.368804) (xy 134.994422 -29.316898) (xy 134.971486 -29.261525)
			(xy 134.955973 -29.203632) (xy 134.94815 -29.14421) (xy 134.94766 -29.114242) (xy 125.622812 -29.114242)
			(xy 125.622812 -29.12237) (xy 125.622322 -29.152354) (xy 125.614494 -29.21181) (xy 125.598973 -29.269735)
			(xy 125.576024 -29.325139) (xy 125.54604 -29.377073) (xy 125.509534 -29.424649) (xy 125.467129 -29.467054)
			(xy 125.419553 -29.50356) (xy 125.367619 -29.533544) (xy 125.312215 -29.556493) (xy 125.25429 -29.572014)
			(xy 125.194834 -29.579842) (xy 125.134866 -29.579842) (xy 125.07541 -29.572014) (xy 125.017485 -29.556493)
			(xy 124.962081 -29.533544) (xy 124.910147 -29.50356) (xy 124.862571 -29.467054) (xy 124.820166 -29.424649)
			(xy 124.78366 -29.377073) (xy 124.753676 -29.325139) (xy 124.730727 -29.269735) (xy 124.715206 -29.21181)
			(xy 124.707378 -29.152354) (xy 124.706888 -29.12237) (xy 97.762943 -29.12237) (xy 97.762586 -29.144226)
			(xy 97.754758 -29.203682) (xy 97.739237 -29.261607) (xy 97.716288 -29.317011) (xy 97.686304 -29.368945)
			(xy 97.649798 -29.416521) (xy 97.607393 -29.458926) (xy 97.559817 -29.495432) (xy 97.507883 -29.525416)
			(xy 97.452479 -29.548365) (xy 97.394554 -29.563886) (xy 97.335098 -29.571714) (xy 97.27513 -29.571714)
			(xy 97.215674 -29.563886) (xy 97.157749 -29.548365) (xy 97.102345 -29.525416) (xy 97.050411 -29.495432)
			(xy 97.002835 -29.458926) (xy 96.96043 -29.416521) (xy 96.923924 -29.368945) (xy 96.89394 -29.317011)
			(xy 96.870991 -29.261607) (xy 96.85547 -29.203682) (xy 96.847642 -29.144226) (xy 96.847152 -29.114242)
			(xy 87.522304 -29.114242) (xy 87.522304 -29.12237) (xy 87.521814 -29.152338) (xy 87.513991 -29.21176)
			(xy 87.498478 -29.269653) (xy 87.475542 -29.325026) (xy 87.445575 -29.376932) (xy 87.409088 -29.424482)
			(xy 87.366708 -29.466862) (xy 87.319158 -29.503349) (xy 87.267252 -29.533316) (xy 87.211879 -29.556252)
			(xy 87.153986 -29.571765) (xy 87.094564 -29.579588) (xy 87.034628 -29.579588) (xy 86.975206 -29.571765)
			(xy 86.917313 -29.556252) (xy 86.86194 -29.533316) (xy 86.810034 -29.503349) (xy 86.762484 -29.466862)
			(xy 86.720104 -29.424482) (xy 86.683617 -29.376932) (xy 86.65365 -29.325026) (xy 86.630714 -29.269653)
			(xy 86.615201 -29.21176) (xy 86.607378 -29.152338) (xy 86.606888 -29.12237) (xy 71.762995 -29.12237)
			(xy 71.762638 -29.144226) (xy 71.75481 -29.203682) (xy 71.739289 -29.261607) (xy 71.71634 -29.317011)
			(xy 71.686356 -29.368945) (xy 71.64985 -29.416521) (xy 71.607445 -29.458926) (xy 71.559869 -29.495432)
			(xy 71.507935 -29.525416) (xy 71.452531 -29.548365) (xy 71.394606 -29.563886) (xy 71.33515 -29.571714)
			(xy 71.275182 -29.571714) (xy 71.215726 -29.563886) (xy 71.157801 -29.548365) (xy 71.102397 -29.525416)
			(xy 71.050463 -29.495432) (xy 71.002887 -29.458926) (xy 70.960482 -29.416521) (xy 70.923976 -29.368945)
			(xy 70.893992 -29.317011) (xy 70.871043 -29.261607) (xy 70.855522 -29.203682) (xy 70.847694 -29.144226)
			(xy 70.847204 -29.114242) (xy 61.522356 -29.114242) (xy 61.522356 -29.12237) (xy 61.521866 -29.152338)
			(xy 61.514043 -29.21176) (xy 61.49853 -29.269653) (xy 61.475594 -29.325026) (xy 61.445627 -29.376932)
			(xy 61.40914 -29.424482) (xy 61.36676 -29.466862) (xy 61.31921 -29.503349) (xy 61.267304 -29.533316)
			(xy 61.211931 -29.556252) (xy 61.154038 -29.571765) (xy 61.094616 -29.579588) (xy 61.03468 -29.579588)
			(xy 60.975258 -29.571765) (xy 60.917365 -29.556252) (xy 60.861992 -29.533316) (xy 60.810086 -29.503349)
			(xy 60.762536 -29.466862) (xy 60.720156 -29.424482) (xy 60.683669 -29.376932) (xy 60.653702 -29.325026)
			(xy 60.630766 -29.269653) (xy 60.615253 -29.21176) (xy 60.60743 -29.152338) (xy 60.60694 -29.12237)
			(xy 45.763047 -29.12237) (xy 45.76269 -29.144226) (xy 45.754862 -29.203682) (xy 45.739341 -29.261607)
			(xy 45.716392 -29.317011) (xy 45.686408 -29.368945) (xy 45.649902 -29.416521) (xy 45.607497 -29.458926)
			(xy 45.559921 -29.495432) (xy 45.507987 -29.525416) (xy 45.452583 -29.548365) (xy 45.394658 -29.563886)
			(xy 45.335202 -29.571714) (xy 45.275234 -29.571714) (xy 45.215778 -29.563886) (xy 45.157853 -29.548365)
			(xy 45.102449 -29.525416) (xy 45.050515 -29.495432) (xy 45.002939 -29.458926) (xy 44.960534 -29.416521)
			(xy 44.924028 -29.368945) (xy 44.894044 -29.317011) (xy 44.871095 -29.261607) (xy 44.855574 -29.203682)
			(xy 44.847746 -29.144226) (xy 44.847256 -29.114242) (xy 35.522408 -29.114242) (xy 35.522408 -29.12237)
			(xy 35.521918 -29.152338) (xy 35.514095 -29.21176) (xy 35.498582 -29.269653) (xy 35.475646 -29.325026)
			(xy 35.445679 -29.376932) (xy 35.409192 -29.424482) (xy 35.366812 -29.466862) (xy 35.319262 -29.503349)
			(xy 35.267356 -29.533316) (xy 35.211983 -29.556252) (xy 35.15409 -29.571765) (xy 35.094668 -29.579588)
			(xy 35.034732 -29.579588) (xy 34.97531 -29.571765) (xy 34.917417 -29.556252) (xy 34.862044 -29.533316)
			(xy 34.810138 -29.503349) (xy 34.762588 -29.466862) (xy 34.720208 -29.424482) (xy 34.683721 -29.376932)
			(xy 34.653754 -29.325026) (xy 34.630818 -29.269653) (xy 34.615305 -29.21176) (xy 34.607482 -29.152338)
			(xy 34.606992 -29.12237) (xy 19.763099 -29.12237) (xy 19.762742 -29.144226) (xy 19.754914 -29.203682)
			(xy 19.739393 -29.261607) (xy 19.716444 -29.317011) (xy 19.68646 -29.368945) (xy 19.649954 -29.416521)
			(xy 19.607549 -29.458926) (xy 19.559973 -29.495432) (xy 19.508039 -29.525416) (xy 19.452635 -29.548365)
			(xy 19.39471 -29.563886) (xy 19.335254 -29.571714) (xy 19.275286 -29.571714) (xy 19.21583 -29.563886)
			(xy 19.157905 -29.548365) (xy 19.102501 -29.525416) (xy 19.050567 -29.495432) (xy 19.002991 -29.458926)
			(xy 18.960586 -29.416521) (xy 18.92408 -29.368945) (xy 18.894096 -29.317011) (xy 18.871147 -29.261607)
			(xy 18.855626 -29.203682) (xy 18.847798 -29.144226) (xy 18.847308 -29.114242) (xy 9.52246 -29.114242)
			(xy 9.52246 -29.12237) (xy 9.52197 -29.152338) (xy 9.514147 -29.21176) (xy 9.498634 -29.269653) (xy 9.475698 -29.325026)
			(xy 9.445731 -29.376932) (xy 9.409244 -29.424482) (xy 9.366864 -29.466862) (xy 9.319314 -29.503349)
			(xy 9.267408 -29.533316) (xy 9.212035 -29.556252) (xy 9.154142 -29.571765) (xy 9.09472 -29.579588)
			(xy 9.034784 -29.579588) (xy 8.975362 -29.571765) (xy 8.917469 -29.556252) (xy 8.862096 -29.533316)
			(xy 8.81019 -29.503349) (xy 8.76264 -29.466862) (xy 8.72026 -29.424482) (xy 8.683773 -29.376932)
			(xy 8.653806 -29.325026) (xy 8.63087 -29.269653) (xy 8.615357 -29.21176) (xy 8.607534 -29.152338)
			(xy 8.607044 -29.12237) (xy 0.508 -29.12237) (xy 0.508 -30.922468) (xy 6.752844 -30.922468) (xy 6.752844 -30.058868)
			(xy 6.753334 -30.0289) (xy 6.761157 -29.969478) (xy 6.77667 -29.911585) (xy 6.799606 -29.856212)
			(xy 6.829573 -29.804306) (xy 6.86606 -29.756756) (xy 6.90844 -29.714376) (xy 6.95599 -29.677889)
			(xy 7.007896 -29.647922) (xy 7.063269 -29.624986) (xy 7.121162 -29.609473) (xy 7.180584 -29.60165)
			(xy 7.24052 -29.60165) (xy 7.299942 -29.609473) (xy 7.357835 -29.624986) (xy 7.413208 -29.647922)
			(xy 7.465114 -29.677889) (xy 7.512664 -29.714376) (xy 7.555044 -29.756756) (xy 7.591531 -29.804306)
			(xy 7.621498 -29.856212) (xy 7.644434 -29.911585) (xy 7.659947 -29.969478) (xy 7.66777 -30.0289)
			(xy 7.66826 -30.058868) (xy 7.66826 -30.92069) (xy 21.489416 -30.92069) (xy 21.489416 -30.05709)
			(xy 21.489906 -30.027106) (xy 21.497734 -29.96765) (xy 21.513255 -29.909725) (xy 21.536204 -29.854321)
			(xy 21.566188 -29.802387) (xy 21.602694 -29.754811) (xy 21.645099 -29.712406) (xy 21.692675 -29.6759)
			(xy 21.744609 -29.645916) (xy 21.800013 -29.622967) (xy 21.857938 -29.607446) (xy 21.917394 -29.599618)
			(xy 21.977362 -29.599618) (xy 22.036818 -29.607446) (xy 22.094743 -29.622967) (xy 22.150147 -29.645916)
			(xy 22.202081 -29.6759) (xy 22.249657 -29.712406) (xy 22.292062 -29.754811) (xy 22.328568 -29.802387)
			(xy 22.358552 -29.854321) (xy 22.381501 -29.909725) (xy 22.397022 -29.96765) (xy 22.40485 -30.027106)
			(xy 22.40534 -30.05709) (xy 22.40534 -30.92069) (xy 22.405311 -30.922468) (xy 32.752792 -30.922468)
			(xy 32.752792 -30.058868) (xy 32.753282 -30.0289) (xy 32.761105 -29.969478) (xy 32.776618 -29.911585)
			(xy 32.799554 -29.856212) (xy 32.829521 -29.804306) (xy 32.866008 -29.756756) (xy 32.908388 -29.714376)
			(xy 32.955938 -29.677889) (xy 33.007844 -29.647922) (xy 33.063217 -29.624986) (xy 33.12111 -29.609473)
			(xy 33.180532 -29.60165) (xy 33.240468 -29.60165) (xy 33.29989 -29.609473) (xy 33.357783 -29.624986)
			(xy 33.413156 -29.647922) (xy 33.465062 -29.677889) (xy 33.512612 -29.714376) (xy 33.554992 -29.756756)
			(xy 33.591479 -29.804306) (xy 33.621446 -29.856212) (xy 33.644382 -29.911585) (xy 33.659895 -29.969478)
			(xy 33.667718 -30.0289) (xy 33.668208 -30.058868) (xy 33.668208 -30.92069) (xy 47.489364 -30.92069)
			(xy 47.489364 -30.05709) (xy 47.489854 -30.027106) (xy 47.497682 -29.96765) (xy 47.513203 -29.909725)
			(xy 47.536152 -29.854321) (xy 47.566136 -29.802387) (xy 47.602642 -29.754811) (xy 47.645047 -29.712406)
			(xy 47.692623 -29.6759) (xy 47.744557 -29.645916) (xy 47.799961 -29.622967) (xy 47.857886 -29.607446)
			(xy 47.917342 -29.599618) (xy 47.97731 -29.599618) (xy 48.036766 -29.607446) (xy 48.094691 -29.622967)
			(xy 48.150095 -29.645916) (xy 48.202029 -29.6759) (xy 48.249605 -29.712406) (xy 48.29201 -29.754811)
			(xy 48.328516 -29.802387) (xy 48.3585 -29.854321) (xy 48.381449 -29.909725) (xy 48.39697 -29.96765)
			(xy 48.404798 -30.027106) (xy 48.405288 -30.05709) (xy 48.405288 -30.92069) (xy 48.405259 -30.922468)
			(xy 58.75274 -30.922468) (xy 58.75274 -30.058868) (xy 58.75323 -30.0289) (xy 58.761053 -29.969478)
			(xy 58.776566 -29.911585) (xy 58.799502 -29.856212) (xy 58.829469 -29.804306) (xy 58.865956 -29.756756)
			(xy 58.908336 -29.714376) (xy 58.955886 -29.677889) (xy 59.007792 -29.647922) (xy 59.063165 -29.624986)
			(xy 59.121058 -29.609473) (xy 59.18048 -29.60165) (xy 59.240416 -29.60165) (xy 59.299838 -29.609473)
			(xy 59.357731 -29.624986) (xy 59.413104 -29.647922) (xy 59.46501 -29.677889) (xy 59.51256 -29.714376)
			(xy 59.55494 -29.756756) (xy 59.591427 -29.804306) (xy 59.621394 -29.856212) (xy 59.64433 -29.911585)
			(xy 59.659843 -29.969478) (xy 59.667666 -30.0289) (xy 59.668156 -30.058868) (xy 59.668156 -30.92069)
			(xy 73.489312 -30.92069) (xy 73.489312 -30.05709) (xy 73.489802 -30.027106) (xy 73.49763 -29.96765)
			(xy 73.513151 -29.909725) (xy 73.5361 -29.854321) (xy 73.566084 -29.802387) (xy 73.60259 -29.754811)
			(xy 73.644995 -29.712406) (xy 73.692571 -29.6759) (xy 73.744505 -29.645916) (xy 73.799909 -29.622967)
			(xy 73.857834 -29.607446) (xy 73.91729 -29.599618) (xy 73.977258 -29.599618) (xy 74.036714 -29.607446)
			(xy 74.094639 -29.622967) (xy 74.150043 -29.645916) (xy 74.201977 -29.6759) (xy 74.249553 -29.712406)
			(xy 74.291958 -29.754811) (xy 74.328464 -29.802387) (xy 74.358448 -29.854321) (xy 74.381397 -29.909725)
			(xy 74.396918 -29.96765) (xy 74.404746 -30.027106) (xy 74.405236 -30.05709) (xy 74.405236 -30.92069)
			(xy 74.405207 -30.922468) (xy 84.752688 -30.922468) (xy 84.752688 -30.058868) (xy 84.753178 -30.0289)
			(xy 84.761001 -29.969478) (xy 84.776514 -29.911585) (xy 84.79945 -29.856212) (xy 84.829417 -29.804306)
			(xy 84.865904 -29.756756) (xy 84.908284 -29.714376) (xy 84.955834 -29.677889) (xy 85.00774 -29.647922)
			(xy 85.063113 -29.624986) (xy 85.121006 -29.609473) (xy 85.180428 -29.60165) (xy 85.240364 -29.60165)
			(xy 85.299786 -29.609473) (xy 85.357679 -29.624986) (xy 85.413052 -29.647922) (xy 85.464958 -29.677889)
			(xy 85.512508 -29.714376) (xy 85.554888 -29.756756) (xy 85.591375 -29.804306) (xy 85.621342 -29.856212)
			(xy 85.644278 -29.911585) (xy 85.659791 -29.969478) (xy 85.667614 -30.0289) (xy 85.668104 -30.058868)
			(xy 85.668104 -30.92069) (xy 99.48926 -30.92069) (xy 99.48926 -30.05709) (xy 99.48975 -30.027106)
			(xy 99.497578 -29.96765) (xy 99.513099 -29.909725) (xy 99.536048 -29.854321) (xy 99.566032 -29.802387)
			(xy 99.602538 -29.754811) (xy 99.644943 -29.712406) (xy 99.692519 -29.6759) (xy 99.744453 -29.645916)
			(xy 99.799857 -29.622967) (xy 99.857782 -29.607446) (xy 99.917238 -29.599618) (xy 99.977206 -29.599618)
			(xy 100.036662 -29.607446) (xy 100.094587 -29.622967) (xy 100.149991 -29.645916) (xy 100.201925 -29.6759)
			(xy 100.249501 -29.712406) (xy 100.291906 -29.754811) (xy 100.328412 -29.802387) (xy 100.358396 -29.854321)
			(xy 100.381345 -29.909725) (xy 100.396866 -29.96765) (xy 100.404694 -30.027106) (xy 100.405184 -30.05709)
			(xy 100.405184 -30.92069) (xy 100.405155 -30.922468) (xy 122.852688 -30.922468) (xy 122.852688 -30.058868)
			(xy 122.853178 -30.028884) (xy 122.861006 -29.969428) (xy 122.876527 -29.911503) (xy 122.899476 -29.856099)
			(xy 122.92946 -29.804165) (xy 122.965966 -29.756589) (xy 123.008371 -29.714184) (xy 123.055947 -29.677678)
			(xy 123.107881 -29.647694) (xy 123.163285 -29.624745) (xy 123.22121 -29.609224) (xy 123.280666 -29.601396)
			(xy 123.340634 -29.601396) (xy 123.40009 -29.609224) (xy 123.458015 -29.624745) (xy 123.513419 -29.647694)
			(xy 123.565353 -29.677678) (xy 123.612929 -29.714184) (xy 123.655334 -29.756589) (xy 123.69184 -29.804165)
			(xy 123.721824 -29.856099) (xy 123.744773 -29.911503) (xy 123.760294 -29.969428) (xy 123.768122 -30.028884)
			(xy 123.768612 -30.058868) (xy 123.768612 -30.92069) (xy 137.589768 -30.92069) (xy 137.589768 -30.05709)
			(xy 137.590258 -30.027122) (xy 137.598081 -29.9677) (xy 137.613594 -29.909807) (xy 137.63653 -29.854434)
			(xy 137.666497 -29.802528) (xy 137.702984 -29.754978) (xy 137.745364 -29.712598) (xy 137.792914 -29.676111)
			(xy 137.84482 -29.646144) (xy 137.900193 -29.623208) (xy 137.958086 -29.607695) (xy 138.017508 -29.599872)
			(xy 138.077444 -29.599872) (xy 138.136866 -29.607695) (xy 138.194759 -29.623208) (xy 138.250132 -29.646144)
			(xy 138.302038 -29.676111) (xy 138.349588 -29.712598) (xy 138.391968 -29.754978) (xy 138.428455 -29.802528)
			(xy 138.458422 -29.854434) (xy 138.481358 -29.909807) (xy 138.496871 -29.9677) (xy 138.504694 -30.027122)
			(xy 138.505184 -30.05709) (xy 138.505184 -30.92069) (xy 138.505155 -30.922468) (xy 148.852636 -30.922468)
			(xy 148.852636 -30.058868) (xy 148.853126 -30.028884) (xy 148.860954 -29.969428) (xy 148.876475 -29.911503)
			(xy 148.899424 -29.856099) (xy 148.929408 -29.804165) (xy 148.965914 -29.756589) (xy 149.008319 -29.714184)
			(xy 149.055895 -29.677678) (xy 149.107829 -29.647694) (xy 149.163233 -29.624745) (xy 149.221158 -29.609224)
			(xy 149.280614 -29.601396) (xy 149.340582 -29.601396) (xy 149.400038 -29.609224) (xy 149.457963 -29.624745)
			(xy 149.513367 -29.647694) (xy 149.565301 -29.677678) (xy 149.612877 -29.714184) (xy 149.655282 -29.756589)
			(xy 149.691788 -29.804165) (xy 149.721772 -29.856099) (xy 149.744721 -29.911503) (xy 149.760242 -29.969428)
			(xy 149.76807 -30.028884) (xy 149.76856 -30.058868) (xy 149.76856 -30.92069) (xy 163.589716 -30.92069)
			(xy 163.589716 -30.05709) (xy 163.590206 -30.027122) (xy 163.598029 -29.9677) (xy 163.613542 -29.909807)
			(xy 163.636478 -29.854434) (xy 163.666445 -29.802528) (xy 163.702932 -29.754978) (xy 163.745312 -29.712598)
			(xy 163.792862 -29.676111) (xy 163.844768 -29.646144) (xy 163.900141 -29.623208) (xy 163.958034 -29.607695)
			(xy 164.017456 -29.599872) (xy 164.077392 -29.599872) (xy 164.136814 -29.607695) (xy 164.194707 -29.623208)
			(xy 164.25008 -29.646144) (xy 164.301986 -29.676111) (xy 164.349536 -29.712598) (xy 164.391916 -29.754978)
			(xy 164.428403 -29.802528) (xy 164.45837 -29.854434) (xy 164.481306 -29.909807) (xy 164.496819 -29.9677)
			(xy 164.504642 -30.027122) (xy 164.505132 -30.05709) (xy 164.505132 -30.92069) (xy 164.505103 -30.922468)
			(xy 174.852584 -30.922468) (xy 174.852584 -30.058868) (xy 174.853074 -30.028884) (xy 174.860902 -29.969428)
			(xy 174.876423 -29.911503) (xy 174.899372 -29.856099) (xy 174.929356 -29.804165) (xy 174.965862 -29.756589)
			(xy 175.008267 -29.714184) (xy 175.055843 -29.677678) (xy 175.107777 -29.647694) (xy 175.163181 -29.624745)
			(xy 175.221106 -29.609224) (xy 175.280562 -29.601396) (xy 175.34053 -29.601396) (xy 175.399986 -29.609224)
			(xy 175.457911 -29.624745) (xy 175.513315 -29.647694) (xy 175.565249 -29.677678) (xy 175.612825 -29.714184)
			(xy 175.65523 -29.756589) (xy 175.691736 -29.804165) (xy 175.72172 -29.856099) (xy 175.744669 -29.911503)
			(xy 175.76019 -29.969428) (xy 175.768018 -30.028884) (xy 175.768508 -30.058868) (xy 175.768508 -30.92069)
			(xy 189.589664 -30.92069) (xy 189.589664 -30.05709) (xy 189.590154 -30.027122) (xy 189.597977 -29.9677)
			(xy 189.61349 -29.909807) (xy 189.636426 -29.854434) (xy 189.666393 -29.802528) (xy 189.70288 -29.754978)
			(xy 189.74526 -29.712598) (xy 189.79281 -29.676111) (xy 189.844716 -29.646144) (xy 189.900089 -29.623208)
			(xy 189.957982 -29.607695) (xy 190.017404 -29.599872) (xy 190.07734 -29.599872) (xy 190.136762 -29.607695)
			(xy 190.194655 -29.623208) (xy 190.250028 -29.646144) (xy 190.301934 -29.676111) (xy 190.349484 -29.712598)
			(xy 190.391864 -29.754978) (xy 190.428351 -29.802528) (xy 190.458318 -29.854434) (xy 190.481254 -29.909807)
			(xy 190.496767 -29.9677) (xy 190.50459 -30.027122) (xy 190.50508 -30.05709) (xy 190.50508 -30.92069)
			(xy 190.505051 -30.922468) (xy 200.852532 -30.922468) (xy 200.852532 -30.058868) (xy 200.853022 -30.028884)
			(xy 200.86085 -29.969428) (xy 200.876371 -29.911503) (xy 200.89932 -29.856099) (xy 200.929304 -29.804165)
			(xy 200.96581 -29.756589) (xy 201.008215 -29.714184) (xy 201.055791 -29.677678) (xy 201.107725 -29.647694)
			(xy 201.163129 -29.624745) (xy 201.221054 -29.609224) (xy 201.28051 -29.601396) (xy 201.340478 -29.601396)
			(xy 201.399934 -29.609224) (xy 201.457859 -29.624745) (xy 201.513263 -29.647694) (xy 201.565197 -29.677678)
			(xy 201.612773 -29.714184) (xy 201.655178 -29.756589) (xy 201.691684 -29.804165) (xy 201.721668 -29.856099)
			(xy 201.744617 -29.911503) (xy 201.760138 -29.969428) (xy 201.767966 -30.028884) (xy 201.768456 -30.058868)
			(xy 201.768456 -30.92069) (xy 215.589612 -30.92069) (xy 215.589612 -30.05709) (xy 215.590102 -30.027122)
			(xy 215.597925 -29.9677) (xy 215.613438 -29.909807) (xy 215.636374 -29.854434) (xy 215.666341 -29.802528)
			(xy 215.702828 -29.754978) (xy 215.745208 -29.712598) (xy 215.792758 -29.676111) (xy 215.844664 -29.646144)
			(xy 215.900037 -29.623208) (xy 215.95793 -29.607695) (xy 216.017352 -29.599872) (xy 216.077288 -29.599872)
			(xy 216.13671 -29.607695) (xy 216.194603 -29.623208) (xy 216.249976 -29.646144) (xy 216.301882 -29.676111)
			(xy 216.349432 -29.712598) (xy 216.391812 -29.754978) (xy 216.428299 -29.802528) (xy 216.458266 -29.854434)
			(xy 216.481202 -29.909807) (xy 216.496715 -29.9677) (xy 216.504538 -30.027122) (xy 216.505028 -30.05709)
			(xy 216.505028 -30.92069) (xy 216.504999 -30.922468) (xy 238.952532 -30.922468) (xy 238.952532 -30.058868)
			(xy 238.953022 -30.028884) (xy 238.96085 -29.969428) (xy 238.976371 -29.911503) (xy 238.99932 -29.856099)
			(xy 239.029304 -29.804165) (xy 239.06581 -29.756589) (xy 239.108215 -29.714184) (xy 239.155791 -29.677678)
			(xy 239.207725 -29.647694) (xy 239.263129 -29.624745) (xy 239.321054 -29.609224) (xy 239.38051 -29.601396)
			(xy 239.440478 -29.601396) (xy 239.499934 -29.609224) (xy 239.557859 -29.624745) (xy 239.613263 -29.647694)
			(xy 239.665197 -29.677678) (xy 239.712773 -29.714184) (xy 239.755178 -29.756589) (xy 239.791684 -29.804165)
			(xy 239.821668 -29.856099) (xy 239.844617 -29.911503) (xy 239.860138 -29.969428) (xy 239.867966 -30.028884)
			(xy 239.868456 -30.058868) (xy 239.868456 -30.92069) (xy 253.689612 -30.92069) (xy 253.689612 -30.05709)
			(xy 253.690102 -30.027122) (xy 253.697925 -29.9677) (xy 253.713438 -29.909807) (xy 253.736374 -29.854434)
			(xy 253.766341 -29.802528) (xy 253.802828 -29.754978) (xy 253.845208 -29.712598) (xy 253.892758 -29.676111)
			(xy 253.944664 -29.646144) (xy 254.000037 -29.623208) (xy 254.05793 -29.607695) (xy 254.117352 -29.599872)
			(xy 254.177288 -29.599872) (xy 254.23671 -29.607695) (xy 254.294603 -29.623208) (xy 254.349976 -29.646144)
			(xy 254.401882 -29.676111) (xy 254.449432 -29.712598) (xy 254.491812 -29.754978) (xy 254.528299 -29.802528)
			(xy 254.558266 -29.854434) (xy 254.581202 -29.909807) (xy 254.596715 -29.9677) (xy 254.604538 -30.027122)
			(xy 254.605028 -30.05709) (xy 254.605028 -30.92069) (xy 254.604999 -30.922468) (xy 264.95248 -30.922468)
			(xy 264.95248 -30.058868) (xy 264.95297 -30.028884) (xy 264.960798 -29.969428) (xy 264.976319 -29.911503)
			(xy 264.999268 -29.856099) (xy 265.029252 -29.804165) (xy 265.065758 -29.756589) (xy 265.108163 -29.714184)
			(xy 265.155739 -29.677678) (xy 265.207673 -29.647694) (xy 265.263077 -29.624745) (xy 265.321002 -29.609224)
			(xy 265.380458 -29.601396) (xy 265.440426 -29.601396) (xy 265.499882 -29.609224) (xy 265.557807 -29.624745)
			(xy 265.613211 -29.647694) (xy 265.665145 -29.677678) (xy 265.712721 -29.714184) (xy 265.755126 -29.756589)
			(xy 265.791632 -29.804165) (xy 265.821616 -29.856099) (xy 265.844565 -29.911503) (xy 265.860086 -29.969428)
			(xy 265.867914 -30.028884) (xy 265.868404 -30.058868) (xy 265.868404 -30.92069) (xy 279.68956 -30.92069)
			(xy 279.68956 -30.05709) (xy 279.69005 -30.027122) (xy 279.697873 -29.9677) (xy 279.713386 -29.909807)
			(xy 279.736322 -29.854434) (xy 279.766289 -29.802528) (xy 279.802776 -29.754978) (xy 279.845156 -29.712598)
			(xy 279.892706 -29.676111) (xy 279.944612 -29.646144) (xy 279.999985 -29.623208) (xy 280.057878 -29.607695)
			(xy 280.1173 -29.599872) (xy 280.177236 -29.599872) (xy 280.236658 -29.607695) (xy 280.294551 -29.623208)
			(xy 280.349924 -29.646144) (xy 280.40183 -29.676111) (xy 280.44938 -29.712598) (xy 280.49176 -29.754978)
			(xy 280.528247 -29.802528) (xy 280.558214 -29.854434) (xy 280.58115 -29.909807) (xy 280.596663 -29.9677)
			(xy 280.604486 -30.027122) (xy 280.604976 -30.05709) (xy 280.604976 -30.92069) (xy 280.604947 -30.922468)
			(xy 290.952428 -30.922468) (xy 290.952428 -30.058868) (xy 290.952918 -30.028884) (xy 290.960746 -29.969428)
			(xy 290.976267 -29.911503) (xy 290.999216 -29.856099) (xy 291.0292 -29.804165) (xy 291.065706 -29.756589)
			(xy 291.108111 -29.714184) (xy 291.155687 -29.677678) (xy 291.207621 -29.647694) (xy 291.263025 -29.624745)
			(xy 291.32095 -29.609224) (xy 291.380406 -29.601396) (xy 291.440374 -29.601396) (xy 291.49983 -29.609224)
			(xy 291.557755 -29.624745) (xy 291.613159 -29.647694) (xy 291.665093 -29.677678) (xy 291.712669 -29.714184)
			(xy 291.755074 -29.756589) (xy 291.79158 -29.804165) (xy 291.821564 -29.856099) (xy 291.844513 -29.911503)
			(xy 291.860034 -29.969428) (xy 291.867862 -30.028884) (xy 291.868352 -30.058868) (xy 291.868352 -30.92069)
			(xy 305.689508 -30.92069) (xy 305.689508 -30.05709) (xy 305.689998 -30.027122) (xy 305.697821 -29.9677)
			(xy 305.713334 -29.909807) (xy 305.73627 -29.854434) (xy 305.766237 -29.802528) (xy 305.802724 -29.754978)
			(xy 305.845104 -29.712598) (xy 305.892654 -29.676111) (xy 305.94456 -29.646144) (xy 305.999933 -29.623208)
			(xy 306.057826 -29.607695) (xy 306.117248 -29.599872) (xy 306.177184 -29.599872) (xy 306.236606 -29.607695)
			(xy 306.294499 -29.623208) (xy 306.349872 -29.646144) (xy 306.401778 -29.676111) (xy 306.449328 -29.712598)
			(xy 306.491708 -29.754978) (xy 306.528195 -29.802528) (xy 306.558162 -29.854434) (xy 306.581098 -29.909807)
			(xy 306.596611 -29.9677) (xy 306.604434 -30.027122) (xy 306.604924 -30.05709) (xy 306.604924 -30.92069)
			(xy 306.604895 -30.922468) (xy 316.952376 -30.922468) (xy 316.952376 -30.058868) (xy 316.952866 -30.028884)
			(xy 316.960694 -29.969428) (xy 316.976215 -29.911503) (xy 316.999164 -29.856099) (xy 317.029148 -29.804165)
			(xy 317.065654 -29.756589) (xy 317.108059 -29.714184) (xy 317.155635 -29.677678) (xy 317.207569 -29.647694)
			(xy 317.262973 -29.624745) (xy 317.320898 -29.609224) (xy 317.380354 -29.601396) (xy 317.440322 -29.601396)
			(xy 317.499778 -29.609224) (xy 317.557703 -29.624745) (xy 317.613107 -29.647694) (xy 317.665041 -29.677678)
			(xy 317.712617 -29.714184) (xy 317.755022 -29.756589) (xy 317.791528 -29.804165) (xy 317.821512 -29.856099)
			(xy 317.844461 -29.911503) (xy 317.859982 -29.969428) (xy 317.86781 -30.028884) (xy 317.8683 -30.058868)
			(xy 317.8683 -30.92069) (xy 331.689456 -30.92069) (xy 331.689456 -30.05709) (xy 331.689946 -30.027122)
			(xy 331.697769 -29.9677) (xy 331.713282 -29.909807) (xy 331.736218 -29.854434) (xy 331.766185 -29.802528)
			(xy 331.802672 -29.754978) (xy 331.845052 -29.712598) (xy 331.892602 -29.676111) (xy 331.944508 -29.646144)
			(xy 331.999881 -29.623208) (xy 332.057774 -29.607695) (xy 332.117196 -29.599872) (xy 332.177132 -29.599872)
			(xy 332.236554 -29.607695) (xy 332.294447 -29.623208) (xy 332.34982 -29.646144) (xy 332.401726 -29.676111)
			(xy 332.449276 -29.712598) (xy 332.491656 -29.754978) (xy 332.528143 -29.802528) (xy 332.55811 -29.854434)
			(xy 332.581046 -29.909807) (xy 332.596559 -29.9677) (xy 332.604382 -30.027122) (xy 332.604872 -30.05709)
			(xy 332.604872 -30.92069) (xy 332.604843 -30.922468) (xy 355.052884 -30.922468) (xy 355.052884 -30.058868)
			(xy 355.053374 -30.0289) (xy 355.061197 -29.969478) (xy 355.07671 -29.911585) (xy 355.099646 -29.856212)
			(xy 355.129613 -29.804306) (xy 355.1661 -29.756756) (xy 355.20848 -29.714376) (xy 355.25603 -29.677889)
			(xy 355.307936 -29.647922) (xy 355.363309 -29.624986) (xy 355.421202 -29.609473) (xy 355.480624 -29.60165)
			(xy 355.54056 -29.60165) (xy 355.599982 -29.609473) (xy 355.657875 -29.624986) (xy 355.713248 -29.647922)
			(xy 355.765154 -29.677889) (xy 355.812704 -29.714376) (xy 355.855084 -29.756756) (xy 355.891571 -29.804306)
			(xy 355.921538 -29.856212) (xy 355.944474 -29.911585) (xy 355.959987 -29.969478) (xy 355.96781 -30.0289)
			(xy 355.9683 -30.058868) (xy 355.9683 -30.92069) (xy 369.789456 -30.92069) (xy 369.789456 -30.05709)
			(xy 369.789946 -30.027106) (xy 369.797774 -29.96765) (xy 369.813295 -29.909725) (xy 369.836244 -29.854321)
			(xy 369.866228 -29.802387) (xy 369.902734 -29.754811) (xy 369.945139 -29.712406) (xy 369.992715 -29.6759)
			(xy 370.044649 -29.645916) (xy 370.100053 -29.622967) (xy 370.157978 -29.607446) (xy 370.217434 -29.599618)
			(xy 370.277402 -29.599618) (xy 370.336858 -29.607446) (xy 370.394783 -29.622967) (xy 370.450187 -29.645916)
			(xy 370.502121 -29.6759) (xy 370.549697 -29.712406) (xy 370.592102 -29.754811) (xy 370.628608 -29.802387)
			(xy 370.658592 -29.854321) (xy 370.681541 -29.909725) (xy 370.697062 -29.96765) (xy 370.70489 -30.027106)
			(xy 370.70538 -30.05709) (xy 370.70538 -30.92069) (xy 370.705351 -30.922468) (xy 381.052832 -30.922468)
			(xy 381.052832 -30.058868) (xy 381.053322 -30.0289) (xy 381.061145 -29.969478) (xy 381.076658 -29.911585)
			(xy 381.099594 -29.856212) (xy 381.129561 -29.804306) (xy 381.166048 -29.756756) (xy 381.208428 -29.714376)
			(xy 381.255978 -29.677889) (xy 381.307884 -29.647922) (xy 381.363257 -29.624986) (xy 381.42115 -29.609473)
			(xy 381.480572 -29.60165) (xy 381.540508 -29.60165) (xy 381.59993 -29.609473) (xy 381.657823 -29.624986)
			(xy 381.713196 -29.647922) (xy 381.765102 -29.677889) (xy 381.812652 -29.714376) (xy 381.855032 -29.756756)
			(xy 381.891519 -29.804306) (xy 381.921486 -29.856212) (xy 381.944422 -29.911585) (xy 381.959935 -29.969478)
			(xy 381.967758 -30.0289) (xy 381.968248 -30.058868) (xy 381.968248 -30.92069) (xy 395.789404 -30.92069)
			(xy 395.789404 -30.05709) (xy 395.789894 -30.027106) (xy 395.797722 -29.96765) (xy 395.813243 -29.909725)
			(xy 395.836192 -29.854321) (xy 395.866176 -29.802387) (xy 395.902682 -29.754811) (xy 395.945087 -29.712406)
			(xy 395.992663 -29.6759) (xy 396.044597 -29.645916) (xy 396.100001 -29.622967) (xy 396.157926 -29.607446)
			(xy 396.217382 -29.599618) (xy 396.27735 -29.599618) (xy 396.336806 -29.607446) (xy 396.394731 -29.622967)
			(xy 396.450135 -29.645916) (xy 396.502069 -29.6759) (xy 396.549645 -29.712406) (xy 396.59205 -29.754811)
			(xy 396.628556 -29.802387) (xy 396.65854 -29.854321) (xy 396.681489 -29.909725) (xy 396.69701 -29.96765)
			(xy 396.704838 -30.027106) (xy 396.705328 -30.05709) (xy 396.705328 -30.92069) (xy 396.705299 -30.922468)
			(xy 407.05278 -30.922468) (xy 407.05278 -30.058868) (xy 407.05327 -30.0289) (xy 407.061093 -29.969478)
			(xy 407.076606 -29.911585) (xy 407.099542 -29.856212) (xy 407.129509 -29.804306) (xy 407.165996 -29.756756)
			(xy 407.208376 -29.714376) (xy 407.255926 -29.677889) (xy 407.307832 -29.647922) (xy 407.363205 -29.624986)
			(xy 407.421098 -29.609473) (xy 407.48052 -29.60165) (xy 407.540456 -29.60165) (xy 407.599878 -29.609473)
			(xy 407.657771 -29.624986) (xy 407.713144 -29.647922) (xy 407.76505 -29.677889) (xy 407.8126 -29.714376)
			(xy 407.85498 -29.756756) (xy 407.891467 -29.804306) (xy 407.921434 -29.856212) (xy 407.94437 -29.911585)
			(xy 407.959883 -29.969478) (xy 407.967706 -30.0289) (xy 407.968196 -30.058868) (xy 407.968196 -30.92069)
			(xy 421.789352 -30.92069) (xy 421.789352 -30.05709) (xy 421.789842 -30.027106) (xy 421.79767 -29.96765)
			(xy 421.813191 -29.909725) (xy 421.83614 -29.854321) (xy 421.866124 -29.802387) (xy 421.90263 -29.754811)
			(xy 421.945035 -29.712406) (xy 421.992611 -29.6759) (xy 422.044545 -29.645916) (xy 422.099949 -29.622967)
			(xy 422.157874 -29.607446) (xy 422.21733 -29.599618) (xy 422.277298 -29.599618) (xy 422.336754 -29.607446)
			(xy 422.394679 -29.622967) (xy 422.450083 -29.645916) (xy 422.502017 -29.6759) (xy 422.549593 -29.712406)
			(xy 422.591998 -29.754811) (xy 422.628504 -29.802387) (xy 422.658488 -29.854321) (xy 422.681437 -29.909725)
			(xy 422.696958 -29.96765) (xy 422.704786 -30.027106) (xy 422.705276 -30.05709) (xy 422.705276 -30.92069)
			(xy 422.705247 -30.922468) (xy 433.052728 -30.922468) (xy 433.052728 -30.058868) (xy 433.053218 -30.0289)
			(xy 433.061041 -29.969478) (xy 433.076554 -29.911585) (xy 433.09949 -29.856212) (xy 433.129457 -29.804306)
			(xy 433.165944 -29.756756) (xy 433.208324 -29.714376) (xy 433.255874 -29.677889) (xy 433.30778 -29.647922)
			(xy 433.363153 -29.624986) (xy 433.421046 -29.609473) (xy 433.480468 -29.60165) (xy 433.540404 -29.60165)
			(xy 433.599826 -29.609473) (xy 433.657719 -29.624986) (xy 433.713092 -29.647922) (xy 433.764998 -29.677889)
			(xy 433.812548 -29.714376) (xy 433.854928 -29.756756) (xy 433.891415 -29.804306) (xy 433.921382 -29.856212)
			(xy 433.944318 -29.911585) (xy 433.959831 -29.969478) (xy 433.967654 -30.0289) (xy 433.968144 -30.058868)
			(xy 433.968144 -30.92069) (xy 447.7893 -30.92069) (xy 447.7893 -30.05709) (xy 447.78979 -30.027106)
			(xy 447.797618 -29.96765) (xy 447.813139 -29.909725) (xy 447.836088 -29.854321) (xy 447.866072 -29.802387)
			(xy 447.902578 -29.754811) (xy 447.944983 -29.712406) (xy 447.992559 -29.6759) (xy 448.044493 -29.645916)
			(xy 448.099897 -29.622967) (xy 448.157822 -29.607446) (xy 448.217278 -29.599618) (xy 448.277246 -29.599618)
			(xy 448.336702 -29.607446) (xy 448.394627 -29.622967) (xy 448.450031 -29.645916) (xy 448.501965 -29.6759)
			(xy 448.549541 -29.712406) (xy 448.591946 -29.754811) (xy 448.628452 -29.802387) (xy 448.658436 -29.854321)
			(xy 448.681385 -29.909725) (xy 448.696906 -29.96765) (xy 448.704734 -30.027106) (xy 448.705224 -30.05709)
			(xy 448.705224 -30.745738) (xy 457.614517 -30.745738) (xy 457.614517 -30.616598) (xy 457.622467 -30.487703)
			(xy 457.638337 -30.359543) (xy 457.662066 -30.232602) (xy 457.693565 -30.107363) (xy 457.732714 -29.9843)
			(xy 457.779365 -29.863881) (xy 457.83334 -29.746562) (xy 457.894435 -29.632788) (xy 457.962418 -29.522991)
			(xy 458.037032 -29.417588) (xy 458.117993 -29.316978) (xy 458.204993 -29.221543) (xy 458.297704 -29.131644)
			(xy 458.395774 -29.047623) (xy 458.498829 -28.969799) (xy 458.60648 -28.898467) (xy 458.718319 -28.833897)
			(xy 458.83392 -28.776335) (xy 458.952845 -28.725998) (xy 459.074644 -28.683078) (xy 459.198854 -28.647737)
			(xy 459.325003 -28.62011) (xy 459.452615 -28.600301) (xy 459.581204 -28.588385) (xy 459.710282 -28.584409)
			(xy 459.83936 -28.588385) (xy 459.967949 -28.600301) (xy 460.095561 -28.62011) (xy 460.22171 -28.647737)
			(xy 460.34592 -28.683078) (xy 460.467719 -28.725998) (xy 460.586644 -28.776335) (xy 460.702245 -28.833897)
			(xy 460.814084 -28.898467) (xy 460.921735 -28.969799) (xy 461.02479 -29.047623) (xy 461.12286 -29.131644)
			(xy 461.215571 -29.221543) (xy 461.302571 -29.316978) (xy 461.383532 -29.417588) (xy 461.458146 -29.522991)
			(xy 461.526129 -29.632788) (xy 461.587224 -29.746562) (xy 461.641199 -29.863881) (xy 461.68785 -29.9843)
			(xy 461.726999 -30.107363) (xy 461.758498 -30.232602) (xy 461.782227 -30.359543) (xy 461.798097 -30.487703)
			(xy 461.806047 -30.616598) (xy 461.806544 -30.681168) (xy 461.806047 -30.745738) (xy 461.798097 -30.874633)
			(xy 461.782227 -31.002793) (xy 461.758498 -31.129734) (xy 461.726999 -31.254973) (xy 461.68785 -31.378036)
			(xy 461.641199 -31.498455) (xy 461.587224 -31.615774) (xy 461.526129 -31.729548) (xy 461.458146 -31.839345)
			(xy 461.383532 -31.944748) (xy 461.302571 -32.045358) (xy 461.215571 -32.140793) (xy 461.12286 -32.230692)
			(xy 461.02479 -32.314713) (xy 460.921735 -32.392537) (xy 460.814084 -32.463869) (xy 460.702245 -32.528439)
			(xy 460.586644 -32.586001) (xy 460.467719 -32.636338) (xy 460.34592 -32.679258) (xy 460.22171 -32.714599)
			(xy 460.095561 -32.742226) (xy 459.967949 -32.762035) (xy 459.83936 -32.773951) (xy 459.710282 -32.777928)
			(xy 459.581204 -32.773951) (xy 459.452615 -32.762035) (xy 459.325003 -32.742226) (xy 459.198854 -32.714599)
			(xy 459.074644 -32.679258) (xy 458.952845 -32.636338) (xy 458.83392 -32.586001) (xy 458.718319 -32.528439)
			(xy 458.60648 -32.463869) (xy 458.498829 -32.392537) (xy 458.395774 -32.314713) (xy 458.297704 -32.230692)
			(xy 458.204993 -32.140793) (xy 458.117993 -32.045358) (xy 458.037032 -31.944748) (xy 457.962418 -31.839345)
			(xy 457.894435 -31.729548) (xy 457.83334 -31.615774) (xy 457.779365 -31.498455) (xy 457.732714 -31.378036)
			(xy 457.693565 -31.254973) (xy 457.662066 -31.129734) (xy 457.638337 -31.002793) (xy 457.622467 -30.874633)
			(xy 457.614517 -30.745738) (xy 448.705224 -30.745738) (xy 448.705224 -30.92069) (xy 448.704734 -30.950674)
			(xy 448.696906 -31.01013) (xy 448.681385 -31.068055) (xy 448.658436 -31.123459) (xy 448.628452 -31.175393)
			(xy 448.591946 -31.222969) (xy 448.549541 -31.265374) (xy 448.501965 -31.30188) (xy 448.450031 -31.331864)
			(xy 448.394627 -31.354813) (xy 448.336702 -31.370334) (xy 448.277246 -31.378162) (xy 448.217278 -31.378162)
			(xy 448.157822 -31.370334) (xy 448.099897 -31.354813) (xy 448.044493 -31.331864) (xy 447.992559 -31.30188)
			(xy 447.944983 -31.265374) (xy 447.902578 -31.222969) (xy 447.866072 -31.175393) (xy 447.836088 -31.123459)
			(xy 447.813139 -31.068055) (xy 447.797618 -31.01013) (xy 447.78979 -30.950674) (xy 447.7893 -30.92069)
			(xy 433.968144 -30.92069) (xy 433.968144 -30.922468) (xy 433.967654 -30.952436) (xy 433.959831 -31.011858)
			(xy 433.944318 -31.069751) (xy 433.921382 -31.125124) (xy 433.891415 -31.17703) (xy 433.854928 -31.22458)
			(xy 433.812548 -31.26696) (xy 433.764998 -31.303447) (xy 433.713092 -31.333414) (xy 433.657719 -31.35635)
			(xy 433.599826 -31.371863) (xy 433.540404 -31.379686) (xy 433.480468 -31.379686) (xy 433.421046 -31.371863)
			(xy 433.363153 -31.35635) (xy 433.30778 -31.333414) (xy 433.255874 -31.303447) (xy 433.208324 -31.26696)
			(xy 433.165944 -31.22458) (xy 433.129457 -31.17703) (xy 433.09949 -31.125124) (xy 433.076554 -31.069751)
			(xy 433.061041 -31.011858) (xy 433.053218 -30.952436) (xy 433.052728 -30.922468) (xy 422.705247 -30.922468)
			(xy 422.704786 -30.950674) (xy 422.696958 -31.01013) (xy 422.681437 -31.068055) (xy 422.658488 -31.123459)
			(xy 422.628504 -31.175393) (xy 422.591998 -31.222969) (xy 422.549593 -31.265374) (xy 422.502017 -31.30188)
			(xy 422.450083 -31.331864) (xy 422.394679 -31.354813) (xy 422.336754 -31.370334) (xy 422.277298 -31.378162)
			(xy 422.21733 -31.378162) (xy 422.157874 -31.370334) (xy 422.099949 -31.354813) (xy 422.044545 -31.331864)
			(xy 421.992611 -31.30188) (xy 421.945035 -31.265374) (xy 421.90263 -31.222969) (xy 421.866124 -31.175393)
			(xy 421.83614 -31.123459) (xy 421.813191 -31.068055) (xy 421.79767 -31.01013) (xy 421.789842 -30.950674)
			(xy 421.789352 -30.92069) (xy 407.968196 -30.92069) (xy 407.968196 -30.922468) (xy 407.967706 -30.952436)
			(xy 407.959883 -31.011858) (xy 407.94437 -31.069751) (xy 407.921434 -31.125124) (xy 407.891467 -31.17703)
			(xy 407.85498 -31.22458) (xy 407.8126 -31.26696) (xy 407.76505 -31.303447) (xy 407.713144 -31.333414)
			(xy 407.657771 -31.35635) (xy 407.599878 -31.371863) (xy 407.540456 -31.379686) (xy 407.48052 -31.379686)
			(xy 407.421098 -31.371863) (xy 407.363205 -31.35635) (xy 407.307832 -31.333414) (xy 407.255926 -31.303447)
			(xy 407.208376 -31.26696) (xy 407.165996 -31.22458) (xy 407.129509 -31.17703) (xy 407.099542 -31.125124)
			(xy 407.076606 -31.069751) (xy 407.061093 -31.011858) (xy 407.05327 -30.952436) (xy 407.05278 -30.922468)
			(xy 396.705299 -30.922468) (xy 396.704838 -30.950674) (xy 396.69701 -31.01013) (xy 396.681489 -31.068055)
			(xy 396.65854 -31.123459) (xy 396.628556 -31.175393) (xy 396.59205 -31.222969) (xy 396.549645 -31.265374)
			(xy 396.502069 -31.30188) (xy 396.450135 -31.331864) (xy 396.394731 -31.354813) (xy 396.336806 -31.370334)
			(xy 396.27735 -31.378162) (xy 396.217382 -31.378162) (xy 396.157926 -31.370334) (xy 396.100001 -31.354813)
			(xy 396.044597 -31.331864) (xy 395.992663 -31.30188) (xy 395.945087 -31.265374) (xy 395.902682 -31.222969)
			(xy 395.866176 -31.175393) (xy 395.836192 -31.123459) (xy 395.813243 -31.068055) (xy 395.797722 -31.01013)
			(xy 395.789894 -30.950674) (xy 395.789404 -30.92069) (xy 381.968248 -30.92069) (xy 381.968248 -30.922468)
			(xy 381.967758 -30.952436) (xy 381.959935 -31.011858) (xy 381.944422 -31.069751) (xy 381.921486 -31.125124)
			(xy 381.891519 -31.17703) (xy 381.855032 -31.22458) (xy 381.812652 -31.26696) (xy 381.765102 -31.303447)
			(xy 381.713196 -31.333414) (xy 381.657823 -31.35635) (xy 381.59993 -31.371863) (xy 381.540508 -31.379686)
			(xy 381.480572 -31.379686) (xy 381.42115 -31.371863) (xy 381.363257 -31.35635) (xy 381.307884 -31.333414)
			(xy 381.255978 -31.303447) (xy 381.208428 -31.26696) (xy 381.166048 -31.22458) (xy 381.129561 -31.17703)
			(xy 381.099594 -31.125124) (xy 381.076658 -31.069751) (xy 381.061145 -31.011858) (xy 381.053322 -30.952436)
			(xy 381.052832 -30.922468) (xy 370.705351 -30.922468) (xy 370.70489 -30.950674) (xy 370.697062 -31.01013)
			(xy 370.681541 -31.068055) (xy 370.658592 -31.123459) (xy 370.628608 -31.175393) (xy 370.592102 -31.222969)
			(xy 370.549697 -31.265374) (xy 370.502121 -31.30188) (xy 370.450187 -31.331864) (xy 370.394783 -31.354813)
			(xy 370.336858 -31.370334) (xy 370.277402 -31.378162) (xy 370.217434 -31.378162) (xy 370.157978 -31.370334)
			(xy 370.100053 -31.354813) (xy 370.044649 -31.331864) (xy 369.992715 -31.30188) (xy 369.945139 -31.265374)
			(xy 369.902734 -31.222969) (xy 369.866228 -31.175393) (xy 369.836244 -31.123459) (xy 369.813295 -31.068055)
			(xy 369.797774 -31.01013) (xy 369.789946 -30.950674) (xy 369.789456 -30.92069) (xy 355.9683 -30.92069)
			(xy 355.9683 -30.922468) (xy 355.96781 -30.952436) (xy 355.959987 -31.011858) (xy 355.944474 -31.069751)
			(xy 355.921538 -31.125124) (xy 355.891571 -31.17703) (xy 355.855084 -31.22458) (xy 355.812704 -31.26696)
			(xy 355.765154 -31.303447) (xy 355.713248 -31.333414) (xy 355.657875 -31.35635) (xy 355.599982 -31.371863)
			(xy 355.54056 -31.379686) (xy 355.480624 -31.379686) (xy 355.421202 -31.371863) (xy 355.363309 -31.35635)
			(xy 355.307936 -31.333414) (xy 355.25603 -31.303447) (xy 355.20848 -31.26696) (xy 355.1661 -31.22458)
			(xy 355.129613 -31.17703) (xy 355.099646 -31.125124) (xy 355.07671 -31.069751) (xy 355.061197 -31.011858)
			(xy 355.053374 -30.952436) (xy 355.052884 -30.922468) (xy 332.604843 -30.922468) (xy 332.604382 -30.950658)
			(xy 332.596559 -31.01008) (xy 332.581046 -31.067973) (xy 332.55811 -31.123346) (xy 332.528143 -31.175252)
			(xy 332.491656 -31.222802) (xy 332.449276 -31.265182) (xy 332.401726 -31.301669) (xy 332.34982 -31.331636)
			(xy 332.294447 -31.354572) (xy 332.236554 -31.370085) (xy 332.177132 -31.377908) (xy 332.117196 -31.377908)
			(xy 332.057774 -31.370085) (xy 331.999881 -31.354572) (xy 331.944508 -31.331636) (xy 331.892602 -31.301669)
			(xy 331.845052 -31.265182) (xy 331.802672 -31.222802) (xy 331.766185 -31.175252) (xy 331.736218 -31.123346)
			(xy 331.713282 -31.067973) (xy 331.697769 -31.01008) (xy 331.689946 -30.950658) (xy 331.689456 -30.92069)
			(xy 317.8683 -30.92069) (xy 317.8683 -30.922468) (xy 317.86781 -30.952452) (xy 317.859982 -31.011908)
			(xy 317.844461 -31.069833) (xy 317.821512 -31.125237) (xy 317.791528 -31.177171) (xy 317.755022 -31.224747)
			(xy 317.712617 -31.267152) (xy 317.665041 -31.303658) (xy 317.613107 -31.333642) (xy 317.557703 -31.356591)
			(xy 317.499778 -31.372112) (xy 317.440322 -31.37994) (xy 317.380354 -31.37994) (xy 317.320898 -31.372112)
			(xy 317.262973 -31.356591) (xy 317.207569 -31.333642) (xy 317.155635 -31.303658) (xy 317.108059 -31.267152)
			(xy 317.065654 -31.224747) (xy 317.029148 -31.177171) (xy 316.999164 -31.125237) (xy 316.976215 -31.069833)
			(xy 316.960694 -31.011908) (xy 316.952866 -30.952452) (xy 316.952376 -30.922468) (xy 306.604895 -30.922468)
			(xy 306.604434 -30.950658) (xy 306.596611 -31.01008) (xy 306.581098 -31.067973) (xy 306.558162 -31.123346)
			(xy 306.528195 -31.175252) (xy 306.491708 -31.222802) (xy 306.449328 -31.265182) (xy 306.401778 -31.301669)
			(xy 306.349872 -31.331636) (xy 306.294499 -31.354572) (xy 306.236606 -31.370085) (xy 306.177184 -31.377908)
			(xy 306.117248 -31.377908) (xy 306.057826 -31.370085) (xy 305.999933 -31.354572) (xy 305.94456 -31.331636)
			(xy 305.892654 -31.301669) (xy 305.845104 -31.265182) (xy 305.802724 -31.222802) (xy 305.766237 -31.175252)
			(xy 305.73627 -31.123346) (xy 305.713334 -31.067973) (xy 305.697821 -31.01008) (xy 305.689998 -30.950658)
			(xy 305.689508 -30.92069) (xy 291.868352 -30.92069) (xy 291.868352 -30.922468) (xy 291.867862 -30.952452)
			(xy 291.860034 -31.011908) (xy 291.844513 -31.069833) (xy 291.821564 -31.125237) (xy 291.79158 -31.177171)
			(xy 291.755074 -31.224747) (xy 291.712669 -31.267152) (xy 291.665093 -31.303658) (xy 291.613159 -31.333642)
			(xy 291.557755 -31.356591) (xy 291.49983 -31.372112) (xy 291.440374 -31.37994) (xy 291.380406 -31.37994)
			(xy 291.32095 -31.372112) (xy 291.263025 -31.356591) (xy 291.207621 -31.333642) (xy 291.155687 -31.303658)
			(xy 291.108111 -31.267152) (xy 291.065706 -31.224747) (xy 291.0292 -31.177171) (xy 290.999216 -31.125237)
			(xy 290.976267 -31.069833) (xy 290.960746 -31.011908) (xy 290.952918 -30.952452) (xy 290.952428 -30.922468)
			(xy 280.604947 -30.922468) (xy 280.604486 -30.950658) (xy 280.596663 -31.01008) (xy 280.58115 -31.067973)
			(xy 280.558214 -31.123346) (xy 280.528247 -31.175252) (xy 280.49176 -31.222802) (xy 280.44938 -31.265182)
			(xy 280.40183 -31.301669) (xy 280.349924 -31.331636) (xy 280.294551 -31.354572) (xy 280.236658 -31.370085)
			(xy 280.177236 -31.377908) (xy 280.1173 -31.377908) (xy 280.057878 -31.370085) (xy 279.999985 -31.354572)
			(xy 279.944612 -31.331636) (xy 279.892706 -31.301669) (xy 279.845156 -31.265182) (xy 279.802776 -31.222802)
			(xy 279.766289 -31.175252) (xy 279.736322 -31.123346) (xy 279.713386 -31.067973) (xy 279.697873 -31.01008)
			(xy 279.69005 -30.950658) (xy 279.68956 -30.92069) (xy 265.868404 -30.92069) (xy 265.868404 -30.922468)
			(xy 265.867914 -30.952452) (xy 265.860086 -31.011908) (xy 265.844565 -31.069833) (xy 265.821616 -31.125237)
			(xy 265.791632 -31.177171) (xy 265.755126 -31.224747) (xy 265.712721 -31.267152) (xy 265.665145 -31.303658)
			(xy 265.613211 -31.333642) (xy 265.557807 -31.356591) (xy 265.499882 -31.372112) (xy 265.440426 -31.37994)
			(xy 265.380458 -31.37994) (xy 265.321002 -31.372112) (xy 265.263077 -31.356591) (xy 265.207673 -31.333642)
			(xy 265.155739 -31.303658) (xy 265.108163 -31.267152) (xy 265.065758 -31.224747) (xy 265.029252 -31.177171)
			(xy 264.999268 -31.125237) (xy 264.976319 -31.069833) (xy 264.960798 -31.011908) (xy 264.95297 -30.952452)
			(xy 264.95248 -30.922468) (xy 254.604999 -30.922468) (xy 254.604538 -30.950658) (xy 254.596715 -31.01008)
			(xy 254.581202 -31.067973) (xy 254.558266 -31.123346) (xy 254.528299 -31.175252) (xy 254.491812 -31.222802)
			(xy 254.449432 -31.265182) (xy 254.401882 -31.301669) (xy 254.349976 -31.331636) (xy 254.294603 -31.354572)
			(xy 254.23671 -31.370085) (xy 254.177288 -31.377908) (xy 254.117352 -31.377908) (xy 254.05793 -31.370085)
			(xy 254.000037 -31.354572) (xy 253.944664 -31.331636) (xy 253.892758 -31.301669) (xy 253.845208 -31.265182)
			(xy 253.802828 -31.222802) (xy 253.766341 -31.175252) (xy 253.736374 -31.123346) (xy 253.713438 -31.067973)
			(xy 253.697925 -31.01008) (xy 253.690102 -30.950658) (xy 253.689612 -30.92069) (xy 239.868456 -30.92069)
			(xy 239.868456 -30.922468) (xy 239.867966 -30.952452) (xy 239.860138 -31.011908) (xy 239.844617 -31.069833)
			(xy 239.821668 -31.125237) (xy 239.791684 -31.177171) (xy 239.755178 -31.224747) (xy 239.712773 -31.267152)
			(xy 239.665197 -31.303658) (xy 239.613263 -31.333642) (xy 239.557859 -31.356591) (xy 239.499934 -31.372112)
			(xy 239.440478 -31.37994) (xy 239.38051 -31.37994) (xy 239.321054 -31.372112) (xy 239.263129 -31.356591)
			(xy 239.207725 -31.333642) (xy 239.155791 -31.303658) (xy 239.108215 -31.267152) (xy 239.06581 -31.224747)
			(xy 239.029304 -31.177171) (xy 238.99932 -31.125237) (xy 238.976371 -31.069833) (xy 238.96085 -31.011908)
			(xy 238.953022 -30.952452) (xy 238.952532 -30.922468) (xy 216.504999 -30.922468) (xy 216.504538 -30.950658)
			(xy 216.496715 -31.01008) (xy 216.481202 -31.067973) (xy 216.458266 -31.123346) (xy 216.428299 -31.175252)
			(xy 216.391812 -31.222802) (xy 216.349432 -31.265182) (xy 216.301882 -31.301669) (xy 216.249976 -31.331636)
			(xy 216.194603 -31.354572) (xy 216.13671 -31.370085) (xy 216.077288 -31.377908) (xy 216.017352 -31.377908)
			(xy 215.95793 -31.370085) (xy 215.900037 -31.354572) (xy 215.844664 -31.331636) (xy 215.792758 -31.301669)
			(xy 215.745208 -31.265182) (xy 215.702828 -31.222802) (xy 215.666341 -31.175252) (xy 215.636374 -31.123346)
			(xy 215.613438 -31.067973) (xy 215.597925 -31.01008) (xy 215.590102 -30.950658) (xy 215.589612 -30.92069)
			(xy 201.768456 -30.92069) (xy 201.768456 -30.922468) (xy 201.767966 -30.952452) (xy 201.760138 -31.011908)
			(xy 201.744617 -31.069833) (xy 201.721668 -31.125237) (xy 201.691684 -31.177171) (xy 201.655178 -31.224747)
			(xy 201.612773 -31.267152) (xy 201.565197 -31.303658) (xy 201.513263 -31.333642) (xy 201.457859 -31.356591)
			(xy 201.399934 -31.372112) (xy 201.340478 -31.37994) (xy 201.28051 -31.37994) (xy 201.221054 -31.372112)
			(xy 201.163129 -31.356591) (xy 201.107725 -31.333642) (xy 201.055791 -31.303658) (xy 201.008215 -31.267152)
			(xy 200.96581 -31.224747) (xy 200.929304 -31.177171) (xy 200.89932 -31.125237) (xy 200.876371 -31.069833)
			(xy 200.86085 -31.011908) (xy 200.853022 -30.952452) (xy 200.852532 -30.922468) (xy 190.505051 -30.922468)
			(xy 190.50459 -30.950658) (xy 190.496767 -31.01008) (xy 190.481254 -31.067973) (xy 190.458318 -31.123346)
			(xy 190.428351 -31.175252) (xy 190.391864 -31.222802) (xy 190.349484 -31.265182) (xy 190.301934 -31.301669)
			(xy 190.250028 -31.331636) (xy 190.194655 -31.354572) (xy 190.136762 -31.370085) (xy 190.07734 -31.377908)
			(xy 190.017404 -31.377908) (xy 189.957982 -31.370085) (xy 189.900089 -31.354572) (xy 189.844716 -31.331636)
			(xy 189.79281 -31.301669) (xy 189.74526 -31.265182) (xy 189.70288 -31.222802) (xy 189.666393 -31.175252)
			(xy 189.636426 -31.123346) (xy 189.61349 -31.067973) (xy 189.597977 -31.01008) (xy 189.590154 -30.950658)
			(xy 189.589664 -30.92069) (xy 175.768508 -30.92069) (xy 175.768508 -30.922468) (xy 175.768018 -30.952452)
			(xy 175.76019 -31.011908) (xy 175.744669 -31.069833) (xy 175.72172 -31.125237) (xy 175.691736 -31.177171)
			(xy 175.65523 -31.224747) (xy 175.612825 -31.267152) (xy 175.565249 -31.303658) (xy 175.513315 -31.333642)
			(xy 175.457911 -31.356591) (xy 175.399986 -31.372112) (xy 175.34053 -31.37994) (xy 175.280562 -31.37994)
			(xy 175.221106 -31.372112) (xy 175.163181 -31.356591) (xy 175.107777 -31.333642) (xy 175.055843 -31.303658)
			(xy 175.008267 -31.267152) (xy 174.965862 -31.224747) (xy 174.929356 -31.177171) (xy 174.899372 -31.125237)
			(xy 174.876423 -31.069833) (xy 174.860902 -31.011908) (xy 174.853074 -30.952452) (xy 174.852584 -30.922468)
			(xy 164.505103 -30.922468) (xy 164.504642 -30.950658) (xy 164.496819 -31.01008) (xy 164.481306 -31.067973)
			(xy 164.45837 -31.123346) (xy 164.428403 -31.175252) (xy 164.391916 -31.222802) (xy 164.349536 -31.265182)
			(xy 164.301986 -31.301669) (xy 164.25008 -31.331636) (xy 164.194707 -31.354572) (xy 164.136814 -31.370085)
			(xy 164.077392 -31.377908) (xy 164.017456 -31.377908) (xy 163.958034 -31.370085) (xy 163.900141 -31.354572)
			(xy 163.844768 -31.331636) (xy 163.792862 -31.301669) (xy 163.745312 -31.265182) (xy 163.702932 -31.222802)
			(xy 163.666445 -31.175252) (xy 163.636478 -31.123346) (xy 163.613542 -31.067973) (xy 163.598029 -31.01008)
			(xy 163.590206 -30.950658) (xy 163.589716 -30.92069) (xy 149.76856 -30.92069) (xy 149.76856 -30.922468)
			(xy 149.76807 -30.952452) (xy 149.760242 -31.011908) (xy 149.744721 -31.069833) (xy 149.721772 -31.125237)
			(xy 149.691788 -31.177171) (xy 149.655282 -31.224747) (xy 149.612877 -31.267152) (xy 149.565301 -31.303658)
			(xy 149.513367 -31.333642) (xy 149.457963 -31.356591) (xy 149.400038 -31.372112) (xy 149.340582 -31.37994)
			(xy 149.280614 -31.37994) (xy 149.221158 -31.372112) (xy 149.163233 -31.356591) (xy 149.107829 -31.333642)
			(xy 149.055895 -31.303658) (xy 149.008319 -31.267152) (xy 148.965914 -31.224747) (xy 148.929408 -31.177171)
			(xy 148.899424 -31.125237) (xy 148.876475 -31.069833) (xy 148.860954 -31.011908) (xy 148.853126 -30.952452)
			(xy 148.852636 -30.922468) (xy 138.505155 -30.922468) (xy 138.504694 -30.950658) (xy 138.496871 -31.01008)
			(xy 138.481358 -31.067973) (xy 138.458422 -31.123346) (xy 138.428455 -31.175252) (xy 138.391968 -31.222802)
			(xy 138.349588 -31.265182) (xy 138.302038 -31.301669) (xy 138.250132 -31.331636) (xy 138.194759 -31.354572)
			(xy 138.136866 -31.370085) (xy 138.077444 -31.377908) (xy 138.017508 -31.377908) (xy 137.958086 -31.370085)
			(xy 137.900193 -31.354572) (xy 137.84482 -31.331636) (xy 137.792914 -31.301669) (xy 137.745364 -31.265182)
			(xy 137.702984 -31.222802) (xy 137.666497 -31.175252) (xy 137.63653 -31.123346) (xy 137.613594 -31.067973)
			(xy 137.598081 -31.01008) (xy 137.590258 -30.950658) (xy 137.589768 -30.92069) (xy 123.768612 -30.92069)
			(xy 123.768612 -30.922468) (xy 123.768122 -30.952452) (xy 123.760294 -31.011908) (xy 123.744773 -31.069833)
			(xy 123.721824 -31.125237) (xy 123.69184 -31.177171) (xy 123.655334 -31.224747) (xy 123.612929 -31.267152)
			(xy 123.565353 -31.303658) (xy 123.513419 -31.333642) (xy 123.458015 -31.356591) (xy 123.40009 -31.372112)
			(xy 123.340634 -31.37994) (xy 123.280666 -31.37994) (xy 123.22121 -31.372112) (xy 123.163285 -31.356591)
			(xy 123.107881 -31.333642) (xy 123.055947 -31.303658) (xy 123.008371 -31.267152) (xy 122.965966 -31.224747)
			(xy 122.92946 -31.177171) (xy 122.899476 -31.125237) (xy 122.876527 -31.069833) (xy 122.861006 -31.011908)
			(xy 122.853178 -30.952452) (xy 122.852688 -30.922468) (xy 100.405155 -30.922468) (xy 100.404694 -30.950674)
			(xy 100.396866 -31.01013) (xy 100.381345 -31.068055) (xy 100.358396 -31.123459) (xy 100.328412 -31.175393)
			(xy 100.291906 -31.222969) (xy 100.249501 -31.265374) (xy 100.201925 -31.30188) (xy 100.149991 -31.331864)
			(xy 100.094587 -31.354813) (xy 100.036662 -31.370334) (xy 99.977206 -31.378162) (xy 99.917238 -31.378162)
			(xy 99.857782 -31.370334) (xy 99.799857 -31.354813) (xy 99.744453 -31.331864) (xy 99.692519 -31.30188)
			(xy 99.644943 -31.265374) (xy 99.602538 -31.222969) (xy 99.566032 -31.175393) (xy 99.536048 -31.123459)
			(xy 99.513099 -31.068055) (xy 99.497578 -31.01013) (xy 99.48975 -30.950674) (xy 99.48926 -30.92069)
			(xy 85.668104 -30.92069) (xy 85.668104 -30.922468) (xy 85.667614 -30.952436) (xy 85.659791 -31.011858)
			(xy 85.644278 -31.069751) (xy 85.621342 -31.125124) (xy 85.591375 -31.17703) (xy 85.554888 -31.22458)
			(xy 85.512508 -31.26696) (xy 85.464958 -31.303447) (xy 85.413052 -31.333414) (xy 85.357679 -31.35635)
			(xy 85.299786 -31.371863) (xy 85.240364 -31.379686) (xy 85.180428 -31.379686) (xy 85.121006 -31.371863)
			(xy 85.063113 -31.35635) (xy 85.00774 -31.333414) (xy 84.955834 -31.303447) (xy 84.908284 -31.26696)
			(xy 84.865904 -31.22458) (xy 84.829417 -31.17703) (xy 84.79945 -31.125124) (xy 84.776514 -31.069751)
			(xy 84.761001 -31.011858) (xy 84.753178 -30.952436) (xy 84.752688 -30.922468) (xy 74.405207 -30.922468)
			(xy 74.404746 -30.950674) (xy 74.396918 -31.01013) (xy 74.381397 -31.068055) (xy 74.358448 -31.123459)
			(xy 74.328464 -31.175393) (xy 74.291958 -31.222969) (xy 74.249553 -31.265374) (xy 74.201977 -31.30188)
			(xy 74.150043 -31.331864) (xy 74.094639 -31.354813) (xy 74.036714 -31.370334) (xy 73.977258 -31.378162)
			(xy 73.91729 -31.378162) (xy 73.857834 -31.370334) (xy 73.799909 -31.354813) (xy 73.744505 -31.331864)
			(xy 73.692571 -31.30188) (xy 73.644995 -31.265374) (xy 73.60259 -31.222969) (xy 73.566084 -31.175393)
			(xy 73.5361 -31.123459) (xy 73.513151 -31.068055) (xy 73.49763 -31.01013) (xy 73.489802 -30.950674)
			(xy 73.489312 -30.92069) (xy 59.668156 -30.92069) (xy 59.668156 -30.922468) (xy 59.667666 -30.952436)
			(xy 59.659843 -31.011858) (xy 59.64433 -31.069751) (xy 59.621394 -31.125124) (xy 59.591427 -31.17703)
			(xy 59.55494 -31.22458) (xy 59.51256 -31.26696) (xy 59.46501 -31.303447) (xy 59.413104 -31.333414)
			(xy 59.357731 -31.35635) (xy 59.299838 -31.371863) (xy 59.240416 -31.379686) (xy 59.18048 -31.379686)
			(xy 59.121058 -31.371863) (xy 59.063165 -31.35635) (xy 59.007792 -31.333414) (xy 58.955886 -31.303447)
			(xy 58.908336 -31.26696) (xy 58.865956 -31.22458) (xy 58.829469 -31.17703) (xy 58.799502 -31.125124)
			(xy 58.776566 -31.069751) (xy 58.761053 -31.011858) (xy 58.75323 -30.952436) (xy 58.75274 -30.922468)
			(xy 48.405259 -30.922468) (xy 48.404798 -30.950674) (xy 48.39697 -31.01013) (xy 48.381449 -31.068055)
			(xy 48.3585 -31.123459) (xy 48.328516 -31.175393) (xy 48.29201 -31.222969) (xy 48.249605 -31.265374)
			(xy 48.202029 -31.30188) (xy 48.150095 -31.331864) (xy 48.094691 -31.354813) (xy 48.036766 -31.370334)
			(xy 47.97731 -31.378162) (xy 47.917342 -31.378162) (xy 47.857886 -31.370334) (xy 47.799961 -31.354813)
			(xy 47.744557 -31.331864) (xy 47.692623 -31.30188) (xy 47.645047 -31.265374) (xy 47.602642 -31.222969)
			(xy 47.566136 -31.175393) (xy 47.536152 -31.123459) (xy 47.513203 -31.068055) (xy 47.497682 -31.01013)
			(xy 47.489854 -30.950674) (xy 47.489364 -30.92069) (xy 33.668208 -30.92069) (xy 33.668208 -30.922468)
			(xy 33.667718 -30.952436) (xy 33.659895 -31.011858) (xy 33.644382 -31.069751) (xy 33.621446 -31.125124)
			(xy 33.591479 -31.17703) (xy 33.554992 -31.22458) (xy 33.512612 -31.26696) (xy 33.465062 -31.303447)
			(xy 33.413156 -31.333414) (xy 33.357783 -31.35635) (xy 33.29989 -31.371863) (xy 33.240468 -31.379686)
			(xy 33.180532 -31.379686) (xy 33.12111 -31.371863) (xy 33.063217 -31.35635) (xy 33.007844 -31.333414)
			(xy 32.955938 -31.303447) (xy 32.908388 -31.26696) (xy 32.866008 -31.22458) (xy 32.829521 -31.17703)
			(xy 32.799554 -31.125124) (xy 32.776618 -31.069751) (xy 32.761105 -31.011858) (xy 32.753282 -30.952436)
			(xy 32.752792 -30.922468) (xy 22.405311 -30.922468) (xy 22.40485 -30.950674) (xy 22.397022 -31.01013)
			(xy 22.381501 -31.068055) (xy 22.358552 -31.123459) (xy 22.328568 -31.175393) (xy 22.292062 -31.222969)
			(xy 22.249657 -31.265374) (xy 22.202081 -31.30188) (xy 22.150147 -31.331864) (xy 22.094743 -31.354813)
			(xy 22.036818 -31.370334) (xy 21.977362 -31.378162) (xy 21.917394 -31.378162) (xy 21.857938 -31.370334)
			(xy 21.800013 -31.354813) (xy 21.744609 -31.331864) (xy 21.692675 -31.30188) (xy 21.645099 -31.265374)
			(xy 21.602694 -31.222969) (xy 21.566188 -31.175393) (xy 21.536204 -31.123459) (xy 21.513255 -31.068055)
			(xy 21.497734 -31.01013) (xy 21.489906 -30.950674) (xy 21.489416 -30.92069) (xy 7.66826 -30.92069)
			(xy 7.66826 -30.922468) (xy 7.66777 -30.952436) (xy 7.659947 -31.011858) (xy 7.644434 -31.069751)
			(xy 7.621498 -31.125124) (xy 7.591531 -31.17703) (xy 7.555044 -31.22458) (xy 7.512664 -31.26696)
			(xy 7.465114 -31.303447) (xy 7.413208 -31.333414) (xy 7.357835 -31.35635) (xy 7.299942 -31.371863)
			(xy 7.24052 -31.379686) (xy 7.180584 -31.379686) (xy 7.121162 -31.371863) (xy 7.063269 -31.35635)
			(xy 7.007896 -31.333414) (xy 6.95599 -31.303447) (xy 6.90844 -31.26696) (xy 6.86606 -31.22458) (xy 6.829573 -31.17703)
			(xy 6.799606 -31.125124) (xy 6.77667 -31.069751) (xy 6.761157 -31.011858) (xy 6.753334 -30.952436)
			(xy 6.752844 -30.922468) (xy 0.508 -30.922468) (xy 0.508 -32.722312) (xy 8.607044 -32.722312) (xy 8.607044 -31.858712)
			(xy 8.607534 -31.828744) (xy 8.615357 -31.769322) (xy 8.63087 -31.711429) (xy 8.653806 -31.656056)
			(xy 8.683773 -31.60415) (xy 8.72026 -31.5566) (xy 8.76264 -31.51422) (xy 8.81019 -31.477733) (xy 8.862096 -31.447766)
			(xy 8.917469 -31.42483) (xy 8.975362 -31.409317) (xy 9.034784 -31.401494) (xy 9.09472 -31.401494)
			(xy 9.154142 -31.409317) (xy 9.212035 -31.42483) (xy 9.267408 -31.447766) (xy 9.319314 -31.477733)
			(xy 9.366864 -31.51422) (xy 9.409244 -31.5566) (xy 9.445731 -31.60415) (xy 9.475698 -31.656056) (xy 9.498634 -31.711429)
			(xy 9.514147 -31.769322) (xy 9.52197 -31.828744) (xy 9.52246 -31.858712) (xy 9.52246 -32.714184)
			(xy 18.847308 -32.714184) (xy 18.847308 -31.850584) (xy 18.847798 -31.8206) (xy 18.855626 -31.761144)
			(xy 18.871147 -31.703219) (xy 18.894096 -31.647815) (xy 18.92408 -31.595881) (xy 18.960586 -31.548305)
			(xy 19.002991 -31.5059) (xy 19.050567 -31.469394) (xy 19.102501 -31.43941) (xy 19.157905 -31.416461)
			(xy 19.21583 -31.40094) (xy 19.275286 -31.393112) (xy 19.335254 -31.393112) (xy 19.39471 -31.40094)
			(xy 19.452635 -31.416461) (xy 19.508039 -31.43941) (xy 19.559973 -31.469394) (xy 19.607549 -31.5059)
			(xy 19.649954 -31.548305) (xy 19.68646 -31.595881) (xy 19.716444 -31.647815) (xy 19.739393 -31.703219)
			(xy 19.754914 -31.761144) (xy 19.762742 -31.8206) (xy 19.763232 -31.850584) (xy 19.763232 -32.714184)
			(xy 19.763099 -32.722312) (xy 34.606992 -32.722312) (xy 34.606992 -31.858712) (xy 34.607482 -31.828744)
			(xy 34.615305 -31.769322) (xy 34.630818 -31.711429) (xy 34.653754 -31.656056) (xy 34.683721 -31.60415)
			(xy 34.720208 -31.5566) (xy 34.762588 -31.51422) (xy 34.810138 -31.477733) (xy 34.862044 -31.447766)
			(xy 34.917417 -31.42483) (xy 34.97531 -31.409317) (xy 35.034732 -31.401494) (xy 35.094668 -31.401494)
			(xy 35.15409 -31.409317) (xy 35.211983 -31.42483) (xy 35.267356 -31.447766) (xy 35.319262 -31.477733)
			(xy 35.366812 -31.51422) (xy 35.409192 -31.5566) (xy 35.445679 -31.60415) (xy 35.475646 -31.656056)
			(xy 35.498582 -31.711429) (xy 35.514095 -31.769322) (xy 35.521918 -31.828744) (xy 35.522408 -31.858712)
			(xy 35.522408 -32.714184) (xy 44.847256 -32.714184) (xy 44.847256 -31.850584) (xy 44.847746 -31.8206)
			(xy 44.855574 -31.761144) (xy 44.871095 -31.703219) (xy 44.894044 -31.647815) (xy 44.924028 -31.595881)
			(xy 44.960534 -31.548305) (xy 45.002939 -31.5059) (xy 45.050515 -31.469394) (xy 45.102449 -31.43941)
			(xy 45.157853 -31.416461) (xy 45.215778 -31.40094) (xy 45.275234 -31.393112) (xy 45.335202 -31.393112)
			(xy 45.394658 -31.40094) (xy 45.452583 -31.416461) (xy 45.507987 -31.43941) (xy 45.559921 -31.469394)
			(xy 45.607497 -31.5059) (xy 45.649902 -31.548305) (xy 45.686408 -31.595881) (xy 45.716392 -31.647815)
			(xy 45.739341 -31.703219) (xy 45.754862 -31.761144) (xy 45.76269 -31.8206) (xy 45.76318 -31.850584)
			(xy 45.76318 -32.714184) (xy 45.763047 -32.722312) (xy 60.60694 -32.722312) (xy 60.60694 -31.858712)
			(xy 60.60743 -31.828744) (xy 60.615253 -31.769322) (xy 60.630766 -31.711429) (xy 60.653702 -31.656056)
			(xy 60.683669 -31.60415) (xy 60.720156 -31.5566) (xy 60.762536 -31.51422) (xy 60.810086 -31.477733)
			(xy 60.861992 -31.447766) (xy 60.917365 -31.42483) (xy 60.975258 -31.409317) (xy 61.03468 -31.401494)
			(xy 61.094616 -31.401494) (xy 61.154038 -31.409317) (xy 61.211931 -31.42483) (xy 61.267304 -31.447766)
			(xy 61.31921 -31.477733) (xy 61.36676 -31.51422) (xy 61.40914 -31.5566) (xy 61.445627 -31.60415)
			(xy 61.475594 -31.656056) (xy 61.49853 -31.711429) (xy 61.514043 -31.769322) (xy 61.521866 -31.828744)
			(xy 61.522356 -31.858712) (xy 61.522356 -32.714184) (xy 70.847204 -32.714184) (xy 70.847204 -31.850584)
			(xy 70.847694 -31.8206) (xy 70.855522 -31.761144) (xy 70.871043 -31.703219) (xy 70.893992 -31.647815)
			(xy 70.923976 -31.595881) (xy 70.960482 -31.548305) (xy 71.002887 -31.5059) (xy 71.050463 -31.469394)
			(xy 71.102397 -31.43941) (xy 71.157801 -31.416461) (xy 71.215726 -31.40094) (xy 71.275182 -31.393112)
			(xy 71.33515 -31.393112) (xy 71.394606 -31.40094) (xy 71.452531 -31.416461) (xy 71.507935 -31.43941)
			(xy 71.559869 -31.469394) (xy 71.607445 -31.5059) (xy 71.64985 -31.548305) (xy 71.686356 -31.595881)
			(xy 71.71634 -31.647815) (xy 71.739289 -31.703219) (xy 71.75481 -31.761144) (xy 71.762638 -31.8206)
			(xy 71.763128 -31.850584) (xy 71.763128 -32.714184) (xy 71.762995 -32.722312) (xy 86.606888 -32.722312)
			(xy 86.606888 -31.858712) (xy 86.607378 -31.828744) (xy 86.615201 -31.769322) (xy 86.630714 -31.711429)
			(xy 86.65365 -31.656056) (xy 86.683617 -31.60415) (xy 86.720104 -31.5566) (xy 86.762484 -31.51422)
			(xy 86.810034 -31.477733) (xy 86.86194 -31.447766) (xy 86.917313 -31.42483) (xy 86.975206 -31.409317)
			(xy 87.034628 -31.401494) (xy 87.094564 -31.401494) (xy 87.153986 -31.409317) (xy 87.211879 -31.42483)
			(xy 87.267252 -31.447766) (xy 87.319158 -31.477733) (xy 87.366708 -31.51422) (xy 87.409088 -31.5566)
			(xy 87.445575 -31.60415) (xy 87.475542 -31.656056) (xy 87.498478 -31.711429) (xy 87.513991 -31.769322)
			(xy 87.521814 -31.828744) (xy 87.522304 -31.858712) (xy 87.522304 -32.714184) (xy 96.847152 -32.714184)
			(xy 96.847152 -31.850584) (xy 96.847642 -31.8206) (xy 96.85547 -31.761144) (xy 96.870991 -31.703219)
			(xy 96.89394 -31.647815) (xy 96.923924 -31.595881) (xy 96.96043 -31.548305) (xy 97.002835 -31.5059)
			(xy 97.050411 -31.469394) (xy 97.102345 -31.43941) (xy 97.157749 -31.416461) (xy 97.215674 -31.40094)
			(xy 97.27513 -31.393112) (xy 97.335098 -31.393112) (xy 97.394554 -31.40094) (xy 97.452479 -31.416461)
			(xy 97.507883 -31.43941) (xy 97.559817 -31.469394) (xy 97.607393 -31.5059) (xy 97.649798 -31.548305)
			(xy 97.686304 -31.595881) (xy 97.716288 -31.647815) (xy 97.739237 -31.703219) (xy 97.754758 -31.761144)
			(xy 97.762586 -31.8206) (xy 97.763076 -31.850584) (xy 97.763076 -32.714184) (xy 97.762943 -32.722312)
			(xy 124.706888 -32.722312) (xy 124.706888 -31.858712) (xy 124.707378 -31.828728) (xy 124.715206 -31.769272)
			(xy 124.730727 -31.711347) (xy 124.753676 -31.655943) (xy 124.78366 -31.604009) (xy 124.820166 -31.556433)
			(xy 124.862571 -31.514028) (xy 124.910147 -31.477522) (xy 124.962081 -31.447538) (xy 125.017485 -31.424589)
			(xy 125.07541 -31.409068) (xy 125.134866 -31.40124) (xy 125.194834 -31.40124) (xy 125.25429 -31.409068)
			(xy 125.312215 -31.424589) (xy 125.367619 -31.447538) (xy 125.419553 -31.477522) (xy 125.467129 -31.514028)
			(xy 125.509534 -31.556433) (xy 125.54604 -31.604009) (xy 125.576024 -31.655943) (xy 125.598973 -31.711347)
			(xy 125.614494 -31.769272) (xy 125.622322 -31.828728) (xy 125.622812 -31.858712) (xy 125.622812 -32.714184)
			(xy 134.94766 -32.714184) (xy 134.94766 -31.850584) (xy 134.94815 -31.820616) (xy 134.955973 -31.761194)
			(xy 134.971486 -31.703301) (xy 134.994422 -31.647928) (xy 135.024389 -31.596022) (xy 135.060876 -31.548472)
			(xy 135.103256 -31.506092) (xy 135.150806 -31.469605) (xy 135.202712 -31.439638) (xy 135.258085 -31.416702)
			(xy 135.315978 -31.401189) (xy 135.3754 -31.393366) (xy 135.435336 -31.393366) (xy 135.494758 -31.401189)
			(xy 135.552651 -31.416702) (xy 135.608024 -31.439638) (xy 135.65993 -31.469605) (xy 135.70748 -31.506092)
			(xy 135.74986 -31.548472) (xy 135.786347 -31.596022) (xy 135.816314 -31.647928) (xy 135.83925 -31.703301)
			(xy 135.854763 -31.761194) (xy 135.862586 -31.820616) (xy 135.863076 -31.850584) (xy 135.863076 -32.714184)
			(xy 135.862943 -32.722312) (xy 150.706836 -32.722312) (xy 150.706836 -31.858712) (xy 150.707326 -31.828728)
			(xy 150.715154 -31.769272) (xy 150.730675 -31.711347) (xy 150.753624 -31.655943) (xy 150.783608 -31.604009)
			(xy 150.820114 -31.556433) (xy 150.862519 -31.514028) (xy 150.910095 -31.477522) (xy 150.962029 -31.447538)
			(xy 151.017433 -31.424589) (xy 151.075358 -31.409068) (xy 151.134814 -31.40124) (xy 151.194782 -31.40124)
			(xy 151.254238 -31.409068) (xy 151.312163 -31.424589) (xy 151.367567 -31.447538) (xy 151.419501 -31.477522)
			(xy 151.467077 -31.514028) (xy 151.509482 -31.556433) (xy 151.545988 -31.604009) (xy 151.575972 -31.655943)
			(xy 151.598921 -31.711347) (xy 151.614442 -31.769272) (xy 151.62227 -31.828728) (xy 151.62276 -31.858712)
			(xy 151.62276 -32.714184) (xy 160.947608 -32.714184) (xy 160.947608 -31.850584) (xy 160.948098 -31.820616)
			(xy 160.955921 -31.761194) (xy 160.971434 -31.703301) (xy 160.99437 -31.647928) (xy 161.024337 -31.596022)
			(xy 161.060824 -31.548472) (xy 161.103204 -31.506092) (xy 161.150754 -31.469605) (xy 161.20266 -31.439638)
			(xy 161.258033 -31.416702) (xy 161.315926 -31.401189) (xy 161.375348 -31.393366) (xy 161.435284 -31.393366)
			(xy 161.494706 -31.401189) (xy 161.552599 -31.416702) (xy 161.607972 -31.439638) (xy 161.659878 -31.469605)
			(xy 161.707428 -31.506092) (xy 161.749808 -31.548472) (xy 161.786295 -31.596022) (xy 161.816262 -31.647928)
			(xy 161.839198 -31.703301) (xy 161.854711 -31.761194) (xy 161.862534 -31.820616) (xy 161.863024 -31.850584)
			(xy 161.863024 -32.714184) (xy 161.862891 -32.722312) (xy 176.706784 -32.722312) (xy 176.706784 -31.858712)
			(xy 176.707274 -31.828728) (xy 176.715102 -31.769272) (xy 176.730623 -31.711347) (xy 176.753572 -31.655943)
			(xy 176.783556 -31.604009) (xy 176.820062 -31.556433) (xy 176.862467 -31.514028) (xy 176.910043 -31.477522)
			(xy 176.961977 -31.447538) (xy 177.017381 -31.424589) (xy 177.075306 -31.409068) (xy 177.134762 -31.40124)
			(xy 177.19473 -31.40124) (xy 177.254186 -31.409068) (xy 177.312111 -31.424589) (xy 177.367515 -31.447538)
			(xy 177.419449 -31.477522) (xy 177.467025 -31.514028) (xy 177.50943 -31.556433) (xy 177.545936 -31.604009)
			(xy 177.57592 -31.655943) (xy 177.598869 -31.711347) (xy 177.61439 -31.769272) (xy 177.622218 -31.828728)
			(xy 177.622708 -31.858712) (xy 177.622708 -32.714184) (xy 186.947556 -32.714184) (xy 186.947556 -31.850584)
			(xy 186.948046 -31.820616) (xy 186.955869 -31.761194) (xy 186.971382 -31.703301) (xy 186.994318 -31.647928)
			(xy 187.024285 -31.596022) (xy 187.060772 -31.548472) (xy 187.103152 -31.506092) (xy 187.150702 -31.469605)
			(xy 187.202608 -31.439638) (xy 187.257981 -31.416702) (xy 187.315874 -31.401189) (xy 187.375296 -31.393366)
			(xy 187.435232 -31.393366) (xy 187.494654 -31.401189) (xy 187.552547 -31.416702) (xy 187.60792 -31.439638)
			(xy 187.659826 -31.469605) (xy 187.707376 -31.506092) (xy 187.749756 -31.548472) (xy 187.786243 -31.596022)
			(xy 187.81621 -31.647928) (xy 187.839146 -31.703301) (xy 187.854659 -31.761194) (xy 187.862482 -31.820616)
			(xy 187.862972 -31.850584) (xy 187.862972 -32.714184) (xy 187.862839 -32.722312) (xy 202.706732 -32.722312)
			(xy 202.706732 -31.858712) (xy 202.707222 -31.828728) (xy 202.71505 -31.769272) (xy 202.730571 -31.711347)
			(xy 202.75352 -31.655943) (xy 202.783504 -31.604009) (xy 202.82001 -31.556433) (xy 202.862415 -31.514028)
			(xy 202.909991 -31.477522) (xy 202.961925 -31.447538) (xy 203.017329 -31.424589) (xy 203.075254 -31.409068)
			(xy 203.13471 -31.40124) (xy 203.194678 -31.40124) (xy 203.254134 -31.409068) (xy 203.312059 -31.424589)
			(xy 203.367463 -31.447538) (xy 203.419397 -31.477522) (xy 203.466973 -31.514028) (xy 203.509378 -31.556433)
			(xy 203.545884 -31.604009) (xy 203.575868 -31.655943) (xy 203.598817 -31.711347) (xy 203.614338 -31.769272)
			(xy 203.622166 -31.828728) (xy 203.622656 -31.858712) (xy 203.622656 -32.714184) (xy 212.947504 -32.714184)
			(xy 212.947504 -31.850584) (xy 212.947994 -31.820616) (xy 212.955817 -31.761194) (xy 212.97133 -31.703301)
			(xy 212.994266 -31.647928) (xy 213.024233 -31.596022) (xy 213.06072 -31.548472) (xy 213.1031 -31.506092)
			(xy 213.15065 -31.469605) (xy 213.202556 -31.439638) (xy 213.257929 -31.416702) (xy 213.315822 -31.401189)
			(xy 213.375244 -31.393366) (xy 213.43518 -31.393366) (xy 213.494602 -31.401189) (xy 213.552495 -31.416702)
			(xy 213.607868 -31.439638) (xy 213.659774 -31.469605) (xy 213.707324 -31.506092) (xy 213.749704 -31.548472)
			(xy 213.786191 -31.596022) (xy 213.816158 -31.647928) (xy 213.839094 -31.703301) (xy 213.854607 -31.761194)
			(xy 213.86243 -31.820616) (xy 213.86292 -31.850584) (xy 213.86292 -32.714184) (xy 213.862787 -32.722312)
			(xy 240.806732 -32.722312) (xy 240.806732 -31.858712) (xy 240.807222 -31.828728) (xy 240.81505 -31.769272)
			(xy 240.830571 -31.711347) (xy 240.85352 -31.655943) (xy 240.883504 -31.604009) (xy 240.92001 -31.556433)
			(xy 240.962415 -31.514028) (xy 241.009991 -31.477522) (xy 241.061925 -31.447538) (xy 241.117329 -31.424589)
			(xy 241.175254 -31.409068) (xy 241.23471 -31.40124) (xy 241.294678 -31.40124) (xy 241.354134 -31.409068)
			(xy 241.412059 -31.424589) (xy 241.467463 -31.447538) (xy 241.519397 -31.477522) (xy 241.566973 -31.514028)
			(xy 241.609378 -31.556433) (xy 241.645884 -31.604009) (xy 241.675868 -31.655943) (xy 241.698817 -31.711347)
			(xy 241.714338 -31.769272) (xy 241.722166 -31.828728) (xy 241.722656 -31.858712) (xy 241.722656 -32.714184)
			(xy 251.047504 -32.714184) (xy 251.047504 -31.850584) (xy 251.047994 -31.820616) (xy 251.055817 -31.761194)
			(xy 251.07133 -31.703301) (xy 251.094266 -31.647928) (xy 251.124233 -31.596022) (xy 251.16072 -31.548472)
			(xy 251.2031 -31.506092) (xy 251.25065 -31.469605) (xy 251.302556 -31.439638) (xy 251.357929 -31.416702)
			(xy 251.415822 -31.401189) (xy 251.475244 -31.393366) (xy 251.53518 -31.393366) (xy 251.594602 -31.401189)
			(xy 251.652495 -31.416702) (xy 251.707868 -31.439638) (xy 251.759774 -31.469605) (xy 251.807324 -31.506092)
			(xy 251.849704 -31.548472) (xy 251.886191 -31.596022) (xy 251.916158 -31.647928) (xy 251.939094 -31.703301)
			(xy 251.954607 -31.761194) (xy 251.96243 -31.820616) (xy 251.96292 -31.850584) (xy 251.96292 -32.714184)
			(xy 251.962787 -32.722312) (xy 266.80668 -32.722312) (xy 266.80668 -31.858712) (xy 266.80717 -31.828728)
			(xy 266.814998 -31.769272) (xy 266.830519 -31.711347) (xy 266.853468 -31.655943) (xy 266.883452 -31.604009)
			(xy 266.919958 -31.556433) (xy 266.962363 -31.514028) (xy 267.009939 -31.477522) (xy 267.061873 -31.447538)
			(xy 267.117277 -31.424589) (xy 267.175202 -31.409068) (xy 267.234658 -31.40124) (xy 267.294626 -31.40124)
			(xy 267.354082 -31.409068) (xy 267.412007 -31.424589) (xy 267.467411 -31.447538) (xy 267.519345 -31.477522)
			(xy 267.566921 -31.514028) (xy 267.609326 -31.556433) (xy 267.645832 -31.604009) (xy 267.675816 -31.655943)
			(xy 267.698765 -31.711347) (xy 267.714286 -31.769272) (xy 267.722114 -31.828728) (xy 267.722604 -31.858712)
			(xy 267.722604 -32.714184) (xy 277.047452 -32.714184) (xy 277.047452 -31.850584) (xy 277.047942 -31.820616)
			(xy 277.055765 -31.761194) (xy 277.071278 -31.703301) (xy 277.094214 -31.647928) (xy 277.124181 -31.596022)
			(xy 277.160668 -31.548472) (xy 277.203048 -31.506092) (xy 277.250598 -31.469605) (xy 277.302504 -31.439638)
			(xy 277.357877 -31.416702) (xy 277.41577 -31.401189) (xy 277.475192 -31.393366) (xy 277.535128 -31.393366)
			(xy 277.59455 -31.401189) (xy 277.652443 -31.416702) (xy 277.707816 -31.439638) (xy 277.759722 -31.469605)
			(xy 277.807272 -31.506092) (xy 277.849652 -31.548472) (xy 277.886139 -31.596022) (xy 277.916106 -31.647928)
			(xy 277.939042 -31.703301) (xy 277.954555 -31.761194) (xy 277.962378 -31.820616) (xy 277.962868 -31.850584)
			(xy 277.962868 -32.714184) (xy 277.962735 -32.722312) (xy 292.806628 -32.722312) (xy 292.806628 -31.858712)
			(xy 292.807118 -31.828728) (xy 292.814946 -31.769272) (xy 292.830467 -31.711347) (xy 292.853416 -31.655943)
			(xy 292.8834 -31.604009) (xy 292.919906 -31.556433) (xy 292.962311 -31.514028) (xy 293.009887 -31.477522)
			(xy 293.061821 -31.447538) (xy 293.117225 -31.424589) (xy 293.17515 -31.409068) (xy 293.234606 -31.40124)
			(xy 293.294574 -31.40124) (xy 293.35403 -31.409068) (xy 293.411955 -31.424589) (xy 293.467359 -31.447538)
			(xy 293.519293 -31.477522) (xy 293.566869 -31.514028) (xy 293.609274 -31.556433) (xy 293.64578 -31.604009)
			(xy 293.675764 -31.655943) (xy 293.698713 -31.711347) (xy 293.714234 -31.769272) (xy 293.722062 -31.828728)
			(xy 293.722552 -31.858712) (xy 293.722552 -32.714184) (xy 303.0474 -32.714184) (xy 303.0474 -31.850584)
			(xy 303.04789 -31.820616) (xy 303.055713 -31.761194) (xy 303.071226 -31.703301) (xy 303.094162 -31.647928)
			(xy 303.124129 -31.596022) (xy 303.160616 -31.548472) (xy 303.202996 -31.506092) (xy 303.250546 -31.469605)
			(xy 303.302452 -31.439638) (xy 303.357825 -31.416702) (xy 303.415718 -31.401189) (xy 303.47514 -31.393366)
			(xy 303.535076 -31.393366) (xy 303.594498 -31.401189) (xy 303.652391 -31.416702) (xy 303.707764 -31.439638)
			(xy 303.75967 -31.469605) (xy 303.80722 -31.506092) (xy 303.8496 -31.548472) (xy 303.886087 -31.596022)
			(xy 303.916054 -31.647928) (xy 303.93899 -31.703301) (xy 303.954503 -31.761194) (xy 303.962326 -31.820616)
			(xy 303.962816 -31.850584) (xy 303.962816 -32.714184) (xy 303.962683 -32.722312) (xy 318.806576 -32.722312)
			(xy 318.806576 -31.858712) (xy 318.807066 -31.828728) (xy 318.814894 -31.769272) (xy 318.830415 -31.711347)
			(xy 318.853364 -31.655943) (xy 318.883348 -31.604009) (xy 318.919854 -31.556433) (xy 318.962259 -31.514028)
			(xy 319.009835 -31.477522) (xy 319.061769 -31.447538) (xy 319.117173 -31.424589) (xy 319.175098 -31.409068)
			(xy 319.234554 -31.40124) (xy 319.294522 -31.40124) (xy 319.353978 -31.409068) (xy 319.411903 -31.424589)
			(xy 319.467307 -31.447538) (xy 319.519241 -31.477522) (xy 319.566817 -31.514028) (xy 319.609222 -31.556433)
			(xy 319.645728 -31.604009) (xy 319.675712 -31.655943) (xy 319.698661 -31.711347) (xy 319.714182 -31.769272)
			(xy 319.72201 -31.828728) (xy 319.7225 -31.858712) (xy 319.7225 -32.714184) (xy 329.047348 -32.714184)
			(xy 329.047348 -31.850584) (xy 329.047838 -31.820616) (xy 329.055661 -31.761194) (xy 329.071174 -31.703301)
			(xy 329.09411 -31.647928) (xy 329.124077 -31.596022) (xy 329.160564 -31.548472) (xy 329.202944 -31.506092)
			(xy 329.250494 -31.469605) (xy 329.3024 -31.439638) (xy 329.357773 -31.416702) (xy 329.415666 -31.401189)
			(xy 329.475088 -31.393366) (xy 329.535024 -31.393366) (xy 329.594446 -31.401189) (xy 329.652339 -31.416702)
			(xy 329.707712 -31.439638) (xy 329.759618 -31.469605) (xy 329.807168 -31.506092) (xy 329.849548 -31.548472)
			(xy 329.886035 -31.596022) (xy 329.916002 -31.647928) (xy 329.938938 -31.703301) (xy 329.954451 -31.761194)
			(xy 329.962274 -31.820616) (xy 329.962764 -31.850584) (xy 329.962764 -32.714184) (xy 329.962631 -32.722312)
			(xy 356.907084 -32.722312) (xy 356.907084 -31.858712) (xy 356.907574 -31.828744) (xy 356.915397 -31.769322)
			(xy 356.93091 -31.711429) (xy 356.953846 -31.656056) (xy 356.983813 -31.60415) (xy 357.0203 -31.5566)
			(xy 357.06268 -31.51422) (xy 357.11023 -31.477733) (xy 357.162136 -31.447766) (xy 357.217509 -31.42483)
			(xy 357.275402 -31.409317) (xy 357.334824 -31.401494) (xy 357.39476 -31.401494) (xy 357.454182 -31.409317)
			(xy 357.512075 -31.42483) (xy 357.567448 -31.447766) (xy 357.619354 -31.477733) (xy 357.666904 -31.51422)
			(xy 357.709284 -31.5566) (xy 357.745771 -31.60415) (xy 357.775738 -31.656056) (xy 357.798674 -31.711429)
			(xy 357.814187 -31.769322) (xy 357.82201 -31.828744) (xy 357.8225 -31.858712) (xy 357.8225 -32.714184)
			(xy 367.147348 -32.714184) (xy 367.147348 -31.850584) (xy 367.147838 -31.8206) (xy 367.155666 -31.761144)
			(xy 367.171187 -31.703219) (xy 367.194136 -31.647815) (xy 367.22412 -31.595881) (xy 367.260626 -31.548305)
			(xy 367.303031 -31.5059) (xy 367.350607 -31.469394) (xy 367.402541 -31.43941) (xy 367.457945 -31.416461)
			(xy 367.51587 -31.40094) (xy 367.575326 -31.393112) (xy 367.635294 -31.393112) (xy 367.69475 -31.40094)
			(xy 367.752675 -31.416461) (xy 367.808079 -31.43941) (xy 367.860013 -31.469394) (xy 367.907589 -31.5059)
			(xy 367.949994 -31.548305) (xy 367.9865 -31.595881) (xy 368.016484 -31.647815) (xy 368.039433 -31.703219)
			(xy 368.054954 -31.761144) (xy 368.062782 -31.8206) (xy 368.063272 -31.850584) (xy 368.063272 -32.714184)
			(xy 368.063139 -32.722312) (xy 382.907032 -32.722312) (xy 382.907032 -31.858712) (xy 382.907522 -31.828744)
			(xy 382.915345 -31.769322) (xy 382.930858 -31.711429) (xy 382.953794 -31.656056) (xy 382.983761 -31.60415)
			(xy 383.020248 -31.5566) (xy 383.062628 -31.51422) (xy 383.110178 -31.477733) (xy 383.162084 -31.447766)
			(xy 383.217457 -31.42483) (xy 383.27535 -31.409317) (xy 383.334772 -31.401494) (xy 383.394708 -31.401494)
			(xy 383.45413 -31.409317) (xy 383.512023 -31.42483) (xy 383.567396 -31.447766) (xy 383.619302 -31.477733)
			(xy 383.666852 -31.51422) (xy 383.709232 -31.5566) (xy 383.745719 -31.60415) (xy 383.775686 -31.656056)
			(xy 383.798622 -31.711429) (xy 383.814135 -31.769322) (xy 383.821958 -31.828744) (xy 383.822448 -31.858712)
			(xy 383.822448 -32.714184) (xy 393.147296 -32.714184) (xy 393.147296 -31.850584) (xy 393.147786 -31.8206)
			(xy 393.155614 -31.761144) (xy 393.171135 -31.703219) (xy 393.194084 -31.647815) (xy 393.224068 -31.595881)
			(xy 393.260574 -31.548305) (xy 393.302979 -31.5059) (xy 393.350555 -31.469394) (xy 393.402489 -31.43941)
			(xy 393.457893 -31.416461) (xy 393.515818 -31.40094) (xy 393.575274 -31.393112) (xy 393.635242 -31.393112)
			(xy 393.694698 -31.40094) (xy 393.752623 -31.416461) (xy 393.808027 -31.43941) (xy 393.859961 -31.469394)
			(xy 393.907537 -31.5059) (xy 393.949942 -31.548305) (xy 393.986448 -31.595881) (xy 394.016432 -31.647815)
			(xy 394.039381 -31.703219) (xy 394.054902 -31.761144) (xy 394.06273 -31.8206) (xy 394.06322 -31.850584)
			(xy 394.06322 -32.714184) (xy 394.063087 -32.722312) (xy 408.90698 -32.722312) (xy 408.90698 -31.858712)
			(xy 408.90747 -31.828744) (xy 408.915293 -31.769322) (xy 408.930806 -31.711429) (xy 408.953742 -31.656056)
			(xy 408.983709 -31.60415) (xy 409.020196 -31.5566) (xy 409.062576 -31.51422) (xy 409.110126 -31.477733)
			(xy 409.162032 -31.447766) (xy 409.217405 -31.42483) (xy 409.275298 -31.409317) (xy 409.33472 -31.401494)
			(xy 409.394656 -31.401494) (xy 409.454078 -31.409317) (xy 409.511971 -31.42483) (xy 409.567344 -31.447766)
			(xy 409.61925 -31.477733) (xy 409.6668 -31.51422) (xy 409.70918 -31.5566) (xy 409.745667 -31.60415)
			(xy 409.775634 -31.656056) (xy 409.79857 -31.711429) (xy 409.814083 -31.769322) (xy 409.821906 -31.828744)
			(xy 409.822396 -31.858712) (xy 409.822396 -32.714184) (xy 419.147244 -32.714184) (xy 419.147244 -31.850584)
			(xy 419.147734 -31.8206) (xy 419.155562 -31.761144) (xy 419.171083 -31.703219) (xy 419.194032 -31.647815)
			(xy 419.224016 -31.595881) (xy 419.260522 -31.548305) (xy 419.302927 -31.5059) (xy 419.350503 -31.469394)
			(xy 419.402437 -31.43941) (xy 419.457841 -31.416461) (xy 419.515766 -31.40094) (xy 419.575222 -31.393112)
			(xy 419.63519 -31.393112) (xy 419.694646 -31.40094) (xy 419.752571 -31.416461) (xy 419.807975 -31.43941)
			(xy 419.859909 -31.469394) (xy 419.907485 -31.5059) (xy 419.94989 -31.548305) (xy 419.986396 -31.595881)
			(xy 420.01638 -31.647815) (xy 420.039329 -31.703219) (xy 420.05485 -31.761144) (xy 420.062678 -31.8206)
			(xy 420.063168 -31.850584) (xy 420.063168 -32.714184) (xy 420.063035 -32.722312) (xy 434.906928 -32.722312)
			(xy 434.906928 -31.858712) (xy 434.907418 -31.828744) (xy 434.915241 -31.769322) (xy 434.930754 -31.711429)
			(xy 434.95369 -31.656056) (xy 434.983657 -31.60415) (xy 435.020144 -31.5566) (xy 435.062524 -31.51422)
			(xy 435.110074 -31.477733) (xy 435.16198 -31.447766) (xy 435.217353 -31.42483) (xy 435.275246 -31.409317)
			(xy 435.334668 -31.401494) (xy 435.394604 -31.401494) (xy 435.454026 -31.409317) (xy 435.511919 -31.42483)
			(xy 435.567292 -31.447766) (xy 435.619198 -31.477733) (xy 435.666748 -31.51422) (xy 435.709128 -31.5566)
			(xy 435.745615 -31.60415) (xy 435.775582 -31.656056) (xy 435.798518 -31.711429) (xy 435.814031 -31.769322)
			(xy 435.821854 -31.828744) (xy 435.822344 -31.858712) (xy 435.822344 -32.714184) (xy 445.147192 -32.714184)
			(xy 445.147192 -31.850584) (xy 445.147682 -31.8206) (xy 445.15551 -31.761144) (xy 445.171031 -31.703219)
			(xy 445.19398 -31.647815) (xy 445.223964 -31.595881) (xy 445.26047 -31.548305) (xy 445.302875 -31.5059)
			(xy 445.350451 -31.469394) (xy 445.402385 -31.43941) (xy 445.457789 -31.416461) (xy 445.515714 -31.40094)
			(xy 445.57517 -31.393112) (xy 445.635138 -31.393112) (xy 445.694594 -31.40094) (xy 445.752519 -31.416461)
			(xy 445.807923 -31.43941) (xy 445.859857 -31.469394) (xy 445.907433 -31.5059) (xy 445.949838 -31.548305)
			(xy 445.986344 -31.595881) (xy 446.016328 -31.647815) (xy 446.039277 -31.703219) (xy 446.054798 -31.761144)
			(xy 446.062626 -31.8206) (xy 446.063116 -31.850584) (xy 446.063116 -32.714184) (xy 446.062626 -32.744168)
			(xy 446.054798 -32.803624) (xy 446.039277 -32.861549) (xy 446.016328 -32.916953) (xy 445.986344 -32.968887)
			(xy 445.949838 -33.016463) (xy 445.907433 -33.058868) (xy 445.859857 -33.095374) (xy 445.807923 -33.125358)
			(xy 445.752519 -33.148307) (xy 445.694594 -33.163828) (xy 445.635138 -33.171656) (xy 445.57517 -33.171656)
			(xy 445.515714 -33.163828) (xy 445.457789 -33.148307) (xy 445.402385 -33.125358) (xy 445.350451 -33.095374)
			(xy 445.302875 -33.058868) (xy 445.26047 -33.016463) (xy 445.223964 -32.968887) (xy 445.19398 -32.916953)
			(xy 445.171031 -32.861549) (xy 445.15551 -32.803624) (xy 445.147682 -32.744168) (xy 445.147192 -32.714184)
			(xy 435.822344 -32.714184) (xy 435.822344 -32.722312) (xy 435.821854 -32.75228) (xy 435.814031 -32.811702)
			(xy 435.798518 -32.869595) (xy 435.775582 -32.924968) (xy 435.745615 -32.976874) (xy 435.709128 -33.024424)
			(xy 435.666748 -33.066804) (xy 435.619198 -33.103291) (xy 435.567292 -33.133258) (xy 435.511919 -33.156194)
			(xy 435.454026 -33.171707) (xy 435.394604 -33.17953) (xy 435.334668 -33.17953) (xy 435.275246 -33.171707)
			(xy 435.217353 -33.156194) (xy 435.16198 -33.133258) (xy 435.110074 -33.103291) (xy 435.062524 -33.066804)
			(xy 435.020144 -33.024424) (xy 434.983657 -32.976874) (xy 434.95369 -32.924968) (xy 434.930754 -32.869595)
			(xy 434.915241 -32.811702) (xy 434.907418 -32.75228) (xy 434.906928 -32.722312) (xy 420.063035 -32.722312)
			(xy 420.062678 -32.744168) (xy 420.05485 -32.803624) (xy 420.039329 -32.861549) (xy 420.01638 -32.916953)
			(xy 419.986396 -32.968887) (xy 419.94989 -33.016463) (xy 419.907485 -33.058868) (xy 419.859909 -33.095374)
			(xy 419.807975 -33.125358) (xy 419.752571 -33.148307) (xy 419.694646 -33.163828) (xy 419.63519 -33.171656)
			(xy 419.575222 -33.171656) (xy 419.515766 -33.163828) (xy 419.457841 -33.148307) (xy 419.402437 -33.125358)
			(xy 419.350503 -33.095374) (xy 419.302927 -33.058868) (xy 419.260522 -33.016463) (xy 419.224016 -32.968887)
			(xy 419.194032 -32.916953) (xy 419.171083 -32.861549) (xy 419.155562 -32.803624) (xy 419.147734 -32.744168)
			(xy 419.147244 -32.714184) (xy 409.822396 -32.714184) (xy 409.822396 -32.722312) (xy 409.821906 -32.75228)
			(xy 409.814083 -32.811702) (xy 409.79857 -32.869595) (xy 409.775634 -32.924968) (xy 409.745667 -32.976874)
			(xy 409.70918 -33.024424) (xy 409.6668 -33.066804) (xy 409.61925 -33.103291) (xy 409.567344 -33.133258)
			(xy 409.511971 -33.156194) (xy 409.454078 -33.171707) (xy 409.394656 -33.17953) (xy 409.33472 -33.17953)
			(xy 409.275298 -33.171707) (xy 409.217405 -33.156194) (xy 409.162032 -33.133258) (xy 409.110126 -33.103291)
			(xy 409.062576 -33.066804) (xy 409.020196 -33.024424) (xy 408.983709 -32.976874) (xy 408.953742 -32.924968)
			(xy 408.930806 -32.869595) (xy 408.915293 -32.811702) (xy 408.90747 -32.75228) (xy 408.90698 -32.722312)
			(xy 394.063087 -32.722312) (xy 394.06273 -32.744168) (xy 394.054902 -32.803624) (xy 394.039381 -32.861549)
			(xy 394.016432 -32.916953) (xy 393.986448 -32.968887) (xy 393.949942 -33.016463) (xy 393.907537 -33.058868)
			(xy 393.859961 -33.095374) (xy 393.808027 -33.125358) (xy 393.752623 -33.148307) (xy 393.694698 -33.163828)
			(xy 393.635242 -33.171656) (xy 393.575274 -33.171656) (xy 393.515818 -33.163828) (xy 393.457893 -33.148307)
			(xy 393.402489 -33.125358) (xy 393.350555 -33.095374) (xy 393.302979 -33.058868) (xy 393.260574 -33.016463)
			(xy 393.224068 -32.968887) (xy 393.194084 -32.916953) (xy 393.171135 -32.861549) (xy 393.155614 -32.803624)
			(xy 393.147786 -32.744168) (xy 393.147296 -32.714184) (xy 383.822448 -32.714184) (xy 383.822448 -32.722312)
			(xy 383.821958 -32.75228) (xy 383.814135 -32.811702) (xy 383.798622 -32.869595) (xy 383.775686 -32.924968)
			(xy 383.745719 -32.976874) (xy 383.709232 -33.024424) (xy 383.666852 -33.066804) (xy 383.619302 -33.103291)
			(xy 383.567396 -33.133258) (xy 383.512023 -33.156194) (xy 383.45413 -33.171707) (xy 383.394708 -33.17953)
			(xy 383.334772 -33.17953) (xy 383.27535 -33.171707) (xy 383.217457 -33.156194) (xy 383.162084 -33.133258)
			(xy 383.110178 -33.103291) (xy 383.062628 -33.066804) (xy 383.020248 -33.024424) (xy 382.983761 -32.976874)
			(xy 382.953794 -32.924968) (xy 382.930858 -32.869595) (xy 382.915345 -32.811702) (xy 382.907522 -32.75228)
			(xy 382.907032 -32.722312) (xy 368.063139 -32.722312) (xy 368.062782 -32.744168) (xy 368.054954 -32.803624)
			(xy 368.039433 -32.861549) (xy 368.016484 -32.916953) (xy 367.9865 -32.968887) (xy 367.949994 -33.016463)
			(xy 367.907589 -33.058868) (xy 367.860013 -33.095374) (xy 367.808079 -33.125358) (xy 367.752675 -33.148307)
			(xy 367.69475 -33.163828) (xy 367.635294 -33.171656) (xy 367.575326 -33.171656) (xy 367.51587 -33.163828)
			(xy 367.457945 -33.148307) (xy 367.402541 -33.125358) (xy 367.350607 -33.095374) (xy 367.303031 -33.058868)
			(xy 367.260626 -33.016463) (xy 367.22412 -32.968887) (xy 367.194136 -32.916953) (xy 367.171187 -32.861549)
			(xy 367.155666 -32.803624) (xy 367.147838 -32.744168) (xy 367.147348 -32.714184) (xy 357.8225 -32.714184)
			(xy 357.8225 -32.722312) (xy 357.82201 -32.75228) (xy 357.814187 -32.811702) (xy 357.798674 -32.869595)
			(xy 357.775738 -32.924968) (xy 357.745771 -32.976874) (xy 357.709284 -33.024424) (xy 357.666904 -33.066804)
			(xy 357.619354 -33.103291) (xy 357.567448 -33.133258) (xy 357.512075 -33.156194) (xy 357.454182 -33.171707)
			(xy 357.39476 -33.17953) (xy 357.334824 -33.17953) (xy 357.275402 -33.171707) (xy 357.217509 -33.156194)
			(xy 357.162136 -33.133258) (xy 357.11023 -33.103291) (xy 357.06268 -33.066804) (xy 357.0203 -33.024424)
			(xy 356.983813 -32.976874) (xy 356.953846 -32.924968) (xy 356.93091 -32.869595) (xy 356.915397 -32.811702)
			(xy 356.907574 -32.75228) (xy 356.907084 -32.722312) (xy 329.962631 -32.722312) (xy 329.962274 -32.744152)
			(xy 329.954451 -32.803574) (xy 329.938938 -32.861467) (xy 329.916002 -32.91684) (xy 329.886035 -32.968746)
			(xy 329.849548 -33.016296) (xy 329.807168 -33.058676) (xy 329.759618 -33.095163) (xy 329.707712 -33.12513)
			(xy 329.652339 -33.148066) (xy 329.594446 -33.163579) (xy 329.535024 -33.171402) (xy 329.475088 -33.171402)
			(xy 329.415666 -33.163579) (xy 329.357773 -33.148066) (xy 329.3024 -33.12513) (xy 329.250494 -33.095163)
			(xy 329.202944 -33.058676) (xy 329.160564 -33.016296) (xy 329.124077 -32.968746) (xy 329.09411 -32.91684)
			(xy 329.071174 -32.861467) (xy 329.055661 -32.803574) (xy 329.047838 -32.744152) (xy 329.047348 -32.714184)
			(xy 319.7225 -32.714184) (xy 319.7225 -32.722312) (xy 319.72201 -32.752296) (xy 319.714182 -32.811752)
			(xy 319.698661 -32.869677) (xy 319.675712 -32.925081) (xy 319.645728 -32.977015) (xy 319.609222 -33.024591)
			(xy 319.566817 -33.066996) (xy 319.519241 -33.103502) (xy 319.467307 -33.133486) (xy 319.411903 -33.156435)
			(xy 319.353978 -33.171956) (xy 319.294522 -33.179784) (xy 319.234554 -33.179784) (xy 319.175098 -33.171956)
			(xy 319.117173 -33.156435) (xy 319.061769 -33.133486) (xy 319.009835 -33.103502) (xy 318.962259 -33.066996)
			(xy 318.919854 -33.024591) (xy 318.883348 -32.977015) (xy 318.853364 -32.925081) (xy 318.830415 -32.869677)
			(xy 318.814894 -32.811752) (xy 318.807066 -32.752296) (xy 318.806576 -32.722312) (xy 303.962683 -32.722312)
			(xy 303.962326 -32.744152) (xy 303.954503 -32.803574) (xy 303.93899 -32.861467) (xy 303.916054 -32.91684)
			(xy 303.886087 -32.968746) (xy 303.8496 -33.016296) (xy 303.80722 -33.058676) (xy 303.75967 -33.095163)
			(xy 303.707764 -33.12513) (xy 303.652391 -33.148066) (xy 303.594498 -33.163579) (xy 303.535076 -33.171402)
			(xy 303.47514 -33.171402) (xy 303.415718 -33.163579) (xy 303.357825 -33.148066) (xy 303.302452 -33.12513)
			(xy 303.250546 -33.095163) (xy 303.202996 -33.058676) (xy 303.160616 -33.016296) (xy 303.124129 -32.968746)
			(xy 303.094162 -32.91684) (xy 303.071226 -32.861467) (xy 303.055713 -32.803574) (xy 303.04789 -32.744152)
			(xy 303.0474 -32.714184) (xy 293.722552 -32.714184) (xy 293.722552 -32.722312) (xy 293.722062 -32.752296)
			(xy 293.714234 -32.811752) (xy 293.698713 -32.869677) (xy 293.675764 -32.925081) (xy 293.64578 -32.977015)
			(xy 293.609274 -33.024591) (xy 293.566869 -33.066996) (xy 293.519293 -33.103502) (xy 293.467359 -33.133486)
			(xy 293.411955 -33.156435) (xy 293.35403 -33.171956) (xy 293.294574 -33.179784) (xy 293.234606 -33.179784)
			(xy 293.17515 -33.171956) (xy 293.117225 -33.156435) (xy 293.061821 -33.133486) (xy 293.009887 -33.103502)
			(xy 292.962311 -33.066996) (xy 292.919906 -33.024591) (xy 292.8834 -32.977015) (xy 292.853416 -32.925081)
			(xy 292.830467 -32.869677) (xy 292.814946 -32.811752) (xy 292.807118 -32.752296) (xy 292.806628 -32.722312)
			(xy 277.962735 -32.722312) (xy 277.962378 -32.744152) (xy 277.954555 -32.803574) (xy 277.939042 -32.861467)
			(xy 277.916106 -32.91684) (xy 277.886139 -32.968746) (xy 277.849652 -33.016296) (xy 277.807272 -33.058676)
			(xy 277.759722 -33.095163) (xy 277.707816 -33.12513) (xy 277.652443 -33.148066) (xy 277.59455 -33.163579)
			(xy 277.535128 -33.171402) (xy 277.475192 -33.171402) (xy 277.41577 -33.163579) (xy 277.357877 -33.148066)
			(xy 277.302504 -33.12513) (xy 277.250598 -33.095163) (xy 277.203048 -33.058676) (xy 277.160668 -33.016296)
			(xy 277.124181 -32.968746) (xy 277.094214 -32.91684) (xy 277.071278 -32.861467) (xy 277.055765 -32.803574)
			(xy 277.047942 -32.744152) (xy 277.047452 -32.714184) (xy 267.722604 -32.714184) (xy 267.722604 -32.722312)
			(xy 267.722114 -32.752296) (xy 267.714286 -32.811752) (xy 267.698765 -32.869677) (xy 267.675816 -32.925081)
			(xy 267.645832 -32.977015) (xy 267.609326 -33.024591) (xy 267.566921 -33.066996) (xy 267.519345 -33.103502)
			(xy 267.467411 -33.133486) (xy 267.412007 -33.156435) (xy 267.354082 -33.171956) (xy 267.294626 -33.179784)
			(xy 267.234658 -33.179784) (xy 267.175202 -33.171956) (xy 267.117277 -33.156435) (xy 267.061873 -33.133486)
			(xy 267.009939 -33.103502) (xy 266.962363 -33.066996) (xy 266.919958 -33.024591) (xy 266.883452 -32.977015)
			(xy 266.853468 -32.925081) (xy 266.830519 -32.869677) (xy 266.814998 -32.811752) (xy 266.80717 -32.752296)
			(xy 266.80668 -32.722312) (xy 251.962787 -32.722312) (xy 251.96243 -32.744152) (xy 251.954607 -32.803574)
			(xy 251.939094 -32.861467) (xy 251.916158 -32.91684) (xy 251.886191 -32.968746) (xy 251.849704 -33.016296)
			(xy 251.807324 -33.058676) (xy 251.759774 -33.095163) (xy 251.707868 -33.12513) (xy 251.652495 -33.148066)
			(xy 251.594602 -33.163579) (xy 251.53518 -33.171402) (xy 251.475244 -33.171402) (xy 251.415822 -33.163579)
			(xy 251.357929 -33.148066) (xy 251.302556 -33.12513) (xy 251.25065 -33.095163) (xy 251.2031 -33.058676)
			(xy 251.16072 -33.016296) (xy 251.124233 -32.968746) (xy 251.094266 -32.91684) (xy 251.07133 -32.861467)
			(xy 251.055817 -32.803574) (xy 251.047994 -32.744152) (xy 251.047504 -32.714184) (xy 241.722656 -32.714184)
			(xy 241.722656 -32.722312) (xy 241.722166 -32.752296) (xy 241.714338 -32.811752) (xy 241.698817 -32.869677)
			(xy 241.675868 -32.925081) (xy 241.645884 -32.977015) (xy 241.609378 -33.024591) (xy 241.566973 -33.066996)
			(xy 241.519397 -33.103502) (xy 241.467463 -33.133486) (xy 241.412059 -33.156435) (xy 241.354134 -33.171956)
			(xy 241.294678 -33.179784) (xy 241.23471 -33.179784) (xy 241.175254 -33.171956) (xy 241.117329 -33.156435)
			(xy 241.061925 -33.133486) (xy 241.009991 -33.103502) (xy 240.962415 -33.066996) (xy 240.92001 -33.024591)
			(xy 240.883504 -32.977015) (xy 240.85352 -32.925081) (xy 240.830571 -32.869677) (xy 240.81505 -32.811752)
			(xy 240.807222 -32.752296) (xy 240.806732 -32.722312) (xy 213.862787 -32.722312) (xy 213.86243 -32.744152)
			(xy 213.854607 -32.803574) (xy 213.839094 -32.861467) (xy 213.816158 -32.91684) (xy 213.786191 -32.968746)
			(xy 213.749704 -33.016296) (xy 213.707324 -33.058676) (xy 213.659774 -33.095163) (xy 213.607868 -33.12513)
			(xy 213.552495 -33.148066) (xy 213.494602 -33.163579) (xy 213.43518 -33.171402) (xy 213.375244 -33.171402)
			(xy 213.315822 -33.163579) (xy 213.257929 -33.148066) (xy 213.202556 -33.12513) (xy 213.15065 -33.095163)
			(xy 213.1031 -33.058676) (xy 213.06072 -33.016296) (xy 213.024233 -32.968746) (xy 212.994266 -32.91684)
			(xy 212.97133 -32.861467) (xy 212.955817 -32.803574) (xy 212.947994 -32.744152) (xy 212.947504 -32.714184)
			(xy 203.622656 -32.714184) (xy 203.622656 -32.722312) (xy 203.622166 -32.752296) (xy 203.614338 -32.811752)
			(xy 203.598817 -32.869677) (xy 203.575868 -32.925081) (xy 203.545884 -32.977015) (xy 203.509378 -33.024591)
			(xy 203.466973 -33.066996) (xy 203.419397 -33.103502) (xy 203.367463 -33.133486) (xy 203.312059 -33.156435)
			(xy 203.254134 -33.171956) (xy 203.194678 -33.179784) (xy 203.13471 -33.179784) (xy 203.075254 -33.171956)
			(xy 203.017329 -33.156435) (xy 202.961925 -33.133486) (xy 202.909991 -33.103502) (xy 202.862415 -33.066996)
			(xy 202.82001 -33.024591) (xy 202.783504 -32.977015) (xy 202.75352 -32.925081) (xy 202.730571 -32.869677)
			(xy 202.71505 -32.811752) (xy 202.707222 -32.752296) (xy 202.706732 -32.722312) (xy 187.862839 -32.722312)
			(xy 187.862482 -32.744152) (xy 187.854659 -32.803574) (xy 187.839146 -32.861467) (xy 187.81621 -32.91684)
			(xy 187.786243 -32.968746) (xy 187.749756 -33.016296) (xy 187.707376 -33.058676) (xy 187.659826 -33.095163)
			(xy 187.60792 -33.12513) (xy 187.552547 -33.148066) (xy 187.494654 -33.163579) (xy 187.435232 -33.171402)
			(xy 187.375296 -33.171402) (xy 187.315874 -33.163579) (xy 187.257981 -33.148066) (xy 187.202608 -33.12513)
			(xy 187.150702 -33.095163) (xy 187.103152 -33.058676) (xy 187.060772 -33.016296) (xy 187.024285 -32.968746)
			(xy 186.994318 -32.91684) (xy 186.971382 -32.861467) (xy 186.955869 -32.803574) (xy 186.948046 -32.744152)
			(xy 186.947556 -32.714184) (xy 177.622708 -32.714184) (xy 177.622708 -32.722312) (xy 177.622218 -32.752296)
			(xy 177.61439 -32.811752) (xy 177.598869 -32.869677) (xy 177.57592 -32.925081) (xy 177.545936 -32.977015)
			(xy 177.50943 -33.024591) (xy 177.467025 -33.066996) (xy 177.419449 -33.103502) (xy 177.367515 -33.133486)
			(xy 177.312111 -33.156435) (xy 177.254186 -33.171956) (xy 177.19473 -33.179784) (xy 177.134762 -33.179784)
			(xy 177.075306 -33.171956) (xy 177.017381 -33.156435) (xy 176.961977 -33.133486) (xy 176.910043 -33.103502)
			(xy 176.862467 -33.066996) (xy 176.820062 -33.024591) (xy 176.783556 -32.977015) (xy 176.753572 -32.925081)
			(xy 176.730623 -32.869677) (xy 176.715102 -32.811752) (xy 176.707274 -32.752296) (xy 176.706784 -32.722312)
			(xy 161.862891 -32.722312) (xy 161.862534 -32.744152) (xy 161.854711 -32.803574) (xy 161.839198 -32.861467)
			(xy 161.816262 -32.91684) (xy 161.786295 -32.968746) (xy 161.749808 -33.016296) (xy 161.707428 -33.058676)
			(xy 161.659878 -33.095163) (xy 161.607972 -33.12513) (xy 161.552599 -33.148066) (xy 161.494706 -33.163579)
			(xy 161.435284 -33.171402) (xy 161.375348 -33.171402) (xy 161.315926 -33.163579) (xy 161.258033 -33.148066)
			(xy 161.20266 -33.12513) (xy 161.150754 -33.095163) (xy 161.103204 -33.058676) (xy 161.060824 -33.016296)
			(xy 161.024337 -32.968746) (xy 160.99437 -32.91684) (xy 160.971434 -32.861467) (xy 160.955921 -32.803574)
			(xy 160.948098 -32.744152) (xy 160.947608 -32.714184) (xy 151.62276 -32.714184) (xy 151.62276 -32.722312)
			(xy 151.62227 -32.752296) (xy 151.614442 -32.811752) (xy 151.598921 -32.869677) (xy 151.575972 -32.925081)
			(xy 151.545988 -32.977015) (xy 151.509482 -33.024591) (xy 151.467077 -33.066996) (xy 151.419501 -33.103502)
			(xy 151.367567 -33.133486) (xy 151.312163 -33.156435) (xy 151.254238 -33.171956) (xy 151.194782 -33.179784)
			(xy 151.134814 -33.179784) (xy 151.075358 -33.171956) (xy 151.017433 -33.156435) (xy 150.962029 -33.133486)
			(xy 150.910095 -33.103502) (xy 150.862519 -33.066996) (xy 150.820114 -33.024591) (xy 150.783608 -32.977015)
			(xy 150.753624 -32.925081) (xy 150.730675 -32.869677) (xy 150.715154 -32.811752) (xy 150.707326 -32.752296)
			(xy 150.706836 -32.722312) (xy 135.862943 -32.722312) (xy 135.862586 -32.744152) (xy 135.854763 -32.803574)
			(xy 135.83925 -32.861467) (xy 135.816314 -32.91684) (xy 135.786347 -32.968746) (xy 135.74986 -33.016296)
			(xy 135.70748 -33.058676) (xy 135.65993 -33.095163) (xy 135.608024 -33.12513) (xy 135.552651 -33.148066)
			(xy 135.494758 -33.163579) (xy 135.435336 -33.171402) (xy 135.3754 -33.171402) (xy 135.315978 -33.163579)
			(xy 135.258085 -33.148066) (xy 135.202712 -33.12513) (xy 135.150806 -33.095163) (xy 135.103256 -33.058676)
			(xy 135.060876 -33.016296) (xy 135.024389 -32.968746) (xy 134.994422 -32.91684) (xy 134.971486 -32.861467)
			(xy 134.955973 -32.803574) (xy 134.94815 -32.744152) (xy 134.94766 -32.714184) (xy 125.622812 -32.714184)
			(xy 125.622812 -32.722312) (xy 125.622322 -32.752296) (xy 125.614494 -32.811752) (xy 125.598973 -32.869677)
			(xy 125.576024 -32.925081) (xy 125.54604 -32.977015) (xy 125.509534 -33.024591) (xy 125.467129 -33.066996)
			(xy 125.419553 -33.103502) (xy 125.367619 -33.133486) (xy 125.312215 -33.156435) (xy 125.25429 -33.171956)
			(xy 125.194834 -33.179784) (xy 125.134866 -33.179784) (xy 125.07541 -33.171956) (xy 125.017485 -33.156435)
			(xy 124.962081 -33.133486) (xy 124.910147 -33.103502) (xy 124.862571 -33.066996) (xy 124.820166 -33.024591)
			(xy 124.78366 -32.977015) (xy 124.753676 -32.925081) (xy 124.730727 -32.869677) (xy 124.715206 -32.811752)
			(xy 124.707378 -32.752296) (xy 124.706888 -32.722312) (xy 97.762943 -32.722312) (xy 97.762586 -32.744168)
			(xy 97.754758 -32.803624) (xy 97.739237 -32.861549) (xy 97.716288 -32.916953) (xy 97.686304 -32.968887)
			(xy 97.649798 -33.016463) (xy 97.607393 -33.058868) (xy 97.559817 -33.095374) (xy 97.507883 -33.125358)
			(xy 97.452479 -33.148307) (xy 97.394554 -33.163828) (xy 97.335098 -33.171656) (xy 97.27513 -33.171656)
			(xy 97.215674 -33.163828) (xy 97.157749 -33.148307) (xy 97.102345 -33.125358) (xy 97.050411 -33.095374)
			(xy 97.002835 -33.058868) (xy 96.96043 -33.016463) (xy 96.923924 -32.968887) (xy 96.89394 -32.916953)
			(xy 96.870991 -32.861549) (xy 96.85547 -32.803624) (xy 96.847642 -32.744168) (xy 96.847152 -32.714184)
			(xy 87.522304 -32.714184) (xy 87.522304 -32.722312) (xy 87.521814 -32.75228) (xy 87.513991 -32.811702)
			(xy 87.498478 -32.869595) (xy 87.475542 -32.924968) (xy 87.445575 -32.976874) (xy 87.409088 -33.024424)
			(xy 87.366708 -33.066804) (xy 87.319158 -33.103291) (xy 87.267252 -33.133258) (xy 87.211879 -33.156194)
			(xy 87.153986 -33.171707) (xy 87.094564 -33.17953) (xy 87.034628 -33.17953) (xy 86.975206 -33.171707)
			(xy 86.917313 -33.156194) (xy 86.86194 -33.133258) (xy 86.810034 -33.103291) (xy 86.762484 -33.066804)
			(xy 86.720104 -33.024424) (xy 86.683617 -32.976874) (xy 86.65365 -32.924968) (xy 86.630714 -32.869595)
			(xy 86.615201 -32.811702) (xy 86.607378 -32.75228) (xy 86.606888 -32.722312) (xy 71.762995 -32.722312)
			(xy 71.762638 -32.744168) (xy 71.75481 -32.803624) (xy 71.739289 -32.861549) (xy 71.71634 -32.916953)
			(xy 71.686356 -32.968887) (xy 71.64985 -33.016463) (xy 71.607445 -33.058868) (xy 71.559869 -33.095374)
			(xy 71.507935 -33.125358) (xy 71.452531 -33.148307) (xy 71.394606 -33.163828) (xy 71.33515 -33.171656)
			(xy 71.275182 -33.171656) (xy 71.215726 -33.163828) (xy 71.157801 -33.148307) (xy 71.102397 -33.125358)
			(xy 71.050463 -33.095374) (xy 71.002887 -33.058868) (xy 70.960482 -33.016463) (xy 70.923976 -32.968887)
			(xy 70.893992 -32.916953) (xy 70.871043 -32.861549) (xy 70.855522 -32.803624) (xy 70.847694 -32.744168)
			(xy 70.847204 -32.714184) (xy 61.522356 -32.714184) (xy 61.522356 -32.722312) (xy 61.521866 -32.75228)
			(xy 61.514043 -32.811702) (xy 61.49853 -32.869595) (xy 61.475594 -32.924968) (xy 61.445627 -32.976874)
			(xy 61.40914 -33.024424) (xy 61.36676 -33.066804) (xy 61.31921 -33.103291) (xy 61.267304 -33.133258)
			(xy 61.211931 -33.156194) (xy 61.154038 -33.171707) (xy 61.094616 -33.17953) (xy 61.03468 -33.17953)
			(xy 60.975258 -33.171707) (xy 60.917365 -33.156194) (xy 60.861992 -33.133258) (xy 60.810086 -33.103291)
			(xy 60.762536 -33.066804) (xy 60.720156 -33.024424) (xy 60.683669 -32.976874) (xy 60.653702 -32.924968)
			(xy 60.630766 -32.869595) (xy 60.615253 -32.811702) (xy 60.60743 -32.75228) (xy 60.60694 -32.722312)
			(xy 45.763047 -32.722312) (xy 45.76269 -32.744168) (xy 45.754862 -32.803624) (xy 45.739341 -32.861549)
			(xy 45.716392 -32.916953) (xy 45.686408 -32.968887) (xy 45.649902 -33.016463) (xy 45.607497 -33.058868)
			(xy 45.559921 -33.095374) (xy 45.507987 -33.125358) (xy 45.452583 -33.148307) (xy 45.394658 -33.163828)
			(xy 45.335202 -33.171656) (xy 45.275234 -33.171656) (xy 45.215778 -33.163828) (xy 45.157853 -33.148307)
			(xy 45.102449 -33.125358) (xy 45.050515 -33.095374) (xy 45.002939 -33.058868) (xy 44.960534 -33.016463)
			(xy 44.924028 -32.968887) (xy 44.894044 -32.916953) (xy 44.871095 -32.861549) (xy 44.855574 -32.803624)
			(xy 44.847746 -32.744168) (xy 44.847256 -32.714184) (xy 35.522408 -32.714184) (xy 35.522408 -32.722312)
			(xy 35.521918 -32.75228) (xy 35.514095 -32.811702) (xy 35.498582 -32.869595) (xy 35.475646 -32.924968)
			(xy 35.445679 -32.976874) (xy 35.409192 -33.024424) (xy 35.366812 -33.066804) (xy 35.319262 -33.103291)
			(xy 35.267356 -33.133258) (xy 35.211983 -33.156194) (xy 35.15409 -33.171707) (xy 35.094668 -33.17953)
			(xy 35.034732 -33.17953) (xy 34.97531 -33.171707) (xy 34.917417 -33.156194) (xy 34.862044 -33.133258)
			(xy 34.810138 -33.103291) (xy 34.762588 -33.066804) (xy 34.720208 -33.024424) (xy 34.683721 -32.976874)
			(xy 34.653754 -32.924968) (xy 34.630818 -32.869595) (xy 34.615305 -32.811702) (xy 34.607482 -32.75228)
			(xy 34.606992 -32.722312) (xy 19.763099 -32.722312) (xy 19.762742 -32.744168) (xy 19.754914 -32.803624)
			(xy 19.739393 -32.861549) (xy 19.716444 -32.916953) (xy 19.68646 -32.968887) (xy 19.649954 -33.016463)
			(xy 19.607549 -33.058868) (xy 19.559973 -33.095374) (xy 19.508039 -33.125358) (xy 19.452635 -33.148307)
			(xy 19.39471 -33.163828) (xy 19.335254 -33.171656) (xy 19.275286 -33.171656) (xy 19.21583 -33.163828)
			(xy 19.157905 -33.148307) (xy 19.102501 -33.125358) (xy 19.050567 -33.095374) (xy 19.002991 -33.058868)
			(xy 18.960586 -33.016463) (xy 18.92408 -32.968887) (xy 18.894096 -32.916953) (xy 18.871147 -32.861549)
			(xy 18.855626 -32.803624) (xy 18.847798 -32.744168) (xy 18.847308 -32.714184) (xy 9.52246 -32.714184)
			(xy 9.52246 -32.722312) (xy 9.52197 -32.75228) (xy 9.514147 -32.811702) (xy 9.498634 -32.869595)
			(xy 9.475698 -32.924968) (xy 9.445731 -32.976874) (xy 9.409244 -33.024424) (xy 9.366864 -33.066804)
			(xy 9.319314 -33.103291) (xy 9.267408 -33.133258) (xy 9.212035 -33.156194) (xy 9.154142 -33.171707)
			(xy 9.09472 -33.17953) (xy 9.034784 -33.17953) (xy 8.975362 -33.171707) (xy 8.917469 -33.156194)
			(xy 8.862096 -33.133258) (xy 8.81019 -33.103291) (xy 8.76264 -33.066804) (xy 8.72026 -33.024424)
			(xy 8.683773 -32.976874) (xy 8.653806 -32.924968) (xy 8.63087 -32.869595) (xy 8.615357 -32.811702)
			(xy 8.607534 -32.75228) (xy 8.607044 -32.722312) (xy 0.508 -32.722312) (xy 0.508 -34.52241) (xy 6.752844 -34.52241)
			(xy 6.752844 -33.65881) (xy 6.753334 -33.628842) (xy 6.761157 -33.56942) (xy 6.77667 -33.511527)
			(xy 6.799606 -33.456154) (xy 6.829573 -33.404248) (xy 6.86606 -33.356698) (xy 6.90844 -33.314318)
			(xy 6.95599 -33.277831) (xy 7.007896 -33.247864) (xy 7.063269 -33.224928) (xy 7.121162 -33.209415)
			(xy 7.180584 -33.201592) (xy 7.24052 -33.201592) (xy 7.299942 -33.209415) (xy 7.357835 -33.224928)
			(xy 7.413208 -33.247864) (xy 7.465114 -33.277831) (xy 7.512664 -33.314318) (xy 7.555044 -33.356698)
			(xy 7.591531 -33.404248) (xy 7.621498 -33.456154) (xy 7.644434 -33.511527) (xy 7.659947 -33.56942)
			(xy 7.66777 -33.628842) (xy 7.66826 -33.65881) (xy 7.66826 -34.520886) (xy 21.489416 -34.520886)
			(xy 21.489416 -33.657286) (xy 21.489906 -33.627302) (xy 21.497734 -33.567846) (xy 21.513255 -33.509921)
			(xy 21.536204 -33.454517) (xy 21.566188 -33.402583) (xy 21.602694 -33.355007) (xy 21.645099 -33.312602)
			(xy 21.692675 -33.276096) (xy 21.744609 -33.246112) (xy 21.800013 -33.223163) (xy 21.857938 -33.207642)
			(xy 21.917394 -33.199814) (xy 21.977362 -33.199814) (xy 22.036818 -33.207642) (xy 22.094743 -33.223163)
			(xy 22.150147 -33.246112) (xy 22.202081 -33.276096) (xy 22.249657 -33.312602) (xy 22.292062 -33.355007)
			(xy 22.328568 -33.402583) (xy 22.358552 -33.454517) (xy 22.381501 -33.509921) (xy 22.397022 -33.567846)
			(xy 22.40485 -33.627302) (xy 22.40534 -33.657286) (xy 22.40534 -34.520886) (xy 22.405315 -34.52241)
			(xy 32.752792 -34.52241) (xy 32.752792 -33.65881) (xy 32.753282 -33.628842) (xy 32.761105 -33.56942)
			(xy 32.776618 -33.511527) (xy 32.799554 -33.456154) (xy 32.829521 -33.404248) (xy 32.866008 -33.356698)
			(xy 32.908388 -33.314318) (xy 32.955938 -33.277831) (xy 33.007844 -33.247864) (xy 33.063217 -33.224928)
			(xy 33.12111 -33.209415) (xy 33.180532 -33.201592) (xy 33.240468 -33.201592) (xy 33.29989 -33.209415)
			(xy 33.357783 -33.224928) (xy 33.413156 -33.247864) (xy 33.465062 -33.277831) (xy 33.512612 -33.314318)
			(xy 33.554992 -33.356698) (xy 33.591479 -33.404248) (xy 33.621446 -33.456154) (xy 33.644382 -33.511527)
			(xy 33.659895 -33.56942) (xy 33.667718 -33.628842) (xy 33.668208 -33.65881) (xy 33.668208 -34.520886)
			(xy 47.489364 -34.520886) (xy 47.489364 -33.657286) (xy 47.489854 -33.627302) (xy 47.497682 -33.567846)
			(xy 47.513203 -33.509921) (xy 47.536152 -33.454517) (xy 47.566136 -33.402583) (xy 47.602642 -33.355007)
			(xy 47.645047 -33.312602) (xy 47.692623 -33.276096) (xy 47.744557 -33.246112) (xy 47.799961 -33.223163)
			(xy 47.857886 -33.207642) (xy 47.917342 -33.199814) (xy 47.97731 -33.199814) (xy 48.036766 -33.207642)
			(xy 48.094691 -33.223163) (xy 48.150095 -33.246112) (xy 48.202029 -33.276096) (xy 48.249605 -33.312602)
			(xy 48.29201 -33.355007) (xy 48.328516 -33.402583) (xy 48.3585 -33.454517) (xy 48.381449 -33.509921)
			(xy 48.39697 -33.567846) (xy 48.404798 -33.627302) (xy 48.405288 -33.657286) (xy 48.405288 -34.520886)
			(xy 48.405263 -34.52241) (xy 58.75274 -34.52241) (xy 58.75274 -33.65881) (xy 58.75323 -33.628842)
			(xy 58.761053 -33.56942) (xy 58.776566 -33.511527) (xy 58.799502 -33.456154) (xy 58.829469 -33.404248)
			(xy 58.865956 -33.356698) (xy 58.908336 -33.314318) (xy 58.955886 -33.277831) (xy 59.007792 -33.247864)
			(xy 59.063165 -33.224928) (xy 59.121058 -33.209415) (xy 59.18048 -33.201592) (xy 59.240416 -33.201592)
			(xy 59.299838 -33.209415) (xy 59.357731 -33.224928) (xy 59.413104 -33.247864) (xy 59.46501 -33.277831)
			(xy 59.51256 -33.314318) (xy 59.55494 -33.356698) (xy 59.591427 -33.404248) (xy 59.621394 -33.456154)
			(xy 59.64433 -33.511527) (xy 59.659843 -33.56942) (xy 59.667666 -33.628842) (xy 59.668156 -33.65881)
			(xy 59.668156 -34.520886) (xy 73.489312 -34.520886) (xy 73.489312 -33.657286) (xy 73.489802 -33.627302)
			(xy 73.49763 -33.567846) (xy 73.513151 -33.509921) (xy 73.5361 -33.454517) (xy 73.566084 -33.402583)
			(xy 73.60259 -33.355007) (xy 73.644995 -33.312602) (xy 73.692571 -33.276096) (xy 73.744505 -33.246112)
			(xy 73.799909 -33.223163) (xy 73.857834 -33.207642) (xy 73.91729 -33.199814) (xy 73.977258 -33.199814)
			(xy 74.036714 -33.207642) (xy 74.094639 -33.223163) (xy 74.150043 -33.246112) (xy 74.201977 -33.276096)
			(xy 74.249553 -33.312602) (xy 74.291958 -33.355007) (xy 74.328464 -33.402583) (xy 74.358448 -33.454517)
			(xy 74.381397 -33.509921) (xy 74.396918 -33.567846) (xy 74.404746 -33.627302) (xy 74.405236 -33.657286)
			(xy 74.405236 -34.520886) (xy 74.405211 -34.52241) (xy 84.752688 -34.52241) (xy 84.752688 -33.65881)
			(xy 84.753178 -33.628842) (xy 84.761001 -33.56942) (xy 84.776514 -33.511527) (xy 84.79945 -33.456154)
			(xy 84.829417 -33.404248) (xy 84.865904 -33.356698) (xy 84.908284 -33.314318) (xy 84.955834 -33.277831)
			(xy 85.00774 -33.247864) (xy 85.063113 -33.224928) (xy 85.121006 -33.209415) (xy 85.180428 -33.201592)
			(xy 85.240364 -33.201592) (xy 85.299786 -33.209415) (xy 85.357679 -33.224928) (xy 85.413052 -33.247864)
			(xy 85.464958 -33.277831) (xy 85.512508 -33.314318) (xy 85.554888 -33.356698) (xy 85.591375 -33.404248)
			(xy 85.621342 -33.456154) (xy 85.644278 -33.511527) (xy 85.659791 -33.56942) (xy 85.667614 -33.628842)
			(xy 85.668104 -33.65881) (xy 85.668104 -34.520886) (xy 99.48926 -34.520886) (xy 99.48926 -33.657286)
			(xy 99.48975 -33.627302) (xy 99.497578 -33.567846) (xy 99.513099 -33.509921) (xy 99.536048 -33.454517)
			(xy 99.566032 -33.402583) (xy 99.602538 -33.355007) (xy 99.644943 -33.312602) (xy 99.692519 -33.276096)
			(xy 99.744453 -33.246112) (xy 99.799857 -33.223163) (xy 99.857782 -33.207642) (xy 99.917238 -33.199814)
			(xy 99.977206 -33.199814) (xy 100.036662 -33.207642) (xy 100.094587 -33.223163) (xy 100.149991 -33.246112)
			(xy 100.201925 -33.276096) (xy 100.249501 -33.312602) (xy 100.291906 -33.355007) (xy 100.328412 -33.402583)
			(xy 100.358396 -33.454517) (xy 100.381345 -33.509921) (xy 100.396866 -33.567846) (xy 100.404694 -33.627302)
			(xy 100.405184 -33.657286) (xy 100.405184 -34.520886) (xy 100.405159 -34.52241) (xy 122.852688 -34.52241)
			(xy 122.852688 -33.65881) (xy 122.853178 -33.628826) (xy 122.861006 -33.56937) (xy 122.876527 -33.511445)
			(xy 122.899476 -33.456041) (xy 122.92946 -33.404107) (xy 122.965966 -33.356531) (xy 123.008371 -33.314126)
			(xy 123.055947 -33.27762) (xy 123.107881 -33.247636) (xy 123.163285 -33.224687) (xy 123.22121 -33.209166)
			(xy 123.280666 -33.201338) (xy 123.340634 -33.201338) (xy 123.40009 -33.209166) (xy 123.458015 -33.224687)
			(xy 123.513419 -33.247636) (xy 123.565353 -33.27762) (xy 123.612929 -33.314126) (xy 123.655334 -33.356531)
			(xy 123.69184 -33.404107) (xy 123.721824 -33.456041) (xy 123.744773 -33.511445) (xy 123.760294 -33.56937)
			(xy 123.768122 -33.628826) (xy 123.768612 -33.65881) (xy 123.768612 -34.520886) (xy 137.589768 -34.520886)
			(xy 137.589768 -33.657286) (xy 137.590258 -33.627318) (xy 137.598081 -33.567896) (xy 137.613594 -33.510003)
			(xy 137.63653 -33.45463) (xy 137.666497 -33.402724) (xy 137.702984 -33.355174) (xy 137.745364 -33.312794)
			(xy 137.792914 -33.276307) (xy 137.84482 -33.24634) (xy 137.900193 -33.223404) (xy 137.958086 -33.207891)
			(xy 138.017508 -33.200068) (xy 138.077444 -33.200068) (xy 138.136866 -33.207891) (xy 138.194759 -33.223404)
			(xy 138.250132 -33.24634) (xy 138.302038 -33.276307) (xy 138.349588 -33.312794) (xy 138.391968 -33.355174)
			(xy 138.428455 -33.402724) (xy 138.458422 -33.45463) (xy 138.481358 -33.510003) (xy 138.496871 -33.567896)
			(xy 138.504694 -33.627318) (xy 138.505184 -33.657286) (xy 138.505184 -34.520886) (xy 138.505159 -34.52241)
			(xy 148.852636 -34.52241) (xy 148.852636 -33.65881) (xy 148.853126 -33.628826) (xy 148.860954 -33.56937)
			(xy 148.876475 -33.511445) (xy 148.899424 -33.456041) (xy 148.929408 -33.404107) (xy 148.965914 -33.356531)
			(xy 149.008319 -33.314126) (xy 149.055895 -33.27762) (xy 149.107829 -33.247636) (xy 149.163233 -33.224687)
			(xy 149.221158 -33.209166) (xy 149.280614 -33.201338) (xy 149.340582 -33.201338) (xy 149.400038 -33.209166)
			(xy 149.457963 -33.224687) (xy 149.513367 -33.247636) (xy 149.565301 -33.27762) (xy 149.612877 -33.314126)
			(xy 149.655282 -33.356531) (xy 149.691788 -33.404107) (xy 149.721772 -33.456041) (xy 149.744721 -33.511445)
			(xy 149.760242 -33.56937) (xy 149.76807 -33.628826) (xy 149.76856 -33.65881) (xy 149.76856 -34.520886)
			(xy 163.589716 -34.520886) (xy 163.589716 -33.657286) (xy 163.590206 -33.627318) (xy 163.598029 -33.567896)
			(xy 163.613542 -33.510003) (xy 163.636478 -33.45463) (xy 163.666445 -33.402724) (xy 163.702932 -33.355174)
			(xy 163.745312 -33.312794) (xy 163.792862 -33.276307) (xy 163.844768 -33.24634) (xy 163.900141 -33.223404)
			(xy 163.958034 -33.207891) (xy 164.017456 -33.200068) (xy 164.077392 -33.200068) (xy 164.136814 -33.207891)
			(xy 164.194707 -33.223404) (xy 164.25008 -33.24634) (xy 164.301986 -33.276307) (xy 164.349536 -33.312794)
			(xy 164.391916 -33.355174) (xy 164.428403 -33.402724) (xy 164.45837 -33.45463) (xy 164.481306 -33.510003)
			(xy 164.496819 -33.567896) (xy 164.504642 -33.627318) (xy 164.505132 -33.657286) (xy 164.505132 -34.520886)
			(xy 164.505107 -34.52241) (xy 174.852584 -34.52241) (xy 174.852584 -33.65881) (xy 174.853074 -33.628826)
			(xy 174.860902 -33.56937) (xy 174.876423 -33.511445) (xy 174.899372 -33.456041) (xy 174.929356 -33.404107)
			(xy 174.965862 -33.356531) (xy 175.008267 -33.314126) (xy 175.055843 -33.27762) (xy 175.107777 -33.247636)
			(xy 175.163181 -33.224687) (xy 175.221106 -33.209166) (xy 175.280562 -33.201338) (xy 175.34053 -33.201338)
			(xy 175.399986 -33.209166) (xy 175.457911 -33.224687) (xy 175.513315 -33.247636) (xy 175.565249 -33.27762)
			(xy 175.612825 -33.314126) (xy 175.65523 -33.356531) (xy 175.691736 -33.404107) (xy 175.72172 -33.456041)
			(xy 175.744669 -33.511445) (xy 175.76019 -33.56937) (xy 175.768018 -33.628826) (xy 175.768508 -33.65881)
			(xy 175.768508 -34.520886) (xy 189.589664 -34.520886) (xy 189.589664 -33.657286) (xy 189.590154 -33.627318)
			(xy 189.597977 -33.567896) (xy 189.61349 -33.510003) (xy 189.636426 -33.45463) (xy 189.666393 -33.402724)
			(xy 189.70288 -33.355174) (xy 189.74526 -33.312794) (xy 189.79281 -33.276307) (xy 189.844716 -33.24634)
			(xy 189.900089 -33.223404) (xy 189.957982 -33.207891) (xy 190.017404 -33.200068) (xy 190.07734 -33.200068)
			(xy 190.136762 -33.207891) (xy 190.194655 -33.223404) (xy 190.250028 -33.24634) (xy 190.301934 -33.276307)
			(xy 190.349484 -33.312794) (xy 190.391864 -33.355174) (xy 190.428351 -33.402724) (xy 190.458318 -33.45463)
			(xy 190.481254 -33.510003) (xy 190.496767 -33.567896) (xy 190.50459 -33.627318) (xy 190.50508 -33.657286)
			(xy 190.50508 -34.520886) (xy 190.505055 -34.52241) (xy 200.852532 -34.52241) (xy 200.852532 -33.65881)
			(xy 200.853022 -33.628826) (xy 200.86085 -33.56937) (xy 200.876371 -33.511445) (xy 200.89932 -33.456041)
			(xy 200.929304 -33.404107) (xy 200.96581 -33.356531) (xy 201.008215 -33.314126) (xy 201.055791 -33.27762)
			(xy 201.107725 -33.247636) (xy 201.163129 -33.224687) (xy 201.221054 -33.209166) (xy 201.28051 -33.201338)
			(xy 201.340478 -33.201338) (xy 201.399934 -33.209166) (xy 201.457859 -33.224687) (xy 201.513263 -33.247636)
			(xy 201.565197 -33.27762) (xy 201.612773 -33.314126) (xy 201.655178 -33.356531) (xy 201.691684 -33.404107)
			(xy 201.721668 -33.456041) (xy 201.744617 -33.511445) (xy 201.760138 -33.56937) (xy 201.767966 -33.628826)
			(xy 201.768456 -33.65881) (xy 201.768456 -34.520886) (xy 215.589612 -34.520886) (xy 215.589612 -33.657286)
			(xy 215.590102 -33.627318) (xy 215.597925 -33.567896) (xy 215.613438 -33.510003) (xy 215.636374 -33.45463)
			(xy 215.666341 -33.402724) (xy 215.702828 -33.355174) (xy 215.745208 -33.312794) (xy 215.792758 -33.276307)
			(xy 215.844664 -33.24634) (xy 215.900037 -33.223404) (xy 215.95793 -33.207891) (xy 216.017352 -33.200068)
			(xy 216.077288 -33.200068) (xy 216.13671 -33.207891) (xy 216.194603 -33.223404) (xy 216.249976 -33.24634)
			(xy 216.301882 -33.276307) (xy 216.349432 -33.312794) (xy 216.391812 -33.355174) (xy 216.428299 -33.402724)
			(xy 216.458266 -33.45463) (xy 216.481202 -33.510003) (xy 216.496715 -33.567896) (xy 216.504538 -33.627318)
			(xy 216.505028 -33.657286) (xy 216.505028 -34.520886) (xy 216.505003 -34.52241) (xy 238.952532 -34.52241)
			(xy 238.952532 -33.65881) (xy 238.953022 -33.628826) (xy 238.96085 -33.56937) (xy 238.976371 -33.511445)
			(xy 238.99932 -33.456041) (xy 239.029304 -33.404107) (xy 239.06581 -33.356531) (xy 239.108215 -33.314126)
			(xy 239.155791 -33.27762) (xy 239.207725 -33.247636) (xy 239.263129 -33.224687) (xy 239.321054 -33.209166)
			(xy 239.38051 -33.201338) (xy 239.440478 -33.201338) (xy 239.499934 -33.209166) (xy 239.557859 -33.224687)
			(xy 239.613263 -33.247636) (xy 239.665197 -33.27762) (xy 239.712773 -33.314126) (xy 239.755178 -33.356531)
			(xy 239.791684 -33.404107) (xy 239.821668 -33.456041) (xy 239.844617 -33.511445) (xy 239.860138 -33.56937)
			(xy 239.867966 -33.628826) (xy 239.868456 -33.65881) (xy 239.868456 -34.520886) (xy 253.689612 -34.520886)
			(xy 253.689612 -33.657286) (xy 253.690102 -33.627318) (xy 253.697925 -33.567896) (xy 253.713438 -33.510003)
			(xy 253.736374 -33.45463) (xy 253.766341 -33.402724) (xy 253.802828 -33.355174) (xy 253.845208 -33.312794)
			(xy 253.892758 -33.276307) (xy 253.944664 -33.24634) (xy 254.000037 -33.223404) (xy 254.05793 -33.207891)
			(xy 254.117352 -33.200068) (xy 254.177288 -33.200068) (xy 254.23671 -33.207891) (xy 254.294603 -33.223404)
			(xy 254.349976 -33.24634) (xy 254.401882 -33.276307) (xy 254.449432 -33.312794) (xy 254.491812 -33.355174)
			(xy 254.528299 -33.402724) (xy 254.558266 -33.45463) (xy 254.581202 -33.510003) (xy 254.596715 -33.567896)
			(xy 254.604538 -33.627318) (xy 254.605028 -33.657286) (xy 254.605028 -34.520886) (xy 254.605003 -34.52241)
			(xy 264.95248 -34.52241) (xy 264.95248 -33.65881) (xy 264.95297 -33.628826) (xy 264.960798 -33.56937)
			(xy 264.976319 -33.511445) (xy 264.999268 -33.456041) (xy 265.029252 -33.404107) (xy 265.065758 -33.356531)
			(xy 265.108163 -33.314126) (xy 265.155739 -33.27762) (xy 265.207673 -33.247636) (xy 265.263077 -33.224687)
			(xy 265.321002 -33.209166) (xy 265.380458 -33.201338) (xy 265.440426 -33.201338) (xy 265.499882 -33.209166)
			(xy 265.557807 -33.224687) (xy 265.613211 -33.247636) (xy 265.665145 -33.27762) (xy 265.712721 -33.314126)
			(xy 265.755126 -33.356531) (xy 265.791632 -33.404107) (xy 265.821616 -33.456041) (xy 265.844565 -33.511445)
			(xy 265.860086 -33.56937) (xy 265.867914 -33.628826) (xy 265.868404 -33.65881) (xy 265.868404 -34.520886)
			(xy 279.68956 -34.520886) (xy 279.68956 -33.657286) (xy 279.69005 -33.627318) (xy 279.697873 -33.567896)
			(xy 279.713386 -33.510003) (xy 279.736322 -33.45463) (xy 279.766289 -33.402724) (xy 279.802776 -33.355174)
			(xy 279.845156 -33.312794) (xy 279.892706 -33.276307) (xy 279.944612 -33.24634) (xy 279.999985 -33.223404)
			(xy 280.057878 -33.207891) (xy 280.1173 -33.200068) (xy 280.177236 -33.200068) (xy 280.236658 -33.207891)
			(xy 280.294551 -33.223404) (xy 280.349924 -33.24634) (xy 280.40183 -33.276307) (xy 280.44938 -33.312794)
			(xy 280.49176 -33.355174) (xy 280.528247 -33.402724) (xy 280.558214 -33.45463) (xy 280.58115 -33.510003)
			(xy 280.596663 -33.567896) (xy 280.604486 -33.627318) (xy 280.604976 -33.657286) (xy 280.604976 -34.520886)
			(xy 280.604951 -34.52241) (xy 290.952428 -34.52241) (xy 290.952428 -33.65881) (xy 290.952918 -33.628826)
			(xy 290.960746 -33.56937) (xy 290.976267 -33.511445) (xy 290.999216 -33.456041) (xy 291.0292 -33.404107)
			(xy 291.065706 -33.356531) (xy 291.108111 -33.314126) (xy 291.155687 -33.27762) (xy 291.207621 -33.247636)
			(xy 291.263025 -33.224687) (xy 291.32095 -33.209166) (xy 291.380406 -33.201338) (xy 291.440374 -33.201338)
			(xy 291.49983 -33.209166) (xy 291.557755 -33.224687) (xy 291.613159 -33.247636) (xy 291.665093 -33.27762)
			(xy 291.712669 -33.314126) (xy 291.755074 -33.356531) (xy 291.79158 -33.404107) (xy 291.821564 -33.456041)
			(xy 291.844513 -33.511445) (xy 291.860034 -33.56937) (xy 291.867862 -33.628826) (xy 291.868352 -33.65881)
			(xy 291.868352 -34.520886) (xy 305.689508 -34.520886) (xy 305.689508 -33.657286) (xy 305.689998 -33.627318)
			(xy 305.697821 -33.567896) (xy 305.713334 -33.510003) (xy 305.73627 -33.45463) (xy 305.766237 -33.402724)
			(xy 305.802724 -33.355174) (xy 305.845104 -33.312794) (xy 305.892654 -33.276307) (xy 305.94456 -33.24634)
			(xy 305.999933 -33.223404) (xy 306.057826 -33.207891) (xy 306.117248 -33.200068) (xy 306.177184 -33.200068)
			(xy 306.236606 -33.207891) (xy 306.294499 -33.223404) (xy 306.349872 -33.24634) (xy 306.401778 -33.276307)
			(xy 306.449328 -33.312794) (xy 306.491708 -33.355174) (xy 306.528195 -33.402724) (xy 306.558162 -33.45463)
			(xy 306.581098 -33.510003) (xy 306.596611 -33.567896) (xy 306.604434 -33.627318) (xy 306.604924 -33.657286)
			(xy 306.604924 -34.520886) (xy 306.604899 -34.52241) (xy 316.952376 -34.52241) (xy 316.952376 -33.65881)
			(xy 316.952866 -33.628826) (xy 316.960694 -33.56937) (xy 316.976215 -33.511445) (xy 316.999164 -33.456041)
			(xy 317.029148 -33.404107) (xy 317.065654 -33.356531) (xy 317.108059 -33.314126) (xy 317.155635 -33.27762)
			(xy 317.207569 -33.247636) (xy 317.262973 -33.224687) (xy 317.320898 -33.209166) (xy 317.380354 -33.201338)
			(xy 317.440322 -33.201338) (xy 317.499778 -33.209166) (xy 317.557703 -33.224687) (xy 317.613107 -33.247636)
			(xy 317.665041 -33.27762) (xy 317.712617 -33.314126) (xy 317.755022 -33.356531) (xy 317.791528 -33.404107)
			(xy 317.821512 -33.456041) (xy 317.844461 -33.511445) (xy 317.859982 -33.56937) (xy 317.86781 -33.628826)
			(xy 317.8683 -33.65881) (xy 317.8683 -34.520886) (xy 331.689456 -34.520886) (xy 331.689456 -33.657286)
			(xy 331.689946 -33.627318) (xy 331.697769 -33.567896) (xy 331.713282 -33.510003) (xy 331.736218 -33.45463)
			(xy 331.766185 -33.402724) (xy 331.802672 -33.355174) (xy 331.845052 -33.312794) (xy 331.892602 -33.276307)
			(xy 331.944508 -33.24634) (xy 331.999881 -33.223404) (xy 332.057774 -33.207891) (xy 332.117196 -33.200068)
			(xy 332.177132 -33.200068) (xy 332.236554 -33.207891) (xy 332.294447 -33.223404) (xy 332.34982 -33.24634)
			(xy 332.401726 -33.276307) (xy 332.449276 -33.312794) (xy 332.491656 -33.355174) (xy 332.528143 -33.402724)
			(xy 332.55811 -33.45463) (xy 332.581046 -33.510003) (xy 332.596559 -33.567896) (xy 332.604382 -33.627318)
			(xy 332.604872 -33.657286) (xy 332.604872 -34.520886) (xy 332.604847 -34.52241) (xy 355.052884 -34.52241)
			(xy 355.052884 -33.65881) (xy 355.053374 -33.628842) (xy 355.061197 -33.56942) (xy 355.07671 -33.511527)
			(xy 355.099646 -33.456154) (xy 355.129613 -33.404248) (xy 355.1661 -33.356698) (xy 355.20848 -33.314318)
			(xy 355.25603 -33.277831) (xy 355.307936 -33.247864) (xy 355.363309 -33.224928) (xy 355.421202 -33.209415)
			(xy 355.480624 -33.201592) (xy 355.54056 -33.201592) (xy 355.599982 -33.209415) (xy 355.657875 -33.224928)
			(xy 355.713248 -33.247864) (xy 355.765154 -33.277831) (xy 355.812704 -33.314318) (xy 355.855084 -33.356698)
			(xy 355.891571 -33.404248) (xy 355.921538 -33.456154) (xy 355.944474 -33.511527) (xy 355.959987 -33.56942)
			(xy 355.96781 -33.628842) (xy 355.9683 -33.65881) (xy 355.9683 -34.520886) (xy 369.789456 -34.520886)
			(xy 369.789456 -33.657286) (xy 369.789946 -33.627302) (xy 369.797774 -33.567846) (xy 369.813295 -33.509921)
			(xy 369.836244 -33.454517) (xy 369.866228 -33.402583) (xy 369.902734 -33.355007) (xy 369.945139 -33.312602)
			(xy 369.992715 -33.276096) (xy 370.044649 -33.246112) (xy 370.100053 -33.223163) (xy 370.157978 -33.207642)
			(xy 370.217434 -33.199814) (xy 370.277402 -33.199814) (xy 370.336858 -33.207642) (xy 370.394783 -33.223163)
			(xy 370.450187 -33.246112) (xy 370.502121 -33.276096) (xy 370.549697 -33.312602) (xy 370.592102 -33.355007)
			(xy 370.628608 -33.402583) (xy 370.658592 -33.454517) (xy 370.681541 -33.509921) (xy 370.697062 -33.567846)
			(xy 370.70489 -33.627302) (xy 370.70538 -33.657286) (xy 370.70538 -34.520886) (xy 370.705355 -34.52241)
			(xy 381.052832 -34.52241) (xy 381.052832 -33.65881) (xy 381.053322 -33.628842) (xy 381.061145 -33.56942)
			(xy 381.076658 -33.511527) (xy 381.099594 -33.456154) (xy 381.129561 -33.404248) (xy 381.166048 -33.356698)
			(xy 381.208428 -33.314318) (xy 381.255978 -33.277831) (xy 381.307884 -33.247864) (xy 381.363257 -33.224928)
			(xy 381.42115 -33.209415) (xy 381.480572 -33.201592) (xy 381.540508 -33.201592) (xy 381.59993 -33.209415)
			(xy 381.657823 -33.224928) (xy 381.713196 -33.247864) (xy 381.765102 -33.277831) (xy 381.812652 -33.314318)
			(xy 381.855032 -33.356698) (xy 381.891519 -33.404248) (xy 381.921486 -33.456154) (xy 381.944422 -33.511527)
			(xy 381.959935 -33.56942) (xy 381.967758 -33.628842) (xy 381.968248 -33.65881) (xy 381.968248 -34.520886)
			(xy 395.789404 -34.520886) (xy 395.789404 -33.657286) (xy 395.789894 -33.627302) (xy 395.797722 -33.567846)
			(xy 395.813243 -33.509921) (xy 395.836192 -33.454517) (xy 395.866176 -33.402583) (xy 395.902682 -33.355007)
			(xy 395.945087 -33.312602) (xy 395.992663 -33.276096) (xy 396.044597 -33.246112) (xy 396.100001 -33.223163)
			(xy 396.157926 -33.207642) (xy 396.217382 -33.199814) (xy 396.27735 -33.199814) (xy 396.336806 -33.207642)
			(xy 396.394731 -33.223163) (xy 396.450135 -33.246112) (xy 396.502069 -33.276096) (xy 396.549645 -33.312602)
			(xy 396.59205 -33.355007) (xy 396.628556 -33.402583) (xy 396.65854 -33.454517) (xy 396.681489 -33.509921)
			(xy 396.69701 -33.567846) (xy 396.704838 -33.627302) (xy 396.705328 -33.657286) (xy 396.705328 -34.520886)
			(xy 396.705303 -34.52241) (xy 407.05278 -34.52241) (xy 407.05278 -33.65881) (xy 407.05327 -33.628842)
			(xy 407.061093 -33.56942) (xy 407.076606 -33.511527) (xy 407.099542 -33.456154) (xy 407.129509 -33.404248)
			(xy 407.165996 -33.356698) (xy 407.208376 -33.314318) (xy 407.255926 -33.277831) (xy 407.307832 -33.247864)
			(xy 407.363205 -33.224928) (xy 407.421098 -33.209415) (xy 407.48052 -33.201592) (xy 407.540456 -33.201592)
			(xy 407.599878 -33.209415) (xy 407.657771 -33.224928) (xy 407.713144 -33.247864) (xy 407.76505 -33.277831)
			(xy 407.8126 -33.314318) (xy 407.85498 -33.356698) (xy 407.891467 -33.404248) (xy 407.921434 -33.456154)
			(xy 407.94437 -33.511527) (xy 407.959883 -33.56942) (xy 407.967706 -33.628842) (xy 407.968196 -33.65881)
			(xy 407.968196 -34.520886) (xy 421.789352 -34.520886) (xy 421.789352 -33.657286) (xy 421.789842 -33.627302)
			(xy 421.79767 -33.567846) (xy 421.813191 -33.509921) (xy 421.83614 -33.454517) (xy 421.866124 -33.402583)
			(xy 421.90263 -33.355007) (xy 421.945035 -33.312602) (xy 421.992611 -33.276096) (xy 422.044545 -33.246112)
			(xy 422.099949 -33.223163) (xy 422.157874 -33.207642) (xy 422.21733 -33.199814) (xy 422.277298 -33.199814)
			(xy 422.336754 -33.207642) (xy 422.394679 -33.223163) (xy 422.450083 -33.246112) (xy 422.502017 -33.276096)
			(xy 422.549593 -33.312602) (xy 422.591998 -33.355007) (xy 422.628504 -33.402583) (xy 422.658488 -33.454517)
			(xy 422.681437 -33.509921) (xy 422.696958 -33.567846) (xy 422.704786 -33.627302) (xy 422.705276 -33.657286)
			(xy 422.705276 -34.520886) (xy 422.705251 -34.52241) (xy 433.052728 -34.52241) (xy 433.052728 -33.65881)
			(xy 433.053218 -33.628842) (xy 433.061041 -33.56942) (xy 433.076554 -33.511527) (xy 433.09949 -33.456154)
			(xy 433.129457 -33.404248) (xy 433.165944 -33.356698) (xy 433.208324 -33.314318) (xy 433.255874 -33.277831)
			(xy 433.30778 -33.247864) (xy 433.363153 -33.224928) (xy 433.421046 -33.209415) (xy 433.480468 -33.201592)
			(xy 433.540404 -33.201592) (xy 433.599826 -33.209415) (xy 433.657719 -33.224928) (xy 433.713092 -33.247864)
			(xy 433.764998 -33.277831) (xy 433.812548 -33.314318) (xy 433.854928 -33.356698) (xy 433.891415 -33.404248)
			(xy 433.921382 -33.456154) (xy 433.944318 -33.511527) (xy 433.959831 -33.56942) (xy 433.967654 -33.628842)
			(xy 433.968144 -33.65881) (xy 433.968144 -34.520886) (xy 447.7893 -34.520886) (xy 447.7893 -33.657286)
			(xy 447.78979 -33.627302) (xy 447.797618 -33.567846) (xy 447.813139 -33.509921) (xy 447.836088 -33.454517)
			(xy 447.866072 -33.402583) (xy 447.902578 -33.355007) (xy 447.944983 -33.312602) (xy 447.992559 -33.276096)
			(xy 448.044493 -33.246112) (xy 448.099897 -33.223163) (xy 448.157822 -33.207642) (xy 448.217278 -33.199814)
			(xy 448.277246 -33.199814) (xy 448.336702 -33.207642) (xy 448.394627 -33.223163) (xy 448.450031 -33.246112)
			(xy 448.501965 -33.276096) (xy 448.549541 -33.312602) (xy 448.591946 -33.355007) (xy 448.628452 -33.402583)
			(xy 448.658436 -33.454517) (xy 448.681385 -33.509921) (xy 448.696906 -33.567846) (xy 448.704734 -33.627302)
			(xy 448.705224 -33.657286) (xy 448.705224 -34.520886) (xy 448.704734 -34.55087) (xy 448.696906 -34.610326)
			(xy 448.681385 -34.668251) (xy 448.658436 -34.723655) (xy 448.628452 -34.775589) (xy 448.591946 -34.823165)
			(xy 448.549541 -34.86557) (xy 448.501965 -34.902076) (xy 448.450031 -34.93206) (xy 448.394627 -34.955009)
			(xy 448.336702 -34.97053) (xy 448.277246 -34.978358) (xy 448.217278 -34.978358) (xy 448.157822 -34.97053)
			(xy 448.099897 -34.955009) (xy 448.044493 -34.93206) (xy 447.992559 -34.902076) (xy 447.944983 -34.86557)
			(xy 447.902578 -34.823165) (xy 447.866072 -34.775589) (xy 447.836088 -34.723655) (xy 447.813139 -34.668251)
			(xy 447.797618 -34.610326) (xy 447.78979 -34.55087) (xy 447.7893 -34.520886) (xy 433.968144 -34.520886)
			(xy 433.968144 -34.52241) (xy 433.967654 -34.552378) (xy 433.959831 -34.6118) (xy 433.944318 -34.669693)
			(xy 433.921382 -34.725066) (xy 433.891415 -34.776972) (xy 433.854928 -34.824522) (xy 433.812548 -34.866902)
			(xy 433.764998 -34.903389) (xy 433.713092 -34.933356) (xy 433.657719 -34.956292) (xy 433.599826 -34.971805)
			(xy 433.540404 -34.979628) (xy 433.480468 -34.979628) (xy 433.421046 -34.971805) (xy 433.363153 -34.956292)
			(xy 433.30778 -34.933356) (xy 433.255874 -34.903389) (xy 433.208324 -34.866902) (xy 433.165944 -34.824522)
			(xy 433.129457 -34.776972) (xy 433.09949 -34.725066) (xy 433.076554 -34.669693) (xy 433.061041 -34.6118)
			(xy 433.053218 -34.552378) (xy 433.052728 -34.52241) (xy 422.705251 -34.52241) (xy 422.704786 -34.55087)
			(xy 422.696958 -34.610326) (xy 422.681437 -34.668251) (xy 422.658488 -34.723655) (xy 422.628504 -34.775589)
			(xy 422.591998 -34.823165) (xy 422.549593 -34.86557) (xy 422.502017 -34.902076) (xy 422.450083 -34.93206)
			(xy 422.394679 -34.955009) (xy 422.336754 -34.97053) (xy 422.277298 -34.978358) (xy 422.21733 -34.978358)
			(xy 422.157874 -34.97053) (xy 422.099949 -34.955009) (xy 422.044545 -34.93206) (xy 421.992611 -34.902076)
			(xy 421.945035 -34.86557) (xy 421.90263 -34.823165) (xy 421.866124 -34.775589) (xy 421.83614 -34.723655)
			(xy 421.813191 -34.668251) (xy 421.79767 -34.610326) (xy 421.789842 -34.55087) (xy 421.789352 -34.520886)
			(xy 407.968196 -34.520886) (xy 407.968196 -34.52241) (xy 407.967706 -34.552378) (xy 407.959883 -34.6118)
			(xy 407.94437 -34.669693) (xy 407.921434 -34.725066) (xy 407.891467 -34.776972) (xy 407.85498 -34.824522)
			(xy 407.8126 -34.866902) (xy 407.76505 -34.903389) (xy 407.713144 -34.933356) (xy 407.657771 -34.956292)
			(xy 407.599878 -34.971805) (xy 407.540456 -34.979628) (xy 407.48052 -34.979628) (xy 407.421098 -34.971805)
			(xy 407.363205 -34.956292) (xy 407.307832 -34.933356) (xy 407.255926 -34.903389) (xy 407.208376 -34.866902)
			(xy 407.165996 -34.824522) (xy 407.129509 -34.776972) (xy 407.099542 -34.725066) (xy 407.076606 -34.669693)
			(xy 407.061093 -34.6118) (xy 407.05327 -34.552378) (xy 407.05278 -34.52241) (xy 396.705303 -34.52241)
			(xy 396.704838 -34.55087) (xy 396.69701 -34.610326) (xy 396.681489 -34.668251) (xy 396.65854 -34.723655)
			(xy 396.628556 -34.775589) (xy 396.59205 -34.823165) (xy 396.549645 -34.86557) (xy 396.502069 -34.902076)
			(xy 396.450135 -34.93206) (xy 396.394731 -34.955009) (xy 396.336806 -34.97053) (xy 396.27735 -34.978358)
			(xy 396.217382 -34.978358) (xy 396.157926 -34.97053) (xy 396.100001 -34.955009) (xy 396.044597 -34.93206)
			(xy 395.992663 -34.902076) (xy 395.945087 -34.86557) (xy 395.902682 -34.823165) (xy 395.866176 -34.775589)
			(xy 395.836192 -34.723655) (xy 395.813243 -34.668251) (xy 395.797722 -34.610326) (xy 395.789894 -34.55087)
			(xy 395.789404 -34.520886) (xy 381.968248 -34.520886) (xy 381.968248 -34.52241) (xy 381.967758 -34.552378)
			(xy 381.959935 -34.6118) (xy 381.944422 -34.669693) (xy 381.921486 -34.725066) (xy 381.891519 -34.776972)
			(xy 381.855032 -34.824522) (xy 381.812652 -34.866902) (xy 381.765102 -34.903389) (xy 381.713196 -34.933356)
			(xy 381.657823 -34.956292) (xy 381.59993 -34.971805) (xy 381.540508 -34.979628) (xy 381.480572 -34.979628)
			(xy 381.42115 -34.971805) (xy 381.363257 -34.956292) (xy 381.307884 -34.933356) (xy 381.255978 -34.903389)
			(xy 381.208428 -34.866902) (xy 381.166048 -34.824522) (xy 381.129561 -34.776972) (xy 381.099594 -34.725066)
			(xy 381.076658 -34.669693) (xy 381.061145 -34.6118) (xy 381.053322 -34.552378) (xy 381.052832 -34.52241)
			(xy 370.705355 -34.52241) (xy 370.70489 -34.55087) (xy 370.697062 -34.610326) (xy 370.681541 -34.668251)
			(xy 370.658592 -34.723655) (xy 370.628608 -34.775589) (xy 370.592102 -34.823165) (xy 370.549697 -34.86557)
			(xy 370.502121 -34.902076) (xy 370.450187 -34.93206) (xy 370.394783 -34.955009) (xy 370.336858 -34.97053)
			(xy 370.277402 -34.978358) (xy 370.217434 -34.978358) (xy 370.157978 -34.97053) (xy 370.100053 -34.955009)
			(xy 370.044649 -34.93206) (xy 369.992715 -34.902076) (xy 369.945139 -34.86557) (xy 369.902734 -34.823165)
			(xy 369.866228 -34.775589) (xy 369.836244 -34.723655) (xy 369.813295 -34.668251) (xy 369.797774 -34.610326)
			(xy 369.789946 -34.55087) (xy 369.789456 -34.520886) (xy 355.9683 -34.520886) (xy 355.9683 -34.52241)
			(xy 355.96781 -34.552378) (xy 355.959987 -34.6118) (xy 355.944474 -34.669693) (xy 355.921538 -34.725066)
			(xy 355.891571 -34.776972) (xy 355.855084 -34.824522) (xy 355.812704 -34.866902) (xy 355.765154 -34.903389)
			(xy 355.713248 -34.933356) (xy 355.657875 -34.956292) (xy 355.599982 -34.971805) (xy 355.54056 -34.979628)
			(xy 355.480624 -34.979628) (xy 355.421202 -34.971805) (xy 355.363309 -34.956292) (xy 355.307936 -34.933356)
			(xy 355.25603 -34.903389) (xy 355.20848 -34.866902) (xy 355.1661 -34.824522) (xy 355.129613 -34.776972)
			(xy 355.099646 -34.725066) (xy 355.07671 -34.669693) (xy 355.061197 -34.6118) (xy 355.053374 -34.552378)
			(xy 355.052884 -34.52241) (xy 332.604847 -34.52241) (xy 332.604382 -34.550854) (xy 332.596559 -34.610276)
			(xy 332.581046 -34.668169) (xy 332.55811 -34.723542) (xy 332.528143 -34.775448) (xy 332.491656 -34.822998)
			(xy 332.449276 -34.865378) (xy 332.401726 -34.901865) (xy 332.34982 -34.931832) (xy 332.294447 -34.954768)
			(xy 332.236554 -34.970281) (xy 332.177132 -34.978104) (xy 332.117196 -34.978104) (xy 332.057774 -34.970281)
			(xy 331.999881 -34.954768) (xy 331.944508 -34.931832) (xy 331.892602 -34.901865) (xy 331.845052 -34.865378)
			(xy 331.802672 -34.822998) (xy 331.766185 -34.775448) (xy 331.736218 -34.723542) (xy 331.713282 -34.668169)
			(xy 331.697769 -34.610276) (xy 331.689946 -34.550854) (xy 331.689456 -34.520886) (xy 317.8683 -34.520886)
			(xy 317.8683 -34.52241) (xy 317.86781 -34.552394) (xy 317.859982 -34.61185) (xy 317.844461 -34.669775)
			(xy 317.821512 -34.725179) (xy 317.791528 -34.777113) (xy 317.755022 -34.824689) (xy 317.712617 -34.867094)
			(xy 317.665041 -34.9036) (xy 317.613107 -34.933584) (xy 317.557703 -34.956533) (xy 317.499778 -34.972054)
			(xy 317.440322 -34.979882) (xy 317.380354 -34.979882) (xy 317.320898 -34.972054) (xy 317.262973 -34.956533)
			(xy 317.207569 -34.933584) (xy 317.155635 -34.9036) (xy 317.108059 -34.867094) (xy 317.065654 -34.824689)
			(xy 317.029148 -34.777113) (xy 316.999164 -34.725179) (xy 316.976215 -34.669775) (xy 316.960694 -34.61185)
			(xy 316.952866 -34.552394) (xy 316.952376 -34.52241) (xy 306.604899 -34.52241) (xy 306.604434 -34.550854)
			(xy 306.596611 -34.610276) (xy 306.581098 -34.668169) (xy 306.558162 -34.723542) (xy 306.528195 -34.775448)
			(xy 306.491708 -34.822998) (xy 306.449328 -34.865378) (xy 306.401778 -34.901865) (xy 306.349872 -34.931832)
			(xy 306.294499 -34.954768) (xy 306.236606 -34.970281) (xy 306.177184 -34.978104) (xy 306.117248 -34.978104)
			(xy 306.057826 -34.970281) (xy 305.999933 -34.954768) (xy 305.94456 -34.931832) (xy 305.892654 -34.901865)
			(xy 305.845104 -34.865378) (xy 305.802724 -34.822998) (xy 305.766237 -34.775448) (xy 305.73627 -34.723542)
			(xy 305.713334 -34.668169) (xy 305.697821 -34.610276) (xy 305.689998 -34.550854) (xy 305.689508 -34.520886)
			(xy 291.868352 -34.520886) (xy 291.868352 -34.52241) (xy 291.867862 -34.552394) (xy 291.860034 -34.61185)
			(xy 291.844513 -34.669775) (xy 291.821564 -34.725179) (xy 291.79158 -34.777113) (xy 291.755074 -34.824689)
			(xy 291.712669 -34.867094) (xy 291.665093 -34.9036) (xy 291.613159 -34.933584) (xy 291.557755 -34.956533)
			(xy 291.49983 -34.972054) (xy 291.440374 -34.979882) (xy 291.380406 -34.979882) (xy 291.32095 -34.972054)
			(xy 291.263025 -34.956533) (xy 291.207621 -34.933584) (xy 291.155687 -34.9036) (xy 291.108111 -34.867094)
			(xy 291.065706 -34.824689) (xy 291.0292 -34.777113) (xy 290.999216 -34.725179) (xy 290.976267 -34.669775)
			(xy 290.960746 -34.61185) (xy 290.952918 -34.552394) (xy 290.952428 -34.52241) (xy 280.604951 -34.52241)
			(xy 280.604486 -34.550854) (xy 280.596663 -34.610276) (xy 280.58115 -34.668169) (xy 280.558214 -34.723542)
			(xy 280.528247 -34.775448) (xy 280.49176 -34.822998) (xy 280.44938 -34.865378) (xy 280.40183 -34.901865)
			(xy 280.349924 -34.931832) (xy 280.294551 -34.954768) (xy 280.236658 -34.970281) (xy 280.177236 -34.978104)
			(xy 280.1173 -34.978104) (xy 280.057878 -34.970281) (xy 279.999985 -34.954768) (xy 279.944612 -34.931832)
			(xy 279.892706 -34.901865) (xy 279.845156 -34.865378) (xy 279.802776 -34.822998) (xy 279.766289 -34.775448)
			(xy 279.736322 -34.723542) (xy 279.713386 -34.668169) (xy 279.697873 -34.610276) (xy 279.69005 -34.550854)
			(xy 279.68956 -34.520886) (xy 265.868404 -34.520886) (xy 265.868404 -34.52241) (xy 265.867914 -34.552394)
			(xy 265.860086 -34.61185) (xy 265.844565 -34.669775) (xy 265.821616 -34.725179) (xy 265.791632 -34.777113)
			(xy 265.755126 -34.824689) (xy 265.712721 -34.867094) (xy 265.665145 -34.9036) (xy 265.613211 -34.933584)
			(xy 265.557807 -34.956533) (xy 265.499882 -34.972054) (xy 265.440426 -34.979882) (xy 265.380458 -34.979882)
			(xy 265.321002 -34.972054) (xy 265.263077 -34.956533) (xy 265.207673 -34.933584) (xy 265.155739 -34.9036)
			(xy 265.108163 -34.867094) (xy 265.065758 -34.824689) (xy 265.029252 -34.777113) (xy 264.999268 -34.725179)
			(xy 264.976319 -34.669775) (xy 264.960798 -34.61185) (xy 264.95297 -34.552394) (xy 264.95248 -34.52241)
			(xy 254.605003 -34.52241) (xy 254.604538 -34.550854) (xy 254.596715 -34.610276) (xy 254.581202 -34.668169)
			(xy 254.558266 -34.723542) (xy 254.528299 -34.775448) (xy 254.491812 -34.822998) (xy 254.449432 -34.865378)
			(xy 254.401882 -34.901865) (xy 254.349976 -34.931832) (xy 254.294603 -34.954768) (xy 254.23671 -34.970281)
			(xy 254.177288 -34.978104) (xy 254.117352 -34.978104) (xy 254.05793 -34.970281) (xy 254.000037 -34.954768)
			(xy 253.944664 -34.931832) (xy 253.892758 -34.901865) (xy 253.845208 -34.865378) (xy 253.802828 -34.822998)
			(xy 253.766341 -34.775448) (xy 253.736374 -34.723542) (xy 253.713438 -34.668169) (xy 253.697925 -34.610276)
			(xy 253.690102 -34.550854) (xy 253.689612 -34.520886) (xy 239.868456 -34.520886) (xy 239.868456 -34.52241)
			(xy 239.867966 -34.552394) (xy 239.860138 -34.61185) (xy 239.844617 -34.669775) (xy 239.821668 -34.725179)
			(xy 239.791684 -34.777113) (xy 239.755178 -34.824689) (xy 239.712773 -34.867094) (xy 239.665197 -34.9036)
			(xy 239.613263 -34.933584) (xy 239.557859 -34.956533) (xy 239.499934 -34.972054) (xy 239.440478 -34.979882)
			(xy 239.38051 -34.979882) (xy 239.321054 -34.972054) (xy 239.263129 -34.956533) (xy 239.207725 -34.933584)
			(xy 239.155791 -34.9036) (xy 239.108215 -34.867094) (xy 239.06581 -34.824689) (xy 239.029304 -34.777113)
			(xy 238.99932 -34.725179) (xy 238.976371 -34.669775) (xy 238.96085 -34.61185) (xy 238.953022 -34.552394)
			(xy 238.952532 -34.52241) (xy 216.505003 -34.52241) (xy 216.504538 -34.550854) (xy 216.496715 -34.610276)
			(xy 216.481202 -34.668169) (xy 216.458266 -34.723542) (xy 216.428299 -34.775448) (xy 216.391812 -34.822998)
			(xy 216.349432 -34.865378) (xy 216.301882 -34.901865) (xy 216.249976 -34.931832) (xy 216.194603 -34.954768)
			(xy 216.13671 -34.970281) (xy 216.077288 -34.978104) (xy 216.017352 -34.978104) (xy 215.95793 -34.970281)
			(xy 215.900037 -34.954768) (xy 215.844664 -34.931832) (xy 215.792758 -34.901865) (xy 215.745208 -34.865378)
			(xy 215.702828 -34.822998) (xy 215.666341 -34.775448) (xy 215.636374 -34.723542) (xy 215.613438 -34.668169)
			(xy 215.597925 -34.610276) (xy 215.590102 -34.550854) (xy 215.589612 -34.520886) (xy 201.768456 -34.520886)
			(xy 201.768456 -34.52241) (xy 201.767966 -34.552394) (xy 201.760138 -34.61185) (xy 201.744617 -34.669775)
			(xy 201.721668 -34.725179) (xy 201.691684 -34.777113) (xy 201.655178 -34.824689) (xy 201.612773 -34.867094)
			(xy 201.565197 -34.9036) (xy 201.513263 -34.933584) (xy 201.457859 -34.956533) (xy 201.399934 -34.972054)
			(xy 201.340478 -34.979882) (xy 201.28051 -34.979882) (xy 201.221054 -34.972054) (xy 201.163129 -34.956533)
			(xy 201.107725 -34.933584) (xy 201.055791 -34.9036) (xy 201.008215 -34.867094) (xy 200.96581 -34.824689)
			(xy 200.929304 -34.777113) (xy 200.89932 -34.725179) (xy 200.876371 -34.669775) (xy 200.86085 -34.61185)
			(xy 200.853022 -34.552394) (xy 200.852532 -34.52241) (xy 190.505055 -34.52241) (xy 190.50459 -34.550854)
			(xy 190.496767 -34.610276) (xy 190.481254 -34.668169) (xy 190.458318 -34.723542) (xy 190.428351 -34.775448)
			(xy 190.391864 -34.822998) (xy 190.349484 -34.865378) (xy 190.301934 -34.901865) (xy 190.250028 -34.931832)
			(xy 190.194655 -34.954768) (xy 190.136762 -34.970281) (xy 190.07734 -34.978104) (xy 190.017404 -34.978104)
			(xy 189.957982 -34.970281) (xy 189.900089 -34.954768) (xy 189.844716 -34.931832) (xy 189.79281 -34.901865)
			(xy 189.74526 -34.865378) (xy 189.70288 -34.822998) (xy 189.666393 -34.775448) (xy 189.636426 -34.723542)
			(xy 189.61349 -34.668169) (xy 189.597977 -34.610276) (xy 189.590154 -34.550854) (xy 189.589664 -34.520886)
			(xy 175.768508 -34.520886) (xy 175.768508 -34.52241) (xy 175.768018 -34.552394) (xy 175.76019 -34.61185)
			(xy 175.744669 -34.669775) (xy 175.72172 -34.725179) (xy 175.691736 -34.777113) (xy 175.65523 -34.824689)
			(xy 175.612825 -34.867094) (xy 175.565249 -34.9036) (xy 175.513315 -34.933584) (xy 175.457911 -34.956533)
			(xy 175.399986 -34.972054) (xy 175.34053 -34.979882) (xy 175.280562 -34.979882) (xy 175.221106 -34.972054)
			(xy 175.163181 -34.956533) (xy 175.107777 -34.933584) (xy 175.055843 -34.9036) (xy 175.008267 -34.867094)
			(xy 174.965862 -34.824689) (xy 174.929356 -34.777113) (xy 174.899372 -34.725179) (xy 174.876423 -34.669775)
			(xy 174.860902 -34.61185) (xy 174.853074 -34.552394) (xy 174.852584 -34.52241) (xy 164.505107 -34.52241)
			(xy 164.504642 -34.550854) (xy 164.496819 -34.610276) (xy 164.481306 -34.668169) (xy 164.45837 -34.723542)
			(xy 164.428403 -34.775448) (xy 164.391916 -34.822998) (xy 164.349536 -34.865378) (xy 164.301986 -34.901865)
			(xy 164.25008 -34.931832) (xy 164.194707 -34.954768) (xy 164.136814 -34.970281) (xy 164.077392 -34.978104)
			(xy 164.017456 -34.978104) (xy 163.958034 -34.970281) (xy 163.900141 -34.954768) (xy 163.844768 -34.931832)
			(xy 163.792862 -34.901865) (xy 163.745312 -34.865378) (xy 163.702932 -34.822998) (xy 163.666445 -34.775448)
			(xy 163.636478 -34.723542) (xy 163.613542 -34.668169) (xy 163.598029 -34.610276) (xy 163.590206 -34.550854)
			(xy 163.589716 -34.520886) (xy 149.76856 -34.520886) (xy 149.76856 -34.52241) (xy 149.76807 -34.552394)
			(xy 149.760242 -34.61185) (xy 149.744721 -34.669775) (xy 149.721772 -34.725179) (xy 149.691788 -34.777113)
			(xy 149.655282 -34.824689) (xy 149.612877 -34.867094) (xy 149.565301 -34.9036) (xy 149.513367 -34.933584)
			(xy 149.457963 -34.956533) (xy 149.400038 -34.972054) (xy 149.340582 -34.979882) (xy 149.280614 -34.979882)
			(xy 149.221158 -34.972054) (xy 149.163233 -34.956533) (xy 149.107829 -34.933584) (xy 149.055895 -34.9036)
			(xy 149.008319 -34.867094) (xy 148.965914 -34.824689) (xy 148.929408 -34.777113) (xy 148.899424 -34.725179)
			(xy 148.876475 -34.669775) (xy 148.860954 -34.61185) (xy 148.853126 -34.552394) (xy 148.852636 -34.52241)
			(xy 138.505159 -34.52241) (xy 138.504694 -34.550854) (xy 138.496871 -34.610276) (xy 138.481358 -34.668169)
			(xy 138.458422 -34.723542) (xy 138.428455 -34.775448) (xy 138.391968 -34.822998) (xy 138.349588 -34.865378)
			(xy 138.302038 -34.901865) (xy 138.250132 -34.931832) (xy 138.194759 -34.954768) (xy 138.136866 -34.970281)
			(xy 138.077444 -34.978104) (xy 138.017508 -34.978104) (xy 137.958086 -34.970281) (xy 137.900193 -34.954768)
			(xy 137.84482 -34.931832) (xy 137.792914 -34.901865) (xy 137.745364 -34.865378) (xy 137.702984 -34.822998)
			(xy 137.666497 -34.775448) (xy 137.63653 -34.723542) (xy 137.613594 -34.668169) (xy 137.598081 -34.610276)
			(xy 137.590258 -34.550854) (xy 137.589768 -34.520886) (xy 123.768612 -34.520886) (xy 123.768612 -34.52241)
			(xy 123.768122 -34.552394) (xy 123.760294 -34.61185) (xy 123.744773 -34.669775) (xy 123.721824 -34.725179)
			(xy 123.69184 -34.777113) (xy 123.655334 -34.824689) (xy 123.612929 -34.867094) (xy 123.565353 -34.9036)
			(xy 123.513419 -34.933584) (xy 123.458015 -34.956533) (xy 123.40009 -34.972054) (xy 123.340634 -34.979882)
			(xy 123.280666 -34.979882) (xy 123.22121 -34.972054) (xy 123.163285 -34.956533) (xy 123.107881 -34.933584)
			(xy 123.055947 -34.9036) (xy 123.008371 -34.867094) (xy 122.965966 -34.824689) (xy 122.92946 -34.777113)
			(xy 122.899476 -34.725179) (xy 122.876527 -34.669775) (xy 122.861006 -34.61185) (xy 122.853178 -34.552394)
			(xy 122.852688 -34.52241) (xy 100.405159 -34.52241) (xy 100.404694 -34.55087) (xy 100.396866 -34.610326)
			(xy 100.381345 -34.668251) (xy 100.358396 -34.723655) (xy 100.328412 -34.775589) (xy 100.291906 -34.823165)
			(xy 100.249501 -34.86557) (xy 100.201925 -34.902076) (xy 100.149991 -34.93206) (xy 100.094587 -34.955009)
			(xy 100.036662 -34.97053) (xy 99.977206 -34.978358) (xy 99.917238 -34.978358) (xy 99.857782 -34.97053)
			(xy 99.799857 -34.955009) (xy 99.744453 -34.93206) (xy 99.692519 -34.902076) (xy 99.644943 -34.86557)
			(xy 99.602538 -34.823165) (xy 99.566032 -34.775589) (xy 99.536048 -34.723655) (xy 99.513099 -34.668251)
			(xy 99.497578 -34.610326) (xy 99.48975 -34.55087) (xy 99.48926 -34.520886) (xy 85.668104 -34.520886)
			(xy 85.668104 -34.52241) (xy 85.667614 -34.552378) (xy 85.659791 -34.6118) (xy 85.644278 -34.669693)
			(xy 85.621342 -34.725066) (xy 85.591375 -34.776972) (xy 85.554888 -34.824522) (xy 85.512508 -34.866902)
			(xy 85.464958 -34.903389) (xy 85.413052 -34.933356) (xy 85.357679 -34.956292) (xy 85.299786 -34.971805)
			(xy 85.240364 -34.979628) (xy 85.180428 -34.979628) (xy 85.121006 -34.971805) (xy 85.063113 -34.956292)
			(xy 85.00774 -34.933356) (xy 84.955834 -34.903389) (xy 84.908284 -34.866902) (xy 84.865904 -34.824522)
			(xy 84.829417 -34.776972) (xy 84.79945 -34.725066) (xy 84.776514 -34.669693) (xy 84.761001 -34.6118)
			(xy 84.753178 -34.552378) (xy 84.752688 -34.52241) (xy 74.405211 -34.52241) (xy 74.404746 -34.55087)
			(xy 74.396918 -34.610326) (xy 74.381397 -34.668251) (xy 74.358448 -34.723655) (xy 74.328464 -34.775589)
			(xy 74.291958 -34.823165) (xy 74.249553 -34.86557) (xy 74.201977 -34.902076) (xy 74.150043 -34.93206)
			(xy 74.094639 -34.955009) (xy 74.036714 -34.97053) (xy 73.977258 -34.978358) (xy 73.91729 -34.978358)
			(xy 73.857834 -34.97053) (xy 73.799909 -34.955009) (xy 73.744505 -34.93206) (xy 73.692571 -34.902076)
			(xy 73.644995 -34.86557) (xy 73.60259 -34.823165) (xy 73.566084 -34.775589) (xy 73.5361 -34.723655)
			(xy 73.513151 -34.668251) (xy 73.49763 -34.610326) (xy 73.489802 -34.55087) (xy 73.489312 -34.520886)
			(xy 59.668156 -34.520886) (xy 59.668156 -34.52241) (xy 59.667666 -34.552378) (xy 59.659843 -34.6118)
			(xy 59.64433 -34.669693) (xy 59.621394 -34.725066) (xy 59.591427 -34.776972) (xy 59.55494 -34.824522)
			(xy 59.51256 -34.866902) (xy 59.46501 -34.903389) (xy 59.413104 -34.933356) (xy 59.357731 -34.956292)
			(xy 59.299838 -34.971805) (xy 59.240416 -34.979628) (xy 59.18048 -34.979628) (xy 59.121058 -34.971805)
			(xy 59.063165 -34.956292) (xy 59.007792 -34.933356) (xy 58.955886 -34.903389) (xy 58.908336 -34.866902)
			(xy 58.865956 -34.824522) (xy 58.829469 -34.776972) (xy 58.799502 -34.725066) (xy 58.776566 -34.669693)
			(xy 58.761053 -34.6118) (xy 58.75323 -34.552378) (xy 58.75274 -34.52241) (xy 48.405263 -34.52241)
			(xy 48.404798 -34.55087) (xy 48.39697 -34.610326) (xy 48.381449 -34.668251) (xy 48.3585 -34.723655)
			(xy 48.328516 -34.775589) (xy 48.29201 -34.823165) (xy 48.249605 -34.86557) (xy 48.202029 -34.902076)
			(xy 48.150095 -34.93206) (xy 48.094691 -34.955009) (xy 48.036766 -34.97053) (xy 47.97731 -34.978358)
			(xy 47.917342 -34.978358) (xy 47.857886 -34.97053) (xy 47.799961 -34.955009) (xy 47.744557 -34.93206)
			(xy 47.692623 -34.902076) (xy 47.645047 -34.86557) (xy 47.602642 -34.823165) (xy 47.566136 -34.775589)
			(xy 47.536152 -34.723655) (xy 47.513203 -34.668251) (xy 47.497682 -34.610326) (xy 47.489854 -34.55087)
			(xy 47.489364 -34.520886) (xy 33.668208 -34.520886) (xy 33.668208 -34.52241) (xy 33.667718 -34.552378)
			(xy 33.659895 -34.6118) (xy 33.644382 -34.669693) (xy 33.621446 -34.725066) (xy 33.591479 -34.776972)
			(xy 33.554992 -34.824522) (xy 33.512612 -34.866902) (xy 33.465062 -34.903389) (xy 33.413156 -34.933356)
			(xy 33.357783 -34.956292) (xy 33.29989 -34.971805) (xy 33.240468 -34.979628) (xy 33.180532 -34.979628)
			(xy 33.12111 -34.971805) (xy 33.063217 -34.956292) (xy 33.007844 -34.933356) (xy 32.955938 -34.903389)
			(xy 32.908388 -34.866902) (xy 32.866008 -34.824522) (xy 32.829521 -34.776972) (xy 32.799554 -34.725066)
			(xy 32.776618 -34.669693) (xy 32.761105 -34.6118) (xy 32.753282 -34.552378) (xy 32.752792 -34.52241)
			(xy 22.405315 -34.52241) (xy 22.40485 -34.55087) (xy 22.397022 -34.610326) (xy 22.381501 -34.668251)
			(xy 22.358552 -34.723655) (xy 22.328568 -34.775589) (xy 22.292062 -34.823165) (xy 22.249657 -34.86557)
			(xy 22.202081 -34.902076) (xy 22.150147 -34.93206) (xy 22.094743 -34.955009) (xy 22.036818 -34.97053)
			(xy 21.977362 -34.978358) (xy 21.917394 -34.978358) (xy 21.857938 -34.97053) (xy 21.800013 -34.955009)
			(xy 21.744609 -34.93206) (xy 21.692675 -34.902076) (xy 21.645099 -34.86557) (xy 21.602694 -34.823165)
			(xy 21.566188 -34.775589) (xy 21.536204 -34.723655) (xy 21.513255 -34.668251) (xy 21.497734 -34.610326)
			(xy 21.489906 -34.55087) (xy 21.489416 -34.520886) (xy 7.66826 -34.520886) (xy 7.66826 -34.52241)
			(xy 7.66777 -34.552378) (xy 7.659947 -34.6118) (xy 7.644434 -34.669693) (xy 7.621498 -34.725066)
			(xy 7.591531 -34.776972) (xy 7.555044 -34.824522) (xy 7.512664 -34.866902) (xy 7.465114 -34.903389)
			(xy 7.413208 -34.933356) (xy 7.357835 -34.956292) (xy 7.299942 -34.971805) (xy 7.24052 -34.979628)
			(xy 7.180584 -34.979628) (xy 7.121162 -34.971805) (xy 7.063269 -34.956292) (xy 7.007896 -34.933356)
			(xy 6.95599 -34.903389) (xy 6.90844 -34.866902) (xy 6.86606 -34.824522) (xy 6.829573 -34.776972)
			(xy 6.799606 -34.725066) (xy 6.77667 -34.669693) (xy 6.761157 -34.6118) (xy 6.753334 -34.552378)
			(xy 6.752844 -34.52241) (xy 0.508 -34.52241) (xy 0.508 -36.60013) (xy 11.998205 -36.60013) (xy 12.00221 -36.512222)
			(xy 12.014193 -36.425042) (xy 12.034053 -36.339313) (xy 12.061628 -36.255745) (xy 12.096687 -36.175031)
			(xy 12.13894 -36.097839) (xy 12.188038 -36.02481) (xy 12.243574 -35.956548) (xy 12.305086 -35.893618)
			(xy 12.372067 -35.836544) (xy 12.44396 -35.785796) (xy 12.520169 -35.741796) (xy 12.600064 -35.704909)
			(xy 12.682983 -35.67544) (xy 12.768238 -35.653633) (xy 12.855122 -35.639669) (xy 12.942916 -35.633663)
			(xy 13.030893 -35.635667) (xy 13.118323 -35.645662) (xy 13.204482 -35.663566) (xy 13.288656 -35.68923)
			(xy 13.370147 -35.722443) (xy 13.448281 -35.762929) (xy 13.522409 -35.810351) (xy 13.591917 -35.864318)
			(xy 13.656231 -35.924383) (xy 13.714815 -35.990047) (xy 13.767186 -36.060766) (xy 13.812909 -36.135954)
			(xy 13.851606 -36.214989) (xy 13.882955 -36.297215) (xy 13.906697 -36.381951) (xy 13.922635 -36.468495)
			(xy 13.930637 -36.55613) (xy 13.931138 -36.60013) (xy 37.998153 -36.60013) (xy 38.002158 -36.512222)
			(xy 38.014141 -36.425042) (xy 38.034001 -36.339313) (xy 38.061576 -36.255745) (xy 38.096635 -36.175031)
			(xy 38.138888 -36.097839) (xy 38.187986 -36.02481) (xy 38.243522 -35.956548) (xy 38.305034 -35.893618)
			(xy 38.372015 -35.836544) (xy 38.443908 -35.785796) (xy 38.520117 -35.741796) (xy 38.600012 -35.704909)
			(xy 38.682931 -35.67544) (xy 38.768186 -35.653633) (xy 38.85507 -35.639669) (xy 38.942864 -35.633663)
			(xy 39.030841 -35.635667) (xy 39.118271 -35.645662) (xy 39.20443 -35.663566) (xy 39.288604 -35.68923)
			(xy 39.370095 -35.722443) (xy 39.448229 -35.762929) (xy 39.522357 -35.810351) (xy 39.591865 -35.864318)
			(xy 39.656179 -35.924383) (xy 39.714763 -35.990047) (xy 39.767134 -36.060766) (xy 39.812857 -36.135954)
			(xy 39.851554 -36.214989) (xy 39.882903 -36.297215) (xy 39.906645 -36.381951) (xy 39.922583 -36.468495)
			(xy 39.930585 -36.55613) (xy 39.931086 -36.60013) (xy 63.998101 -36.60013) (xy 64.002106 -36.512222)
			(xy 64.014089 -36.425042) (xy 64.033949 -36.339313) (xy 64.061524 -36.255745) (xy 64.096583 -36.175031)
			(xy 64.138836 -36.097839) (xy 64.187934 -36.02481) (xy 64.24347 -35.956548) (xy 64.304982 -35.893618)
			(xy 64.371963 -35.836544) (xy 64.443856 -35.785796) (xy 64.520065 -35.741796) (xy 64.59996 -35.704909)
			(xy 64.682879 -35.67544) (xy 64.768134 -35.653633) (xy 64.855018 -35.639669) (xy 64.942812 -35.633663)
			(xy 65.030789 -35.635667) (xy 65.118219 -35.645662) (xy 65.204378 -35.663566) (xy 65.288552 -35.68923)
			(xy 65.370043 -35.722443) (xy 65.448177 -35.762929) (xy 65.522305 -35.810351) (xy 65.591813 -35.864318)
			(xy 65.656127 -35.924383) (xy 65.714711 -35.990047) (xy 65.767082 -36.060766) (xy 65.812805 -36.135954)
			(xy 65.851502 -36.214989) (xy 65.882851 -36.297215) (xy 65.906593 -36.381951) (xy 65.922531 -36.468495)
			(xy 65.930533 -36.55613) (xy 65.931034 -36.60013) (xy 89.998049 -36.60013) (xy 90.002054 -36.512222)
			(xy 90.014037 -36.425042) (xy 90.033897 -36.339313) (xy 90.061472 -36.255745) (xy 90.096531 -36.175031)
			(xy 90.138784 -36.097839) (xy 90.187882 -36.02481) (xy 90.243418 -35.956548) (xy 90.30493 -35.893618)
			(xy 90.371911 -35.836544) (xy 90.443804 -35.785796) (xy 90.520013 -35.741796) (xy 90.599908 -35.704909)
			(xy 90.682827 -35.67544) (xy 90.768082 -35.653633) (xy 90.854966 -35.639669) (xy 90.94276 -35.633663)
			(xy 91.030737 -35.635667) (xy 91.118167 -35.645662) (xy 91.204326 -35.663566) (xy 91.2885 -35.68923)
			(xy 91.369991 -35.722443) (xy 91.448125 -35.762929) (xy 91.522253 -35.810351) (xy 91.591761 -35.864318)
			(xy 91.656075 -35.924383) (xy 91.714659 -35.990047) (xy 91.76703 -36.060766) (xy 91.812753 -36.135954)
			(xy 91.85145 -36.214989) (xy 91.882799 -36.297215) (xy 91.906541 -36.381951) (xy 91.922479 -36.468495)
			(xy 91.930481 -36.55613) (xy 91.930982 -36.60013) (xy 128.098303 -36.60013) (xy 128.102308 -36.512222)
			(xy 128.114291 -36.425042) (xy 128.134151 -36.339313) (xy 128.161726 -36.255745) (xy 128.196785 -36.175031)
			(xy 128.239038 -36.097839) (xy 128.288136 -36.02481) (xy 128.343672 -35.956548) (xy 128.405184 -35.893618)
			(xy 128.472165 -35.836544) (xy 128.544058 -35.785796) (xy 128.620267 -35.741796) (xy 128.700162 -35.704909)
			(xy 128.783081 -35.67544) (xy 128.868336 -35.653633) (xy 128.95522 -35.639669) (xy 129.043014 -35.633663)
			(xy 129.130991 -35.635667) (xy 129.218421 -35.645662) (xy 129.30458 -35.663566) (xy 129.388754 -35.68923)
			(xy 129.470245 -35.722443) (xy 129.548379 -35.762929) (xy 129.622507 -35.810351) (xy 129.692015 -35.864318)
			(xy 129.756329 -35.924383) (xy 129.814913 -35.990047) (xy 129.867284 -36.060766) (xy 129.913007 -36.135954)
			(xy 129.951704 -36.214989) (xy 129.983053 -36.297215) (xy 130.006795 -36.381951) (xy 130.022733 -36.468495)
			(xy 130.030735 -36.55613) (xy 130.031236 -36.60013) (xy 154.098251 -36.60013) (xy 154.102256 -36.512222)
			(xy 154.114239 -36.425042) (xy 154.134099 -36.339313) (xy 154.161674 -36.255745) (xy 154.196733 -36.175031)
			(xy 154.238986 -36.097839) (xy 154.288084 -36.02481) (xy 154.34362 -35.956548) (xy 154.405132 -35.893618)
			(xy 154.472113 -35.836544) (xy 154.544006 -35.785796) (xy 154.620215 -35.741796) (xy 154.70011 -35.704909)
			(xy 154.783029 -35.67544) (xy 154.868284 -35.653633) (xy 154.955168 -35.639669) (xy 155.042962 -35.633663)
			(xy 155.130939 -35.635667) (xy 155.218369 -35.645662) (xy 155.304528 -35.663566) (xy 155.388702 -35.68923)
			(xy 155.470193 -35.722443) (xy 155.548327 -35.762929) (xy 155.622455 -35.810351) (xy 155.691963 -35.864318)
			(xy 155.756277 -35.924383) (xy 155.814861 -35.990047) (xy 155.867232 -36.060766) (xy 155.912955 -36.135954)
			(xy 155.951652 -36.214989) (xy 155.983001 -36.297215) (xy 156.006743 -36.381951) (xy 156.022681 -36.468495)
			(xy 156.030683 -36.55613) (xy 156.031184 -36.60013) (xy 180.098199 -36.60013) (xy 180.102204 -36.512222)
			(xy 180.114187 -36.425042) (xy 180.134047 -36.339313) (xy 180.161622 -36.255745) (xy 180.196681 -36.175031)
			(xy 180.238934 -36.097839) (xy 180.288032 -36.02481) (xy 180.343568 -35.956548) (xy 180.40508 -35.893618)
			(xy 180.472061 -35.836544) (xy 180.543954 -35.785796) (xy 180.620163 -35.741796) (xy 180.700058 -35.704909)
			(xy 180.782977 -35.67544) (xy 180.868232 -35.653633) (xy 180.955116 -35.639669) (xy 181.04291 -35.633663)
			(xy 181.130887 -35.635667) (xy 181.218317 -35.645662) (xy 181.304476 -35.663566) (xy 181.38865 -35.68923)
			(xy 181.470141 -35.722443) (xy 181.548275 -35.762929) (xy 181.622403 -35.810351) (xy 181.691911 -35.864318)
			(xy 181.756225 -35.924383) (xy 181.814809 -35.990047) (xy 181.86718 -36.060766) (xy 181.912903 -36.135954)
			(xy 181.9516 -36.214989) (xy 181.982949 -36.297215) (xy 182.006691 -36.381951) (xy 182.022629 -36.468495)
			(xy 182.030631 -36.55613) (xy 182.031132 -36.60013) (xy 206.098655 -36.60013) (xy 206.102659 -36.512245)
			(xy 206.114639 -36.425088) (xy 206.134494 -36.339381) (xy 206.162061 -36.255836) (xy 206.197111 -36.175143)
			(xy 206.239353 -36.097971) (xy 206.288438 -36.024961) (xy 206.343959 -35.956717) (xy 206.405456 -35.893804)
			(xy 206.472418 -35.836744) (xy 206.544292 -35.78601) (xy 206.620482 -35.742022) (xy 206.700356 -35.705144)
			(xy 206.783253 -35.675683) (xy 206.868485 -35.653881) (xy 206.955347 -35.639921) (xy 207.043118 -35.633917)
			(xy 207.131072 -35.63592) (xy 207.218479 -35.645912) (xy 207.304615 -35.663812) (xy 207.388767 -35.68947)
			(xy 207.470237 -35.722674) (xy 207.54835 -35.763148) (xy 207.622458 -35.810559) (xy 207.691949 -35.864512)
			(xy 207.756245 -35.92456) (xy 207.814814 -35.990207) (xy 207.867171 -36.060907) (xy 207.912883 -36.136076)
			(xy 207.951569 -36.21509) (xy 207.98291 -36.297295) (xy 208.006645 -36.382009) (xy 208.022579 -36.46853)
			(xy 208.030579 -36.556142) (xy 208.03108 -36.60013) (xy 244.198655 -36.60013) (xy 244.202659 -36.512245)
			(xy 244.214639 -36.425088) (xy 244.234494 -36.339381) (xy 244.262061 -36.255836) (xy 244.297111 -36.175143)
			(xy 244.339353 -36.097971) (xy 244.388438 -36.024961) (xy 244.443959 -35.956717) (xy 244.505456 -35.893804)
			(xy 244.572418 -35.836744) (xy 244.644292 -35.78601) (xy 244.720482 -35.742022) (xy 244.800356 -35.705144)
			(xy 244.883253 -35.675683) (xy 244.968485 -35.653881) (xy 245.055347 -35.639921) (xy 245.143118 -35.633917)
			(xy 245.231072 -35.63592) (xy 245.318479 -35.645912) (xy 245.404615 -35.663812) (xy 245.488767 -35.68947)
			(xy 245.570237 -35.722674) (xy 245.64835 -35.763148) (xy 245.722458 -35.810559) (xy 245.791949 -35.864512)
			(xy 245.856245 -35.92456) (xy 245.914814 -35.990207) (xy 245.967171 -36.060907) (xy 246.012883 -36.136076)
			(xy 246.051569 -36.21509) (xy 246.08291 -36.297295) (xy 246.106645 -36.382009) (xy 246.122579 -36.46853)
			(xy 246.130579 -36.556142) (xy 246.13108 -36.60013) (xy 270.198603 -36.60013) (xy 270.202607 -36.512245)
			(xy 270.214587 -36.425088) (xy 270.234442 -36.339381) (xy 270.262009 -36.255836) (xy 270.297059 -36.175143)
			(xy 270.339301 -36.097971) (xy 270.388386 -36.024961) (xy 270.443907 -35.956717) (xy 270.505404 -35.893804)
			(xy 270.572366 -35.836744) (xy 270.64424 -35.78601) (xy 270.72043 -35.742022) (xy 270.800304 -35.705144)
			(xy 270.883201 -35.675683) (xy 270.968433 -35.653881) (xy 271.055295 -35.639921) (xy 271.143066 -35.633917)
			(xy 271.23102 -35.63592) (xy 271.318427 -35.645912) (xy 271.404563 -35.663812) (xy 271.488715 -35.68947)
			(xy 271.570185 -35.722674) (xy 271.648298 -35.763148) (xy 271.722406 -35.810559) (xy 271.791897 -35.864512)
			(xy 271.856193 -35.92456) (xy 271.914762 -35.990207) (xy 271.967119 -36.060907) (xy 272.012831 -36.136076)
			(xy 272.051517 -36.21509) (xy 272.082858 -36.297295) (xy 272.106593 -36.382009) (xy 272.122527 -36.46853)
			(xy 272.130527 -36.556142) (xy 272.131028 -36.60013) (xy 296.198551 -36.60013) (xy 296.202555 -36.512245)
			(xy 296.214535 -36.425088) (xy 296.23439 -36.339381) (xy 296.261957 -36.255836) (xy 296.297007 -36.175143)
			(xy 296.339249 -36.097971) (xy 296.388334 -36.024961) (xy 296.443855 -35.956717) (xy 296.505352 -35.893804)
			(xy 296.572314 -35.836744) (xy 296.644188 -35.78601) (xy 296.720378 -35.742022) (xy 296.800252 -35.705144)
			(xy 296.883149 -35.675683) (xy 296.968381 -35.653881) (xy 297.055243 -35.639921) (xy 297.143014 -35.633917)
			(xy 297.230968 -35.63592) (xy 297.318375 -35.645912) (xy 297.404511 -35.663812) (xy 297.488663 -35.68947)
			(xy 297.570133 -35.722674) (xy 297.648246 -35.763148) (xy 297.722354 -35.810559) (xy 297.791845 -35.864512)
			(xy 297.856141 -35.92456) (xy 297.91471 -35.990207) (xy 297.967067 -36.060907) (xy 298.012779 -36.136076)
			(xy 298.051465 -36.21509) (xy 298.082806 -36.297295) (xy 298.106541 -36.382009) (xy 298.122475 -36.46853)
			(xy 298.130475 -36.556142) (xy 298.130976 -36.60013) (xy 322.197991 -36.60013) (xy 322.201996 -36.512222)
			(xy 322.213979 -36.425042) (xy 322.233839 -36.339313) (xy 322.261414 -36.255745) (xy 322.296473 -36.175031)
			(xy 322.338726 -36.097839) (xy 322.387824 -36.02481) (xy 322.44336 -35.956548) (xy 322.504872 -35.893618)
			(xy 322.571853 -35.836544) (xy 322.643746 -35.785796) (xy 322.719955 -35.741796) (xy 322.79985 -35.704909)
			(xy 322.882769 -35.67544) (xy 322.968024 -35.653633) (xy 323.054908 -35.639669) (xy 323.142702 -35.633663)
			(xy 323.230679 -35.635667) (xy 323.318109 -35.645662) (xy 323.404268 -35.663566) (xy 323.488442 -35.68923)
			(xy 323.569933 -35.722443) (xy 323.648067 -35.762929) (xy 323.722195 -35.810351) (xy 323.791703 -35.864318)
			(xy 323.856017 -35.924383) (xy 323.914601 -35.990047) (xy 323.966972 -36.060766) (xy 324.012695 -36.135954)
			(xy 324.051392 -36.214989) (xy 324.082741 -36.297215) (xy 324.106483 -36.381951) (xy 324.122421 -36.468495)
			(xy 324.130423 -36.55613) (xy 324.130924 -36.60013) (xy 360.298245 -36.60013) (xy 360.30225 -36.512222)
			(xy 360.314233 -36.425042) (xy 360.334093 -36.339313) (xy 360.361668 -36.255745) (xy 360.396727 -36.175031)
			(xy 360.43898 -36.097839) (xy 360.488078 -36.02481) (xy 360.543614 -35.956548) (xy 360.605126 -35.893618)
			(xy 360.672107 -35.836544) (xy 360.744 -35.785796) (xy 360.820209 -35.741796) (xy 360.900104 -35.704909)
			(xy 360.983023 -35.67544) (xy 361.068278 -35.653633) (xy 361.155162 -35.639669) (xy 361.242956 -35.633663)
			(xy 361.330933 -35.635667) (xy 361.418363 -35.645662) (xy 361.504522 -35.663566) (xy 361.588696 -35.68923)
			(xy 361.670187 -35.722443) (xy 361.748321 -35.762929) (xy 361.822449 -35.810351) (xy 361.891957 -35.864318)
			(xy 361.956271 -35.924383) (xy 362.014855 -35.990047) (xy 362.067226 -36.060766) (xy 362.112949 -36.135954)
			(xy 362.151646 -36.214989) (xy 362.182995 -36.297215) (xy 362.206737 -36.381951) (xy 362.222675 -36.468495)
			(xy 362.230677 -36.55613) (xy 362.231178 -36.60013) (xy 386.298193 -36.60013) (xy 386.302198 -36.512222)
			(xy 386.314181 -36.425042) (xy 386.334041 -36.339313) (xy 386.361616 -36.255745) (xy 386.396675 -36.175031)
			(xy 386.438928 -36.097839) (xy 386.488026 -36.02481) (xy 386.543562 -35.956548) (xy 386.605074 -35.893618)
			(xy 386.672055 -35.836544) (xy 386.743948 -35.785796) (xy 386.820157 -35.741796) (xy 386.900052 -35.704909)
			(xy 386.982971 -35.67544) (xy 387.068226 -35.653633) (xy 387.15511 -35.639669) (xy 387.242904 -35.633663)
			(xy 387.330881 -35.635667) (xy 387.418311 -35.645662) (xy 387.50447 -35.663566) (xy 387.588644 -35.68923)
			(xy 387.670135 -35.722443) (xy 387.748269 -35.762929) (xy 387.822397 -35.810351) (xy 387.891905 -35.864318)
			(xy 387.956219 -35.924383) (xy 388.014803 -35.990047) (xy 388.067174 -36.060766) (xy 388.112897 -36.135954)
			(xy 388.151594 -36.214989) (xy 388.182943 -36.297215) (xy 388.206685 -36.381951) (xy 388.222623 -36.468495)
			(xy 388.230625 -36.55613) (xy 388.231126 -36.60013) (xy 412.298649 -36.60013) (xy 412.302653 -36.512245)
			(xy 412.314633 -36.425088) (xy 412.334488 -36.339381) (xy 412.362055 -36.255836) (xy 412.397105 -36.175143)
			(xy 412.439347 -36.097971) (xy 412.488432 -36.024961) (xy 412.543953 -35.956717) (xy 412.60545 -35.893804)
			(xy 412.672412 -35.836744) (xy 412.744286 -35.78601) (xy 412.820476 -35.742022) (xy 412.90035 -35.705144)
			(xy 412.983247 -35.675683) (xy 413.068479 -35.653881) (xy 413.155341 -35.639921) (xy 413.243112 -35.633917)
			(xy 413.331066 -35.63592) (xy 413.418473 -35.645912) (xy 413.504609 -35.663812) (xy 413.588761 -35.68947)
			(xy 413.670231 -35.722674) (xy 413.748344 -35.763148) (xy 413.822452 -35.810559) (xy 413.891943 -35.864512)
			(xy 413.956239 -35.92456) (xy 414.014808 -35.990207) (xy 414.067165 -36.060907) (xy 414.112877 -36.136076)
			(xy 414.151563 -36.21509) (xy 414.182904 -36.297295) (xy 414.206639 -36.382009) (xy 414.222573 -36.46853)
			(xy 414.230573 -36.556142) (xy 414.231074 -36.60013) (xy 438.298597 -36.60013) (xy 438.302601 -36.512245)
			(xy 438.314581 -36.425088) (xy 438.334436 -36.339381) (xy 438.362003 -36.255836) (xy 438.397053 -36.175143)
			(xy 438.439295 -36.097971) (xy 438.48838 -36.024961) (xy 438.543901 -35.956717) (xy 438.605398 -35.893804)
			(xy 438.67236 -35.836744) (xy 438.744234 -35.78601) (xy 438.820424 -35.742022) (xy 438.900298 -35.705144)
			(xy 438.983195 -35.675683) (xy 439.068427 -35.653881) (xy 439.155289 -35.639921) (xy 439.24306 -35.633917)
			(xy 439.331014 -35.63592) (xy 439.418421 -35.645912) (xy 439.504557 -35.663812) (xy 439.588709 -35.68947)
			(xy 439.670179 -35.722674) (xy 439.748292 -35.763148) (xy 439.8224 -35.810559) (xy 439.891891 -35.864512)
			(xy 439.956187 -35.92456) (xy 440.014756 -35.990207) (xy 440.067113 -36.060907) (xy 440.112825 -36.136076)
			(xy 440.151511 -36.21509) (xy 440.182852 -36.297295) (xy 440.206587 -36.382009) (xy 440.222521 -36.46853)
			(xy 440.230521 -36.556142) (xy 440.231022 -36.60013) (xy 440.230521 -36.644118) (xy 440.222521 -36.73173)
			(xy 440.206587 -36.818251) (xy 440.182852 -36.902965) (xy 440.151511 -36.98517) (xy 440.112825 -37.064184)
			(xy 440.067113 -37.139353) (xy 440.014756 -37.210053) (xy 439.956187 -37.2757) (xy 439.891891 -37.335748)
			(xy 439.8224 -37.389701) (xy 439.748292 -37.437112) (xy 439.670179 -37.477586) (xy 439.588709 -37.51079)
			(xy 439.504557 -37.536448) (xy 439.418421 -37.554348) (xy 439.331014 -37.56434) (xy 439.24306 -37.566343)
			(xy 439.155289 -37.560339) (xy 439.068427 -37.546379) (xy 438.983195 -37.524577) (xy 438.900298 -37.495116)
			(xy 438.820424 -37.458238) (xy 438.744234 -37.41425) (xy 438.67236 -37.363516) (xy 438.605398 -37.306456)
			(xy 438.543901 -37.243543) (xy 438.48838 -37.175299) (xy 438.439295 -37.102289) (xy 438.397053 -37.025117)
			(xy 438.362003 -36.944424) (xy 438.334436 -36.860879) (xy 438.314581 -36.775172) (xy 438.302601 -36.688015)
			(xy 438.298597 -36.60013) (xy 414.231074 -36.60013) (xy 414.230573 -36.644118) (xy 414.222573 -36.73173)
			(xy 414.206639 -36.818251) (xy 414.182904 -36.902965) (xy 414.151563 -36.98517) (xy 414.112877 -37.064184)
			(xy 414.067165 -37.139353) (xy 414.014808 -37.210053) (xy 413.956239 -37.2757) (xy 413.891943 -37.335748)
			(xy 413.822452 -37.389701) (xy 413.748344 -37.437112) (xy 413.670231 -37.477586) (xy 413.588761 -37.51079)
			(xy 413.504609 -37.536448) (xy 413.418473 -37.554348) (xy 413.331066 -37.56434) (xy 413.243112 -37.566343)
			(xy 413.155341 -37.560339) (xy 413.068479 -37.546379) (xy 412.983247 -37.524577) (xy 412.90035 -37.495116)
			(xy 412.820476 -37.458238) (xy 412.744286 -37.41425) (xy 412.672412 -37.363516) (xy 412.60545 -37.306456)
			(xy 412.543953 -37.243543) (xy 412.488432 -37.175299) (xy 412.439347 -37.102289) (xy 412.397105 -37.025117)
			(xy 412.362055 -36.944424) (xy 412.334488 -36.860879) (xy 412.314633 -36.775172) (xy 412.302653 -36.688015)
			(xy 412.298649 -36.60013) (xy 388.231126 -36.60013) (xy 388.230625 -36.64413) (xy 388.222623 -36.731765)
			(xy 388.206685 -36.818309) (xy 388.182943 -36.903045) (xy 388.151594 -36.985271) (xy 388.112897 -37.064306)
			(xy 388.067174 -37.139494) (xy 388.014803 -37.210213) (xy 387.956219 -37.275877) (xy 387.891905 -37.335942)
			(xy 387.822397 -37.389909) (xy 387.748269 -37.437331) (xy 387.670135 -37.477817) (xy 387.588644 -37.51103)
			(xy 387.50447 -37.536694) (xy 387.418311 -37.554598) (xy 387.330881 -37.564593) (xy 387.242904 -37.566597)
			(xy 387.15511 -37.560591) (xy 387.068226 -37.546627) (xy 386.982971 -37.52482) (xy 386.900052 -37.495351)
			(xy 386.820157 -37.458464) (xy 386.743948 -37.414464) (xy 386.672055 -37.363716) (xy 386.605074 -37.306642)
			(xy 386.543562 -37.243712) (xy 386.488026 -37.17545) (xy 386.438928 -37.102421) (xy 386.396675 -37.025229)
			(xy 386.361616 -36.944515) (xy 386.334041 -36.860947) (xy 386.314181 -36.775218) (xy 386.302198 -36.688038)
			(xy 386.298193 -36.60013) (xy 362.231178 -36.60013) (xy 362.230677 -36.64413) (xy 362.222675 -36.731765)
			(xy 362.206737 -36.818309) (xy 362.182995 -36.903045) (xy 362.151646 -36.985271) (xy 362.112949 -37.064306)
			(xy 362.067226 -37.139494) (xy 362.014855 -37.210213) (xy 361.956271 -37.275877) (xy 361.891957 -37.335942)
			(xy 361.822449 -37.389909) (xy 361.748321 -37.437331) (xy 361.670187 -37.477817) (xy 361.588696 -37.51103)
			(xy 361.504522 -37.536694) (xy 361.418363 -37.554598) (xy 361.330933 -37.564593) (xy 361.242956 -37.566597)
			(xy 361.155162 -37.560591) (xy 361.068278 -37.546627) (xy 360.983023 -37.52482) (xy 360.900104 -37.495351)
			(xy 360.820209 -37.458464) (xy 360.744 -37.414464) (xy 360.672107 -37.363716) (xy 360.605126 -37.306642)
			(xy 360.543614 -37.243712) (xy 360.488078 -37.17545) (xy 360.43898 -37.102421) (xy 360.396727 -37.025229)
			(xy 360.361668 -36.944515) (xy 360.334093 -36.860947) (xy 360.314233 -36.775218) (xy 360.30225 -36.688038)
			(xy 360.298245 -36.60013) (xy 324.130924 -36.60013) (xy 324.130423 -36.64413) (xy 324.122421 -36.731765)
			(xy 324.106483 -36.818309) (xy 324.082741 -36.903045) (xy 324.051392 -36.985271) (xy 324.012695 -37.064306)
			(xy 323.966972 -37.139494) (xy 323.914601 -37.210213) (xy 323.856017 -37.275877) (xy 323.791703 -37.335942)
			(xy 323.722195 -37.389909) (xy 323.648067 -37.437331) (xy 323.569933 -37.477817) (xy 323.488442 -37.51103)
			(xy 323.404268 -37.536694) (xy 323.318109 -37.554598) (xy 323.230679 -37.564593) (xy 323.142702 -37.566597)
			(xy 323.054908 -37.560591) (xy 322.968024 -37.546627) (xy 322.882769 -37.52482) (xy 322.79985 -37.495351)
			(xy 322.719955 -37.458464) (xy 322.643746 -37.414464) (xy 322.571853 -37.363716) (xy 322.504872 -37.306642)
			(xy 322.44336 -37.243712) (xy 322.387824 -37.17545) (xy 322.338726 -37.102421) (xy 322.296473 -37.025229)
			(xy 322.261414 -36.944515) (xy 322.233839 -36.860947) (xy 322.213979 -36.775218) (xy 322.201996 -36.688038)
			(xy 322.197991 -36.60013) (xy 298.130976 -36.60013) (xy 298.130475 -36.644118) (xy 298.122475 -36.73173)
			(xy 298.106541 -36.818251) (xy 298.082806 -36.902965) (xy 298.051465 -36.98517) (xy 298.012779 -37.064184)
			(xy 297.967067 -37.139353) (xy 297.91471 -37.210053) (xy 297.856141 -37.2757) (xy 297.791845 -37.335748)
			(xy 297.722354 -37.389701) (xy 297.648246 -37.437112) (xy 297.570133 -37.477586) (xy 297.488663 -37.51079)
			(xy 297.404511 -37.536448) (xy 297.318375 -37.554348) (xy 297.230968 -37.56434) (xy 297.143014 -37.566343)
			(xy 297.055243 -37.560339) (xy 296.968381 -37.546379) (xy 296.883149 -37.524577) (xy 296.800252 -37.495116)
			(xy 296.720378 -37.458238) (xy 296.644188 -37.41425) (xy 296.572314 -37.363516) (xy 296.505352 -37.306456)
			(xy 296.443855 -37.243543) (xy 296.388334 -37.175299) (xy 296.339249 -37.102289) (xy 296.297007 -37.025117)
			(xy 296.261957 -36.944424) (xy 296.23439 -36.860879) (xy 296.214535 -36.775172) (xy 296.202555 -36.688015)
			(xy 296.198551 -36.60013) (xy 272.131028 -36.60013) (xy 272.130527 -36.644118) (xy 272.122527 -36.73173)
			(xy 272.106593 -36.818251) (xy 272.082858 -36.902965) (xy 272.051517 -36.98517) (xy 272.012831 -37.064184)
			(xy 271.967119 -37.139353) (xy 271.914762 -37.210053) (xy 271.856193 -37.2757) (xy 271.791897 -37.335748)
			(xy 271.722406 -37.389701) (xy 271.648298 -37.437112) (xy 271.570185 -37.477586) (xy 271.488715 -37.51079)
			(xy 271.404563 -37.536448) (xy 271.318427 -37.554348) (xy 271.23102 -37.56434) (xy 271.143066 -37.566343)
			(xy 271.055295 -37.560339) (xy 270.968433 -37.546379) (xy 270.883201 -37.524577) (xy 270.800304 -37.495116)
			(xy 270.72043 -37.458238) (xy 270.64424 -37.41425) (xy 270.572366 -37.363516) (xy 270.505404 -37.306456)
			(xy 270.443907 -37.243543) (xy 270.388386 -37.175299) (xy 270.339301 -37.102289) (xy 270.297059 -37.025117)
			(xy 270.262009 -36.944424) (xy 270.234442 -36.860879) (xy 270.214587 -36.775172) (xy 270.202607 -36.688015)
			(xy 270.198603 -36.60013) (xy 246.13108 -36.60013) (xy 246.130579 -36.644118) (xy 246.122579 -36.73173)
			(xy 246.106645 -36.818251) (xy 246.08291 -36.902965) (xy 246.051569 -36.98517) (xy 246.012883 -37.064184)
			(xy 245.967171 -37.139353) (xy 245.914814 -37.210053) (xy 245.856245 -37.2757) (xy 245.791949 -37.335748)
			(xy 245.722458 -37.389701) (xy 245.64835 -37.437112) (xy 245.570237 -37.477586) (xy 245.488767 -37.51079)
			(xy 245.404615 -37.536448) (xy 245.318479 -37.554348) (xy 245.231072 -37.56434) (xy 245.143118 -37.566343)
			(xy 245.055347 -37.560339) (xy 244.968485 -37.546379) (xy 244.883253 -37.524577) (xy 244.800356 -37.495116)
			(xy 244.720482 -37.458238) (xy 244.644292 -37.41425) (xy 244.572418 -37.363516) (xy 244.505456 -37.306456)
			(xy 244.443959 -37.243543) (xy 244.388438 -37.175299) (xy 244.339353 -37.102289) (xy 244.297111 -37.025117)
			(xy 244.262061 -36.944424) (xy 244.234494 -36.860879) (xy 244.214639 -36.775172) (xy 244.202659 -36.688015)
			(xy 244.198655 -36.60013) (xy 208.03108 -36.60013) (xy 208.030579 -36.644118) (xy 208.022579 -36.73173)
			(xy 208.006645 -36.818251) (xy 207.98291 -36.902965) (xy 207.951569 -36.98517) (xy 207.912883 -37.064184)
			(xy 207.867171 -37.139353) (xy 207.814814 -37.210053) (xy 207.756245 -37.2757) (xy 207.691949 -37.335748)
			(xy 207.622458 -37.389701) (xy 207.54835 -37.437112) (xy 207.470237 -37.477586) (xy 207.388767 -37.51079)
			(xy 207.304615 -37.536448) (xy 207.218479 -37.554348) (xy 207.131072 -37.56434) (xy 207.043118 -37.566343)
			(xy 206.955347 -37.560339) (xy 206.868485 -37.546379) (xy 206.783253 -37.524577) (xy 206.700356 -37.495116)
			(xy 206.620482 -37.458238) (xy 206.544292 -37.41425) (xy 206.472418 -37.363516) (xy 206.405456 -37.306456)
			(xy 206.343959 -37.243543) (xy 206.288438 -37.175299) (xy 206.239353 -37.102289) (xy 206.197111 -37.025117)
			(xy 206.162061 -36.944424) (xy 206.134494 -36.860879) (xy 206.114639 -36.775172) (xy 206.102659 -36.688015)
			(xy 206.098655 -36.60013) (xy 182.031132 -36.60013) (xy 182.030631 -36.64413) (xy 182.022629 -36.731765)
			(xy 182.006691 -36.818309) (xy 181.982949 -36.903045) (xy 181.9516 -36.985271) (xy 181.912903 -37.064306)
			(xy 181.86718 -37.139494) (xy 181.814809 -37.210213) (xy 181.756225 -37.275877) (xy 181.691911 -37.335942)
			(xy 181.622403 -37.389909) (xy 181.548275 -37.437331) (xy 181.470141 -37.477817) (xy 181.38865 -37.51103)
			(xy 181.304476 -37.536694) (xy 181.218317 -37.554598) (xy 181.130887 -37.564593) (xy 181.04291 -37.566597)
			(xy 180.955116 -37.560591) (xy 180.868232 -37.546627) (xy 180.782977 -37.52482) (xy 180.700058 -37.495351)
			(xy 180.620163 -37.458464) (xy 180.543954 -37.414464) (xy 180.472061 -37.363716) (xy 180.40508 -37.306642)
			(xy 180.343568 -37.243712) (xy 180.288032 -37.17545) (xy 180.238934 -37.102421) (xy 180.196681 -37.025229)
			(xy 180.161622 -36.944515) (xy 180.134047 -36.860947) (xy 180.114187 -36.775218) (xy 180.102204 -36.688038)
			(xy 180.098199 -36.60013) (xy 156.031184 -36.60013) (xy 156.030683 -36.64413) (xy 156.022681 -36.731765)
			(xy 156.006743 -36.818309) (xy 155.983001 -36.903045) (xy 155.951652 -36.985271) (xy 155.912955 -37.064306)
			(xy 155.867232 -37.139494) (xy 155.814861 -37.210213) (xy 155.756277 -37.275877) (xy 155.691963 -37.335942)
			(xy 155.622455 -37.389909) (xy 155.548327 -37.437331) (xy 155.470193 -37.477817) (xy 155.388702 -37.51103)
			(xy 155.304528 -37.536694) (xy 155.218369 -37.554598) (xy 155.130939 -37.564593) (xy 155.042962 -37.566597)
			(xy 154.955168 -37.560591) (xy 154.868284 -37.546627) (xy 154.783029 -37.52482) (xy 154.70011 -37.495351)
			(xy 154.620215 -37.458464) (xy 154.544006 -37.414464) (xy 154.472113 -37.363716) (xy 154.405132 -37.306642)
			(xy 154.34362 -37.243712) (xy 154.288084 -37.17545) (xy 154.238986 -37.102421) (xy 154.196733 -37.025229)
			(xy 154.161674 -36.944515) (xy 154.134099 -36.860947) (xy 154.114239 -36.775218) (xy 154.102256 -36.688038)
			(xy 154.098251 -36.60013) (xy 130.031236 -36.60013) (xy 130.030735 -36.64413) (xy 130.022733 -36.731765)
			(xy 130.006795 -36.818309) (xy 129.983053 -36.903045) (xy 129.951704 -36.985271) (xy 129.913007 -37.064306)
			(xy 129.867284 -37.139494) (xy 129.814913 -37.210213) (xy 129.756329 -37.275877) (xy 129.692015 -37.335942)
			(xy 129.622507 -37.389909) (xy 129.548379 -37.437331) (xy 129.470245 -37.477817) (xy 129.388754 -37.51103)
			(xy 129.30458 -37.536694) (xy 129.218421 -37.554598) (xy 129.130991 -37.564593) (xy 129.043014 -37.566597)
			(xy 128.95522 -37.560591) (xy 128.868336 -37.546627) (xy 128.783081 -37.52482) (xy 128.700162 -37.495351)
			(xy 128.620267 -37.458464) (xy 128.544058 -37.414464) (xy 128.472165 -37.363716) (xy 128.405184 -37.306642)
			(xy 128.343672 -37.243712) (xy 128.288136 -37.17545) (xy 128.239038 -37.102421) (xy 128.196785 -37.025229)
			(xy 128.161726 -36.944515) (xy 128.134151 -36.860947) (xy 128.114291 -36.775218) (xy 128.102308 -36.688038)
			(xy 128.098303 -36.60013) (xy 91.930982 -36.60013) (xy 91.930481 -36.64413) (xy 91.922479 -36.731765)
			(xy 91.906541 -36.818309) (xy 91.882799 -36.903045) (xy 91.85145 -36.985271) (xy 91.812753 -37.064306)
			(xy 91.76703 -37.139494) (xy 91.714659 -37.210213) (xy 91.656075 -37.275877) (xy 91.591761 -37.335942)
			(xy 91.522253 -37.389909) (xy 91.448125 -37.437331) (xy 91.369991 -37.477817) (xy 91.2885 -37.51103)
			(xy 91.204326 -37.536694) (xy 91.118167 -37.554598) (xy 91.030737 -37.564593) (xy 90.94276 -37.566597)
			(xy 90.854966 -37.560591) (xy 90.768082 -37.546627) (xy 90.682827 -37.52482) (xy 90.599908 -37.495351)
			(xy 90.520013 -37.458464) (xy 90.443804 -37.414464) (xy 90.371911 -37.363716) (xy 90.30493 -37.306642)
			(xy 90.243418 -37.243712) (xy 90.187882 -37.17545) (xy 90.138784 -37.102421) (xy 90.096531 -37.025229)
			(xy 90.061472 -36.944515) (xy 90.033897 -36.860947) (xy 90.014037 -36.775218) (xy 90.002054 -36.688038)
			(xy 89.998049 -36.60013) (xy 65.931034 -36.60013) (xy 65.930533 -36.64413) (xy 65.922531 -36.731765)
			(xy 65.906593 -36.818309) (xy 65.882851 -36.903045) (xy 65.851502 -36.985271) (xy 65.812805 -37.064306)
			(xy 65.767082 -37.139494) (xy 65.714711 -37.210213) (xy 65.656127 -37.275877) (xy 65.591813 -37.335942)
			(xy 65.522305 -37.389909) (xy 65.448177 -37.437331) (xy 65.370043 -37.477817) (xy 65.288552 -37.51103)
			(xy 65.204378 -37.536694) (xy 65.118219 -37.554598) (xy 65.030789 -37.564593) (xy 64.942812 -37.566597)
			(xy 64.855018 -37.560591) (xy 64.768134 -37.546627) (xy 64.682879 -37.52482) (xy 64.59996 -37.495351)
			(xy 64.520065 -37.458464) (xy 64.443856 -37.414464) (xy 64.371963 -37.363716) (xy 64.304982 -37.306642)
			(xy 64.24347 -37.243712) (xy 64.187934 -37.17545) (xy 64.138836 -37.102421) (xy 64.096583 -37.025229)
			(xy 64.061524 -36.944515) (xy 64.033949 -36.860947) (xy 64.014089 -36.775218) (xy 64.002106 -36.688038)
			(xy 63.998101 -36.60013) (xy 39.931086 -36.60013) (xy 39.930585 -36.64413) (xy 39.922583 -36.731765)
			(xy 39.906645 -36.818309) (xy 39.882903 -36.903045) (xy 39.851554 -36.985271) (xy 39.812857 -37.064306)
			(xy 39.767134 -37.139494) (xy 39.714763 -37.210213) (xy 39.656179 -37.275877) (xy 39.591865 -37.335942)
			(xy 39.522357 -37.389909) (xy 39.448229 -37.437331) (xy 39.370095 -37.477817) (xy 39.288604 -37.51103)
			(xy 39.20443 -37.536694) (xy 39.118271 -37.554598) (xy 39.030841 -37.564593) (xy 38.942864 -37.566597)
			(xy 38.85507 -37.560591) (xy 38.768186 -37.546627) (xy 38.682931 -37.52482) (xy 38.600012 -37.495351)
			(xy 38.520117 -37.458464) (xy 38.443908 -37.414464) (xy 38.372015 -37.363716) (xy 38.305034 -37.306642)
			(xy 38.243522 -37.243712) (xy 38.187986 -37.17545) (xy 38.138888 -37.102421) (xy 38.096635 -37.025229)
			(xy 38.061576 -36.944515) (xy 38.034001 -36.860947) (xy 38.014141 -36.775218) (xy 38.002158 -36.688038)
			(xy 37.998153 -36.60013) (xy 13.931138 -36.60013) (xy 13.930637 -36.64413) (xy 13.922635 -36.731765)
			(xy 13.906697 -36.818309) (xy 13.882955 -36.903045) (xy 13.851606 -36.985271) (xy 13.812909 -37.064306)
			(xy 13.767186 -37.139494) (xy 13.714815 -37.210213) (xy 13.656231 -37.275877) (xy 13.591917 -37.335942)
			(xy 13.522409 -37.389909) (xy 13.448281 -37.437331) (xy 13.370147 -37.477817) (xy 13.288656 -37.51103)
			(xy 13.204482 -37.536694) (xy 13.118323 -37.554598) (xy 13.030893 -37.564593) (xy 12.942916 -37.566597)
			(xy 12.855122 -37.560591) (xy 12.768238 -37.546627) (xy 12.682983 -37.52482) (xy 12.600064 -37.495351)
			(xy 12.520169 -37.458464) (xy 12.44396 -37.414464) (xy 12.372067 -37.363716) (xy 12.305086 -37.306642)
			(xy 12.243574 -37.243712) (xy 12.188038 -37.17545) (xy 12.13894 -37.102421) (xy 12.096687 -37.025229)
			(xy 12.061628 -36.944515) (xy 12.034053 -36.860947) (xy 12.014193 -36.775218) (xy 12.00221 -36.688038)
			(xy 11.998205 -36.60013) (xy 0.508 -36.60013) (xy 0.508 -58.698471) (xy 229.808523 -58.698471) (xy 229.808523 -58.601777)
			(xy 229.816508 -58.505414) (xy 229.832424 -58.410039) (xy 229.85616 -58.316305) (xy 229.887557 -58.22485)
			(xy 229.926398 -58.136301) (xy 229.972419 -58.051261) (xy 230.025305 -57.970313) (xy 230.084696 -57.894008)
			(xy 230.150184 -57.822868) (xy 230.221324 -57.75738) (xy 230.297629 -57.697989) (xy 230.378577 -57.645103)
			(xy 230.463617 -57.599082) (xy 230.552166 -57.560241) (xy 230.643621 -57.528844) (xy 230.737355 -57.505108)
			(xy 230.83273 -57.489192) (xy 230.929093 -57.481207) (xy 231.025787 -57.481207) (xy 231.12215 -57.489192)
			(xy 231.217525 -57.505108) (xy 231.311259 -57.528844) (xy 231.402714 -57.560241) (xy 231.491263 -57.599082)
			(xy 231.576303 -57.645103) (xy 231.657251 -57.697989) (xy 231.733556 -57.75738) (xy 231.804696 -57.822868)
			(xy 231.870184 -57.894008) (xy 231.929575 -57.970313) (xy 231.982461 -58.051261) (xy 232.028482 -58.136301)
			(xy 232.067323 -58.22485) (xy 232.09872 -58.316305) (xy 232.122456 -58.410039) (xy 232.138372 -58.505414)
			(xy 232.146357 -58.601777) (xy 232.146856 -58.650124) (xy 232.146357 -58.698471) (xy 232.138372 -58.794834)
			(xy 232.122456 -58.890209) (xy 232.09872 -58.983943) (xy 232.067323 -59.075398) (xy 232.028482 -59.163947)
			(xy 231.982461 -59.248987) (xy 231.929575 -59.329935) (xy 231.870184 -59.40624) (xy 231.804696 -59.47738)
			(xy 231.733556 -59.542868) (xy 231.657251 -59.602259) (xy 231.576303 -59.655145) (xy 231.491263 -59.701166)
			(xy 231.402714 -59.740007) (xy 231.311259 -59.771404) (xy 231.217525 -59.79514) (xy 231.12215 -59.811056)
			(xy 231.025787 -59.819041) (xy 230.929093 -59.819041) (xy 230.83273 -59.811056) (xy 230.737355 -59.79514)
			(xy 230.643621 -59.771404) (xy 230.552166 -59.740007) (xy 230.463617 -59.701166) (xy 230.378577 -59.655145)
			(xy 230.297629 -59.602259) (xy 230.221324 -59.542868) (xy 230.150184 -59.47738) (xy 230.084696 -59.40624)
			(xy 230.025305 -59.329935) (xy 229.972419 -59.248987) (xy 229.926398 -59.163947) (xy 229.887557 -59.075398)
			(xy 229.85616 -58.983943) (xy 229.832424 -58.890209) (xy 229.816508 -58.794834) (xy 229.808523 -58.698471)
			(xy 0.508 -58.698471) (xy 0.508 -60.13196) (xy 226.436428 -60.13196) (xy 226.436428 -59.26836) (xy 226.436918 -59.238392)
			(xy 226.444741 -59.17897) (xy 226.460254 -59.121077) (xy 226.48319 -59.065704) (xy 226.513157 -59.013798)
			(xy 226.549644 -58.966248) (xy 226.592024 -58.923868) (xy 226.639574 -58.887381) (xy 226.69148 -58.857414)
			(xy 226.746853 -58.834478) (xy 226.804746 -58.818965) (xy 226.864168 -58.811142) (xy 226.924104 -58.811142)
			(xy 226.983526 -58.818965) (xy 227.041419 -58.834478) (xy 227.096792 -58.857414) (xy 227.148698 -58.887381)
			(xy 227.196248 -58.923868) (xy 227.238628 -58.966248) (xy 227.275115 -59.013798) (xy 227.305082 -59.065704)
			(xy 227.328018 -59.121077) (xy 227.343531 -59.17897) (xy 227.351354 -59.238392) (xy 227.351844 -59.26836)
			(xy 227.351844 -60.13196) (xy 227.351354 -60.161928) (xy 227.343531 -60.22135) (xy 227.328018 -60.279243)
			(xy 227.305082 -60.334616) (xy 227.275115 -60.386522) (xy 227.238628 -60.434072) (xy 227.196248 -60.476452)
			(xy 227.148698 -60.512939) (xy 227.096792 -60.542906) (xy 227.041419 -60.565842) (xy 226.983526 -60.581355)
			(xy 226.924104 -60.589178) (xy 226.864168 -60.589178) (xy 226.804746 -60.581355) (xy 226.746853 -60.565842)
			(xy 226.69148 -60.542906) (xy 226.639574 -60.512939) (xy 226.592024 -60.476452) (xy 226.549644 -60.434072)
			(xy 226.513157 -60.386522) (xy 226.48319 -60.334616) (xy 226.460254 -60.279243) (xy 226.444741 -60.22135)
			(xy 226.436918 -60.161928) (xy 226.436428 -60.13196) (xy 0.508 -60.13196) (xy 0.508 -69.798271) (xy 229.808523 -69.798271)
			(xy 229.808523 -69.701577) (xy 229.816508 -69.605214) (xy 229.832424 -69.509839) (xy 229.85616 -69.416105)
			(xy 229.887557 -69.32465) (xy 229.926398 -69.236101) (xy 229.972419 -69.151061) (xy 230.025305 -69.070113)
			(xy 230.084696 -68.993808) (xy 230.150184 -68.922668) (xy 230.221324 -68.85718) (xy 230.297629 -68.797789)
			(xy 230.378577 -68.744903) (xy 230.463617 -68.698882) (xy 230.552166 -68.660041) (xy 230.643621 -68.628644)
			(xy 230.737355 -68.604908) (xy 230.83273 -68.588992) (xy 230.929093 -68.581007) (xy 231.025787 -68.581007)
			(xy 231.12215 -68.588992) (xy 231.217525 -68.604908) (xy 231.311259 -68.628644) (xy 231.402714 -68.660041)
			(xy 231.491263 -68.698882) (xy 231.576303 -68.744903) (xy 231.657251 -68.797789) (xy 231.733556 -68.85718)
			(xy 231.804696 -68.922668) (xy 231.870184 -68.993808) (xy 231.929575 -69.070113) (xy 231.982461 -69.151061)
			(xy 232.028482 -69.236101) (xy 232.067323 -69.32465) (xy 232.09872 -69.416105) (xy 232.122456 -69.509839)
			(xy 232.138372 -69.605214) (xy 232.146357 -69.701577) (xy 232.146856 -69.749924) (xy 232.146357 -69.798271)
			(xy 232.138372 -69.894634) (xy 232.122456 -69.990009) (xy 232.09872 -70.083743) (xy 232.067323 -70.175198)
			(xy 232.028482 -70.263747) (xy 231.982461 -70.348787) (xy 231.929575 -70.429735) (xy 231.870184 -70.50604)
			(xy 231.804696 -70.57718) (xy 231.733556 -70.642668) (xy 231.657251 -70.702059) (xy 231.576303 -70.754945)
			(xy 231.491263 -70.800966) (xy 231.402714 -70.839807) (xy 231.311259 -70.871204) (xy 231.217525 -70.89494)
			(xy 231.12215 -70.910856) (xy 231.025787 -70.918841) (xy 230.929093 -70.918841) (xy 230.83273 -70.910856)
			(xy 230.737355 -70.89494) (xy 230.643621 -70.871204) (xy 230.552166 -70.839807) (xy 230.463617 -70.800966)
			(xy 230.378577 -70.754945) (xy 230.297629 -70.702059) (xy 230.221324 -70.642668) (xy 230.150184 -70.57718)
			(xy 230.084696 -70.50604) (xy 230.025305 -70.429735) (xy 229.972419 -70.348787) (xy 229.926398 -70.263747)
			(xy 229.887557 -70.175198) (xy 229.85616 -70.083743) (xy 229.832424 -69.990009) (xy 229.816508 -69.894634)
			(xy 229.808523 -69.798271) (xy 0.508 -69.798271) (xy 0.508 -75.288385) (xy 262.150829 -75.288385)
			(xy 262.150829 -75.228415) (xy 262.158657 -75.168959) (xy 262.174178 -75.111033) (xy 262.197128 -75.055628)
			(xy 262.227114 -75.003693) (xy 262.263621 -74.956116) (xy 262.306027 -74.913712) (xy 262.353605 -74.877206)
			(xy 262.405541 -74.847222) (xy 262.460946 -74.824274) (xy 262.518872 -74.808754) (xy 262.578329 -74.800928)
			(xy 262.608314 -74.80046) (xy 263.471914 -74.80046) (xy 263.501899 -74.800907) (xy 263.561356 -74.808736)
			(xy 263.619283 -74.824259) (xy 263.674687 -74.84721) (xy 263.726623 -74.877196) (xy 263.7742 -74.913705)
			(xy 263.816604 -74.956111) (xy 263.853111 -75.003689) (xy 263.883096 -75.055625) (xy 263.906045 -75.111031)
			(xy 263.921566 -75.168958) (xy 263.929394 -75.228415) (xy 263.929394 -75.288385) (xy 263.921566 -75.347842)
			(xy 263.906045 -75.405769) (xy 263.883096 -75.461175) (xy 263.853111 -75.513111) (xy 263.816604 -75.560689)
			(xy 263.7742 -75.603095) (xy 263.726623 -75.639604) (xy 263.674687 -75.66959) (xy 263.619283 -75.692541)
			(xy 263.561356 -75.708064) (xy 263.501899 -75.715893) (xy 263.471914 -75.716384) (xy 262.608314 -75.716384)
			(xy 262.578329 -75.715872) (xy 262.518872 -75.708046) (xy 262.460946 -75.692526) (xy 262.405541 -75.669578)
			(xy 262.353605 -75.639594) (xy 262.306027 -75.603088) (xy 262.263621 -75.560684) (xy 262.227114 -75.513107)
			(xy 262.197128 -75.461172) (xy 262.174178 -75.405767) (xy 262.158657 -75.347841) (xy 262.150829 -75.288385)
			(xy 0.508 -75.288385) (xy 0.508 -76.826085) (xy 229.640845 -76.826085) (xy 229.640845 -76.766115)
			(xy 229.648673 -76.706658) (xy 229.664196 -76.648731) (xy 229.687147 -76.593327) (xy 229.717134 -76.541392)
			(xy 229.753643 -76.493816) (xy 229.796051 -76.451413) (xy 229.84363 -76.414908) (xy 229.895568 -76.384926)
			(xy 229.950975 -76.361981) (xy 230.008903 -76.346464) (xy 230.068361 -76.338642) (xy 230.098346 -76.338176)
			(xy 230.961946 -76.338176) (xy 230.991931 -76.338593) (xy 231.051387 -76.346426) (xy 231.109312 -76.361952)
			(xy 231.164715 -76.384906) (xy 231.216648 -76.414894) (xy 231.264223 -76.451404) (xy 231.306626 -76.493811)
			(xy 231.343131 -76.54139) (xy 231.373114 -76.593326) (xy 231.396063 -76.648732) (xy 231.411583 -76.706658)
			(xy 231.41941 -76.766115) (xy 231.41941 -76.826085) (xy 231.411583 -76.885542) (xy 231.396063 -76.943468)
			(xy 231.373114 -76.998874) (xy 231.343131 -77.05081) (xy 231.306626 -77.098389) (xy 231.264223 -77.140796)
			(xy 231.216648 -77.177306) (xy 231.164715 -77.207294) (xy 231.109312 -77.230248) (xy 231.051387 -77.245774)
			(xy 230.991931 -77.253607) (xy 230.961946 -77.2541) (xy 230.098346 -77.2541) (xy 230.068361 -77.253558)
			(xy 230.008903 -77.245736) (xy 229.950975 -77.230219) (xy 229.895568 -77.207274) (xy 229.84363 -77.177292)
			(xy 229.796051 -77.140787) (xy 229.753643 -77.098384) (xy 229.717134 -77.050808) (xy 229.687147 -76.998873)
			(xy 229.664196 -76.943469) (xy 229.648673 -76.885542) (xy 229.640845 -76.826085) (xy 0.508 -76.826085)
			(xy 0.508 -77.365367) (xy 105.150162 -77.365367) (xy 105.150162 -77.305433) (xy 105.157985 -77.246011)
			(xy 105.173496 -77.188119) (xy 105.19643 -77.132746) (xy 105.226396 -77.08084) (xy 105.26288 -77.03329)
			(xy 105.305258 -76.990908) (xy 105.352805 -76.954419) (xy 105.404708 -76.924449) (xy 105.460079 -76.901509)
			(xy 105.51797 -76.885993) (xy 105.577391 -76.878165) (xy 105.607358 -76.877672) (xy 106.470958 -76.877672)
			(xy 106.500928 -76.878178) (xy 106.560354 -76.885997) (xy 106.618252 -76.901506) (xy 106.67363 -76.92444)
			(xy 106.72554 -76.954406) (xy 106.773095 -76.990892) (xy 106.81548 -77.033273) (xy 106.851971 -77.080825)
			(xy 106.881942 -77.132732) (xy 106.904881 -77.188108) (xy 106.920395 -77.246004) (xy 106.928219 -77.305431)
			(xy 106.928219 -77.365367) (xy 109.150162 -77.365367) (xy 109.150162 -77.305433) (xy 109.157984 -77.246012)
			(xy 109.173495 -77.18812) (xy 109.196429 -77.132748) (xy 109.226394 -77.080843) (xy 109.262878 -77.033292)
			(xy 109.305255 -76.990911) (xy 109.352801 -76.954422) (xy 109.404703 -76.924452) (xy 109.460073 -76.901511)
			(xy 109.517963 -76.885994) (xy 109.577383 -76.878165) (xy 109.60735 -76.877672) (xy 110.47095 -76.877672)
			(xy 110.50092 -76.878178) (xy 110.560347 -76.885996) (xy 110.618246 -76.901504) (xy 110.673625 -76.924437)
			(xy 110.725536 -76.954403) (xy 110.773092 -76.990889) (xy 110.815478 -77.03327) (xy 110.851969 -77.080822)
			(xy 110.881941 -77.13273) (xy 110.90488 -77.188107) (xy 110.920395 -77.246003) (xy 110.928219 -77.30543)
			(xy 110.928219 -77.36537) (xy 110.920395 -77.424797) (xy 110.90488 -77.482693) (xy 110.881941 -77.53807)
			(xy 110.851969 -77.589978) (xy 110.815478 -77.63753) (xy 110.773092 -77.679911) (xy 110.725536 -77.716397)
			(xy 110.673625 -77.746363) (xy 110.618246 -77.769296) (xy 110.560347 -77.784804) (xy 110.50092 -77.792622)
			(xy 110.47095 -77.793088) (xy 109.60735 -77.793088) (xy 109.577383 -77.792635) (xy 109.517963 -77.784806)
			(xy 109.460073 -77.769289) (xy 109.404703 -77.746348) (xy 109.352801 -77.716378) (xy 109.305255 -77.679889)
			(xy 109.262878 -77.637508) (xy 109.226394 -77.589957) (xy 109.196429 -77.538052) (xy 109.173495 -77.48268)
			(xy 109.157984 -77.424788) (xy 109.150162 -77.365367) (xy 106.928219 -77.365367) (xy 106.928219 -77.365369)
			(xy 106.920395 -77.424796) (xy 106.904881 -77.482692) (xy 106.881942 -77.538068) (xy 106.851971 -77.589975)
			(xy 106.81548 -77.637527) (xy 106.773095 -77.679908) (xy 106.72554 -77.716394) (xy 106.67363 -77.74636)
			(xy 106.618252 -77.769294) (xy 106.560354 -77.784803) (xy 106.500928 -77.792622) (xy 106.470958 -77.793088)
			(xy 105.607358 -77.793088) (xy 105.577391 -77.792635) (xy 105.51797 -77.784807) (xy 105.460079 -77.769291)
			(xy 105.404708 -77.746351) (xy 105.352805 -77.716381) (xy 105.305258 -77.679892) (xy 105.26288 -77.63751)
			(xy 105.226396 -77.58996) (xy 105.19643 -77.538054) (xy 105.173496 -77.482681) (xy 105.157985 -77.424789)
			(xy 105.150162 -77.365367) (xy 0.508 -77.365367) (xy 0.508 -78.127367) (xy 107.150162 -78.127367)
			(xy 107.150162 -78.067433) (xy 107.157984 -78.008012) (xy 107.173496 -77.950119) (xy 107.19643 -77.894747)
			(xy 107.226395 -77.842842) (xy 107.262879 -77.795291) (xy 107.305256 -77.752909) (xy 107.352803 -77.716421)
			(xy 107.404706 -77.68645) (xy 107.460076 -77.66351) (xy 107.517966 -77.647993) (xy 107.577387 -77.640165)
			(xy 107.607354 -77.639672) (xy 108.470954 -77.639672) (xy 108.500924 -77.640178) (xy 108.560351 -77.647996)
			(xy 108.618249 -77.663505) (xy 108.673627 -77.686438) (xy 108.725538 -77.716405) (xy 108.773094 -77.752891)
			(xy 108.815479 -77.795272) (xy 108.85197 -77.842823) (xy 108.881941 -77.894731) (xy 108.90488 -77.950107)
			(xy 108.920395 -78.008004) (xy 108.928219 -78.06743) (xy 108.928219 -78.12737) (xy 108.920395 -78.186796)
			(xy 108.90488 -78.244693) (xy 108.881941 -78.300069) (xy 108.85197 -78.351977) (xy 108.815479 -78.399528)
			(xy 108.773093 -78.441909) (xy 108.725538 -78.478395) (xy 108.673627 -78.508362) (xy 108.618249 -78.531295)
			(xy 108.560351 -78.546804) (xy 108.500924 -78.554622) (xy 108.470954 -78.555088) (xy 107.607354 -78.555088)
			(xy 107.577387 -78.554635) (xy 107.517966 -78.546807) (xy 107.460076 -78.53129) (xy 107.404706 -78.50835)
			(xy 107.352803 -78.478379) (xy 107.305256 -78.441891) (xy 107.262879 -78.399509) (xy 107.226395 -78.351958)
			(xy 107.19643 -78.300053) (xy 107.173496 -78.244681) (xy 107.157984 -78.186788) (xy 107.150162 -78.127367)
			(xy 0.508 -78.127367) (xy 0.508 -79.238094) (xy 227.9777 -79.238094) (xy 227.9777 -78.374494) (xy 227.97819 -78.344526)
			(xy 227.986013 -78.285104) (xy 228.001526 -78.227211) (xy 228.024462 -78.171838) (xy 228.054429 -78.119932)
			(xy 228.090916 -78.072382) (xy 228.133296 -78.030002) (xy 228.180846 -77.993515) (xy 228.232752 -77.963548)
			(xy 228.288125 -77.940612) (xy 228.346018 -77.925099) (xy 228.40544 -77.917276) (xy 228.465376 -77.917276)
			(xy 228.524798 -77.925099) (xy 228.582691 -77.940612) (xy 228.638064 -77.963548) (xy 228.68997 -77.993515)
			(xy 228.73752 -78.030002) (xy 228.7799 -78.072382) (xy 228.816387 -78.119932) (xy 228.83413 -78.150664)
			(xy 336.40703 -78.150664) (xy 336.40703 -78.090736) (xy 336.414852 -78.031319) (xy 336.430363 -77.973433)
			(xy 336.453297 -77.918066) (xy 336.483261 -77.866166) (xy 336.519743 -77.818621) (xy 336.562119 -77.776245)
			(xy 336.609664 -77.739762) (xy 336.661564 -77.709797) (xy 336.716931 -77.686864) (xy 336.774817 -77.671353)
			(xy 336.834234 -77.66353) (xy 336.864198 -77.66304) (xy 337.727798 -77.66304) (xy 337.75777 -77.663413)
			(xy 337.817202 -77.671237) (xy 337.875104 -77.686751) (xy 337.930486 -77.709691) (xy 337.982399 -77.739663)
			(xy 338.029957 -77.776155) (xy 338.072344 -77.818542) (xy 338.108836 -77.866099) (xy 338.138808 -77.918013)
			(xy 338.161748 -77.973394) (xy 338.177263 -78.031296) (xy 338.185087 -78.090728) (xy 338.185087 -78.150672)
			(xy 338.177263 -78.210104) (xy 338.161748 -78.268006) (xy 338.138808 -78.323387) (xy 338.108836 -78.375301)
			(xy 338.072344 -78.422858) (xy 338.029957 -78.465245) (xy 337.982399 -78.501737) (xy 337.930486 -78.531709)
			(xy 337.875104 -78.554649) (xy 337.817202 -78.570163) (xy 337.75777 -78.577987) (xy 337.727798 -78.578456)
			(xy 336.864198 -78.578456) (xy 336.834234 -78.57787) (xy 336.774817 -78.570047) (xy 336.716931 -78.554536)
			(xy 336.661564 -78.531603) (xy 336.609664 -78.501638) (xy 336.562119 -78.465155) (xy 336.519743 -78.422779)
			(xy 336.483261 -78.375234) (xy 336.453297 -78.323334) (xy 336.430363 -78.267967) (xy 336.414852 -78.210081)
			(xy 336.40703 -78.150664) (xy 228.83413 -78.150664) (xy 228.846354 -78.171838) (xy 228.86929 -78.227211)
			(xy 228.884803 -78.285104) (xy 228.892626 -78.344526) (xy 228.893116 -78.374494) (xy 228.893116 -79.238094)
			(xy 228.892626 -79.268062) (xy 228.884803 -79.327484) (xy 228.86929 -79.385377) (xy 228.846354 -79.44075)
			(xy 228.816387 -79.492656) (xy 228.7799 -79.540206) (xy 228.73752 -79.582586) (xy 228.68997 -79.619073)
			(xy 228.638064 -79.64904) (xy 228.582691 -79.671976) (xy 228.524798 -79.687489) (xy 228.465376 -79.695312)
			(xy 228.40544 -79.695312) (xy 228.346018 -79.687489) (xy 228.288125 -79.671976) (xy 228.232752 -79.64904)
			(xy 228.180846 -79.619073) (xy 228.133296 -79.582586) (xy 228.090916 -79.540206) (xy 228.054429 -79.492656)
			(xy 228.024462 -79.44075) (xy 228.001526 -79.385377) (xy 227.986013 -79.327484) (xy 227.97819 -79.268062)
			(xy 227.9777 -79.238094) (xy 0.508 -79.238094) (xy 0.508 -80.183482) (xy 237.540292 -80.183482) (xy 237.540292 -79.319882)
			(xy 237.540782 -79.289914) (xy 237.548605 -79.230492) (xy 237.564118 -79.172599) (xy 237.587054 -79.117226)
			(xy 237.617021 -79.06532) (xy 237.653508 -79.01777) (xy 237.695888 -78.97539) (xy 237.743438 -78.938903)
			(xy 237.795344 -78.908936) (xy 237.850717 -78.886) (xy 237.90861 -78.870487) (xy 237.968032 -78.862664)
			(xy 238.027968 -78.862664) (xy 238.08739 -78.870487) (xy 238.145283 -78.886) (xy 238.200656 -78.908936)
			(xy 238.207117 -78.912666) (xy 334.407009 -78.912666) (xy 334.407009 -78.852734) (xy 334.414832 -78.793315)
			(xy 334.430343 -78.735425) (xy 334.453278 -78.680055) (xy 334.483244 -78.628153) (xy 334.519729 -78.580606)
			(xy 334.562107 -78.538227) (xy 334.609654 -78.501743) (xy 334.661557 -78.471777) (xy 334.716927 -78.448843)
			(xy 334.774817 -78.433331) (xy 334.834236 -78.425509) (xy 334.864202 -78.42504) (xy 335.727802 -78.42504)
			(xy 335.757773 -78.425434) (xy 335.817201 -78.433258) (xy 335.8751 -78.448773) (xy 335.930479 -78.471711)
			(xy 335.982389 -78.501682) (xy 336.029944 -78.538172) (xy 336.072329 -78.580557) (xy 336.108819 -78.628112)
			(xy 336.13879 -78.680023) (xy 336.161728 -78.735402) (xy 336.177242 -78.793301) (xy 336.185066 -78.852729)
			(xy 336.185066 -78.912664) (xy 338.40703 -78.912664) (xy 338.40703 -78.852736) (xy 338.414852 -78.79332)
			(xy 338.430363 -78.735433) (xy 338.453296 -78.680067) (xy 338.48326 -78.628167) (xy 338.519742 -78.580622)
			(xy 338.562118 -78.538246) (xy 338.609662 -78.501763) (xy 338.661561 -78.471799) (xy 338.716928 -78.448865)
			(xy 338.774814 -78.433353) (xy 338.83423 -78.42553) (xy 338.864194 -78.42504) (xy 339.727794 -78.42504)
			(xy 339.757766 -78.425412) (xy 339.817199 -78.433236) (xy 339.875101 -78.44875) (xy 339.930483 -78.47169)
			(xy 339.982397 -78.501662) (xy 340.029955 -78.538153) (xy 340.072343 -78.580541) (xy 340.108835 -78.628098)
			(xy 340.138808 -78.680011) (xy 340.161748 -78.735393) (xy 340.177263 -78.793296) (xy 340.185087 -78.852728)
			(xy 340.185087 -78.912672) (xy 340.177263 -78.972104) (xy 340.161748 -79.030007) (xy 340.138808 -79.085389)
			(xy 340.108835 -79.137302) (xy 340.072343 -79.184859) (xy 340.029955 -79.227247) (xy 339.982397 -79.263738)
			(xy 339.930483 -79.29371) (xy 339.875101 -79.31665) (xy 339.817199 -79.332164) (xy 339.757766 -79.339988)
			(xy 339.727794 -79.340456) (xy 338.864194 -79.340456) (xy 338.83423 -79.33987) (xy 338.774814 -79.332047)
			(xy 338.716928 -79.316535) (xy 338.661561 -79.293601) (xy 338.609662 -79.263637) (xy 338.562118 -79.227154)
			(xy 338.519742 -79.184778) (xy 338.48326 -79.137233) (xy 338.453296 -79.085333) (xy 338.430363 -79.029967)
			(xy 338.414852 -78.97208) (xy 338.40703 -78.912664) (xy 336.185066 -78.912664) (xy 336.185066 -78.912671)
			(xy 336.177242 -78.972099) (xy 336.161728 -79.029998) (xy 336.13879 -79.085377) (xy 336.108819 -79.137288)
			(xy 336.072329 -79.184843) (xy 336.029944 -79.227228) (xy 335.982389 -79.263718) (xy 335.930479 -79.293689)
			(xy 335.8751 -79.316627) (xy 335.817201 -79.332142) (xy 335.757773 -79.339966) (xy 335.727802 -79.340456)
			(xy 334.864202 -79.340456) (xy 334.834236 -79.339891) (xy 334.774817 -79.332069) (xy 334.716927 -79.316557)
			(xy 334.661557 -79.293623) (xy 334.609654 -79.263657) (xy 334.562107 -79.227173) (xy 334.519729 -79.184794)
			(xy 334.483244 -79.137247) (xy 334.453278 -79.085345) (xy 334.430343 -79.029975) (xy 334.414832 -78.972085)
			(xy 334.407009 -78.912666) (xy 238.207117 -78.912666) (xy 238.252562 -78.938903) (xy 238.300112 -78.97539)
			(xy 238.342492 -79.01777) (xy 238.378979 -79.06532) (xy 238.408946 -79.117226) (xy 238.431882 -79.172599)
			(xy 238.447395 -79.230492) (xy 238.455218 -79.289914) (xy 238.455708 -79.319882) (xy 238.455708 -80.183482)
			(xy 238.455218 -80.21345) (xy 238.447395 -80.272872) (xy 238.431882 -80.330765) (xy 238.408946 -80.386138)
			(xy 238.378979 -80.438044) (xy 238.342492 -80.485594) (xy 238.300112 -80.527974) (xy 238.252562 -80.564461)
			(xy 238.200656 -80.594428) (xy 238.145283 -80.617364) (xy 238.08739 -80.632877) (xy 238.027968 -80.6407)
			(xy 237.968032 -80.6407) (xy 237.90861 -80.632877) (xy 237.850717 -80.617364) (xy 237.795344 -80.594428)
			(xy 237.743438 -80.564461) (xy 237.695888 -80.527974) (xy 237.653508 -80.485594) (xy 237.617021 -80.438044)
			(xy 237.587054 -80.386138) (xy 237.564118 -80.330765) (xy 237.548605 -80.272872) (xy 237.540782 -80.21345)
			(xy 237.540292 -80.183482) (xy 0.508 -80.183482) (xy 0.508 -82.131916) (xy 0.508487 -82.185165) (xy 0.516104 -82.291392)
			(xy 0.531277 -82.396804) (xy 0.553928 -82.500867) (xy 0.583941 -82.603049) (xy 0.621164 -82.702831)
			(xy 0.665407 -82.799705) (xy 0.716446 -82.893178) (xy 0.774019 -82.982773) (xy 0.837835 -83.068035)
			(xy 0.907568 -83.14853) (xy 0.94488 -83.186524) (xy 2.783716 -85.025538) (xy 44.856389 -85.025538)
			(xy 44.856389 -84.896398) (xy 44.864339 -84.767503) (xy 44.880209 -84.639343) (xy 44.903938 -84.512402)
			(xy 44.935437 -84.387163) (xy 44.974586 -84.2641) (xy 45.021237 -84.143681) (xy 45.075212 -84.026362)
			(xy 45.136307 -83.912588) (xy 45.20429 -83.802791) (xy 45.278904 -83.697388) (xy 45.359865 -83.596778)
			(xy 45.446865 -83.501343) (xy 45.539576 -83.411444) (xy 45.637646 -83.327423) (xy 45.740701 -83.249599)
			(xy 45.848352 -83.178267) (xy 45.960191 -83.113697) (xy 46.075792 -83.056135) (xy 46.194717 -83.005798)
			(xy 46.316516 -82.962878) (xy 46.440726 -82.927537) (xy 46.566875 -82.89991) (xy 46.694487 -82.880101)
			(xy 46.823076 -82.868185) (xy 46.952154 -82.864209) (xy 47.081232 -82.868185) (xy 47.209821 -82.880101)
			(xy 47.337433 -82.89991) (xy 47.463582 -82.927537) (xy 47.587792 -82.962878) (xy 47.709591 -83.005798)
			(xy 47.828516 -83.056135) (xy 47.944117 -83.113697) (xy 48.055956 -83.178267) (xy 48.163607 -83.249599)
			(xy 48.266662 -83.327423) (xy 48.303507 -83.35899) (xy 116.623592 -83.35899) (xy 116.623592 -82.49539)
			(xy 116.624082 -82.465422) (xy 116.631905 -82.406) (xy 116.647418 -82.348107) (xy 116.670354 -82.292734)
			(xy 116.700321 -82.240828) (xy 116.736808 -82.193278) (xy 116.779188 -82.150898) (xy 116.826738 -82.114411)
			(xy 116.878644 -82.084444) (xy 116.934017 -82.061508) (xy 116.99191 -82.045995) (xy 117.051332 -82.038172)
			(xy 117.111268 -82.038172) (xy 117.17069 -82.045995) (xy 117.228583 -82.061508) (xy 117.283956 -82.084444)
			(xy 117.335862 -82.114411) (xy 117.383412 -82.150898) (xy 117.425792 -82.193278) (xy 117.462279 -82.240828)
			(xy 117.492246 -82.292734) (xy 117.515182 -82.348107) (xy 117.530695 -82.406) (xy 117.538518 -82.465422)
			(xy 117.539008 -82.49539) (xy 117.539008 -83.35899) (xy 117.538875 -83.367118) (xy 232.68432 -83.367118)
			(xy 232.68432 -82.503518) (xy 232.68481 -82.47355) (xy 232.692633 -82.414128) (xy 232.708146 -82.356235)
			(xy 232.731082 -82.300862) (xy 232.761049 -82.248956) (xy 232.797536 -82.201406) (xy 232.839916 -82.159026)
			(xy 232.887466 -82.122539) (xy 232.939372 -82.092572) (xy 232.994745 -82.069636) (xy 233.052638 -82.054123)
			(xy 233.11206 -82.0463) (xy 233.171996 -82.0463) (xy 233.231418 -82.054123) (xy 233.289311 -82.069636)
			(xy 233.344684 -82.092572) (xy 233.39659 -82.122539) (xy 233.44414 -82.159026) (xy 233.48652 -82.201406)
			(xy 233.523007 -82.248956) (xy 233.552974 -82.300862) (xy 233.568014 -82.337171) (xy 238.132537 -82.337171)
			(xy 238.132537 -82.277229) (xy 238.140362 -82.217799) (xy 238.155876 -82.159898) (xy 238.178816 -82.104519)
			(xy 238.208788 -82.052607) (xy 238.24528 -82.005052) (xy 238.287667 -81.962667) (xy 238.335224 -81.926177)
			(xy 238.387137 -81.896207) (xy 238.442517 -81.87327) (xy 238.500418 -81.857758) (xy 238.559849 -81.849936)
			(xy 238.58982 -81.849468) (xy 239.45342 -81.849468) (xy 239.483385 -81.850007) (xy 239.542803 -81.857832)
			(xy 239.600691 -81.873345) (xy 239.656058 -81.896282) (xy 239.707959 -81.926248) (xy 239.755504 -81.962733)
			(xy 239.769238 -81.976468) (xy 273.798284 -81.976468) (xy 273.798284 -81.112868) (xy 273.798774 -81.0829)
			(xy 273.806597 -81.023478) (xy 273.82211 -80.965585) (xy 273.845046 -80.910212) (xy 273.875013 -80.858306)
			(xy 273.9115 -80.810756) (xy 273.95388 -80.768376) (xy 274.00143 -80.731889) (xy 274.053336 -80.701922)
			(xy 274.108709 -80.678986) (xy 274.166602 -80.663473) (xy 274.226024 -80.65565) (xy 274.28596 -80.65565)
			(xy 274.345382 -80.663473) (xy 274.403275 -80.678986) (xy 274.458648 -80.701922) (xy 274.510554 -80.731889)
			(xy 274.558104 -80.768376) (xy 274.600484 -80.810756) (xy 274.636971 -80.858306) (xy 274.666938 -80.910212)
			(xy 274.689874 -80.965585) (xy 274.705387 -81.023478) (xy 274.71321 -81.0829) (xy 274.7137 -81.112868)
			(xy 274.7137 -81.976468) (xy 274.71321 -82.006436) (xy 274.705387 -82.065858) (xy 274.689874 -82.123751)
			(xy 274.666938 -82.179124) (xy 274.636971 -82.23103) (xy 274.600484 -82.27858) (xy 274.558104 -82.32096)
			(xy 274.510554 -82.357447) (xy 274.458648 -82.387414) (xy 274.403275 -82.41035) (xy 274.345382 -82.425863)
			(xy 274.28596 -82.433686) (xy 274.226024 -82.433686) (xy 274.166602 -82.425863) (xy 274.108709 -82.41035)
			(xy 274.053336 -82.387414) (xy 274.00143 -82.357447) (xy 273.95388 -82.32096) (xy 273.9115 -82.27858)
			(xy 273.875013 -82.23103) (xy 273.845046 -82.179124) (xy 273.82211 -82.123751) (xy 273.806597 -82.065858)
			(xy 273.798774 -82.006436) (xy 273.798284 -81.976468) (xy 239.769238 -81.976468) (xy 239.79788 -82.005111)
			(xy 239.834363 -82.052658) (xy 239.864327 -82.10456) (xy 239.887261 -82.159928) (xy 239.902772 -82.217817)
			(xy 239.910594 -82.277235) (xy 239.910594 -82.337165) (xy 239.902772 -82.396583) (xy 239.887261 -82.454472)
			(xy 239.864327 -82.50984) (xy 239.834363 -82.561742) (xy 239.79788 -82.609289) (xy 239.755504 -82.651667)
			(xy 239.707959 -82.688152) (xy 239.656058 -82.718118) (xy 239.600691 -82.741055) (xy 239.542803 -82.756568)
			(xy 239.483385 -82.764393) (xy 239.45342 -82.764884) (xy 238.58982 -82.764884) (xy 238.559849 -82.764464)
			(xy 238.500418 -82.756642) (xy 238.442517 -82.74113) (xy 238.387137 -82.718193) (xy 238.335224 -82.688223)
			(xy 238.287667 -82.651733) (xy 238.24528 -82.609348) (xy 238.208788 -82.561793) (xy 238.178816 -82.509881)
			(xy 238.155876 -82.454502) (xy 238.140362 -82.396601) (xy 238.132537 -82.337171) (xy 233.568014 -82.337171)
			(xy 233.57591 -82.356235) (xy 233.591423 -82.414128) (xy 233.599246 -82.47355) (xy 233.599736 -82.503518)
			(xy 233.599736 -83.367118) (xy 233.599246 -83.397086) (xy 233.591423 -83.456508) (xy 233.57591 -83.514401)
			(xy 233.552974 -83.569774) (xy 233.523007 -83.62168) (xy 233.48652 -83.66923) (xy 233.44414 -83.71161)
			(xy 233.39659 -83.748097) (xy 233.344684 -83.778064) (xy 233.289311 -83.801) (xy 233.231418 -83.816513)
			(xy 233.171996 -83.824336) (xy 233.11206 -83.824336) (xy 233.052638 -83.816513) (xy 232.994745 -83.801)
			(xy 232.939372 -83.778064) (xy 232.887466 -83.748097) (xy 232.839916 -83.71161) (xy 232.797536 -83.66923)
			(xy 232.761049 -83.62168) (xy 232.731082 -83.569774) (xy 232.708146 -83.514401) (xy 232.692633 -83.456508)
			(xy 232.68481 -83.397086) (xy 232.68432 -83.367118) (xy 117.538875 -83.367118) (xy 117.538518 -83.388958)
			(xy 117.530695 -83.44838) (xy 117.515182 -83.506273) (xy 117.492246 -83.561646) (xy 117.462279 -83.613552)
			(xy 117.425792 -83.661102) (xy 117.383412 -83.703482) (xy 117.335862 -83.739969) (xy 117.283956 -83.769936)
			(xy 117.228583 -83.792872) (xy 117.17069 -83.808385) (xy 117.111268 -83.816208) (xy 117.051332 -83.816208)
			(xy 116.99191 -83.808385) (xy 116.934017 -83.792872) (xy 116.878644 -83.769936) (xy 116.826738 -83.739969)
			(xy 116.779188 -83.703482) (xy 116.736808 -83.661102) (xy 116.700321 -83.613552) (xy 116.670354 -83.561646)
			(xy 116.647418 -83.506273) (xy 116.631905 -83.44838) (xy 116.624082 -83.388958) (xy 116.623592 -83.35899)
			(xy 48.303507 -83.35899) (xy 48.364732 -83.411444) (xy 48.457443 -83.501343) (xy 48.544443 -83.596778)
			(xy 48.625404 -83.697388) (xy 48.700018 -83.802791) (xy 48.768001 -83.912588) (xy 48.829096 -84.026362)
			(xy 48.883071 -84.143681) (xy 48.929722 -84.2641) (xy 48.968871 -84.387163) (xy 49.00037 -84.512402)
			(xy 49.024099 -84.639343) (xy 49.039969 -84.767503) (xy 49.047919 -84.896398) (xy 49.048416 -84.960968)
			(xy 49.047919 -85.025538) (xy 49.039969 -85.154433) (xy 49.024099 -85.282593) (xy 49.009819 -85.358986)
			(xy 117.385592 -85.358986) (xy 117.385592 -84.495386) (xy 117.386082 -84.465418) (xy 117.393905 -84.405996)
			(xy 117.409418 -84.348103) (xy 117.432354 -84.29273) (xy 117.462321 -84.240824) (xy 117.498808 -84.193274)
			(xy 117.541188 -84.150894) (xy 117.588738 -84.114407) (xy 117.640644 -84.08444) (xy 117.696017 -84.061504)
			(xy 117.75391 -84.045991) (xy 117.813332 -84.038168) (xy 117.873268 -84.038168) (xy 117.93269 -84.045991)
			(xy 117.990583 -84.061504) (xy 118.045956 -84.08444) (xy 118.097862 -84.114407) (xy 118.145412 -84.150894)
			(xy 118.187792 -84.193274) (xy 118.224279 -84.240824) (xy 118.254246 -84.29273) (xy 118.277182 -84.348103)
			(xy 118.292695 -84.405996) (xy 118.300518 -84.465418) (xy 118.301008 -84.495386) (xy 118.301008 -85.358986)
			(xy 118.300518 -85.388954) (xy 118.292695 -85.448376) (xy 118.289959 -85.458587) (xy 232.264389 -85.458587)
			(xy 232.264389 -85.398613) (xy 232.272218 -85.339151) (xy 232.28774 -85.28122) (xy 232.310692 -85.225811)
			(xy 232.34068 -85.173871) (xy 232.377191 -85.126291) (xy 232.4196 -85.083883) (xy 232.467181 -85.047373)
			(xy 232.519122 -85.017387) (xy 232.574531 -84.994437) (xy 232.632463 -84.978915) (xy 232.691925 -84.971088)
			(xy 232.721912 -84.97062) (xy 233.585512 -84.97062) (xy 233.615495 -84.971147) (xy 233.674947 -84.978975)
			(xy 233.732868 -84.994497) (xy 233.788268 -85.017445) (xy 233.840199 -85.047429) (xy 233.887772 -85.083934)
			(xy 233.930174 -85.126337) (xy 233.963295 -85.169502) (xy 238.555276 -85.169502) (xy 238.555276 -84.305902)
			(xy 238.555766 -84.275918) (xy 238.563594 -84.216462) (xy 238.579115 -84.158537) (xy 238.602064 -84.103133)
			(xy 238.632048 -84.051199) (xy 238.668554 -84.003623) (xy 238.710959 -83.961218) (xy 238.758535 -83.924712)
			(xy 238.810469 -83.894728) (xy 238.865873 -83.871779) (xy 238.923798 -83.856258) (xy 238.983254 -83.84843)
			(xy 239.043222 -83.84843) (xy 239.102678 -83.856258) (xy 239.160603 -83.871779) (xy 239.216007 -83.894728)
			(xy 239.267941 -83.924712) (xy 239.315517 -83.961218) (xy 239.357922 -84.003623) (xy 239.394428 -84.051199)
			(xy 239.424412 -84.103133) (xy 239.447361 -84.158537) (xy 239.462882 -84.216462) (xy 239.46603 -84.24037)
			(xy 273.951192 -84.24037) (xy 273.951192 -83.37677) (xy 273.951682 -83.346786) (xy 273.95951 -83.28733)
			(xy 273.975031 -83.229405) (xy 273.99798 -83.174001) (xy 274.027964 -83.122067) (xy 274.06447 -83.074491)
			(xy 274.106875 -83.032086) (xy 274.154451 -82.99558) (xy 274.206385 -82.965596) (xy 274.261789 -82.942647)
			(xy 274.319714 -82.927126) (xy 274.37917 -82.919298) (xy 274.439138 -82.919298) (xy 274.498594 -82.927126)
			(xy 274.556519 -82.942647) (xy 274.611923 -82.965596) (xy 274.663857 -82.99558) (xy 274.711433 -83.032086)
			(xy 274.753838 -83.074491) (xy 274.790344 -83.122067) (xy 274.820328 -83.174001) (xy 274.843277 -83.229405)
			(xy 274.858798 -83.28733) (xy 274.866626 -83.346786) (xy 274.867116 -83.37677) (xy 274.867116 -84.144612)
			(xy 345.879928 -84.144612) (xy 345.879928 -83.281012) (xy 345.880418 -83.251028) (xy 345.888246 -83.191572)
			(xy 345.903767 -83.133647) (xy 345.926716 -83.078243) (xy 345.9567 -83.026309) (xy 345.993206 -82.978733)
			(xy 346.035611 -82.936328) (xy 346.083187 -82.899822) (xy 346.135121 -82.869838) (xy 346.190525 -82.846889)
			(xy 346.24845 -82.831368) (xy 346.307906 -82.82354) (xy 346.367874 -82.82354) (xy 346.42733 -82.831368)
			(xy 346.485255 -82.846889) (xy 346.540659 -82.869838) (xy 346.592593 -82.899822) (xy 346.640169 -82.936328)
			(xy 346.682574 -82.978733) (xy 346.71908 -83.026309) (xy 346.749064 -83.078243) (xy 346.772013 -83.133647)
			(xy 346.787534 -83.191572) (xy 346.795362 -83.251028) (xy 346.795852 -83.281012) (xy 346.795852 -84.144612)
			(xy 346.795362 -84.174596) (xy 346.787534 -84.234052) (xy 346.772013 -84.291977) (xy 346.749064 -84.347381)
			(xy 346.71908 -84.399315) (xy 346.682574 -84.446891) (xy 346.640169 -84.489296) (xy 346.592593 -84.525802)
			(xy 346.540659 -84.555786) (xy 346.485255 -84.578735) (xy 346.42733 -84.594256) (xy 346.367874 -84.602084)
			(xy 346.307906 -84.602084) (xy 346.24845 -84.594256) (xy 346.190525 -84.578735) (xy 346.135121 -84.555786)
			(xy 346.083187 -84.525802) (xy 346.035611 -84.489296) (xy 345.993206 -84.446891) (xy 345.9567 -84.399315)
			(xy 345.926716 -84.347381) (xy 345.903767 -84.291977) (xy 345.888246 -84.234052) (xy 345.880418 -84.174596)
			(xy 345.879928 -84.144612) (xy 274.867116 -84.144612) (xy 274.867116 -84.24037) (xy 274.866626 -84.270354)
			(xy 274.858798 -84.32981) (xy 274.843277 -84.387735) (xy 274.820328 -84.443139) (xy 274.790344 -84.495073)
			(xy 274.753838 -84.542649) (xy 274.711433 -84.585054) (xy 274.663857 -84.62156) (xy 274.611923 -84.651544)
			(xy 274.556519 -84.674493) (xy 274.498594 -84.690014) (xy 274.439138 -84.697842) (xy 274.37917 -84.697842)
			(xy 274.319714 -84.690014) (xy 274.261789 -84.674493) (xy 274.206385 -84.651544) (xy 274.154451 -84.62156)
			(xy 274.106875 -84.585054) (xy 274.06447 -84.542649) (xy 274.027964 -84.495073) (xy 273.99798 -84.443139)
			(xy 273.975031 -84.387735) (xy 273.95951 -84.32981) (xy 273.951682 -84.270354) (xy 273.951192 -84.24037)
			(xy 239.46603 -84.24037) (xy 239.47071 -84.275918) (xy 239.4712 -84.305902) (xy 239.4712 -85.169502)
			(xy 239.47071 -85.199486) (xy 239.462882 -85.258942) (xy 239.447361 -85.316867) (xy 239.424412 -85.372271)
			(xy 239.394428 -85.424205) (xy 239.357922 -85.471781) (xy 239.315517 -85.514186) (xy 239.267941 -85.550692)
			(xy 239.216007 -85.580676) (xy 239.160603 -85.603625) (xy 239.102678 -85.619146) (xy 239.043222 -85.626974)
			(xy 238.983254 -85.626974) (xy 238.923798 -85.619146) (xy 238.865873 -85.603625) (xy 238.810469 -85.580676)
			(xy 238.758535 -85.550692) (xy 238.710959 -85.514186) (xy 238.668554 -85.471781) (xy 238.632048 -85.424205)
			(xy 238.602064 -85.372271) (xy 238.579115 -85.316867) (xy 238.563594 -85.258942) (xy 238.555766 -85.199486)
			(xy 238.555276 -85.169502) (xy 233.963295 -85.169502) (xy 233.966678 -85.173911) (xy 233.99666 -85.225842)
			(xy 234.019607 -85.281243) (xy 234.035127 -85.339165) (xy 234.042954 -85.398617) (xy 234.042954 -85.458583)
			(xy 234.035127 -85.518035) (xy 234.019607 -85.575957) (xy 233.99666 -85.631358) (xy 233.966678 -85.683289)
			(xy 233.930174 -85.730863) (xy 233.887772 -85.773266) (xy 233.840199 -85.809771) (xy 233.788268 -85.839755)
			(xy 233.732868 -85.862703) (xy 233.674947 -85.878225) (xy 233.615495 -85.886053) (xy 233.585512 -85.886544)
			(xy 232.721912 -85.886544) (xy 232.691925 -85.886112) (xy 232.632463 -85.878285) (xy 232.574531 -85.862763)
			(xy 232.519122 -85.839813) (xy 232.467181 -85.809827) (xy 232.4196 -85.773317) (xy 232.377191 -85.730909)
			(xy 232.34068 -85.683329) (xy 232.310692 -85.631389) (xy 232.28774 -85.57598) (xy 232.272218 -85.518049)
			(xy 232.264389 -85.458587) (xy 118.289959 -85.458587) (xy 118.277182 -85.506269) (xy 118.254246 -85.561642)
			(xy 118.224279 -85.613548) (xy 118.187792 -85.661098) (xy 118.145412 -85.703478) (xy 118.097862 -85.739965)
			(xy 118.045956 -85.769932) (xy 117.990583 -85.792868) (xy 117.93269 -85.808381) (xy 117.873268 -85.816204)
			(xy 117.813332 -85.816204) (xy 117.75391 -85.808381) (xy 117.696017 -85.792868) (xy 117.640644 -85.769932)
			(xy 117.588738 -85.739965) (xy 117.541188 -85.703478) (xy 117.498808 -85.661098) (xy 117.462321 -85.613548)
			(xy 117.432354 -85.561642) (xy 117.409418 -85.506269) (xy 117.393905 -85.448376) (xy 117.386082 -85.388954)
			(xy 117.385592 -85.358986) (xy 49.009819 -85.358986) (xy 49.00037 -85.409534) (xy 48.968871 -85.534773)
			(xy 48.929722 -85.657836) (xy 48.883071 -85.778255) (xy 48.829096 -85.895574) (xy 48.768001 -86.009348)
			(xy 48.700018 -86.119145) (xy 48.625404 -86.224548) (xy 48.544443 -86.325158) (xy 48.457443 -86.420593)
			(xy 48.364732 -86.510492) (xy 48.266662 -86.594513) (xy 48.163607 -86.672337) (xy 48.055956 -86.743669)
			(xy 47.944117 -86.808239) (xy 47.937853 -86.811358) (xy 99.84232 -86.811358) (xy 99.84232 -85.947758)
			(xy 99.84281 -85.917774) (xy 99.850638 -85.858318) (xy 99.866159 -85.800393) (xy 99.889108 -85.744989)
			(xy 99.919092 -85.693055) (xy 99.955598 -85.645479) (xy 99.998003 -85.603074) (xy 100.045579 -85.566568)
			(xy 100.097513 -85.536584) (xy 100.152917 -85.513635) (xy 100.210842 -85.498114) (xy 100.270298 -85.490286)
			(xy 100.330266 -85.490286) (xy 100.389722 -85.498114) (xy 100.447647 -85.513635) (xy 100.503051 -85.536584)
			(xy 100.554985 -85.566568) (xy 100.602561 -85.603074) (xy 100.644966 -85.645479) (xy 100.681472 -85.693055)
			(xy 100.711456 -85.744989) (xy 100.734405 -85.800393) (xy 100.749926 -85.858318) (xy 100.757754 -85.917774)
			(xy 100.758244 -85.947758) (xy 100.758244 -86.811358) (xy 100.757754 -86.841342) (xy 100.749926 -86.900798)
			(xy 100.734405 -86.958723) (xy 100.711456 -87.014127) (xy 100.681472 -87.066061) (xy 100.644966 -87.113637)
			(xy 100.602561 -87.156042) (xy 100.554985 -87.192548) (xy 100.503051 -87.222532) (xy 100.447647 -87.245481)
			(xy 100.389722 -87.261002) (xy 100.330266 -87.26883) (xy 100.270298 -87.26883) (xy 100.210842 -87.261002)
			(xy 100.152917 -87.245481) (xy 100.097513 -87.222532) (xy 100.045579 -87.192548) (xy 99.998003 -87.156042)
			(xy 99.955598 -87.113637) (xy 99.919092 -87.066061) (xy 99.889108 -87.014127) (xy 99.866159 -86.958723)
			(xy 99.850638 -86.900798) (xy 99.84281 -86.841342) (xy 99.84232 -86.811358) (xy 47.937853 -86.811358)
			(xy 47.828516 -86.865801) (xy 47.709591 -86.916138) (xy 47.587792 -86.959058) (xy 47.463582 -86.994399)
			(xy 47.337433 -87.022026) (xy 47.209821 -87.041835) (xy 47.081232 -87.053751) (xy 46.952154 -87.057728)
			(xy 46.823076 -87.053751) (xy 46.694487 -87.041835) (xy 46.566875 -87.022026) (xy 46.440726 -86.994399)
			(xy 46.316516 -86.959058) (xy 46.194717 -86.916138) (xy 46.075792 -86.865801) (xy 45.960191 -86.808239)
			(xy 45.848352 -86.743669) (xy 45.740701 -86.672337) (xy 45.637646 -86.594513) (xy 45.539576 -86.510492)
			(xy 45.446865 -86.420593) (xy 45.359865 -86.325158) (xy 45.278904 -86.224548) (xy 45.20429 -86.119145)
			(xy 45.136307 -86.009348) (xy 45.075212 -85.895574) (xy 45.021237 -85.778255) (xy 44.974586 -85.657836)
			(xy 44.935437 -85.534773) (xy 44.903938 -85.409534) (xy 44.880209 -85.282593) (xy 44.864339 -85.154433)
			(xy 44.856389 -85.025538) (xy 2.783716 -85.025538) (xy 3.573272 -85.81517) (xy 3.622687 -85.865245)
			(xy 3.716468 -85.970133) (xy 3.804219 -86.080117) (xy 3.885663 -86.194848) (xy 3.960544 -86.313966)
			(xy 4.028628 -86.437097) (xy 4.089698 -86.563852) (xy 4.143563 -86.693833) (xy 4.190054 -86.82663)
			(xy 4.229024 -86.961825) (xy 4.260351 -87.098994) (xy 4.283935 -87.237703) (xy 4.297613 -87.358982)
			(xy 116.623592 -87.358982) (xy 116.623592 -86.495382) (xy 116.624082 -86.465414) (xy 116.631905 -86.405992)
			(xy 116.647418 -86.348099) (xy 116.670354 -86.292726) (xy 116.700321 -86.24082) (xy 116.736808 -86.19327)
			(xy 116.779188 -86.15089) (xy 116.826738 -86.114403) (xy 116.878644 -86.084436) (xy 116.934017 -86.0615)
			(xy 116.99191 -86.045987) (xy 117.051332 -86.038164) (xy 117.111268 -86.038164) (xy 117.17069 -86.045987)
			(xy 117.228583 -86.0615) (xy 117.283956 -86.084436) (xy 117.335862 -86.114403) (xy 117.383412 -86.15089)
			(xy 117.425792 -86.19327) (xy 117.462279 -86.24082) (xy 117.492246 -86.292726) (xy 117.515182 -86.348099)
			(xy 117.530695 -86.405992) (xy 117.538518 -86.465414) (xy 117.539008 -86.495382) (xy 117.539008 -87.358982)
			(xy 117.538518 -87.38895) (xy 117.531262 -87.444066) (xy 232.194882 -87.444066) (xy 232.194882 -87.384134)
			(xy 232.202704 -87.324714) (xy 232.218215 -87.266824) (xy 232.241149 -87.211454) (xy 232.271114 -87.15955)
			(xy 232.307596 -87.112002) (xy 232.349973 -87.069621) (xy 232.397519 -87.033135) (xy 232.44942 -87.003166)
			(xy 232.504788 -86.980227) (xy 232.562677 -86.964712) (xy 232.622096 -86.956884) (xy 232.652062 -86.956392)
			(xy 233.515662 -86.956392) (xy 233.545633 -86.956859) (xy 233.605062 -86.964678) (xy 233.662961 -86.980188)
			(xy 233.718341 -87.003123) (xy 233.770254 -87.033091) (xy 233.81781 -87.069578) (xy 233.860197 -87.111961)
			(xy 233.896688 -87.159515) (xy 233.92666 -87.211425) (xy 233.9496 -87.266803) (xy 233.965115 -87.324701)
			(xy 233.972939 -87.384129) (xy 233.972939 -87.416385) (xy 234.381521 -87.416385) (xy 234.381521 -87.356415)
			(xy 234.389349 -87.296959) (xy 234.40487 -87.239032) (xy 234.42782 -87.183628) (xy 234.457804 -87.131692)
			(xy 234.494312 -87.084115) (xy 234.536717 -87.04171) (xy 234.584294 -87.005203) (xy 234.636229 -86.975219)
			(xy 234.691634 -86.952269) (xy 234.749561 -86.936748) (xy 234.809017 -86.928921) (xy 234.839002 -86.928452)
			(xy 235.702602 -86.928452) (xy 235.732587 -86.928914) (xy 235.792044 -86.936742) (xy 235.849971 -86.952264)
			(xy 235.905376 -86.975214) (xy 235.957312 -87.005199) (xy 236.004889 -87.041707) (xy 236.047295 -87.084112)
			(xy 236.083802 -87.13169) (xy 236.113787 -87.183626) (xy 236.136737 -87.239031) (xy 236.152258 -87.296958)
			(xy 236.155843 -87.324184) (xy 330.477876 -87.324184) (xy 330.477876 -86.460584) (xy 330.478366 -86.430616)
			(xy 330.486189 -86.371194) (xy 330.501702 -86.313301) (xy 330.524638 -86.257928) (xy 330.554605 -86.206022)
			(xy 330.591092 -86.158472) (xy 330.633472 -86.116092) (xy 330.681022 -86.079605) (xy 330.732928 -86.049638)
			(xy 330.788301 -86.026702) (xy 330.846194 -86.011189) (xy 330.905616 -86.003366) (xy 330.965552 -86.003366)
			(xy 331.024974 -86.011189) (xy 331.082867 -86.026702) (xy 331.13824 -86.049638) (xy 331.190146 -86.079605)
			(xy 331.237696 -86.116092) (xy 331.266212 -86.144608) (xy 346.641928 -86.144608) (xy 346.641928 -85.281008)
			(xy 346.642418 -85.251024) (xy 346.650246 -85.191568) (xy 346.665767 -85.133643) (xy 346.688716 -85.078239)
			(xy 346.7187 -85.026305) (xy 346.755206 -84.978729) (xy 346.797611 -84.936324) (xy 346.845187 -84.899818)
			(xy 346.897121 -84.869834) (xy 346.952525 -84.846885) (xy 347.01045 -84.831364) (xy 347.069906 -84.823536)
			(xy 347.129874 -84.823536) (xy 347.18933 -84.831364) (xy 347.247255 -84.846885) (xy 347.302659 -84.869834)
			(xy 347.354593 -84.899818) (xy 347.402169 -84.936324) (xy 347.444574 -84.978729) (xy 347.48108 -85.026305)
			(xy 347.511064 -85.078239) (xy 347.534013 -85.133643) (xy 347.549534 -85.191568) (xy 347.557362 -85.251024)
			(xy 347.557852 -85.281008) (xy 347.557852 -86.144608) (xy 347.557362 -86.174592) (xy 347.549534 -86.234048)
			(xy 347.534013 -86.291973) (xy 347.511064 -86.347377) (xy 347.48108 -86.399311) (xy 347.444574 -86.446887)
			(xy 347.402169 -86.489292) (xy 347.354593 -86.525798) (xy 347.302659 -86.555782) (xy 347.247255 -86.578731)
			(xy 347.18933 -86.594252) (xy 347.129874 -86.60208) (xy 347.069906 -86.60208) (xy 347.01045 -86.594252)
			(xy 346.952525 -86.578731) (xy 346.897121 -86.555782) (xy 346.845187 -86.525798) (xy 346.797611 -86.489292)
			(xy 346.755206 -86.446887) (xy 346.7187 -86.399311) (xy 346.688716 -86.347377) (xy 346.665767 -86.291973)
			(xy 346.650246 -86.234048) (xy 346.642418 -86.174592) (xy 346.641928 -86.144608) (xy 331.266212 -86.144608)
			(xy 331.280076 -86.158472) (xy 331.316563 -86.206022) (xy 331.34653 -86.257928) (xy 331.369466 -86.313301)
			(xy 331.384979 -86.371194) (xy 331.392802 -86.430616) (xy 331.393292 -86.460584) (xy 331.393292 -87.324184)
			(xy 331.392802 -87.354152) (xy 331.384979 -87.413574) (xy 331.369466 -87.471467) (xy 331.34653 -87.52684)
			(xy 331.316563 -87.578746) (xy 331.280076 -87.626296) (xy 331.237696 -87.668676) (xy 331.190146 -87.705163)
			(xy 331.13824 -87.73513) (xy 331.082867 -87.758066) (xy 331.024974 -87.773579) (xy 330.965552 -87.781402)
			(xy 330.905616 -87.781402) (xy 330.846194 -87.773579) (xy 330.788301 -87.758066) (xy 330.732928 -87.73513)
			(xy 330.681022 -87.705163) (xy 330.633472 -87.668676) (xy 330.591092 -87.626296) (xy 330.554605 -87.578746)
			(xy 330.524638 -87.52684) (xy 330.501702 -87.471467) (xy 330.486189 -87.413574) (xy 330.478366 -87.354152)
			(xy 330.477876 -87.324184) (xy 236.155843 -87.324184) (xy 236.160086 -87.356415) (xy 236.160086 -87.416385)
			(xy 236.152258 -87.475842) (xy 236.136737 -87.533769) (xy 236.113787 -87.589174) (xy 236.083802 -87.64111)
			(xy 236.047295 -87.688688) (xy 236.004889 -87.731093) (xy 235.957312 -87.767601) (xy 235.905376 -87.797586)
			(xy 235.849971 -87.820536) (xy 235.792044 -87.836058) (xy 235.732587 -87.843886) (xy 235.702602 -87.844376)
			(xy 234.839002 -87.844376) (xy 234.809017 -87.843879) (xy 234.749561 -87.836052) (xy 234.691634 -87.820531)
			(xy 234.636229 -87.797581) (xy 234.584294 -87.767597) (xy 234.536717 -87.73109) (xy 234.494312 -87.688685)
			(xy 234.457804 -87.641108) (xy 234.42782 -87.589172) (xy 234.40487 -87.533768) (xy 234.389349 -87.475841)
			(xy 234.381521 -87.416385) (xy 233.972939 -87.416385) (xy 233.972939 -87.444071) (xy 233.965115 -87.503499)
			(xy 233.9496 -87.561397) (xy 233.92666 -87.616775) (xy 233.896688 -87.668685) (xy 233.860197 -87.716239)
			(xy 233.81781 -87.758622) (xy 233.770254 -87.795109) (xy 233.718341 -87.825077) (xy 233.662961 -87.848012)
			(xy 233.605062 -87.863522) (xy 233.545633 -87.871341) (xy 233.515662 -87.871808) (xy 232.652062 -87.871808)
			(xy 232.622096 -87.871316) (xy 232.562677 -87.863488) (xy 232.504788 -87.847973) (xy 232.44942 -87.825034)
			(xy 232.397519 -87.795065) (xy 232.349973 -87.758579) (xy 232.307596 -87.716198) (xy 232.271114 -87.66865)
			(xy 232.241149 -87.616746) (xy 232.218215 -87.561376) (xy 232.202704 -87.503486) (xy 232.194882 -87.444066)
			(xy 117.531262 -87.444066) (xy 117.530695 -87.448372) (xy 117.515182 -87.506265) (xy 117.492246 -87.561638)
			(xy 117.462279 -87.613544) (xy 117.425792 -87.661094) (xy 117.383412 -87.703474) (xy 117.335862 -87.739961)
			(xy 117.283956 -87.769928) (xy 117.228583 -87.792864) (xy 117.17069 -87.808377) (xy 117.111268 -87.8162)
			(xy 117.051332 -87.8162) (xy 116.99191 -87.808377) (xy 116.934017 -87.792864) (xy 116.878644 -87.769928)
			(xy 116.826738 -87.739961) (xy 116.779188 -87.703474) (xy 116.736808 -87.661094) (xy 116.700321 -87.613544)
			(xy 116.670354 -87.561638) (xy 116.647418 -87.506265) (xy 116.631905 -87.448372) (xy 116.624082 -87.38895)
			(xy 116.623592 -87.358982) (xy 4.297613 -87.358982) (xy 4.299703 -87.377516) (xy 4.307605 -87.517994)
			(xy 4.308094 -87.588344) (xy 4.308094 -88.006187) (xy 238.124409 -88.006187) (xy 238.124409 -87.946213)
			(xy 238.132238 -87.886751) (xy 238.147762 -87.82882) (xy 238.170714 -87.773411) (xy 238.200704 -87.721472)
			(xy 238.237216 -87.673892) (xy 238.279627 -87.631486) (xy 238.32721 -87.594978) (xy 238.379152 -87.564994)
			(xy 238.434563 -87.542047) (xy 238.492496 -87.526529) (xy 238.551959 -87.518706) (xy 238.581946 -87.51824)
			(xy 239.445546 -87.51824) (xy 239.475528 -87.518729) (xy 239.53498 -87.526561) (xy 239.5929 -87.542086)
			(xy 239.648299 -87.565038) (xy 239.700228 -87.595024) (xy 239.747799 -87.631531) (xy 239.790199 -87.673935)
			(xy 239.826701 -87.72151) (xy 239.856682 -87.773442) (xy 239.879628 -87.828843) (xy 239.895148 -87.886765)
			(xy 239.902974 -87.946217) (xy 239.902974 -88.006183) (xy 239.895148 -88.065635) (xy 239.879628 -88.123557)
			(xy 239.870911 -88.144604) (xy 345.879928 -88.144604) (xy 345.879928 -87.281004) (xy 345.880418 -87.25102)
			(xy 345.888246 -87.191564) (xy 345.903767 -87.133639) (xy 345.926716 -87.078235) (xy 345.9567 -87.026301)
			(xy 345.993206 -86.978725) (xy 346.035611 -86.93632) (xy 346.083187 -86.899814) (xy 346.135121 -86.86983)
			(xy 346.190525 -86.846881) (xy 346.24845 -86.83136) (xy 346.307906 -86.823532) (xy 346.367874 -86.823532)
			(xy 346.42733 -86.83136) (xy 346.485255 -86.846881) (xy 346.540659 -86.86983) (xy 346.592593 -86.899814)
			(xy 346.640169 -86.93632) (xy 346.682574 -86.978725) (xy 346.71908 -87.026301) (xy 346.749064 -87.078235)
			(xy 346.772013 -87.133639) (xy 346.787534 -87.191564) (xy 346.795362 -87.25102) (xy 346.795852 -87.281004)
			(xy 346.795852 -88.144604) (xy 346.795362 -88.174588) (xy 346.787534 -88.234044) (xy 346.772013 -88.291969)
			(xy 346.749064 -88.347373) (xy 346.71908 -88.399307) (xy 346.682574 -88.446883) (xy 346.640169 -88.489288)
			(xy 346.592593 -88.525794) (xy 346.540659 -88.555778) (xy 346.485255 -88.578727) (xy 346.42733 -88.594248)
			(xy 346.367874 -88.602076) (xy 346.307906 -88.602076) (xy 346.24845 -88.594248) (xy 346.190525 -88.578727)
			(xy 346.135121 -88.555778) (xy 346.083187 -88.525794) (xy 346.035611 -88.489288) (xy 345.993206 -88.446883)
			(xy 345.9567 -88.399307) (xy 345.926716 -88.347373) (xy 345.903767 -88.291969) (xy 345.888246 -88.234044)
			(xy 345.880418 -88.174588) (xy 345.879928 -88.144604) (xy 239.870911 -88.144604) (xy 239.856682 -88.178958)
			(xy 239.826701 -88.23089) (xy 239.790199 -88.278465) (xy 239.747799 -88.320869) (xy 239.700228 -88.357376)
			(xy 239.648299 -88.387362) (xy 239.5929 -88.410314) (xy 239.53498 -88.425839) (xy 239.475528 -88.433671)
			(xy 239.445546 -88.434164) (xy 238.581946 -88.434164) (xy 238.551959 -88.433694) (xy 238.492496 -88.425871)
			(xy 238.434563 -88.410353) (xy 238.379152 -88.387406) (xy 238.32721 -88.357422) (xy 238.279627 -88.320914)
			(xy 238.237216 -88.278508) (xy 238.200704 -88.230928) (xy 238.170714 -88.178989) (xy 238.147762 -88.12358)
			(xy 238.132238 -88.065649) (xy 238.124409 -88.006187) (xy 4.308094 -88.006187) (xy 4.308094 -89.358978)
			(xy 117.385592 -89.358978) (xy 117.385592 -88.495378) (xy 117.386082 -88.46541) (xy 117.393905 -88.405988)
			(xy 117.409418 -88.348095) (xy 117.432354 -88.292722) (xy 117.462321 -88.240816) (xy 117.498808 -88.193266)
			(xy 117.541188 -88.150886) (xy 117.588738 -88.114399) (xy 117.640644 -88.084432) (xy 117.696017 -88.061496)
			(xy 117.75391 -88.045983) (xy 117.813332 -88.03816) (xy 117.873268 -88.03816) (xy 117.93269 -88.045983)
			(xy 117.990583 -88.061496) (xy 118.045956 -88.084432) (xy 118.097862 -88.114399) (xy 118.145412 -88.150886)
			(xy 118.187792 -88.193266) (xy 118.224279 -88.240816) (xy 118.254246 -88.292722) (xy 118.277182 -88.348095)
			(xy 118.292695 -88.405988) (xy 118.300518 -88.46541) (xy 118.301008 -88.495378) (xy 118.301008 -89.358978)
			(xy 118.300518 -89.388946) (xy 118.292695 -89.448368) (xy 118.277182 -89.506261) (xy 118.254246 -89.561634)
			(xy 118.224279 -89.61354) (xy 118.187792 -89.66109) (xy 118.145412 -89.70347) (xy 118.097862 -89.739957)
			(xy 118.045956 -89.769924) (xy 117.990583 -89.79286) (xy 117.93269 -89.808373) (xy 117.873268 -89.816196)
			(xy 117.813332 -89.816196) (xy 117.75391 -89.808373) (xy 117.696017 -89.79286) (xy 117.640644 -89.769924)
			(xy 117.588738 -89.739957) (xy 117.541188 -89.70347) (xy 117.498808 -89.66109) (xy 117.462321 -89.61354)
			(xy 117.432354 -89.561634) (xy 117.409418 -89.506261) (xy 117.393905 -89.448368) (xy 117.386082 -89.388946)
			(xy 117.385592 -89.358978) (xy 4.308094 -89.358978) (xy 4.308094 -90.1446) (xy 346.641928 -90.1446)
			(xy 346.641928 -89.281) (xy 346.642418 -89.251016) (xy 346.650246 -89.19156) (xy 346.665767 -89.133635)
			(xy 346.688716 -89.078231) (xy 346.7187 -89.026297) (xy 346.755206 -88.978721) (xy 346.797611 -88.936316)
			(xy 346.845187 -88.89981) (xy 346.897121 -88.869826) (xy 346.952525 -88.846877) (xy 347.01045 -88.831356)
			(xy 347.069906 -88.823528) (xy 347.129874 -88.823528) (xy 347.18933 -88.831356) (xy 347.247255 -88.846877)
			(xy 347.302659 -88.869826) (xy 347.354593 -88.89981) (xy 347.402169 -88.936316) (xy 347.444574 -88.978721)
			(xy 347.48108 -89.026297) (xy 347.511064 -89.078231) (xy 347.534013 -89.133635) (xy 347.549534 -89.19156)
			(xy 347.557362 -89.251016) (xy 347.557852 -89.281) (xy 347.557852 -90.1446) (xy 347.557362 -90.174584)
			(xy 347.549534 -90.23404) (xy 347.534013 -90.291965) (xy 347.511064 -90.347369) (xy 347.48108 -90.399303)
			(xy 347.444574 -90.446879) (xy 347.402169 -90.489284) (xy 347.354593 -90.52579) (xy 347.302659 -90.555774)
			(xy 347.247255 -90.578723) (xy 347.18933 -90.594244) (xy 347.129874 -90.602072) (xy 347.069906 -90.602072)
			(xy 347.01045 -90.594244) (xy 346.952525 -90.578723) (xy 346.897121 -90.555774) (xy 346.845187 -90.52579)
			(xy 346.797611 -90.489284) (xy 346.755206 -90.446879) (xy 346.7187 -90.399303) (xy 346.688716 -90.347369)
			(xy 346.665767 -90.291965) (xy 346.650246 -90.23404) (xy 346.642418 -90.174584) (xy 346.641928 -90.1446)
			(xy 4.308094 -90.1446) (xy 4.308094 -94.088485) (xy 109.149614 -94.088485) (xy 109.149614 -94.028515)
			(xy 109.157442 -93.969058) (xy 109.172963 -93.911131) (xy 109.195912 -93.855726) (xy 109.225897 -93.80379)
			(xy 109.262405 -93.756213) (xy 109.30481 -93.713807) (xy 109.352387 -93.6773) (xy 109.404322 -93.647314)
			(xy 109.459727 -93.624364) (xy 109.517654 -93.608843) (xy 109.577111 -93.601014) (xy 109.607096 -93.600524)
			(xy 110.470696 -93.600524) (xy 110.500681 -93.601021) (xy 110.560138 -93.608848) (xy 110.618064 -93.624369)
			(xy 110.673469 -93.647318) (xy 110.725405 -93.677303) (xy 110.772982 -93.71381) (xy 110.815388 -93.756215)
			(xy 110.851895 -93.803792) (xy 110.88188 -93.855727) (xy 110.90483 -93.911132) (xy 110.920351 -93.969058)
			(xy 110.928179 -94.028515) (xy 110.928179 -94.088485) (xy 110.920351 -94.147942) (xy 110.90483 -94.205868)
			(xy 110.88188 -94.261273) (xy 110.851895 -94.313208) (xy 110.815388 -94.360785) (xy 110.772982 -94.40319)
			(xy 110.725405 -94.439697) (xy 110.673469 -94.469682) (xy 110.618064 -94.492631) (xy 110.560138 -94.508152)
			(xy 110.500681 -94.515979) (xy 110.470696 -94.516448) (xy 109.607096 -94.516448) (xy 109.577111 -94.515986)
			(xy 109.517654 -94.508157) (xy 109.459727 -94.492636) (xy 109.404322 -94.469686) (xy 109.352387 -94.4397)
			(xy 109.30481 -94.403193) (xy 109.262405 -94.360787) (xy 109.225897 -94.31321) (xy 109.195912 -94.261274)
			(xy 109.172963 -94.205869) (xy 109.157442 -94.147942) (xy 109.149614 -94.088485) (xy 4.308094 -94.088485)
			(xy 4.308094 -95.214948) (xy 47.274239 -95.214948) (xy 47.278194 -95.123111) (xy 47.290029 -95.031954)
			(xy 47.309656 -94.942151) (xy 47.33693 -94.854369) (xy 47.37165 -94.769255) (xy 47.413558 -94.687442)
			(xy 47.462344 -94.609534) (xy 47.517647 -94.536109) (xy 47.579057 -94.467709) (xy 47.646119 -94.404842)
			(xy 47.718338 -94.347972) (xy 47.795178 -94.297521) (xy 47.876071 -94.253862) (xy 47.960417 -94.217319)
			(xy 48.047593 -94.188162) (xy 48.136952 -94.166608) (xy 48.227833 -94.152814) (xy 48.319564 -94.146884)
			(xy 48.411465 -94.148862) (xy 48.502856 -94.158733) (xy 48.59306 -94.176423) (xy 48.681409 -94.201803)
			(xy 48.767249 -94.234683) (xy 48.849945 -94.274821) (xy 48.928885 -94.32192) (xy 49.003483 -94.37563)
			(xy 49.073189 -94.435554) (xy 49.137484 -94.501248) (xy 49.195895 -94.572226) (xy 49.247987 -94.647963)
			(xy 49.293376 -94.727898) (xy 49.331726 -94.811438) (xy 49.362751 -94.897966) (xy 49.386224 -94.986841)
			(xy 49.40197 -95.077405) (xy 49.409872 -95.168987) (xy 49.410366 -95.214948) (xy 71.639189 -95.214948)
			(xy 71.643144 -95.123111) (xy 71.654979 -95.031954) (xy 71.674606 -94.942151) (xy 71.70188 -94.854369)
			(xy 71.7366 -94.769255) (xy 71.778508 -94.687442) (xy 71.827294 -94.609534) (xy 71.882597 -94.536109)
			(xy 71.944007 -94.467709) (xy 72.011069 -94.404842) (xy 72.083288 -94.347972) (xy 72.160128 -94.297521)
			(xy 72.241021 -94.253862) (xy 72.325367 -94.217319) (xy 72.412543 -94.188162) (xy 72.501902 -94.166608)
			(xy 72.592783 -94.152814) (xy 72.684514 -94.146884) (xy 72.776415 -94.148862) (xy 72.867806 -94.158733)
			(xy 72.95801 -94.176423) (xy 73.046359 -94.201803) (xy 73.132199 -94.234683) (xy 73.214895 -94.274821)
			(xy 73.293835 -94.32192) (xy 73.368433 -94.37563) (xy 73.438139 -94.435554) (xy 73.502434 -94.501248)
			(xy 73.560845 -94.572226) (xy 73.612937 -94.647963) (xy 73.658326 -94.727898) (xy 73.696676 -94.811438)
			(xy 73.727701 -94.897966) (xy 73.751174 -94.986841) (xy 73.76692 -95.077405) (xy 73.774822 -95.168987)
			(xy 73.775316 -95.214948) (xy 73.774822 -95.260909) (xy 73.774772 -95.261486) (xy 163.375394 -95.261486)
			(xy 163.375394 -95.168314) (xy 163.383515 -95.075496) (xy 163.399694 -94.983738) (xy 163.423808 -94.893741)
			(xy 163.455675 -94.806187) (xy 163.495052 -94.721744) (xy 163.541638 -94.641054) (xy 163.595079 -94.564731)
			(xy 163.654969 -94.493357) (xy 163.720852 -94.427473) (xy 163.792226 -94.367583) (xy 163.868549 -94.314141)
			(xy 163.949238 -94.267554) (xy 164.033681 -94.228178) (xy 164.121235 -94.19631) (xy 164.211233 -94.172195)
			(xy 164.30299 -94.156015) (xy 164.395808 -94.147894) (xy 164.442394 -94.147386) (xy 164.442648 -94.147386)
			(xy 164.489237 -94.1478) (xy 164.582061 -94.155925) (xy 164.673824 -94.172109) (xy 164.763826 -94.196229)
			(xy 164.851385 -94.228101) (xy 164.935832 -94.267483) (xy 165.016526 -94.314074) (xy 165.092852 -94.367522)
			(xy 165.164229 -94.427418) (xy 165.230115 -94.493306) (xy 165.290008 -94.564687) (xy 165.343451 -94.641015)
			(xy 165.390039 -94.721711) (xy 165.429417 -94.80616) (xy 165.461286 -94.893719) (xy 165.485401 -94.983723)
			(xy 165.501581 -95.075487) (xy 165.509702 -95.168311) (xy 165.509702 -95.214948) (xy 187.739796 -95.214948)
			(xy 187.743748 -95.123155) (xy 187.755578 -95.032041) (xy 187.775195 -94.942281) (xy 187.802457 -94.85454)
			(xy 187.83716 -94.769468) (xy 187.879048 -94.687693) (xy 187.927811 -94.609822) (xy 187.983087 -94.536432)
			(xy 188.044468 -94.468065) (xy 188.111499 -94.405227) (xy 188.183683 -94.348385) (xy 188.260487 -94.297958)
			(xy 188.341341 -94.25432) (xy 188.425647 -94.217794) (xy 188.512781 -94.188651) (xy 188.602098 -94.167106)
			(xy 188.692936 -94.15332) (xy 188.784623 -94.147393) (xy 188.87648 -94.14937) (xy 188.967828 -94.159236)
			(xy 189.057988 -94.176918) (xy 189.146296 -94.202285) (xy 189.232095 -94.23515) (xy 189.314752 -94.275269)
			(xy 189.393654 -94.322345) (xy 189.468217 -94.376029) (xy 189.537889 -94.435925) (xy 189.602154 -94.501588)
			(xy 189.660537 -94.572532) (xy 189.712604 -94.648233) (xy 189.757972 -94.72813) (xy 189.796303 -94.81163)
			(xy 189.827314 -94.898117) (xy 189.850775 -94.98695) (xy 189.866514 -95.07747) (xy 189.874412 -95.169009)
			(xy 189.874906 -95.214948) (xy 279.474181 -95.214948) (xy 279.478136 -95.123111) (xy 279.489971 -95.031954)
			(xy 279.509598 -94.942151) (xy 279.536872 -94.854369) (xy 279.571592 -94.769255) (xy 279.6135 -94.687442)
			(xy 279.662286 -94.609534) (xy 279.717589 -94.536109) (xy 279.778999 -94.467709) (xy 279.846061 -94.404842)
			(xy 279.91828 -94.347972) (xy 279.99512 -94.297521) (xy 280.076013 -94.253862) (xy 280.160359 -94.217319)
			(xy 280.247535 -94.188162) (xy 280.336894 -94.166608) (xy 280.427775 -94.152814) (xy 280.519506 -94.146884)
			(xy 280.611407 -94.148862) (xy 280.702798 -94.158733) (xy 280.793002 -94.176423) (xy 280.881351 -94.201803)
			(xy 280.967191 -94.234683) (xy 281.049887 -94.274821) (xy 281.128827 -94.32192) (xy 281.203425 -94.37563)
			(xy 281.273131 -94.435554) (xy 281.337426 -94.501248) (xy 281.395837 -94.572226) (xy 281.447929 -94.647963)
			(xy 281.493318 -94.727898) (xy 281.531668 -94.811438) (xy 281.562693 -94.897966) (xy 281.586166 -94.986841)
			(xy 281.601912 -95.077405) (xy 281.609814 -95.168987) (xy 281.610308 -95.214948) (xy 303.839131 -95.214948)
			(xy 303.843086 -95.123111) (xy 303.854921 -95.031954) (xy 303.874548 -94.942151) (xy 303.901822 -94.854369)
			(xy 303.936542 -94.769255) (xy 303.97845 -94.687442) (xy 304.027236 -94.609534) (xy 304.082539 -94.536109)
			(xy 304.143949 -94.467709) (xy 304.211011 -94.404842) (xy 304.28323 -94.347972) (xy 304.36007 -94.297521)
			(xy 304.440963 -94.253862) (xy 304.525309 -94.217319) (xy 304.612485 -94.188162) (xy 304.701844 -94.166608)
			(xy 304.792725 -94.152814) (xy 304.884456 -94.146884) (xy 304.976357 -94.148862) (xy 305.067748 -94.158733)
			(xy 305.157952 -94.176423) (xy 305.246301 -94.201803) (xy 305.332141 -94.234683) (xy 305.414837 -94.274821)
			(xy 305.493777 -94.32192) (xy 305.568375 -94.37563) (xy 305.638081 -94.435554) (xy 305.702376 -94.501248)
			(xy 305.760787 -94.572226) (xy 305.812879 -94.647963) (xy 305.858268 -94.727898) (xy 305.896618 -94.811438)
			(xy 305.91901 -94.87389) (xy 338.405861 -94.87389) (xy 338.405861 -94.81391) (xy 338.413691 -94.754443)
			(xy 338.429215 -94.696507) (xy 338.45217 -94.641093) (xy 338.482161 -94.58915) (xy 338.518676 -94.541565)
			(xy 338.561089 -94.499155) (xy 338.608676 -94.462643) (xy 338.660622 -94.432655) (xy 338.716037 -94.409705)
			(xy 338.773975 -94.394184) (xy 338.833442 -94.386359) (xy 338.863432 -94.385892) (xy 339.727032 -94.385892)
			(xy 339.757012 -94.386476) (xy 339.816458 -94.394306) (xy 339.874374 -94.409828) (xy 339.929769 -94.432777)
			(xy 339.981694 -94.462759) (xy 340.029262 -94.499262) (xy 340.071659 -94.541662) (xy 340.108159 -94.589232)
			(xy 340.138137 -94.64116) (xy 340.161082 -94.696556) (xy 340.1766 -94.754473) (xy 340.184426 -94.81392)
			(xy 340.184426 -94.87388) (xy 340.1766 -94.933327) (xy 340.161082 -94.991244) (xy 340.138137 -95.04664)
			(xy 340.108159 -95.098568) (xy 340.071659 -95.146138) (xy 340.029262 -95.188538) (xy 339.994846 -95.214948)
			(xy 395.574279 -95.214948) (xy 395.578234 -95.123111) (xy 395.590069 -95.031954) (xy 395.609696 -94.942151)
			(xy 395.63697 -94.854369) (xy 395.67169 -94.769255) (xy 395.713598 -94.687442) (xy 395.762384 -94.609534)
			(xy 395.817687 -94.536109) (xy 395.879097 -94.467709) (xy 395.946159 -94.404842) (xy 396.018378 -94.347972)
			(xy 396.095218 -94.297521) (xy 396.176111 -94.253862) (xy 396.260457 -94.217319) (xy 396.347633 -94.188162)
			(xy 396.436992 -94.166608) (xy 396.527873 -94.152814) (xy 396.619604 -94.146884) (xy 396.711505 -94.148862)
			(xy 396.802896 -94.158733) (xy 396.8931 -94.176423) (xy 396.981449 -94.201803) (xy 397.067289 -94.234683)
			(xy 397.149985 -94.274821) (xy 397.228925 -94.32192) (xy 397.303523 -94.37563) (xy 397.373229 -94.435554)
			(xy 397.437524 -94.501248) (xy 397.495935 -94.572226) (xy 397.548027 -94.647963) (xy 397.593416 -94.727898)
			(xy 397.631766 -94.811438) (xy 397.662791 -94.897966) (xy 397.686264 -94.986841) (xy 397.70201 -95.077405)
			(xy 397.709912 -95.168987) (xy 397.710406 -95.214948) (xy 419.939229 -95.214948) (xy 419.943184 -95.123111)
			(xy 419.955019 -95.031954) (xy 419.974646 -94.942151) (xy 420.00192 -94.854369) (xy 420.03664 -94.769255)
			(xy 420.078548 -94.687442) (xy 420.127334 -94.609534) (xy 420.182637 -94.536109) (xy 420.244047 -94.467709)
			(xy 420.311109 -94.404842) (xy 420.383328 -94.347972) (xy 420.460168 -94.297521) (xy 420.541061 -94.253862)
			(xy 420.625407 -94.217319) (xy 420.712583 -94.188162) (xy 420.801942 -94.166608) (xy 420.892823 -94.152814)
			(xy 420.984554 -94.146884) (xy 421.076455 -94.148862) (xy 421.167846 -94.158733) (xy 421.25805 -94.176423)
			(xy 421.346399 -94.201803) (xy 421.432239 -94.234683) (xy 421.514935 -94.274821) (xy 421.593875 -94.32192)
			(xy 421.668473 -94.37563) (xy 421.738179 -94.435554) (xy 421.802474 -94.501248) (xy 421.860885 -94.572226)
			(xy 421.912977 -94.647963) (xy 421.958366 -94.727898) (xy 421.996716 -94.811438) (xy 422.027741 -94.897966)
			(xy 422.051214 -94.986841) (xy 422.06696 -95.077405) (xy 422.074862 -95.168987) (xy 422.075356 -95.214948)
			(xy 422.074862 -95.260909) (xy 422.06696 -95.352491) (xy 422.051214 -95.443055) (xy 422.027741 -95.53193)
			(xy 421.996716 -95.618458) (xy 421.958366 -95.701998) (xy 421.912977 -95.781933) (xy 421.860885 -95.85767)
			(xy 421.802474 -95.928648) (xy 421.738179 -95.994342) (xy 421.668473 -96.054266) (xy 421.593875 -96.107976)
			(xy 421.514935 -96.155075) (xy 421.432239 -96.195213) (xy 421.346399 -96.228093) (xy 421.25805 -96.253473)
			(xy 421.167846 -96.271163) (xy 421.076455 -96.281034) (xy 420.984554 -96.283012) (xy 420.892823 -96.277082)
			(xy 420.801942 -96.263288) (xy 420.712583 -96.241734) (xy 420.625407 -96.212577) (xy 420.541061 -96.176034)
			(xy 420.460168 -96.132375) (xy 420.383328 -96.081924) (xy 420.311109 -96.025054) (xy 420.244047 -95.962187)
			(xy 420.182637 -95.893787) (xy 420.127334 -95.820362) (xy 420.078548 -95.742454) (xy 420.03664 -95.660641)
			(xy 420.00192 -95.575527) (xy 419.974646 -95.487745) (xy 419.955019 -95.397942) (xy 419.943184 -95.306785)
			(xy 419.939229 -95.214948) (xy 397.710406 -95.214948) (xy 397.709912 -95.260909) (xy 397.70201 -95.352491)
			(xy 397.686264 -95.443055) (xy 397.662791 -95.53193) (xy 397.631766 -95.618458) (xy 397.593416 -95.701998)
			(xy 397.548027 -95.781933) (xy 397.495935 -95.85767) (xy 397.437524 -95.928648) (xy 397.373229 -95.994342)
			(xy 397.303523 -96.054266) (xy 397.228925 -96.107976) (xy 397.149985 -96.155075) (xy 397.067289 -96.195213)
			(xy 396.981449 -96.228093) (xy 396.8931 -96.253473) (xy 396.802896 -96.271163) (xy 396.711505 -96.281034)
			(xy 396.619604 -96.283012) (xy 396.527873 -96.277082) (xy 396.436992 -96.263288) (xy 396.347633 -96.241734)
			(xy 396.260457 -96.212577) (xy 396.176111 -96.176034) (xy 396.095218 -96.132375) (xy 396.018378 -96.081924)
			(xy 395.946159 -96.025054) (xy 395.879097 -95.962187) (xy 395.817687 -95.893787) (xy 395.762384 -95.820362)
			(xy 395.713598 -95.742454) (xy 395.67169 -95.660641) (xy 395.63697 -95.575527) (xy 395.609696 -95.487745)
			(xy 395.590069 -95.397942) (xy 395.578234 -95.306785) (xy 395.574279 -95.214948) (xy 339.994846 -95.214948)
			(xy 339.981694 -95.225041) (xy 339.929769 -95.255023) (xy 339.874374 -95.277972) (xy 339.816458 -95.293494)
			(xy 339.757012 -95.301324) (xy 339.727032 -95.301816) (xy 338.863432 -95.301816) (xy 338.833442 -95.301441)
			(xy 338.773975 -95.293616) (xy 338.716037 -95.278095) (xy 338.660622 -95.255145) (xy 338.608676 -95.225157)
			(xy 338.561089 -95.188645) (xy 338.518676 -95.146235) (xy 338.482161 -95.09865) (xy 338.45217 -95.046707)
			(xy 338.429215 -94.991293) (xy 338.413691 -94.933357) (xy 338.405861 -94.87389) (xy 305.91901 -94.87389)
			(xy 305.927643 -94.897966) (xy 305.951116 -94.986841) (xy 305.966862 -95.077405) (xy 305.974764 -95.168987)
			(xy 305.975258 -95.214948) (xy 305.974764 -95.260909) (xy 305.966862 -95.352491) (xy 305.951116 -95.443055)
			(xy 305.927643 -95.53193) (xy 305.896618 -95.618458) (xy 305.858268 -95.701998) (xy 305.812879 -95.781933)
			(xy 305.760787 -95.85767) (xy 305.702376 -95.928648) (xy 305.638081 -95.994342) (xy 305.568375 -96.054266)
			(xy 305.493777 -96.107976) (xy 305.414837 -96.155075) (xy 305.332141 -96.195213) (xy 305.246301 -96.228093)
			(xy 305.157952 -96.253473) (xy 305.067748 -96.271163) (xy 304.976357 -96.281034) (xy 304.884456 -96.283012)
			(xy 304.792725 -96.277082) (xy 304.701844 -96.263288) (xy 304.612485 -96.241734) (xy 304.525309 -96.212577)
			(xy 304.440963 -96.176034) (xy 304.36007 -96.132375) (xy 304.28323 -96.081924) (xy 304.211011 -96.025054)
			(xy 304.143949 -95.962187) (xy 304.082539 -95.893787) (xy 304.027236 -95.820362) (xy 303.97845 -95.742454)
			(xy 303.936542 -95.660641) (xy 303.901822 -95.575527) (xy 303.874548 -95.487745) (xy 303.854921 -95.397942)
			(xy 303.843086 -95.306785) (xy 303.839131 -95.214948) (xy 281.610308 -95.214948) (xy 281.609814 -95.260909)
			(xy 281.601912 -95.352491) (xy 281.586166 -95.443055) (xy 281.562693 -95.53193) (xy 281.531668 -95.618458)
			(xy 281.493318 -95.701998) (xy 281.447929 -95.781933) (xy 281.395837 -95.85767) (xy 281.337426 -95.928648)
			(xy 281.273131 -95.994342) (xy 281.203425 -96.054266) (xy 281.128827 -96.107976) (xy 281.049887 -96.155075)
			(xy 280.967191 -96.195213) (xy 280.881351 -96.228093) (xy 280.793002 -96.253473) (xy 280.702798 -96.271163)
			(xy 280.611407 -96.281034) (xy 280.519506 -96.283012) (xy 280.427775 -96.277082) (xy 280.336894 -96.263288)
			(xy 280.247535 -96.241734) (xy 280.160359 -96.212577) (xy 280.076013 -96.176034) (xy 279.99512 -96.132375)
			(xy 279.91828 -96.081924) (xy 279.846061 -96.025054) (xy 279.778999 -95.962187) (xy 279.717589 -95.893787)
			(xy 279.662286 -95.820362) (xy 279.6135 -95.742454) (xy 279.571592 -95.660641) (xy 279.536872 -95.575527)
			(xy 279.509598 -95.487745) (xy 279.489971 -95.397942) (xy 279.478136 -95.306785) (xy 279.474181 -95.214948)
			(xy 189.874906 -95.214948) (xy 189.874412 -95.260887) (xy 189.866514 -95.352426) (xy 189.850775 -95.442946)
			(xy 189.827314 -95.531779) (xy 189.796303 -95.618266) (xy 189.757972 -95.701766) (xy 189.712604 -95.781663)
			(xy 189.660537 -95.857364) (xy 189.602154 -95.928308) (xy 189.537889 -95.993971) (xy 189.468217 -96.053867)
			(xy 189.393654 -96.107551) (xy 189.314752 -96.154627) (xy 189.232095 -96.194746) (xy 189.146296 -96.227611)
			(xy 189.057988 -96.252978) (xy 188.967828 -96.27066) (xy 188.87648 -96.280526) (xy 188.784623 -96.282503)
			(xy 188.692936 -96.276576) (xy 188.602098 -96.26279) (xy 188.512781 -96.241245) (xy 188.425647 -96.212102)
			(xy 188.341341 -96.175576) (xy 188.260487 -96.131938) (xy 188.183683 -96.081511) (xy 188.111499 -96.024669)
			(xy 188.044468 -95.961831) (xy 187.983087 -95.893464) (xy 187.927811 -95.820074) (xy 187.879048 -95.742203)
			(xy 187.83716 -95.660428) (xy 187.802457 -95.575356) (xy 187.775195 -95.487615) (xy 187.755578 -95.397855)
			(xy 187.743748 -95.306741) (xy 187.739796 -95.214948) (xy 165.509702 -95.214948) (xy 165.509702 -95.261489)
			(xy 165.501581 -95.354313) (xy 165.485401 -95.446077) (xy 165.461286 -95.536081) (xy 165.429417 -95.62364)
			(xy 165.390039 -95.708089) (xy 165.343451 -95.788785) (xy 165.290008 -95.865113) (xy 165.230115 -95.936494)
			(xy 165.164229 -96.002382) (xy 165.092852 -96.062278) (xy 165.016526 -96.115726) (xy 164.935832 -96.162317)
			(xy 164.851385 -96.201699) (xy 164.763826 -96.233571) (xy 164.673824 -96.257691) (xy 164.582061 -96.273875)
			(xy 164.489237 -96.282) (xy 164.442648 -96.28251) (xy 164.442394 -96.28251) (xy 164.395808 -96.281906)
			(xy 164.30299 -96.273785) (xy 164.211233 -96.257605) (xy 164.121235 -96.23349) (xy 164.033681 -96.201622)
			(xy 163.949238 -96.162246) (xy 163.868549 -96.115659) (xy 163.792226 -96.062217) (xy 163.720852 -96.002327)
			(xy 163.654969 -95.936443) (xy 163.595079 -95.865069) (xy 163.541638 -95.788746) (xy 163.495052 -95.708056)
			(xy 163.455675 -95.623613) (xy 163.423808 -95.536059) (xy 163.399694 -95.446062) (xy 163.383515 -95.354304)
			(xy 163.375394 -95.261486) (xy 73.774772 -95.261486) (xy 73.76692 -95.352491) (xy 73.751174 -95.443055)
			(xy 73.727701 -95.53193) (xy 73.696676 -95.618458) (xy 73.658326 -95.701998) (xy 73.612937 -95.781933)
			(xy 73.560845 -95.85767) (xy 73.502434 -95.928648) (xy 73.438139 -95.994342) (xy 73.368433 -96.054266)
			(xy 73.293835 -96.107976) (xy 73.214895 -96.155075) (xy 73.132199 -96.195213) (xy 73.046359 -96.228093)
			(xy 72.95801 -96.253473) (xy 72.867806 -96.271163) (xy 72.776415 -96.281034) (xy 72.684514 -96.283012)
			(xy 72.592783 -96.277082) (xy 72.501902 -96.263288) (xy 72.412543 -96.241734) (xy 72.325367 -96.212577)
			(xy 72.241021 -96.176034) (xy 72.160128 -96.132375) (xy 72.083288 -96.081924) (xy 72.011069 -96.025054)
			(xy 71.944007 -95.962187) (xy 71.882597 -95.893787) (xy 71.827294 -95.820362) (xy 71.778508 -95.742454)
			(xy 71.7366 -95.660641) (xy 71.70188 -95.575527) (xy 71.674606 -95.487745) (xy 71.654979 -95.397942)
			(xy 71.643144 -95.306785) (xy 71.639189 -95.214948) (xy 49.410366 -95.214948) (xy 49.409872 -95.260909)
			(xy 49.40197 -95.352491) (xy 49.386224 -95.443055) (xy 49.362751 -95.53193) (xy 49.331726 -95.618458)
			(xy 49.293376 -95.701998) (xy 49.247987 -95.781933) (xy 49.195895 -95.85767) (xy 49.137484 -95.928648)
			(xy 49.073189 -95.994342) (xy 49.003483 -96.054266) (xy 48.928885 -96.107976) (xy 48.849945 -96.155075)
			(xy 48.767249 -96.195213) (xy 48.681409 -96.228093) (xy 48.59306 -96.253473) (xy 48.502856 -96.271163)
			(xy 48.411465 -96.281034) (xy 48.319564 -96.283012) (xy 48.227833 -96.277082) (xy 48.136952 -96.263288)
			(xy 48.047593 -96.241734) (xy 47.960417 -96.212577) (xy 47.876071 -96.176034) (xy 47.795178 -96.132375)
			(xy 47.718338 -96.081924) (xy 47.646119 -96.025054) (xy 47.579057 -95.962187) (xy 47.517647 -95.893787)
			(xy 47.462344 -95.820362) (xy 47.413558 -95.742454) (xy 47.37165 -95.660641) (xy 47.33693 -95.575527)
			(xy 47.309656 -95.487745) (xy 47.290029 -95.397942) (xy 47.278194 -95.306785) (xy 47.274239 -95.214948)
			(xy 4.308094 -95.214948) (xy 4.308094 -98.766863) (xy 206.090008 -98.766863) (xy 206.090008 -98.633301)
			(xy 206.098072 -98.499983) (xy 206.114172 -98.367395) (xy 206.138247 -98.236021) (xy 206.17021 -98.10634)
			(xy 206.209945 -97.978826) (xy 206.257307 -97.853943) (xy 206.312122 -97.732148) (xy 206.374192 -97.613885)
			(xy 206.443288 -97.499586) (xy 206.51916 -97.389666) (xy 206.60153 -97.284529) (xy 206.690098 -97.184556)
			(xy 206.78454 -97.090114) (xy 206.884513 -97.001546) (xy 206.98965 -96.919176) (xy 207.09957 -96.843304)
			(xy 207.213869 -96.774208) (xy 207.332132 -96.712138) (xy 207.453927 -96.657323) (xy 207.57881 -96.609961)
			(xy 207.706324 -96.570226) (xy 207.836005 -96.538263) (xy 207.967379 -96.514188) (xy 208.099967 -96.498088)
			(xy 208.233285 -96.490024) (xy 208.366847 -96.490024) (xy 208.500165 -96.498088) (xy 208.632753 -96.514188)
			(xy 208.764127 -96.538263) (xy 208.893808 -96.570226) (xy 209.021322 -96.609961) (xy 209.146205 -96.657323)
			(xy 209.268 -96.712138) (xy 209.386263 -96.774208) (xy 209.500562 -96.843304) (xy 209.610482 -96.919176)
			(xy 209.715619 -97.001546) (xy 209.815592 -97.090114) (xy 209.910034 -97.184556) (xy 209.998602 -97.284529)
			(xy 210.080972 -97.389666) (xy 210.156844 -97.499586) (xy 210.22594 -97.613885) (xy 210.28801 -97.732148)
			(xy 210.342825 -97.853943) (xy 210.390187 -97.978826) (xy 210.429922 -98.10634) (xy 210.461885 -98.236021)
			(xy 210.48596 -98.367395) (xy 210.50206 -98.499983) (xy 210.510124 -98.633301) (xy 210.510628 -98.700082)
			(xy 210.510124 -98.766863) (xy 257.089906 -98.766863) (xy 257.089906 -98.633301) (xy 257.09797 -98.499983)
			(xy 257.11407 -98.367395) (xy 257.138145 -98.236021) (xy 257.170108 -98.10634) (xy 257.209843 -97.978826)
			(xy 257.257205 -97.853943) (xy 257.31202 -97.732148) (xy 257.37409 -97.613885) (xy 257.443186 -97.499586)
			(xy 257.519058 -97.389666) (xy 257.601428 -97.284529) (xy 257.689996 -97.184556) (xy 257.784438 -97.090114)
			(xy 257.884411 -97.001546) (xy 257.989548 -96.919176) (xy 258.099468 -96.843304) (xy 258.213767 -96.774208)
			(xy 258.33203 -96.712138) (xy 258.453825 -96.657323) (xy 258.578708 -96.609961) (xy 258.706222 -96.570226)
			(xy 258.835903 -96.538263) (xy 258.967277 -96.514188) (xy 259.099865 -96.498088) (xy 259.233183 -96.490024)
			(xy 259.366745 -96.490024) (xy 259.500063 -96.498088) (xy 259.632651 -96.514188) (xy 259.764025 -96.538263)
			(xy 259.893706 -96.570226) (xy 260.02122 -96.609961) (xy 260.146103 -96.657323) (xy 260.267898 -96.712138)
			(xy 260.386161 -96.774208) (xy 260.50046 -96.843304) (xy 260.61038 -96.919176) (xy 260.715517 -97.001546)
			(xy 260.81549 -97.090114) (xy 260.909932 -97.184556) (xy 260.9985 -97.284529) (xy 261.08087 -97.389666)
			(xy 261.156742 -97.499586) (xy 261.225838 -97.613885) (xy 261.287908 -97.732148) (xy 261.342723 -97.853943)
			(xy 261.390085 -97.978826) (xy 261.42982 -98.10634) (xy 261.461783 -98.236021) (xy 261.485858 -98.367395)
			(xy 261.501958 -98.499983) (xy 261.510022 -98.633301) (xy 261.510526 -98.700082) (xy 261.510022 -98.766863)
			(xy 261.501958 -98.900181) (xy 261.485858 -99.032769) (xy 261.461783 -99.164143) (xy 261.42982 -99.293824)
			(xy 261.390085 -99.421338) (xy 261.342723 -99.546221) (xy 261.287908 -99.668016) (xy 261.225838 -99.786279)
			(xy 261.156742 -99.900578) (xy 261.08087 -100.010498) (xy 260.9985 -100.115635) (xy 260.943379 -100.177854)
			(xy 269.509748 -100.177854) (xy 269.509748 -99.314254) (xy 269.510238 -99.28427) (xy 269.518066 -99.224814)
			(xy 269.533587 -99.166889) (xy 269.556536 -99.111485) (xy 269.58652 -99.059551) (xy 269.623026 -99.011975)
			(xy 269.665431 -98.96957) (xy 269.713007 -98.933064) (xy 269.764941 -98.90308) (xy 269.820345 -98.880131)
			(xy 269.87827 -98.86461) (xy 269.937726 -98.856782) (xy 269.997694 -98.856782) (xy 270.05715 -98.86461)
			(xy 270.115075 -98.880131) (xy 270.170479 -98.90308) (xy 270.222413 -98.933064) (xy 270.269989 -98.96957)
			(xy 270.312394 -99.011975) (xy 270.3489 -99.059551) (xy 270.378884 -99.111485) (xy 270.401833 -99.166889)
			(xy 270.417354 -99.224814) (xy 270.425182 -99.28427) (xy 270.425672 -99.314254) (xy 270.425672 -100.17633)
			(xy 285.8389 -100.17633) (xy 285.8389 -99.31273) (xy 285.83939 -99.282746) (xy 285.847218 -99.22329)
			(xy 285.862739 -99.165365) (xy 285.885688 -99.109961) (xy 285.915672 -99.058027) (xy 285.952178 -99.010451)
			(xy 285.994583 -98.968046) (xy 286.042159 -98.93154) (xy 286.094093 -98.901556) (xy 286.149497 -98.878607)
			(xy 286.207422 -98.863086) (xy 286.266878 -98.855258) (xy 286.326846 -98.855258) (xy 286.386302 -98.863086)
			(xy 286.444227 -98.878607) (xy 286.499631 -98.901556) (xy 286.551565 -98.93154) (xy 286.599141 -98.968046)
			(xy 286.641546 -99.010451) (xy 286.678052 -99.058027) (xy 286.708036 -99.109961) (xy 286.730985 -99.165365)
			(xy 286.746506 -99.22329) (xy 286.754334 -99.282746) (xy 286.754824 -99.31273) (xy 286.754824 -100.17633)
			(xy 286.754799 -100.177854) (xy 385.6101 -100.177854) (xy 385.6101 -99.314254) (xy 385.61059 -99.284286)
			(xy 385.618413 -99.224864) (xy 385.633926 -99.166971) (xy 385.656862 -99.111598) (xy 385.686829 -99.059692)
			(xy 385.723316 -99.012142) (xy 385.765696 -98.969762) (xy 385.813246 -98.933275) (xy 385.865152 -98.903308)
			(xy 385.920525 -98.880372) (xy 385.978418 -98.864859) (xy 386.03784 -98.857036) (xy 386.097776 -98.857036)
			(xy 386.157198 -98.864859) (xy 386.215091 -98.880372) (xy 386.270464 -98.903308) (xy 386.32237 -98.933275)
			(xy 386.36992 -98.969762) (xy 386.4123 -99.012142) (xy 386.448787 -99.059692) (xy 386.478754 -99.111598)
			(xy 386.50169 -99.166971) (xy 386.517203 -99.224864) (xy 386.525026 -99.284286) (xy 386.525516 -99.314254)
			(xy 386.525516 -100.17633) (xy 401.939252 -100.17633) (xy 401.939252 -99.31273) (xy 401.939742 -99.282762)
			(xy 401.947565 -99.22334) (xy 401.963078 -99.165447) (xy 401.986014 -99.110074) (xy 402.015981 -99.058168)
			(xy 402.052468 -99.010618) (xy 402.094848 -98.968238) (xy 402.142398 -98.931751) (xy 402.194304 -98.901784)
			(xy 402.249677 -98.878848) (xy 402.30757 -98.863335) (xy 402.366992 -98.855512) (xy 402.426928 -98.855512)
			(xy 402.48635 -98.863335) (xy 402.544243 -98.878848) (xy 402.599616 -98.901784) (xy 402.651522 -98.931751)
			(xy 402.699072 -98.968238) (xy 402.741452 -99.010618) (xy 402.777939 -99.058168) (xy 402.807906 -99.110074)
			(xy 402.830842 -99.165447) (xy 402.846355 -99.22334) (xy 402.854178 -99.282762) (xy 402.854668 -99.31273)
			(xy 402.854668 -100.17633) (xy 402.854178 -100.206298) (xy 402.846355 -100.26572) (xy 402.830842 -100.323613)
			(xy 402.807906 -100.378986) (xy 402.777939 -100.430892) (xy 402.741452 -100.478442) (xy 402.699072 -100.520822)
			(xy 402.651522 -100.557309) (xy 402.599616 -100.587276) (xy 402.544243 -100.610212) (xy 402.48635 -100.625725)
			(xy 402.426928 -100.633548) (xy 402.366992 -100.633548) (xy 402.30757 -100.625725) (xy 402.249677 -100.610212)
			(xy 402.194304 -100.587276) (xy 402.142398 -100.557309) (xy 402.094848 -100.520822) (xy 402.052468 -100.478442)
			(xy 402.015981 -100.430892) (xy 401.986014 -100.378986) (xy 401.963078 -100.323613) (xy 401.947565 -100.26572)
			(xy 401.939742 -100.206298) (xy 401.939252 -100.17633) (xy 386.525516 -100.17633) (xy 386.525516 -100.177854)
			(xy 386.525026 -100.207822) (xy 386.517203 -100.267244) (xy 386.50169 -100.325137) (xy 386.478754 -100.38051)
			(xy 386.448787 -100.432416) (xy 386.4123 -100.479966) (xy 386.36992 -100.522346) (xy 386.32237 -100.558833)
			(xy 386.270464 -100.5888) (xy 386.215091 -100.611736) (xy 386.157198 -100.627249) (xy 386.097776 -100.635072)
			(xy 386.03784 -100.635072) (xy 385.978418 -100.627249) (xy 385.920525 -100.611736) (xy 385.865152 -100.5888)
			(xy 385.813246 -100.558833) (xy 385.765696 -100.522346) (xy 385.723316 -100.479966) (xy 385.686829 -100.432416)
			(xy 385.656862 -100.38051) (xy 385.633926 -100.325137) (xy 385.618413 -100.267244) (xy 385.61059 -100.207822)
			(xy 385.6101 -100.177854) (xy 286.754799 -100.177854) (xy 286.754334 -100.206314) (xy 286.746506 -100.26577)
			(xy 286.730985 -100.323695) (xy 286.708036 -100.379099) (xy 286.678052 -100.431033) (xy 286.641546 -100.478609)
			(xy 286.599141 -100.521014) (xy 286.551565 -100.55752) (xy 286.499631 -100.587504) (xy 286.444227 -100.610453)
			(xy 286.386302 -100.625974) (xy 286.326846 -100.633802) (xy 286.266878 -100.633802) (xy 286.207422 -100.625974)
			(xy 286.149497 -100.610453) (xy 286.094093 -100.587504) (xy 286.042159 -100.55752) (xy 285.994583 -100.521014)
			(xy 285.952178 -100.478609) (xy 285.915672 -100.431033) (xy 285.885688 -100.379099) (xy 285.862739 -100.323695)
			(xy 285.847218 -100.26577) (xy 285.83939 -100.206314) (xy 285.8389 -100.17633) (xy 270.425672 -100.17633)
			(xy 270.425672 -100.177854) (xy 270.425182 -100.207838) (xy 270.417354 -100.267294) (xy 270.401833 -100.325219)
			(xy 270.378884 -100.380623) (xy 270.3489 -100.432557) (xy 270.312394 -100.480133) (xy 270.269989 -100.522538)
			(xy 270.222413 -100.559044) (xy 270.170479 -100.589028) (xy 270.115075 -100.611977) (xy 270.05715 -100.627498)
			(xy 269.997694 -100.635326) (xy 269.937726 -100.635326) (xy 269.87827 -100.627498) (xy 269.820345 -100.611977)
			(xy 269.764941 -100.589028) (xy 269.713007 -100.559044) (xy 269.665431 -100.522538) (xy 269.623026 -100.480133)
			(xy 269.58652 -100.432557) (xy 269.556536 -100.380623) (xy 269.533587 -100.325219) (xy 269.518066 -100.267294)
			(xy 269.510238 -100.207838) (xy 269.509748 -100.177854) (xy 260.943379 -100.177854) (xy 260.909932 -100.215608)
			(xy 260.81549 -100.31005) (xy 260.715517 -100.398618) (xy 260.61038 -100.480988) (xy 260.50046 -100.55686)
			(xy 260.386161 -100.625956) (xy 260.267898 -100.688026) (xy 260.146103 -100.742841) (xy 260.02122 -100.790203)
			(xy 259.893706 -100.829938) (xy 259.764025 -100.861901) (xy 259.632651 -100.885976) (xy 259.500063 -100.902076)
			(xy 259.366745 -100.91014) (xy 259.233183 -100.91014) (xy 259.099865 -100.902076) (xy 258.967277 -100.885976)
			(xy 258.835903 -100.861901) (xy 258.706222 -100.829938) (xy 258.578708 -100.790203) (xy 258.453825 -100.742841)
			(xy 258.33203 -100.688026) (xy 258.213767 -100.625956) (xy 258.099468 -100.55686) (xy 257.989548 -100.480988)
			(xy 257.884411 -100.398618) (xy 257.784438 -100.31005) (xy 257.689996 -100.215608) (xy 257.601428 -100.115635)
			(xy 257.519058 -100.010498) (xy 257.443186 -99.900578) (xy 257.37409 -99.786279) (xy 257.31202 -99.668016)
			(xy 257.257205 -99.546221) (xy 257.209843 -99.421338) (xy 257.170108 -99.293824) (xy 257.138145 -99.164143)
			(xy 257.11407 -99.032769) (xy 257.09797 -98.900181) (xy 257.089906 -98.766863) (xy 210.510124 -98.766863)
			(xy 210.50206 -98.900181) (xy 210.48596 -99.032769) (xy 210.461885 -99.164143) (xy 210.429922 -99.293824)
			(xy 210.390187 -99.421338) (xy 210.342825 -99.546221) (xy 210.28801 -99.668016) (xy 210.22594 -99.786279)
			(xy 210.156844 -99.900578) (xy 210.080972 -100.010498) (xy 209.998602 -100.115635) (xy 209.910034 -100.215608)
			(xy 209.815592 -100.31005) (xy 209.715619 -100.398618) (xy 209.610482 -100.480988) (xy 209.500562 -100.55686)
			(xy 209.386263 -100.625956) (xy 209.268 -100.688026) (xy 209.146205 -100.742841) (xy 209.021322 -100.790203)
			(xy 208.893808 -100.829938) (xy 208.764127 -100.861901) (xy 208.632753 -100.885976) (xy 208.500165 -100.902076)
			(xy 208.366847 -100.91014) (xy 208.233285 -100.91014) (xy 208.099967 -100.902076) (xy 207.967379 -100.885976)
			(xy 207.836005 -100.861901) (xy 207.706324 -100.829938) (xy 207.57881 -100.790203) (xy 207.453927 -100.742841)
			(xy 207.332132 -100.688026) (xy 207.213869 -100.625956) (xy 207.09957 -100.55686) (xy 206.98965 -100.480988)
			(xy 206.884513 -100.398618) (xy 206.78454 -100.31005) (xy 206.690098 -100.215608) (xy 206.60153 -100.115635)
			(xy 206.51916 -100.010498) (xy 206.443288 -99.900578) (xy 206.374192 -99.786279) (xy 206.312122 -99.668016)
			(xy 206.257307 -99.546221) (xy 206.209945 -99.421338) (xy 206.17021 -99.293824) (xy 206.138247 -99.164143)
			(xy 206.114172 -99.032769) (xy 206.098072 -98.900181) (xy 206.090008 -98.766863) (xy 4.308094 -98.766863)
			(xy 4.308094 -100.177854) (xy 37.31006 -100.177854) (xy 37.31006 -99.314254) (xy 37.31055 -99.284286)
			(xy 37.318373 -99.224864) (xy 37.333886 -99.166971) (xy 37.356822 -99.111598) (xy 37.386789 -99.059692)
			(xy 37.423276 -99.012142) (xy 37.465656 -98.969762) (xy 37.513206 -98.933275) (xy 37.565112 -98.903308)
			(xy 37.620485 -98.880372) (xy 37.678378 -98.864859) (xy 37.7378 -98.857036) (xy 37.797736 -98.857036)
			(xy 37.857158 -98.864859) (xy 37.915051 -98.880372) (xy 37.970424 -98.903308) (xy 38.02233 -98.933275)
			(xy 38.06988 -98.969762) (xy 38.11226 -99.012142) (xy 38.148747 -99.059692) (xy 38.178714 -99.111598)
			(xy 38.20165 -99.166971) (xy 38.217163 -99.224864) (xy 38.224986 -99.284286) (xy 38.225476 -99.314254)
			(xy 38.225476 -100.17633) (xy 53.639212 -100.17633) (xy 53.639212 -99.31273) (xy 53.639702 -99.282762)
			(xy 53.647525 -99.22334) (xy 53.663038 -99.165447) (xy 53.685974 -99.110074) (xy 53.715941 -99.058168)
			(xy 53.752428 -99.010618) (xy 53.794808 -98.968238) (xy 53.842358 -98.931751) (xy 53.894264 -98.901784)
			(xy 53.949637 -98.878848) (xy 54.00753 -98.863335) (xy 54.066952 -98.855512) (xy 54.126888 -98.855512)
			(xy 54.18631 -98.863335) (xy 54.244203 -98.878848) (xy 54.299576 -98.901784) (xy 54.351482 -98.931751)
			(xy 54.399032 -98.968238) (xy 54.441412 -99.010618) (xy 54.477899 -99.058168) (xy 54.507866 -99.110074)
			(xy 54.530802 -99.165447) (xy 54.546315 -99.22334) (xy 54.554138 -99.282762) (xy 54.554628 -99.31273)
			(xy 54.554628 -100.17633) (xy 54.554603 -100.177854) (xy 153.409904 -100.177854) (xy 153.409904 -99.314254)
			(xy 153.410394 -99.28427) (xy 153.418222 -99.224814) (xy 153.433743 -99.166889) (xy 153.456692 -99.111485)
			(xy 153.486676 -99.059551) (xy 153.523182 -99.011975) (xy 153.565587 -98.96957) (xy 153.613163 -98.933064)
			(xy 153.665097 -98.90308) (xy 153.720501 -98.880131) (xy 153.778426 -98.86461) (xy 153.837882 -98.856782)
			(xy 153.89785 -98.856782) (xy 153.957306 -98.86461) (xy 154.015231 -98.880131) (xy 154.070635 -98.90308)
			(xy 154.122569 -98.933064) (xy 154.170145 -98.96957) (xy 154.21255 -99.011975) (xy 154.249056 -99.059551)
			(xy 154.27904 -99.111485) (xy 154.301989 -99.166889) (xy 154.31751 -99.224814) (xy 154.325338 -99.28427)
			(xy 154.325828 -99.314254) (xy 154.325828 -100.17633) (xy 169.739056 -100.17633) (xy 169.739056 -99.31273)
			(xy 169.739546 -99.282746) (xy 169.747374 -99.22329) (xy 169.762895 -99.165365) (xy 169.785844 -99.109961)
			(xy 169.815828 -99.058027) (xy 169.852334 -99.010451) (xy 169.894739 -98.968046) (xy 169.942315 -98.93154)
			(xy 169.994249 -98.901556) (xy 170.049653 -98.878607) (xy 170.107578 -98.863086) (xy 170.167034 -98.855258)
			(xy 170.227002 -98.855258) (xy 170.286458 -98.863086) (xy 170.344383 -98.878607) (xy 170.399787 -98.901556)
			(xy 170.451721 -98.93154) (xy 170.499297 -98.968046) (xy 170.541702 -99.010451) (xy 170.578208 -99.058027)
			(xy 170.608192 -99.109961) (xy 170.631141 -99.165365) (xy 170.646662 -99.22329) (xy 170.65449 -99.282746)
			(xy 170.65498 -99.31273) (xy 170.65498 -100.17633) (xy 170.65449 -100.206314) (xy 170.646662 -100.26577)
			(xy 170.631141 -100.323695) (xy 170.608192 -100.379099) (xy 170.578208 -100.431033) (xy 170.541702 -100.478609)
			(xy 170.499297 -100.521014) (xy 170.451721 -100.55752) (xy 170.399787 -100.587504) (xy 170.344383 -100.610453)
			(xy 170.286458 -100.625974) (xy 170.227002 -100.633802) (xy 170.167034 -100.633802) (xy 170.107578 -100.625974)
			(xy 170.049653 -100.610453) (xy 169.994249 -100.587504) (xy 169.942315 -100.55752) (xy 169.894739 -100.521014)
			(xy 169.852334 -100.478609) (xy 169.815828 -100.431033) (xy 169.785844 -100.379099) (xy 169.762895 -100.323695)
			(xy 169.747374 -100.26577) (xy 169.739546 -100.206314) (xy 169.739056 -100.17633) (xy 154.325828 -100.17633)
			(xy 154.325828 -100.177854) (xy 154.325338 -100.207838) (xy 154.31751 -100.267294) (xy 154.301989 -100.325219)
			(xy 154.27904 -100.380623) (xy 154.249056 -100.432557) (xy 154.21255 -100.480133) (xy 154.170145 -100.522538)
			(xy 154.122569 -100.559044) (xy 154.070635 -100.589028) (xy 154.015231 -100.611977) (xy 153.957306 -100.627498)
			(xy 153.89785 -100.635326) (xy 153.837882 -100.635326) (xy 153.778426 -100.627498) (xy 153.720501 -100.611977)
			(xy 153.665097 -100.589028) (xy 153.613163 -100.559044) (xy 153.565587 -100.522538) (xy 153.523182 -100.480133)
			(xy 153.486676 -100.432557) (xy 153.456692 -100.380623) (xy 153.433743 -100.325219) (xy 153.418222 -100.267294)
			(xy 153.410394 -100.207838) (xy 153.409904 -100.177854) (xy 54.554603 -100.177854) (xy 54.554138 -100.206298)
			(xy 54.546315 -100.26572) (xy 54.530802 -100.323613) (xy 54.507866 -100.378986) (xy 54.477899 -100.430892)
			(xy 54.441412 -100.478442) (xy 54.399032 -100.520822) (xy 54.351482 -100.557309) (xy 54.299576 -100.587276)
			(xy 54.244203 -100.610212) (xy 54.18631 -100.625725) (xy 54.126888 -100.633548) (xy 54.066952 -100.633548)
			(xy 54.00753 -100.625725) (xy 53.949637 -100.610212) (xy 53.894264 -100.587276) (xy 53.842358 -100.557309)
			(xy 53.794808 -100.520822) (xy 53.752428 -100.478442) (xy 53.715941 -100.430892) (xy 53.685974 -100.378986)
			(xy 53.663038 -100.323613) (xy 53.647525 -100.26572) (xy 53.639702 -100.206298) (xy 53.639212 -100.17633)
			(xy 38.225476 -100.17633) (xy 38.225476 -100.177854) (xy 38.224986 -100.207822) (xy 38.217163 -100.267244)
			(xy 38.20165 -100.325137) (xy 38.178714 -100.38051) (xy 38.148747 -100.432416) (xy 38.11226 -100.479966)
			(xy 38.06988 -100.522346) (xy 38.02233 -100.558833) (xy 37.970424 -100.5888) (xy 37.915051 -100.611736)
			(xy 37.857158 -100.627249) (xy 37.797736 -100.635072) (xy 37.7378 -100.635072) (xy 37.678378 -100.627249)
			(xy 37.620485 -100.611736) (xy 37.565112 -100.5888) (xy 37.513206 -100.558833) (xy 37.465656 -100.522346)
			(xy 37.423276 -100.479966) (xy 37.386789 -100.432416) (xy 37.356822 -100.38051) (xy 37.333886 -100.325137)
			(xy 37.318373 -100.267244) (xy 37.31055 -100.207822) (xy 37.31006 -100.177854) (xy 4.308094 -100.177854)
			(xy 4.308094 -101.984302) (xy 35.277552 -101.984302) (xy 35.277552 -101.120702) (xy 35.278042 -101.090734)
			(xy 35.285865 -101.031312) (xy 35.301378 -100.973419) (xy 35.324314 -100.918046) (xy 35.354281 -100.86614)
			(xy 35.390768 -100.81859) (xy 35.433148 -100.77621) (xy 35.480698 -100.739723) (xy 35.532604 -100.709756)
			(xy 35.587977 -100.68682) (xy 35.64587 -100.671307) (xy 35.705292 -100.663484) (xy 35.765228 -100.663484)
			(xy 35.82465 -100.671307) (xy 35.882543 -100.68682) (xy 35.937916 -100.709756) (xy 35.989822 -100.739723)
			(xy 36.037372 -100.77621) (xy 36.079752 -100.81859) (xy 36.116239 -100.86614) (xy 36.146206 -100.918046)
			(xy 36.169142 -100.973419) (xy 36.184655 -101.031312) (xy 36.192478 -101.090734) (xy 36.192968 -101.120702)
			(xy 36.192968 -101.976428) (xy 51.785012 -101.976428) (xy 51.785012 -101.112828) (xy 51.785502 -101.08286)
			(xy 51.793325 -101.023438) (xy 51.808838 -100.965545) (xy 51.831774 -100.910172) (xy 51.861741 -100.858266)
			(xy 51.898228 -100.810716) (xy 51.940608 -100.768336) (xy 51.988158 -100.731849) (xy 52.040064 -100.701882)
			(xy 52.095437 -100.678946) (xy 52.15333 -100.663433) (xy 52.212752 -100.65561) (xy 52.272688 -100.65561)
			(xy 52.33211 -100.663433) (xy 52.390003 -100.678946) (xy 52.445376 -100.701882) (xy 52.497282 -100.731849)
			(xy 52.544832 -100.768336) (xy 52.587212 -100.810716) (xy 52.623699 -100.858266) (xy 52.653666 -100.910172)
			(xy 52.676602 -100.965545) (xy 52.692115 -101.023438) (xy 52.699938 -101.08286) (xy 52.700428 -101.112828)
			(xy 52.700428 -101.976428) (xy 52.700299 -101.984302) (xy 151.377396 -101.984302) (xy 151.377396 -101.120702)
			(xy 151.377886 -101.090718) (xy 151.385714 -101.031262) (xy 151.401235 -100.973337) (xy 151.424184 -100.917933)
			(xy 151.454168 -100.865999) (xy 151.490674 -100.818423) (xy 151.533079 -100.776018) (xy 151.580655 -100.739512)
			(xy 151.632589 -100.709528) (xy 151.687993 -100.686579) (xy 151.745918 -100.671058) (xy 151.805374 -100.66323)
			(xy 151.865342 -100.66323) (xy 151.924798 -100.671058) (xy 151.982723 -100.686579) (xy 152.038127 -100.709528)
			(xy 152.090061 -100.739512) (xy 152.137637 -100.776018) (xy 152.180042 -100.818423) (xy 152.216548 -100.865999)
			(xy 152.246532 -100.917933) (xy 152.269481 -100.973337) (xy 152.285002 -101.031262) (xy 152.29283 -101.090718)
			(xy 152.29332 -101.120702) (xy 152.29332 -101.976428) (xy 167.884856 -101.976428) (xy 167.884856 -101.112828)
			(xy 167.885346 -101.082844) (xy 167.893174 -101.023388) (xy 167.908695 -100.965463) (xy 167.931644 -100.910059)
			(xy 167.961628 -100.858125) (xy 167.998134 -100.810549) (xy 168.040539 -100.768144) (xy 168.088115 -100.731638)
			(xy 168.140049 -100.701654) (xy 168.195453 -100.678705) (xy 168.253378 -100.663184) (xy 168.312834 -100.655356)
			(xy 168.372802 -100.655356) (xy 168.432258 -100.663184) (xy 168.490183 -100.678705) (xy 168.545587 -100.701654)
			(xy 168.597521 -100.731638) (xy 168.645097 -100.768144) (xy 168.687502 -100.810549) (xy 168.724008 -100.858125)
			(xy 168.753992 -100.910059) (xy 168.776941 -100.965463) (xy 168.792462 -101.023388) (xy 168.80029 -101.082844)
			(xy 168.80078 -101.112828) (xy 168.80078 -101.976428) (xy 168.800651 -101.984302) (xy 267.47724 -101.984302)
			(xy 267.47724 -101.120702) (xy 267.47773 -101.090718) (xy 267.485558 -101.031262) (xy 267.501079 -100.973337)
			(xy 267.524028 -100.917933) (xy 267.554012 -100.865999) (xy 267.590518 -100.818423) (xy 267.632923 -100.776018)
			(xy 267.680499 -100.739512) (xy 267.732433 -100.709528) (xy 267.787837 -100.686579) (xy 267.845762 -100.671058)
			(xy 267.905218 -100.66323) (xy 267.965186 -100.66323) (xy 268.024642 -100.671058) (xy 268.082567 -100.686579)
			(xy 268.137971 -100.709528) (xy 268.189905 -100.739512) (xy 268.237481 -100.776018) (xy 268.279886 -100.818423)
			(xy 268.316392 -100.865999) (xy 268.346376 -100.917933) (xy 268.369325 -100.973337) (xy 268.384846 -101.031262)
			(xy 268.392674 -101.090718) (xy 268.393164 -101.120702) (xy 268.393164 -101.976428) (xy 283.9847 -101.976428)
			(xy 283.9847 -101.112828) (xy 283.98519 -101.082844) (xy 283.993018 -101.023388) (xy 284.008539 -100.965463)
			(xy 284.031488 -100.910059) (xy 284.061472 -100.858125) (xy 284.097978 -100.810549) (xy 284.140383 -100.768144)
			(xy 284.187959 -100.731638) (xy 284.239893 -100.701654) (xy 284.295297 -100.678705) (xy 284.353222 -100.663184)
			(xy 284.412678 -100.655356) (xy 284.472646 -100.655356) (xy 284.532102 -100.663184) (xy 284.590027 -100.678705)
			(xy 284.645431 -100.701654) (xy 284.697365 -100.731638) (xy 284.744941 -100.768144) (xy 284.787346 -100.810549)
			(xy 284.823852 -100.858125) (xy 284.853836 -100.910059) (xy 284.876785 -100.965463) (xy 284.892306 -101.023388)
			(xy 284.900134 -101.082844) (xy 284.900624 -101.112828) (xy 284.900624 -101.976428) (xy 284.900495 -101.984302)
			(xy 383.577592 -101.984302) (xy 383.577592 -101.120702) (xy 383.578082 -101.090734) (xy 383.585905 -101.031312)
			(xy 383.601418 -100.973419) (xy 383.624354 -100.918046) (xy 383.654321 -100.86614) (xy 383.690808 -100.81859)
			(xy 383.733188 -100.77621) (xy 383.780738 -100.739723) (xy 383.832644 -100.709756) (xy 383.888017 -100.68682)
			(xy 383.94591 -100.671307) (xy 384.005332 -100.663484) (xy 384.065268 -100.663484) (xy 384.12469 -100.671307)
			(xy 384.182583 -100.68682) (xy 384.237956 -100.709756) (xy 384.289862 -100.739723) (xy 384.337412 -100.77621)
			(xy 384.379792 -100.81859) (xy 384.416279 -100.86614) (xy 384.446246 -100.918046) (xy 384.469182 -100.973419)
			(xy 384.484695 -101.031312) (xy 384.492518 -101.090734) (xy 384.493008 -101.120702) (xy 384.493008 -101.976428)
			(xy 400.085052 -101.976428) (xy 400.085052 -101.112828) (xy 400.085542 -101.08286) (xy 400.093365 -101.023438)
			(xy 400.108878 -100.965545) (xy 400.131814 -100.910172) (xy 400.161781 -100.858266) (xy 400.198268 -100.810716)
			(xy 400.240648 -100.768336) (xy 400.288198 -100.731849) (xy 400.340104 -100.701882) (xy 400.395477 -100.678946)
			(xy 400.45337 -100.663433) (xy 400.512792 -100.65561) (xy 400.572728 -100.65561) (xy 400.63215 -100.663433)
			(xy 400.690043 -100.678946) (xy 400.745416 -100.701882) (xy 400.797322 -100.731849) (xy 400.844872 -100.768336)
			(xy 400.887252 -100.810716) (xy 400.923739 -100.858266) (xy 400.953706 -100.910172) (xy 400.976642 -100.965545)
			(xy 400.992155 -101.023438) (xy 400.999978 -101.08286) (xy 401.000468 -101.112828) (xy 401.000468 -101.976428)
			(xy 400.999978 -102.006396) (xy 400.992155 -102.065818) (xy 400.976642 -102.123711) (xy 400.953706 -102.179084)
			(xy 400.923739 -102.23099) (xy 400.887252 -102.27854) (xy 400.844872 -102.32092) (xy 400.797322 -102.357407)
			(xy 400.745416 -102.387374) (xy 400.690043 -102.41031) (xy 400.63215 -102.425823) (xy 400.572728 -102.433646)
			(xy 400.512792 -102.433646) (xy 400.45337 -102.425823) (xy 400.395477 -102.41031) (xy 400.340104 -102.387374)
			(xy 400.288198 -102.357407) (xy 400.240648 -102.32092) (xy 400.198268 -102.27854) (xy 400.161781 -102.23099)
			(xy 400.131814 -102.179084) (xy 400.108878 -102.123711) (xy 400.093365 -102.065818) (xy 400.085542 -102.006396)
			(xy 400.085052 -101.976428) (xy 384.493008 -101.976428) (xy 384.493008 -101.984302) (xy 384.492518 -102.01427)
			(xy 384.484695 -102.073692) (xy 384.469182 -102.131585) (xy 384.446246 -102.186958) (xy 384.416279 -102.238864)
			(xy 384.379792 -102.286414) (xy 384.337412 -102.328794) (xy 384.289862 -102.365281) (xy 384.237956 -102.395248)
			(xy 384.182583 -102.418184) (xy 384.12469 -102.433697) (xy 384.065268 -102.44152) (xy 384.005332 -102.44152)
			(xy 383.94591 -102.433697) (xy 383.888017 -102.418184) (xy 383.832644 -102.395248) (xy 383.780738 -102.365281)
			(xy 383.733188 -102.328794) (xy 383.690808 -102.286414) (xy 383.654321 -102.238864) (xy 383.624354 -102.186958)
			(xy 383.601418 -102.131585) (xy 383.585905 -102.073692) (xy 383.578082 -102.01427) (xy 383.577592 -101.984302)
			(xy 284.900495 -101.984302) (xy 284.900134 -102.006412) (xy 284.892306 -102.065868) (xy 284.876785 -102.123793)
			(xy 284.853836 -102.179197) (xy 284.823852 -102.231131) (xy 284.787346 -102.278707) (xy 284.744941 -102.321112)
			(xy 284.697365 -102.357618) (xy 284.645431 -102.387602) (xy 284.590027 -102.410551) (xy 284.532102 -102.426072)
			(xy 284.472646 -102.4339) (xy 284.412678 -102.4339) (xy 284.353222 -102.426072) (xy 284.295297 -102.410551)
			(xy 284.239893 -102.387602) (xy 284.187959 -102.357618) (xy 284.140383 -102.321112) (xy 284.097978 -102.278707)
			(xy 284.061472 -102.231131) (xy 284.031488 -102.179197) (xy 284.008539 -102.123793) (xy 283.993018 -102.065868)
			(xy 283.98519 -102.006412) (xy 283.9847 -101.976428) (xy 268.393164 -101.976428) (xy 268.393164 -101.984302)
			(xy 268.392674 -102.014286) (xy 268.384846 -102.073742) (xy 268.369325 -102.131667) (xy 268.346376 -102.187071)
			(xy 268.316392 -102.239005) (xy 268.279886 -102.286581) (xy 268.237481 -102.328986) (xy 268.189905 -102.365492)
			(xy 268.137971 -102.395476) (xy 268.082567 -102.418425) (xy 268.024642 -102.433946) (xy 267.965186 -102.441774)
			(xy 267.905218 -102.441774) (xy 267.845762 -102.433946) (xy 267.787837 -102.418425) (xy 267.732433 -102.395476)
			(xy 267.680499 -102.365492) (xy 267.632923 -102.328986) (xy 267.590518 -102.286581) (xy 267.554012 -102.239005)
			(xy 267.524028 -102.187071) (xy 267.501079 -102.131667) (xy 267.485558 -102.073742) (xy 267.47773 -102.014286)
			(xy 267.47724 -101.984302) (xy 168.800651 -101.984302) (xy 168.80029 -102.006412) (xy 168.792462 -102.065868)
			(xy 168.776941 -102.123793) (xy 168.753992 -102.179197) (xy 168.724008 -102.231131) (xy 168.687502 -102.278707)
			(xy 168.645097 -102.321112) (xy 168.597521 -102.357618) (xy 168.545587 -102.387602) (xy 168.490183 -102.410551)
			(xy 168.432258 -102.426072) (xy 168.372802 -102.4339) (xy 168.312834 -102.4339) (xy 168.253378 -102.426072)
			(xy 168.195453 -102.410551) (xy 168.140049 -102.387602) (xy 168.088115 -102.357618) (xy 168.040539 -102.321112)
			(xy 167.998134 -102.278707) (xy 167.961628 -102.231131) (xy 167.931644 -102.179197) (xy 167.908695 -102.123793)
			(xy 167.893174 -102.065868) (xy 167.885346 -102.006412) (xy 167.884856 -101.976428) (xy 152.29332 -101.976428)
			(xy 152.29332 -101.984302) (xy 152.29283 -102.014286) (xy 152.285002 -102.073742) (xy 152.269481 -102.131667)
			(xy 152.246532 -102.187071) (xy 152.216548 -102.239005) (xy 152.180042 -102.286581) (xy 152.137637 -102.328986)
			(xy 152.090061 -102.365492) (xy 152.038127 -102.395476) (xy 151.982723 -102.418425) (xy 151.924798 -102.433946)
			(xy 151.865342 -102.441774) (xy 151.805374 -102.441774) (xy 151.745918 -102.433946) (xy 151.687993 -102.418425)
			(xy 151.632589 -102.395476) (xy 151.580655 -102.365492) (xy 151.533079 -102.328986) (xy 151.490674 -102.286581)
			(xy 151.454168 -102.239005) (xy 151.424184 -102.187071) (xy 151.401235 -102.131667) (xy 151.385714 -102.073742)
			(xy 151.377886 -102.014286) (xy 151.377396 -101.984302) (xy 52.700299 -101.984302) (xy 52.699938 -102.006396)
			(xy 52.692115 -102.065818) (xy 52.676602 -102.123711) (xy 52.653666 -102.179084) (xy 52.623699 -102.23099)
			(xy 52.587212 -102.27854) (xy 52.544832 -102.32092) (xy 52.497282 -102.357407) (xy 52.445376 -102.387374)
			(xy 52.390003 -102.41031) (xy 52.33211 -102.425823) (xy 52.272688 -102.433646) (xy 52.212752 -102.433646)
			(xy 52.15333 -102.425823) (xy 52.095437 -102.41031) (xy 52.040064 -102.387374) (xy 51.988158 -102.357407)
			(xy 51.940608 -102.32092) (xy 51.898228 -102.27854) (xy 51.861741 -102.23099) (xy 51.831774 -102.179084)
			(xy 51.808838 -102.123711) (xy 51.793325 -102.065818) (xy 51.785502 -102.006396) (xy 51.785012 -101.976428)
			(xy 36.192968 -101.976428) (xy 36.192968 -101.984302) (xy 36.192478 -102.01427) (xy 36.184655 -102.073692)
			(xy 36.169142 -102.131585) (xy 36.146206 -102.186958) (xy 36.116239 -102.238864) (xy 36.079752 -102.286414)
			(xy 36.037372 -102.328794) (xy 35.989822 -102.365281) (xy 35.937916 -102.395248) (xy 35.882543 -102.418184)
			(xy 35.82465 -102.433697) (xy 35.765228 -102.44152) (xy 35.705292 -102.44152) (xy 35.64587 -102.433697)
			(xy 35.587977 -102.418184) (xy 35.532604 -102.395248) (xy 35.480698 -102.365281) (xy 35.433148 -102.328794)
			(xy 35.390768 -102.286414) (xy 35.354281 -102.238864) (xy 35.324314 -102.186958) (xy 35.301378 -102.131585)
			(xy 35.285865 -102.073692) (xy 35.278042 -102.01427) (xy 35.277552 -101.984302) (xy 4.308094 -101.984302)
			(xy 4.308094 -103.777796) (xy 37.31006 -103.777796) (xy 37.31006 -102.914196) (xy 37.31055 -102.884228)
			(xy 37.318373 -102.824806) (xy 37.333886 -102.766913) (xy 37.356822 -102.71154) (xy 37.386789 -102.659634)
			(xy 37.423276 -102.612084) (xy 37.465656 -102.569704) (xy 37.513206 -102.533217) (xy 37.565112 -102.50325)
			(xy 37.620485 -102.480314) (xy 37.678378 -102.464801) (xy 37.7378 -102.456978) (xy 37.797736 -102.456978)
			(xy 37.857158 -102.464801) (xy 37.915051 -102.480314) (xy 37.970424 -102.50325) (xy 38.02233 -102.533217)
			(xy 38.06988 -102.569704) (xy 38.11226 -102.612084) (xy 38.148747 -102.659634) (xy 38.178714 -102.71154)
			(xy 38.20165 -102.766913) (xy 38.217163 -102.824806) (xy 38.224986 -102.884228) (xy 38.225476 -102.914196)
			(xy 38.225476 -103.776272) (xy 53.639212 -103.776272) (xy 53.639212 -102.912672) (xy 53.639702 -102.882704)
			(xy 53.647525 -102.823282) (xy 53.663038 -102.765389) (xy 53.685974 -102.710016) (xy 53.715941 -102.65811)
			(xy 53.752428 -102.61056) (xy 53.794808 -102.56818) (xy 53.842358 -102.531693) (xy 53.894264 -102.501726)
			(xy 53.949637 -102.47879) (xy 54.00753 -102.463277) (xy 54.066952 -102.455454) (xy 54.126888 -102.455454)
			(xy 54.18631 -102.463277) (xy 54.244203 -102.47879) (xy 54.299576 -102.501726) (xy 54.351482 -102.531693)
			(xy 54.399032 -102.56818) (xy 54.441412 -102.61056) (xy 54.477899 -102.65811) (xy 54.507866 -102.710016)
			(xy 54.530802 -102.765389) (xy 54.546315 -102.823282) (xy 54.554138 -102.882704) (xy 54.554628 -102.912672)
			(xy 54.554628 -103.776272) (xy 54.554603 -103.777796) (xy 153.409904 -103.777796) (xy 153.409904 -102.914196)
			(xy 153.410394 -102.884212) (xy 153.418222 -102.824756) (xy 153.433743 -102.766831) (xy 153.456692 -102.711427)
			(xy 153.486676 -102.659493) (xy 153.523182 -102.611917) (xy 153.565587 -102.569512) (xy 153.613163 -102.533006)
			(xy 153.665097 -102.503022) (xy 153.720501 -102.480073) (xy 153.778426 -102.464552) (xy 153.837882 -102.456724)
			(xy 153.89785 -102.456724) (xy 153.957306 -102.464552) (xy 154.015231 -102.480073) (xy 154.070635 -102.503022)
			(xy 154.122569 -102.533006) (xy 154.170145 -102.569512) (xy 154.21255 -102.611917) (xy 154.249056 -102.659493)
			(xy 154.27904 -102.711427) (xy 154.301989 -102.766831) (xy 154.31751 -102.824756) (xy 154.325338 -102.884212)
			(xy 154.325828 -102.914196) (xy 154.325828 -103.776272) (xy 169.739056 -103.776272) (xy 169.739056 -102.912672)
			(xy 169.739546 -102.882688) (xy 169.747374 -102.823232) (xy 169.762895 -102.765307) (xy 169.785844 -102.709903)
			(xy 169.815828 -102.657969) (xy 169.852334 -102.610393) (xy 169.894739 -102.567988) (xy 169.942315 -102.531482)
			(xy 169.994249 -102.501498) (xy 170.049653 -102.478549) (xy 170.107578 -102.463028) (xy 170.167034 -102.4552)
			(xy 170.227002 -102.4552) (xy 170.286458 -102.463028) (xy 170.344383 -102.478549) (xy 170.399787 -102.501498)
			(xy 170.451721 -102.531482) (xy 170.499297 -102.567988) (xy 170.541702 -102.610393) (xy 170.578208 -102.657969)
			(xy 170.608192 -102.709903) (xy 170.631141 -102.765307) (xy 170.646662 -102.823232) (xy 170.65449 -102.882688)
			(xy 170.65498 -102.912672) (xy 170.65498 -103.776272) (xy 170.654955 -103.777796) (xy 269.509748 -103.777796)
			(xy 269.509748 -102.914196) (xy 269.510238 -102.884212) (xy 269.518066 -102.824756) (xy 269.533587 -102.766831)
			(xy 269.556536 -102.711427) (xy 269.58652 -102.659493) (xy 269.623026 -102.611917) (xy 269.665431 -102.569512)
			(xy 269.713007 -102.533006) (xy 269.764941 -102.503022) (xy 269.820345 -102.480073) (xy 269.87827 -102.464552)
			(xy 269.937726 -102.456724) (xy 269.997694 -102.456724) (xy 270.05715 -102.464552) (xy 270.115075 -102.480073)
			(xy 270.170479 -102.503022) (xy 270.222413 -102.533006) (xy 270.269989 -102.569512) (xy 270.312394 -102.611917)
			(xy 270.3489 -102.659493) (xy 270.378884 -102.711427) (xy 270.401833 -102.766831) (xy 270.417354 -102.824756)
			(xy 270.425182 -102.884212) (xy 270.425672 -102.914196) (xy 270.425672 -103.776272) (xy 285.8389 -103.776272)
			(xy 285.8389 -102.912672) (xy 285.83939 -102.882688) (xy 285.847218 -102.823232) (xy 285.862739 -102.765307)
			(xy 285.885688 -102.709903) (xy 285.915672 -102.657969) (xy 285.952178 -102.610393) (xy 285.994583 -102.567988)
			(xy 286.042159 -102.531482) (xy 286.094093 -102.501498) (xy 286.149497 -102.478549) (xy 286.207422 -102.463028)
			(xy 286.266878 -102.4552) (xy 286.326846 -102.4552) (xy 286.386302 -102.463028) (xy 286.444227 -102.478549)
			(xy 286.499631 -102.501498) (xy 286.551565 -102.531482) (xy 286.599141 -102.567988) (xy 286.641546 -102.610393)
			(xy 286.678052 -102.657969) (xy 286.708036 -102.709903) (xy 286.730985 -102.765307) (xy 286.746506 -102.823232)
			(xy 286.754334 -102.882688) (xy 286.754824 -102.912672) (xy 286.754824 -103.776272) (xy 286.754799 -103.777796)
			(xy 385.6101 -103.777796) (xy 385.6101 -102.914196) (xy 385.61059 -102.884228) (xy 385.618413 -102.824806)
			(xy 385.633926 -102.766913) (xy 385.656862 -102.71154) (xy 385.686829 -102.659634) (xy 385.723316 -102.612084)
			(xy 385.765696 -102.569704) (xy 385.813246 -102.533217) (xy 385.865152 -102.50325) (xy 385.920525 -102.480314)
			(xy 385.978418 -102.464801) (xy 386.03784 -102.456978) (xy 386.097776 -102.456978) (xy 386.157198 -102.464801)
			(xy 386.215091 -102.480314) (xy 386.270464 -102.50325) (xy 386.32237 -102.533217) (xy 386.36992 -102.569704)
			(xy 386.4123 -102.612084) (xy 386.448787 -102.659634) (xy 386.478754 -102.71154) (xy 386.50169 -102.766913)
			(xy 386.517203 -102.824806) (xy 386.525026 -102.884228) (xy 386.525516 -102.914196) (xy 386.525516 -103.776272)
			(xy 401.939252 -103.776272) (xy 401.939252 -102.912672) (xy 401.939742 -102.882704) (xy 401.947565 -102.823282)
			(xy 401.963078 -102.765389) (xy 401.986014 -102.710016) (xy 402.015981 -102.65811) (xy 402.052468 -102.61056)
			(xy 402.094848 -102.56818) (xy 402.142398 -102.531693) (xy 402.194304 -102.501726) (xy 402.249677 -102.47879)
			(xy 402.30757 -102.463277) (xy 402.366992 -102.455454) (xy 402.426928 -102.455454) (xy 402.48635 -102.463277)
			(xy 402.544243 -102.47879) (xy 402.599616 -102.501726) (xy 402.651522 -102.531693) (xy 402.699072 -102.56818)
			(xy 402.741452 -102.61056) (xy 402.777939 -102.65811) (xy 402.807906 -102.710016) (xy 402.830842 -102.765389)
			(xy 402.846355 -102.823282) (xy 402.854178 -102.882704) (xy 402.854668 -102.912672) (xy 402.854668 -103.776272)
			(xy 402.854178 -103.80624) (xy 402.846355 -103.865662) (xy 402.830842 -103.923555) (xy 402.807906 -103.978928)
			(xy 402.777939 -104.030834) (xy 402.741452 -104.078384) (xy 402.699072 -104.120764) (xy 402.651522 -104.157251)
			(xy 402.599616 -104.187218) (xy 402.544243 -104.210154) (xy 402.48635 -104.225667) (xy 402.426928 -104.23349)
			(xy 402.366992 -104.23349) (xy 402.30757 -104.225667) (xy 402.249677 -104.210154) (xy 402.194304 -104.187218)
			(xy 402.142398 -104.157251) (xy 402.094848 -104.120764) (xy 402.052468 -104.078384) (xy 402.015981 -104.030834)
			(xy 401.986014 -103.978928) (xy 401.963078 -103.923555) (xy 401.947565 -103.865662) (xy 401.939742 -103.80624)
			(xy 401.939252 -103.776272) (xy 386.525516 -103.776272) (xy 386.525516 -103.777796) (xy 386.525026 -103.807764)
			(xy 386.517203 -103.867186) (xy 386.50169 -103.925079) (xy 386.478754 -103.980452) (xy 386.448787 -104.032358)
			(xy 386.4123 -104.079908) (xy 386.36992 -104.122288) (xy 386.32237 -104.158775) (xy 386.270464 -104.188742)
			(xy 386.215091 -104.211678) (xy 386.157198 -104.227191) (xy 386.097776 -104.235014) (xy 386.03784 -104.235014)
			(xy 385.978418 -104.227191) (xy 385.920525 -104.211678) (xy 385.865152 -104.188742) (xy 385.813246 -104.158775)
			(xy 385.765696 -104.122288) (xy 385.723316 -104.079908) (xy 385.686829 -104.032358) (xy 385.656862 -103.980452)
			(xy 385.633926 -103.925079) (xy 385.618413 -103.867186) (xy 385.61059 -103.807764) (xy 385.6101 -103.777796)
			(xy 286.754799 -103.777796) (xy 286.754334 -103.806256) (xy 286.746506 -103.865712) (xy 286.730985 -103.923637)
			(xy 286.708036 -103.979041) (xy 286.678052 -104.030975) (xy 286.641546 -104.078551) (xy 286.599141 -104.120956)
			(xy 286.551565 -104.157462) (xy 286.499631 -104.187446) (xy 286.444227 -104.210395) (xy 286.386302 -104.225916)
			(xy 286.326846 -104.233744) (xy 286.266878 -104.233744) (xy 286.207422 -104.225916) (xy 286.149497 -104.210395)
			(xy 286.094093 -104.187446) (xy 286.042159 -104.157462) (xy 285.994583 -104.120956) (xy 285.952178 -104.078551)
			(xy 285.915672 -104.030975) (xy 285.885688 -103.979041) (xy 285.862739 -103.923637) (xy 285.847218 -103.865712)
			(xy 285.83939 -103.806256) (xy 285.8389 -103.776272) (xy 270.425672 -103.776272) (xy 270.425672 -103.777796)
			(xy 270.425182 -103.80778) (xy 270.417354 -103.867236) (xy 270.401833 -103.925161) (xy 270.378884 -103.980565)
			(xy 270.3489 -104.032499) (xy 270.312394 -104.080075) (xy 270.269989 -104.12248) (xy 270.222413 -104.158986)
			(xy 270.170479 -104.18897) (xy 270.115075 -104.211919) (xy 270.05715 -104.22744) (xy 269.997694 -104.235268)
			(xy 269.937726 -104.235268) (xy 269.87827 -104.22744) (xy 269.820345 -104.211919) (xy 269.764941 -104.18897)
			(xy 269.713007 -104.158986) (xy 269.665431 -104.12248) (xy 269.623026 -104.080075) (xy 269.58652 -104.032499)
			(xy 269.556536 -103.980565) (xy 269.533587 -103.925161) (xy 269.518066 -103.867236) (xy 269.510238 -103.80778)
			(xy 269.509748 -103.777796) (xy 170.654955 -103.777796) (xy 170.65449 -103.806256) (xy 170.646662 -103.865712)
			(xy 170.631141 -103.923637) (xy 170.608192 -103.979041) (xy 170.578208 -104.030975) (xy 170.541702 -104.078551)
			(xy 170.499297 -104.120956) (xy 170.451721 -104.157462) (xy 170.399787 -104.187446) (xy 170.344383 -104.210395)
			(xy 170.286458 -104.225916) (xy 170.227002 -104.233744) (xy 170.167034 -104.233744) (xy 170.107578 -104.225916)
			(xy 170.049653 -104.210395) (xy 169.994249 -104.187446) (xy 169.942315 -104.157462) (xy 169.894739 -104.120956)
			(xy 169.852334 -104.078551) (xy 169.815828 -104.030975) (xy 169.785844 -103.979041) (xy 169.762895 -103.923637)
			(xy 169.747374 -103.865712) (xy 169.739546 -103.806256) (xy 169.739056 -103.776272) (xy 154.325828 -103.776272)
			(xy 154.325828 -103.777796) (xy 154.325338 -103.80778) (xy 154.31751 -103.867236) (xy 154.301989 -103.925161)
			(xy 154.27904 -103.980565) (xy 154.249056 -104.032499) (xy 154.21255 -104.080075) (xy 154.170145 -104.12248)
			(xy 154.122569 -104.158986) (xy 154.070635 -104.18897) (xy 154.015231 -104.211919) (xy 153.957306 -104.22744)
			(xy 153.89785 -104.235268) (xy 153.837882 -104.235268) (xy 153.778426 -104.22744) (xy 153.720501 -104.211919)
			(xy 153.665097 -104.18897) (xy 153.613163 -104.158986) (xy 153.565587 -104.12248) (xy 153.523182 -104.080075)
			(xy 153.486676 -104.032499) (xy 153.456692 -103.980565) (xy 153.433743 -103.925161) (xy 153.418222 -103.867236)
			(xy 153.410394 -103.80778) (xy 153.409904 -103.777796) (xy 54.554603 -103.777796) (xy 54.554138 -103.80624)
			(xy 54.546315 -103.865662) (xy 54.530802 -103.923555) (xy 54.507866 -103.978928) (xy 54.477899 -104.030834)
			(xy 54.441412 -104.078384) (xy 54.399032 -104.120764) (xy 54.351482 -104.157251) (xy 54.299576 -104.187218)
			(xy 54.244203 -104.210154) (xy 54.18631 -104.225667) (xy 54.126888 -104.23349) (xy 54.066952 -104.23349)
			(xy 54.00753 -104.225667) (xy 53.949637 -104.210154) (xy 53.894264 -104.187218) (xy 53.842358 -104.157251)
			(xy 53.794808 -104.120764) (xy 53.752428 -104.078384) (xy 53.715941 -104.030834) (xy 53.685974 -103.978928)
			(xy 53.663038 -103.923555) (xy 53.647525 -103.865662) (xy 53.639702 -103.80624) (xy 53.639212 -103.776272)
			(xy 38.225476 -103.776272) (xy 38.225476 -103.777796) (xy 38.224986 -103.807764) (xy 38.217163 -103.867186)
			(xy 38.20165 -103.925079) (xy 38.178714 -103.980452) (xy 38.148747 -104.032358) (xy 38.11226 -104.079908)
			(xy 38.06988 -104.122288) (xy 38.02233 -104.158775) (xy 37.970424 -104.188742) (xy 37.915051 -104.211678)
			(xy 37.857158 -104.227191) (xy 37.797736 -104.235014) (xy 37.7378 -104.235014) (xy 37.678378 -104.227191)
			(xy 37.620485 -104.211678) (xy 37.565112 -104.188742) (xy 37.513206 -104.158775) (xy 37.465656 -104.122288)
			(xy 37.423276 -104.079908) (xy 37.386789 -104.032358) (xy 37.356822 -103.980452) (xy 37.333886 -103.925079)
			(xy 37.318373 -103.867186) (xy 37.31055 -103.807764) (xy 37.31006 -103.777796) (xy 4.308094 -103.777796)
			(xy 4.308094 -105.584498) (xy 34.667952 -105.584498) (xy 34.667952 -104.720898) (xy 34.668442 -104.69093)
			(xy 34.676265 -104.631508) (xy 34.691778 -104.573615) (xy 34.714714 -104.518242) (xy 34.744681 -104.466336)
			(xy 34.781168 -104.418786) (xy 34.823548 -104.376406) (xy 34.871098 -104.339919) (xy 34.923004 -104.309952)
			(xy 34.978377 -104.287016) (xy 35.03627 -104.271503) (xy 35.095692 -104.26368) (xy 35.155628 -104.26368)
			(xy 35.21505 -104.271503) (xy 35.272943 -104.287016) (xy 35.328316 -104.309952) (xy 35.380222 -104.339919)
			(xy 35.427772 -104.376406) (xy 35.470152 -104.418786) (xy 35.506639 -104.466336) (xy 35.536606 -104.518242)
			(xy 35.559542 -104.573615) (xy 35.575055 -104.631508) (xy 35.582878 -104.69093) (xy 35.583368 -104.720898)
			(xy 35.583368 -105.57637) (xy 51.785012 -105.57637) (xy 51.785012 -104.71277) (xy 51.785502 -104.682802)
			(xy 51.793325 -104.62338) (xy 51.808838 -104.565487) (xy 51.831774 -104.510114) (xy 51.861741 -104.458208)
			(xy 51.898228 -104.410658) (xy 51.940608 -104.368278) (xy 51.988158 -104.331791) (xy 52.040064 -104.301824)
			(xy 52.095437 -104.278888) (xy 52.15333 -104.263375) (xy 52.212752 -104.255552) (xy 52.272688 -104.255552)
			(xy 52.33211 -104.263375) (xy 52.390003 -104.278888) (xy 52.445376 -104.301824) (xy 52.497282 -104.331791)
			(xy 52.544832 -104.368278) (xy 52.587212 -104.410658) (xy 52.623699 -104.458208) (xy 52.653666 -104.510114)
			(xy 52.676602 -104.565487) (xy 52.692115 -104.62338) (xy 52.699938 -104.682802) (xy 52.700428 -104.71277)
			(xy 52.700428 -105.57637) (xy 52.700295 -105.584498) (xy 150.767796 -105.584498) (xy 150.767796 -104.720898)
			(xy 150.768286 -104.690914) (xy 150.776114 -104.631458) (xy 150.791635 -104.573533) (xy 150.814584 -104.518129)
			(xy 150.844568 -104.466195) (xy 150.881074 -104.418619) (xy 150.923479 -104.376214) (xy 150.971055 -104.339708)
			(xy 151.022989 -104.309724) (xy 151.078393 -104.286775) (xy 151.136318 -104.271254) (xy 151.195774 -104.263426)
			(xy 151.255742 -104.263426) (xy 151.315198 -104.271254) (xy 151.373123 -104.286775) (xy 151.428527 -104.309724)
			(xy 151.480461 -104.339708) (xy 151.528037 -104.376214) (xy 151.570442 -104.418619) (xy 151.606948 -104.466195)
			(xy 151.636932 -104.518129) (xy 151.659881 -104.573533) (xy 151.675402 -104.631458) (xy 151.68323 -104.690914)
			(xy 151.68372 -104.720898) (xy 151.68372 -105.57637) (xy 167.884856 -105.57637) (xy 167.884856 -104.71277)
			(xy 167.885346 -104.682786) (xy 167.893174 -104.62333) (xy 167.908695 -104.565405) (xy 167.931644 -104.510001)
			(xy 167.961628 -104.458067) (xy 167.998134 -104.410491) (xy 168.040539 -104.368086) (xy 168.088115 -104.33158)
			(xy 168.140049 -104.301596) (xy 168.195453 -104.278647) (xy 168.253378 -104.263126) (xy 168.312834 -104.255298)
			(xy 168.372802 -104.255298) (xy 168.432258 -104.263126) (xy 168.490183 -104.278647) (xy 168.545587 -104.301596)
			(xy 168.597521 -104.33158) (xy 168.645097 -104.368086) (xy 168.687502 -104.410491) (xy 168.724008 -104.458067)
			(xy 168.753992 -104.510001) (xy 168.776941 -104.565405) (xy 168.792462 -104.62333) (xy 168.80029 -104.682786)
			(xy 168.80078 -104.71277) (xy 168.80078 -105.57637) (xy 168.800647 -105.584498) (xy 266.86764 -105.584498)
			(xy 266.86764 -104.720898) (xy 266.86813 -104.690914) (xy 266.875958 -104.631458) (xy 266.891479 -104.573533)
			(xy 266.914428 -104.518129) (xy 266.944412 -104.466195) (xy 266.980918 -104.418619) (xy 267.023323 -104.376214)
			(xy 267.070899 -104.339708) (xy 267.122833 -104.309724) (xy 267.178237 -104.286775) (xy 267.236162 -104.271254)
			(xy 267.295618 -104.263426) (xy 267.355586 -104.263426) (xy 267.415042 -104.271254) (xy 267.472967 -104.286775)
			(xy 267.528371 -104.309724) (xy 267.580305 -104.339708) (xy 267.627881 -104.376214) (xy 267.670286 -104.418619)
			(xy 267.706792 -104.466195) (xy 267.736776 -104.518129) (xy 267.759725 -104.573533) (xy 267.775246 -104.631458)
			(xy 267.783074 -104.690914) (xy 267.783564 -104.720898) (xy 267.783564 -105.57637) (xy 283.9847 -105.57637)
			(xy 283.9847 -104.71277) (xy 283.98519 -104.682786) (xy 283.993018 -104.62333) (xy 284.008539 -104.565405)
			(xy 284.031488 -104.510001) (xy 284.061472 -104.458067) (xy 284.097978 -104.410491) (xy 284.140383 -104.368086)
			(xy 284.187959 -104.33158) (xy 284.239893 -104.301596) (xy 284.295297 -104.278647) (xy 284.353222 -104.263126)
			(xy 284.412678 -104.255298) (xy 284.472646 -104.255298) (xy 284.532102 -104.263126) (xy 284.590027 -104.278647)
			(xy 284.645431 -104.301596) (xy 284.697365 -104.33158) (xy 284.744941 -104.368086) (xy 284.787346 -104.410491)
			(xy 284.823852 -104.458067) (xy 284.853836 -104.510001) (xy 284.876785 -104.565405) (xy 284.892306 -104.62333)
			(xy 284.900134 -104.682786) (xy 284.900624 -104.71277) (xy 284.900624 -105.57637) (xy 284.900491 -105.584498)
			(xy 382.967992 -105.584498) (xy 382.967992 -104.720898) (xy 382.968482 -104.69093) (xy 382.976305 -104.631508)
			(xy 382.991818 -104.573615) (xy 383.014754 -104.518242) (xy 383.044721 -104.466336) (xy 383.081208 -104.418786)
			(xy 383.123588 -104.376406) (xy 383.171138 -104.339919) (xy 383.223044 -104.309952) (xy 383.278417 -104.287016)
			(xy 383.33631 -104.271503) (xy 383.395732 -104.26368) (xy 383.455668 -104.26368) (xy 383.51509 -104.271503)
			(xy 383.572983 -104.287016) (xy 383.628356 -104.309952) (xy 383.680262 -104.339919) (xy 383.727812 -104.376406)
			(xy 383.770192 -104.418786) (xy 383.806679 -104.466336) (xy 383.836646 -104.518242) (xy 383.859582 -104.573615)
			(xy 383.875095 -104.631508) (xy 383.882918 -104.69093) (xy 383.883408 -104.720898) (xy 383.883408 -105.57637)
			(xy 400.085052 -105.57637) (xy 400.085052 -104.71277) (xy 400.085542 -104.682802) (xy 400.093365 -104.62338)
			(xy 400.108878 -104.565487) (xy 400.131814 -104.510114) (xy 400.161781 -104.458208) (xy 400.198268 -104.410658)
			(xy 400.240648 -104.368278) (xy 400.288198 -104.331791) (xy 400.340104 -104.301824) (xy 400.395477 -104.278888)
			(xy 400.45337 -104.263375) (xy 400.512792 -104.255552) (xy 400.572728 -104.255552) (xy 400.63215 -104.263375)
			(xy 400.690043 -104.278888) (xy 400.745416 -104.301824) (xy 400.797322 -104.331791) (xy 400.844872 -104.368278)
			(xy 400.887252 -104.410658) (xy 400.923739 -104.458208) (xy 400.953706 -104.510114) (xy 400.976642 -104.565487)
			(xy 400.992155 -104.62338) (xy 400.999978 -104.682802) (xy 401.000468 -104.71277) (xy 401.000468 -105.57637)
			(xy 400.999978 -105.606338) (xy 400.992155 -105.66576) (xy 400.976642 -105.723653) (xy 400.953706 -105.779026)
			(xy 400.923739 -105.830932) (xy 400.887252 -105.878482) (xy 400.844872 -105.920862) (xy 400.797322 -105.957349)
			(xy 400.745416 -105.987316) (xy 400.690043 -106.010252) (xy 400.63215 -106.025765) (xy 400.572728 -106.033588)
			(xy 400.512792 -106.033588) (xy 400.45337 -106.025765) (xy 400.395477 -106.010252) (xy 400.340104 -105.987316)
			(xy 400.288198 -105.957349) (xy 400.240648 -105.920862) (xy 400.198268 -105.878482) (xy 400.161781 -105.830932)
			(xy 400.131814 -105.779026) (xy 400.108878 -105.723653) (xy 400.093365 -105.66576) (xy 400.085542 -105.606338)
			(xy 400.085052 -105.57637) (xy 383.883408 -105.57637) (xy 383.883408 -105.584498) (xy 383.882918 -105.614466)
			(xy 383.875095 -105.673888) (xy 383.859582 -105.731781) (xy 383.836646 -105.787154) (xy 383.806679 -105.83906)
			(xy 383.770192 -105.88661) (xy 383.727812 -105.92899) (xy 383.680262 -105.965477) (xy 383.628356 -105.995444)
			(xy 383.572983 -106.01838) (xy 383.51509 -106.033893) (xy 383.455668 -106.041716) (xy 383.395732 -106.041716)
			(xy 383.33631 -106.033893) (xy 383.278417 -106.01838) (xy 383.223044 -105.995444) (xy 383.171138 -105.965477)
			(xy 383.123588 -105.92899) (xy 383.081208 -105.88661) (xy 383.044721 -105.83906) (xy 383.014754 -105.787154)
			(xy 382.991818 -105.731781) (xy 382.976305 -105.673888) (xy 382.968482 -105.614466) (xy 382.967992 -105.584498)
			(xy 284.900491 -105.584498) (xy 284.900134 -105.606354) (xy 284.892306 -105.66581) (xy 284.876785 -105.723735)
			(xy 284.853836 -105.779139) (xy 284.823852 -105.831073) (xy 284.787346 -105.878649) (xy 284.744941 -105.921054)
			(xy 284.697365 -105.95756) (xy 284.645431 -105.987544) (xy 284.590027 -106.010493) (xy 284.532102 -106.026014)
			(xy 284.472646 -106.033842) (xy 284.412678 -106.033842) (xy 284.353222 -106.026014) (xy 284.295297 -106.010493)
			(xy 284.239893 -105.987544) (xy 284.187959 -105.95756) (xy 284.140383 -105.921054) (xy 284.097978 -105.878649)
			(xy 284.061472 -105.831073) (xy 284.031488 -105.779139) (xy 284.008539 -105.723735) (xy 283.993018 -105.66581)
			(xy 283.98519 -105.606354) (xy 283.9847 -105.57637) (xy 267.783564 -105.57637) (xy 267.783564 -105.584498)
			(xy 267.783074 -105.614482) (xy 267.775246 -105.673938) (xy 267.759725 -105.731863) (xy 267.736776 -105.787267)
			(xy 267.706792 -105.839201) (xy 267.670286 -105.886777) (xy 267.627881 -105.929182) (xy 267.580305 -105.965688)
			(xy 267.528371 -105.995672) (xy 267.472967 -106.018621) (xy 267.415042 -106.034142) (xy 267.355586 -106.04197)
			(xy 267.295618 -106.04197) (xy 267.236162 -106.034142) (xy 267.178237 -106.018621) (xy 267.122833 -105.995672)
			(xy 267.070899 -105.965688) (xy 267.023323 -105.929182) (xy 266.980918 -105.886777) (xy 266.944412 -105.839201)
			(xy 266.914428 -105.787267) (xy 266.891479 -105.731863) (xy 266.875958 -105.673938) (xy 266.86813 -105.614482)
			(xy 266.86764 -105.584498) (xy 168.800647 -105.584498) (xy 168.80029 -105.606354) (xy 168.792462 -105.66581)
			(xy 168.776941 -105.723735) (xy 168.753992 -105.779139) (xy 168.724008 -105.831073) (xy 168.687502 -105.878649)
			(xy 168.645097 -105.921054) (xy 168.597521 -105.95756) (xy 168.545587 -105.987544) (xy 168.490183 -106.010493)
			(xy 168.432258 -106.026014) (xy 168.372802 -106.033842) (xy 168.312834 -106.033842) (xy 168.253378 -106.026014)
			(xy 168.195453 -106.010493) (xy 168.140049 -105.987544) (xy 168.088115 -105.95756) (xy 168.040539 -105.921054)
			(xy 167.998134 -105.878649) (xy 167.961628 -105.831073) (xy 167.931644 -105.779139) (xy 167.908695 -105.723735)
			(xy 167.893174 -105.66581) (xy 167.885346 -105.606354) (xy 167.884856 -105.57637) (xy 151.68372 -105.57637)
			(xy 151.68372 -105.584498) (xy 151.68323 -105.614482) (xy 151.675402 -105.673938) (xy 151.659881 -105.731863)
			(xy 151.636932 -105.787267) (xy 151.606948 -105.839201) (xy 151.570442 -105.886777) (xy 151.528037 -105.929182)
			(xy 151.480461 -105.965688) (xy 151.428527 -105.995672) (xy 151.373123 -106.018621) (xy 151.315198 -106.034142)
			(xy 151.255742 -106.04197) (xy 151.195774 -106.04197) (xy 151.136318 -106.034142) (xy 151.078393 -106.018621)
			(xy 151.022989 -105.995672) (xy 150.971055 -105.965688) (xy 150.923479 -105.929182) (xy 150.881074 -105.886777)
			(xy 150.844568 -105.839201) (xy 150.814584 -105.787267) (xy 150.791635 -105.731863) (xy 150.776114 -105.673938)
			(xy 150.768286 -105.614482) (xy 150.767796 -105.584498) (xy 52.700295 -105.584498) (xy 52.699938 -105.606338)
			(xy 52.692115 -105.66576) (xy 52.676602 -105.723653) (xy 52.653666 -105.779026) (xy 52.623699 -105.830932)
			(xy 52.587212 -105.878482) (xy 52.544832 -105.920862) (xy 52.497282 -105.957349) (xy 52.445376 -105.987316)
			(xy 52.390003 -106.010252) (xy 52.33211 -106.025765) (xy 52.272688 -106.033588) (xy 52.212752 -106.033588)
			(xy 52.15333 -106.025765) (xy 52.095437 -106.010252) (xy 52.040064 -105.987316) (xy 51.988158 -105.957349)
			(xy 51.940608 -105.920862) (xy 51.898228 -105.878482) (xy 51.861741 -105.830932) (xy 51.831774 -105.779026)
			(xy 51.808838 -105.723653) (xy 51.793325 -105.66576) (xy 51.785502 -105.606338) (xy 51.785012 -105.57637)
			(xy 35.583368 -105.57637) (xy 35.583368 -105.584498) (xy 35.582878 -105.614466) (xy 35.575055 -105.673888)
			(xy 35.559542 -105.731781) (xy 35.536606 -105.787154) (xy 35.506639 -105.83906) (xy 35.470152 -105.88661)
			(xy 35.427772 -105.92899) (xy 35.380222 -105.965477) (xy 35.328316 -105.995444) (xy 35.272943 -106.01838)
			(xy 35.21505 -106.033893) (xy 35.155628 -106.041716) (xy 35.095692 -106.041716) (xy 35.03627 -106.033893)
			(xy 34.978377 -106.01838) (xy 34.923004 -105.995444) (xy 34.871098 -105.965477) (xy 34.823548 -105.92899)
			(xy 34.781168 -105.88661) (xy 34.744681 -105.83906) (xy 34.714714 -105.787154) (xy 34.691778 -105.731781)
			(xy 34.676265 -105.673888) (xy 34.668442 -105.614466) (xy 34.667952 -105.584498) (xy 4.308094 -105.584498)
			(xy 4.308094 -107.377738) (xy 37.31006 -107.377738) (xy 37.31006 -106.514138) (xy 37.31055 -106.48417)
			(xy 37.318373 -106.424748) (xy 37.333886 -106.366855) (xy 37.356822 -106.311482) (xy 37.386789 -106.259576)
			(xy 37.423276 -106.212026) (xy 37.465656 -106.169646) (xy 37.513206 -106.133159) (xy 37.565112 -106.103192)
			(xy 37.620485 -106.080256) (xy 37.678378 -106.064743) (xy 37.7378 -106.05692) (xy 37.797736 -106.05692)
			(xy 37.857158 -106.064743) (xy 37.915051 -106.080256) (xy 37.970424 -106.103192) (xy 38.02233 -106.133159)
			(xy 38.06988 -106.169646) (xy 38.11226 -106.212026) (xy 38.148747 -106.259576) (xy 38.178714 -106.311482)
			(xy 38.20165 -106.366855) (xy 38.217163 -106.424748) (xy 38.224986 -106.48417) (xy 38.225476 -106.514138)
			(xy 38.225476 -107.376214) (xy 53.639212 -107.376214) (xy 53.639212 -106.512614) (xy 53.639702 -106.482646)
			(xy 53.647525 -106.423224) (xy 53.663038 -106.365331) (xy 53.685974 -106.309958) (xy 53.715941 -106.258052)
			(xy 53.752428 -106.210502) (xy 53.794808 -106.168122) (xy 53.842358 -106.131635) (xy 53.894264 -106.101668)
			(xy 53.949637 -106.078732) (xy 54.00753 -106.063219) (xy 54.066952 -106.055396) (xy 54.126888 -106.055396)
			(xy 54.18631 -106.063219) (xy 54.244203 -106.078732) (xy 54.299576 -106.101668) (xy 54.351482 -106.131635)
			(xy 54.399032 -106.168122) (xy 54.441412 -106.210502) (xy 54.477899 -106.258052) (xy 54.507866 -106.309958)
			(xy 54.530802 -106.365331) (xy 54.546315 -106.423224) (xy 54.554138 -106.482646) (xy 54.554628 -106.512614)
			(xy 54.554628 -107.376214) (xy 54.554603 -107.377738) (xy 153.409904 -107.377738) (xy 153.409904 -106.514138)
			(xy 153.410394 -106.484154) (xy 153.418222 -106.424698) (xy 153.433743 -106.366773) (xy 153.456692 -106.311369)
			(xy 153.486676 -106.259435) (xy 153.523182 -106.211859) (xy 153.565587 -106.169454) (xy 153.613163 -106.132948)
			(xy 153.665097 -106.102964) (xy 153.720501 -106.080015) (xy 153.778426 -106.064494) (xy 153.837882 -106.056666)
			(xy 153.89785 -106.056666) (xy 153.957306 -106.064494) (xy 154.015231 -106.080015) (xy 154.070635 -106.102964)
			(xy 154.122569 -106.132948) (xy 154.170145 -106.169454) (xy 154.21255 -106.211859) (xy 154.249056 -106.259435)
			(xy 154.27904 -106.311369) (xy 154.301989 -106.366773) (xy 154.31751 -106.424698) (xy 154.325338 -106.484154)
			(xy 154.325828 -106.514138) (xy 154.325828 -107.376214) (xy 169.739056 -107.376214) (xy 169.739056 -106.512614)
			(xy 169.739546 -106.48263) (xy 169.747374 -106.423174) (xy 169.762895 -106.365249) (xy 169.785844 -106.309845)
			(xy 169.815828 -106.257911) (xy 169.852334 -106.210335) (xy 169.894739 -106.16793) (xy 169.942315 -106.131424)
			(xy 169.994249 -106.10144) (xy 170.049653 -106.078491) (xy 170.107578 -106.06297) (xy 170.167034 -106.055142)
			(xy 170.227002 -106.055142) (xy 170.286458 -106.06297) (xy 170.344383 -106.078491) (xy 170.399787 -106.10144)
			(xy 170.451721 -106.131424) (xy 170.499297 -106.16793) (xy 170.541702 -106.210335) (xy 170.578208 -106.257911)
			(xy 170.608192 -106.309845) (xy 170.631141 -106.365249) (xy 170.646662 -106.423174) (xy 170.65449 -106.48263)
			(xy 170.65498 -106.512614) (xy 170.65498 -107.376214) (xy 170.654955 -107.377738) (xy 269.509748 -107.377738)
			(xy 269.509748 -106.514138) (xy 269.510238 -106.484154) (xy 269.518066 -106.424698) (xy 269.533587 -106.366773)
			(xy 269.556536 -106.311369) (xy 269.58652 -106.259435) (xy 269.623026 -106.211859) (xy 269.665431 -106.169454)
			(xy 269.713007 -106.132948) (xy 269.764941 -106.102964) (xy 269.820345 -106.080015) (xy 269.87827 -106.064494)
			(xy 269.937726 -106.056666) (xy 269.997694 -106.056666) (xy 270.05715 -106.064494) (xy 270.115075 -106.080015)
			(xy 270.170479 -106.102964) (xy 270.222413 -106.132948) (xy 270.269989 -106.169454) (xy 270.312394 -106.211859)
			(xy 270.3489 -106.259435) (xy 270.378884 -106.311369) (xy 270.401833 -106.366773) (xy 270.417354 -106.424698)
			(xy 270.425182 -106.484154) (xy 270.425672 -106.514138) (xy 270.425672 -107.376214) (xy 285.8389 -107.376214)
			(xy 285.8389 -106.512614) (xy 285.83939 -106.48263) (xy 285.847218 -106.423174) (xy 285.862739 -106.365249)
			(xy 285.885688 -106.309845) (xy 285.915672 -106.257911) (xy 285.952178 -106.210335) (xy 285.994583 -106.16793)
			(xy 286.042159 -106.131424) (xy 286.094093 -106.10144) (xy 286.149497 -106.078491) (xy 286.207422 -106.06297)
			(xy 286.266878 -106.055142) (xy 286.326846 -106.055142) (xy 286.386302 -106.06297) (xy 286.444227 -106.078491)
			(xy 286.499631 -106.10144) (xy 286.551565 -106.131424) (xy 286.599141 -106.16793) (xy 286.641546 -106.210335)
			(xy 286.678052 -106.257911) (xy 286.708036 -106.309845) (xy 286.730985 -106.365249) (xy 286.746506 -106.423174)
			(xy 286.754334 -106.48263) (xy 286.754824 -106.512614) (xy 286.754824 -107.376214) (xy 286.754799 -107.377738)
			(xy 385.6101 -107.377738) (xy 385.6101 -106.514138) (xy 385.61059 -106.48417) (xy 385.618413 -106.424748)
			(xy 385.633926 -106.366855) (xy 385.656862 -106.311482) (xy 385.686829 -106.259576) (xy 385.723316 -106.212026)
			(xy 385.765696 -106.169646) (xy 385.813246 -106.133159) (xy 385.865152 -106.103192) (xy 385.920525 -106.080256)
			(xy 385.978418 -106.064743) (xy 386.03784 -106.05692) (xy 386.097776 -106.05692) (xy 386.157198 -106.064743)
			(xy 386.215091 -106.080256) (xy 386.270464 -106.103192) (xy 386.32237 -106.133159) (xy 386.36992 -106.169646)
			(xy 386.4123 -106.212026) (xy 386.448787 -106.259576) (xy 386.478754 -106.311482) (xy 386.50169 -106.366855)
			(xy 386.517203 -106.424748) (xy 386.525026 -106.48417) (xy 386.525516 -106.514138) (xy 386.525516 -107.376214)
			(xy 401.939252 -107.376214) (xy 401.939252 -106.512614) (xy 401.939742 -106.482646) (xy 401.947565 -106.423224)
			(xy 401.963078 -106.365331) (xy 401.986014 -106.309958) (xy 402.015981 -106.258052) (xy 402.052468 -106.210502)
			(xy 402.094848 -106.168122) (xy 402.142398 -106.131635) (xy 402.194304 -106.101668) (xy 402.249677 -106.078732)
			(xy 402.30757 -106.063219) (xy 402.366992 -106.055396) (xy 402.426928 -106.055396) (xy 402.48635 -106.063219)
			(xy 402.544243 -106.078732) (xy 402.599616 -106.101668) (xy 402.651522 -106.131635) (xy 402.699072 -106.168122)
			(xy 402.741452 -106.210502) (xy 402.777939 -106.258052) (xy 402.807906 -106.309958) (xy 402.830842 -106.365331)
			(xy 402.846355 -106.423224) (xy 402.854178 -106.482646) (xy 402.854668 -106.512614) (xy 402.854668 -107.376214)
			(xy 402.854178 -107.406182) (xy 402.846355 -107.465604) (xy 402.830842 -107.523497) (xy 402.807906 -107.57887)
			(xy 402.777939 -107.630776) (xy 402.741452 -107.678326) (xy 402.699072 -107.720706) (xy 402.651522 -107.757193)
			(xy 402.599616 -107.78716) (xy 402.544243 -107.810096) (xy 402.48635 -107.825609) (xy 402.426928 -107.833432)
			(xy 402.366992 -107.833432) (xy 402.30757 -107.825609) (xy 402.249677 -107.810096) (xy 402.194304 -107.78716)
			(xy 402.142398 -107.757193) (xy 402.094848 -107.720706) (xy 402.052468 -107.678326) (xy 402.015981 -107.630776)
			(xy 401.986014 -107.57887) (xy 401.963078 -107.523497) (xy 401.947565 -107.465604) (xy 401.939742 -107.406182)
			(xy 401.939252 -107.376214) (xy 386.525516 -107.376214) (xy 386.525516 -107.377738) (xy 386.525026 -107.407706)
			(xy 386.517203 -107.467128) (xy 386.50169 -107.525021) (xy 386.478754 -107.580394) (xy 386.448787 -107.6323)
			(xy 386.4123 -107.67985) (xy 386.36992 -107.72223) (xy 386.32237 -107.758717) (xy 386.270464 -107.788684)
			(xy 386.215091 -107.81162) (xy 386.157198 -107.827133) (xy 386.097776 -107.834956) (xy 386.03784 -107.834956)
			(xy 385.978418 -107.827133) (xy 385.920525 -107.81162) (xy 385.865152 -107.788684) (xy 385.813246 -107.758717)
			(xy 385.765696 -107.72223) (xy 385.723316 -107.67985) (xy 385.686829 -107.6323) (xy 385.656862 -107.580394)
			(xy 385.633926 -107.525021) (xy 385.618413 -107.467128) (xy 385.61059 -107.407706) (xy 385.6101 -107.377738)
			(xy 286.754799 -107.377738) (xy 286.754334 -107.406198) (xy 286.746506 -107.465654) (xy 286.730985 -107.523579)
			(xy 286.708036 -107.578983) (xy 286.678052 -107.630917) (xy 286.641546 -107.678493) (xy 286.599141 -107.720898)
			(xy 286.551565 -107.757404) (xy 286.499631 -107.787388) (xy 286.444227 -107.810337) (xy 286.386302 -107.825858)
			(xy 286.326846 -107.833686) (xy 286.266878 -107.833686) (xy 286.207422 -107.825858) (xy 286.149497 -107.810337)
			(xy 286.094093 -107.787388) (xy 286.042159 -107.757404) (xy 285.994583 -107.720898) (xy 285.952178 -107.678493)
			(xy 285.915672 -107.630917) (xy 285.885688 -107.578983) (xy 285.862739 -107.523579) (xy 285.847218 -107.465654)
			(xy 285.83939 -107.406198) (xy 285.8389 -107.376214) (xy 270.425672 -107.376214) (xy 270.425672 -107.377738)
			(xy 270.425182 -107.407722) (xy 270.417354 -107.467178) (xy 270.401833 -107.525103) (xy 270.378884 -107.580507)
			(xy 270.3489 -107.632441) (xy 270.312394 -107.680017) (xy 270.269989 -107.722422) (xy 270.222413 -107.758928)
			(xy 270.170479 -107.788912) (xy 270.115075 -107.811861) (xy 270.05715 -107.827382) (xy 269.997694 -107.83521)
			(xy 269.937726 -107.83521) (xy 269.87827 -107.827382) (xy 269.820345 -107.811861) (xy 269.764941 -107.788912)
			(xy 269.713007 -107.758928) (xy 269.665431 -107.722422) (xy 269.623026 -107.680017) (xy 269.58652 -107.632441)
			(xy 269.556536 -107.580507) (xy 269.533587 -107.525103) (xy 269.518066 -107.467178) (xy 269.510238 -107.407722)
			(xy 269.509748 -107.377738) (xy 170.654955 -107.377738) (xy 170.65449 -107.406198) (xy 170.646662 -107.465654)
			(xy 170.631141 -107.523579) (xy 170.608192 -107.578983) (xy 170.578208 -107.630917) (xy 170.541702 -107.678493)
			(xy 170.499297 -107.720898) (xy 170.451721 -107.757404) (xy 170.399787 -107.787388) (xy 170.344383 -107.810337)
			(xy 170.286458 -107.825858) (xy 170.227002 -107.833686) (xy 170.167034 -107.833686) (xy 170.107578 -107.825858)
			(xy 170.049653 -107.810337) (xy 169.994249 -107.787388) (xy 169.942315 -107.757404) (xy 169.894739 -107.720898)
			(xy 169.852334 -107.678493) (xy 169.815828 -107.630917) (xy 169.785844 -107.578983) (xy 169.762895 -107.523579)
			(xy 169.747374 -107.465654) (xy 169.739546 -107.406198) (xy 169.739056 -107.376214) (xy 154.325828 -107.376214)
			(xy 154.325828 -107.377738) (xy 154.325338 -107.407722) (xy 154.31751 -107.467178) (xy 154.301989 -107.525103)
			(xy 154.27904 -107.580507) (xy 154.249056 -107.632441) (xy 154.21255 -107.680017) (xy 154.170145 -107.722422)
			(xy 154.122569 -107.758928) (xy 154.070635 -107.788912) (xy 154.015231 -107.811861) (xy 153.957306 -107.827382)
			(xy 153.89785 -107.83521) (xy 153.837882 -107.83521) (xy 153.778426 -107.827382) (xy 153.720501 -107.811861)
			(xy 153.665097 -107.788912) (xy 153.613163 -107.758928) (xy 153.565587 -107.722422) (xy 153.523182 -107.680017)
			(xy 153.486676 -107.632441) (xy 153.456692 -107.580507) (xy 153.433743 -107.525103) (xy 153.418222 -107.467178)
			(xy 153.410394 -107.407722) (xy 153.409904 -107.377738) (xy 54.554603 -107.377738) (xy 54.554138 -107.406182)
			(xy 54.546315 -107.465604) (xy 54.530802 -107.523497) (xy 54.507866 -107.57887) (xy 54.477899 -107.630776)
			(xy 54.441412 -107.678326) (xy 54.399032 -107.720706) (xy 54.351482 -107.757193) (xy 54.299576 -107.78716)
			(xy 54.244203 -107.810096) (xy 54.18631 -107.825609) (xy 54.126888 -107.833432) (xy 54.066952 -107.833432)
			(xy 54.00753 -107.825609) (xy 53.949637 -107.810096) (xy 53.894264 -107.78716) (xy 53.842358 -107.757193)
			(xy 53.794808 -107.720706) (xy 53.752428 -107.678326) (xy 53.715941 -107.630776) (xy 53.685974 -107.57887)
			(xy 53.663038 -107.523497) (xy 53.647525 -107.465604) (xy 53.639702 -107.406182) (xy 53.639212 -107.376214)
			(xy 38.225476 -107.376214) (xy 38.225476 -107.377738) (xy 38.224986 -107.407706) (xy 38.217163 -107.467128)
			(xy 38.20165 -107.525021) (xy 38.178714 -107.580394) (xy 38.148747 -107.6323) (xy 38.11226 -107.67985)
			(xy 38.06988 -107.72223) (xy 38.02233 -107.758717) (xy 37.970424 -107.788684) (xy 37.915051 -107.81162)
			(xy 37.857158 -107.827133) (xy 37.797736 -107.834956) (xy 37.7378 -107.834956) (xy 37.678378 -107.827133)
			(xy 37.620485 -107.81162) (xy 37.565112 -107.788684) (xy 37.513206 -107.758717) (xy 37.465656 -107.72223)
			(xy 37.423276 -107.67985) (xy 37.386789 -107.6323) (xy 37.356822 -107.580394) (xy 37.333886 -107.525021)
			(xy 37.318373 -107.467128) (xy 37.31055 -107.407706) (xy 37.31006 -107.377738) (xy 4.308094 -107.377738)
			(xy 4.308094 -109.18444) (xy 34.667952 -109.18444) (xy 34.667952 -108.32084) (xy 34.668442 -108.290872)
			(xy 34.676265 -108.23145) (xy 34.691778 -108.173557) (xy 34.714714 -108.118184) (xy 34.744681 -108.066278)
			(xy 34.781168 -108.018728) (xy 34.823548 -107.976348) (xy 34.871098 -107.939861) (xy 34.923004 -107.909894)
			(xy 34.978377 -107.886958) (xy 35.03627 -107.871445) (xy 35.095692 -107.863622) (xy 35.155628 -107.863622)
			(xy 35.21505 -107.871445) (xy 35.272943 -107.886958) (xy 35.328316 -107.909894) (xy 35.380222 -107.939861)
			(xy 35.427772 -107.976348) (xy 35.470152 -108.018728) (xy 35.506639 -108.066278) (xy 35.536606 -108.118184)
			(xy 35.559542 -108.173557) (xy 35.575055 -108.23145) (xy 35.582878 -108.290872) (xy 35.583368 -108.32084)
			(xy 35.583368 -109.176312) (xy 51.785012 -109.176312) (xy 51.785012 -108.312712) (xy 51.785502 -108.282744)
			(xy 51.793325 -108.223322) (xy 51.808838 -108.165429) (xy 51.831774 -108.110056) (xy 51.861741 -108.05815)
			(xy 51.898228 -108.0106) (xy 51.940608 -107.96822) (xy 51.988158 -107.931733) (xy 52.040064 -107.901766)
			(xy 52.095437 -107.87883) (xy 52.15333 -107.863317) (xy 52.212752 -107.855494) (xy 52.272688 -107.855494)
			(xy 52.33211 -107.863317) (xy 52.390003 -107.87883) (xy 52.445376 -107.901766) (xy 52.497282 -107.931733)
			(xy 52.544832 -107.96822) (xy 52.587212 -108.0106) (xy 52.623699 -108.05815) (xy 52.653666 -108.110056)
			(xy 52.676602 -108.165429) (xy 52.692115 -108.223322) (xy 52.699938 -108.282744) (xy 52.700428 -108.312712)
			(xy 52.700428 -109.176312) (xy 52.700295 -109.18444) (xy 150.767796 -109.18444) (xy 150.767796 -108.32084)
			(xy 150.768286 -108.290856) (xy 150.776114 -108.2314) (xy 150.791635 -108.173475) (xy 150.814584 -108.118071)
			(xy 150.844568 -108.066137) (xy 150.881074 -108.018561) (xy 150.923479 -107.976156) (xy 150.971055 -107.93965)
			(xy 151.022989 -107.909666) (xy 151.078393 -107.886717) (xy 151.136318 -107.871196) (xy 151.195774 -107.863368)
			(xy 151.255742 -107.863368) (xy 151.315198 -107.871196) (xy 151.373123 -107.886717) (xy 151.428527 -107.909666)
			(xy 151.480461 -107.93965) (xy 151.528037 -107.976156) (xy 151.570442 -108.018561) (xy 151.606948 -108.066137)
			(xy 151.636932 -108.118071) (xy 151.659881 -108.173475) (xy 151.675402 -108.2314) (xy 151.68323 -108.290856)
			(xy 151.68372 -108.32084) (xy 151.68372 -109.176312) (xy 167.884856 -109.176312) (xy 167.884856 -108.312712)
			(xy 167.885346 -108.282728) (xy 167.893174 -108.223272) (xy 167.908695 -108.165347) (xy 167.931644 -108.109943)
			(xy 167.961628 -108.058009) (xy 167.998134 -108.010433) (xy 168.040539 -107.968028) (xy 168.088115 -107.931522)
			(xy 168.140049 -107.901538) (xy 168.195453 -107.878589) (xy 168.253378 -107.863068) (xy 168.312834 -107.85524)
			(xy 168.372802 -107.85524) (xy 168.432258 -107.863068) (xy 168.490183 -107.878589) (xy 168.545587 -107.901538)
			(xy 168.597521 -107.931522) (xy 168.645097 -107.968028) (xy 168.687502 -108.010433) (xy 168.724008 -108.058009)
			(xy 168.753992 -108.109943) (xy 168.776941 -108.165347) (xy 168.792462 -108.223272) (xy 168.80029 -108.282728)
			(xy 168.80078 -108.312712) (xy 168.80078 -109.176312) (xy 168.800647 -109.18444) (xy 266.86764 -109.18444)
			(xy 266.86764 -108.32084) (xy 266.86813 -108.290856) (xy 266.875958 -108.2314) (xy 266.891479 -108.173475)
			(xy 266.914428 -108.118071) (xy 266.944412 -108.066137) (xy 266.980918 -108.018561) (xy 267.023323 -107.976156)
			(xy 267.070899 -107.93965) (xy 267.122833 -107.909666) (xy 267.178237 -107.886717) (xy 267.236162 -107.871196)
			(xy 267.295618 -107.863368) (xy 267.355586 -107.863368) (xy 267.415042 -107.871196) (xy 267.472967 -107.886717)
			(xy 267.528371 -107.909666) (xy 267.580305 -107.93965) (xy 267.627881 -107.976156) (xy 267.670286 -108.018561)
			(xy 267.706792 -108.066137) (xy 267.736776 -108.118071) (xy 267.759725 -108.173475) (xy 267.775246 -108.2314)
			(xy 267.783074 -108.290856) (xy 267.783564 -108.32084) (xy 267.783564 -109.176312) (xy 283.9847 -109.176312)
			(xy 283.9847 -108.312712) (xy 283.98519 -108.282728) (xy 283.993018 -108.223272) (xy 284.008539 -108.165347)
			(xy 284.031488 -108.109943) (xy 284.061472 -108.058009) (xy 284.097978 -108.010433) (xy 284.140383 -107.968028)
			(xy 284.187959 -107.931522) (xy 284.239893 -107.901538) (xy 284.295297 -107.878589) (xy 284.353222 -107.863068)
			(xy 284.412678 -107.85524) (xy 284.472646 -107.85524) (xy 284.532102 -107.863068) (xy 284.590027 -107.878589)
			(xy 284.645431 -107.901538) (xy 284.697365 -107.931522) (xy 284.744941 -107.968028) (xy 284.787346 -108.010433)
			(xy 284.823852 -108.058009) (xy 284.853836 -108.109943) (xy 284.876785 -108.165347) (xy 284.892306 -108.223272)
			(xy 284.900134 -108.282728) (xy 284.900624 -108.312712) (xy 284.900624 -109.176312) (xy 284.900491 -109.18444)
			(xy 382.967992 -109.18444) (xy 382.967992 -108.32084) (xy 382.968482 -108.290872) (xy 382.976305 -108.23145)
			(xy 382.991818 -108.173557) (xy 383.014754 -108.118184) (xy 383.044721 -108.066278) (xy 383.081208 -108.018728)
			(xy 383.123588 -107.976348) (xy 383.171138 -107.939861) (xy 383.223044 -107.909894) (xy 383.278417 -107.886958)
			(xy 383.33631 -107.871445) (xy 383.395732 -107.863622) (xy 383.455668 -107.863622) (xy 383.51509 -107.871445)
			(xy 383.572983 -107.886958) (xy 383.628356 -107.909894) (xy 383.680262 -107.939861) (xy 383.727812 -107.976348)
			(xy 383.770192 -108.018728) (xy 383.806679 -108.066278) (xy 383.836646 -108.118184) (xy 383.859582 -108.173557)
			(xy 383.875095 -108.23145) (xy 383.882918 -108.290872) (xy 383.883408 -108.32084) (xy 383.883408 -109.176312)
			(xy 400.085052 -109.176312) (xy 400.085052 -108.312712) (xy 400.085542 -108.282744) (xy 400.093365 -108.223322)
			(xy 400.108878 -108.165429) (xy 400.131814 -108.110056) (xy 400.161781 -108.05815) (xy 400.198268 -108.0106)
			(xy 400.240648 -107.96822) (xy 400.288198 -107.931733) (xy 400.340104 -107.901766) (xy 400.395477 -107.87883)
			(xy 400.45337 -107.863317) (xy 400.512792 -107.855494) (xy 400.572728 -107.855494) (xy 400.63215 -107.863317)
			(xy 400.690043 -107.87883) (xy 400.745416 -107.901766) (xy 400.797322 -107.931733) (xy 400.844872 -107.96822)
			(xy 400.887252 -108.0106) (xy 400.923739 -108.05815) (xy 400.953706 -108.110056) (xy 400.976642 -108.165429)
			(xy 400.992155 -108.223322) (xy 400.999978 -108.282744) (xy 401.000468 -108.312712) (xy 401.000468 -109.176312)
			(xy 400.999978 -109.20628) (xy 400.992155 -109.265702) (xy 400.976642 -109.323595) (xy 400.953706 -109.378968)
			(xy 400.923739 -109.430874) (xy 400.887252 -109.478424) (xy 400.844872 -109.520804) (xy 400.797322 -109.557291)
			(xy 400.745416 -109.587258) (xy 400.690043 -109.610194) (xy 400.63215 -109.625707) (xy 400.572728 -109.63353)
			(xy 400.512792 -109.63353) (xy 400.45337 -109.625707) (xy 400.395477 -109.610194) (xy 400.340104 -109.587258)
			(xy 400.288198 -109.557291) (xy 400.240648 -109.520804) (xy 400.198268 -109.478424) (xy 400.161781 -109.430874)
			(xy 400.131814 -109.378968) (xy 400.108878 -109.323595) (xy 400.093365 -109.265702) (xy 400.085542 -109.20628)
			(xy 400.085052 -109.176312) (xy 383.883408 -109.176312) (xy 383.883408 -109.18444) (xy 383.882918 -109.214408)
			(xy 383.875095 -109.27383) (xy 383.859582 -109.331723) (xy 383.836646 -109.387096) (xy 383.806679 -109.439002)
			(xy 383.770192 -109.486552) (xy 383.727812 -109.528932) (xy 383.680262 -109.565419) (xy 383.628356 -109.595386)
			(xy 383.572983 -109.618322) (xy 383.51509 -109.633835) (xy 383.455668 -109.641658) (xy 383.395732 -109.641658)
			(xy 383.33631 -109.633835) (xy 383.278417 -109.618322) (xy 383.223044 -109.595386) (xy 383.171138 -109.565419)
			(xy 383.123588 -109.528932) (xy 383.081208 -109.486552) (xy 383.044721 -109.439002) (xy 383.014754 -109.387096)
			(xy 382.991818 -109.331723) (xy 382.976305 -109.27383) (xy 382.968482 -109.214408) (xy 382.967992 -109.18444)
			(xy 284.900491 -109.18444) (xy 284.900134 -109.206296) (xy 284.892306 -109.265752) (xy 284.876785 -109.323677)
			(xy 284.853836 -109.379081) (xy 284.823852 -109.431015) (xy 284.787346 -109.478591) (xy 284.744941 -109.520996)
			(xy 284.697365 -109.557502) (xy 284.645431 -109.587486) (xy 284.590027 -109.610435) (xy 284.532102 -109.625956)
			(xy 284.472646 -109.633784) (xy 284.412678 -109.633784) (xy 284.353222 -109.625956) (xy 284.295297 -109.610435)
			(xy 284.239893 -109.587486) (xy 284.187959 -109.557502) (xy 284.140383 -109.520996) (xy 284.097978 -109.478591)
			(xy 284.061472 -109.431015) (xy 284.031488 -109.379081) (xy 284.008539 -109.323677) (xy 283.993018 -109.265752)
			(xy 283.98519 -109.206296) (xy 283.9847 -109.176312) (xy 267.783564 -109.176312) (xy 267.783564 -109.18444)
			(xy 267.783074 -109.214424) (xy 267.775246 -109.27388) (xy 267.759725 -109.331805) (xy 267.736776 -109.387209)
			(xy 267.706792 -109.439143) (xy 267.670286 -109.486719) (xy 267.627881 -109.529124) (xy 267.580305 -109.56563)
			(xy 267.528371 -109.595614) (xy 267.472967 -109.618563) (xy 267.415042 -109.634084) (xy 267.355586 -109.641912)
			(xy 267.295618 -109.641912) (xy 267.236162 -109.634084) (xy 267.178237 -109.618563) (xy 267.122833 -109.595614)
			(xy 267.070899 -109.56563) (xy 267.023323 -109.529124) (xy 266.980918 -109.486719) (xy 266.944412 -109.439143)
			(xy 266.914428 -109.387209) (xy 266.891479 -109.331805) (xy 266.875958 -109.27388) (xy 266.86813 -109.214424)
			(xy 266.86764 -109.18444) (xy 168.800647 -109.18444) (xy 168.80029 -109.206296) (xy 168.792462 -109.265752)
			(xy 168.776941 -109.323677) (xy 168.753992 -109.379081) (xy 168.724008 -109.431015) (xy 168.687502 -109.478591)
			(xy 168.645097 -109.520996) (xy 168.597521 -109.557502) (xy 168.545587 -109.587486) (xy 168.490183 -109.610435)
			(xy 168.432258 -109.625956) (xy 168.372802 -109.633784) (xy 168.312834 -109.633784) (xy 168.253378 -109.625956)
			(xy 168.195453 -109.610435) (xy 168.140049 -109.587486) (xy 168.088115 -109.557502) (xy 168.040539 -109.520996)
			(xy 167.998134 -109.478591) (xy 167.961628 -109.431015) (xy 167.931644 -109.379081) (xy 167.908695 -109.323677)
			(xy 167.893174 -109.265752) (xy 167.885346 -109.206296) (xy 167.884856 -109.176312) (xy 151.68372 -109.176312)
			(xy 151.68372 -109.18444) (xy 151.68323 -109.214424) (xy 151.675402 -109.27388) (xy 151.659881 -109.331805)
			(xy 151.636932 -109.387209) (xy 151.606948 -109.439143) (xy 151.570442 -109.486719) (xy 151.528037 -109.529124)
			(xy 151.480461 -109.56563) (xy 151.428527 -109.595614) (xy 151.373123 -109.618563) (xy 151.315198 -109.634084)
			(xy 151.255742 -109.641912) (xy 151.195774 -109.641912) (xy 151.136318 -109.634084) (xy 151.078393 -109.618563)
			(xy 151.022989 -109.595614) (xy 150.971055 -109.56563) (xy 150.923479 -109.529124) (xy 150.881074 -109.486719)
			(xy 150.844568 -109.439143) (xy 150.814584 -109.387209) (xy 150.791635 -109.331805) (xy 150.776114 -109.27388)
			(xy 150.768286 -109.214424) (xy 150.767796 -109.18444) (xy 52.700295 -109.18444) (xy 52.699938 -109.20628)
			(xy 52.692115 -109.265702) (xy 52.676602 -109.323595) (xy 52.653666 -109.378968) (xy 52.623699 -109.430874)
			(xy 52.587212 -109.478424) (xy 52.544832 -109.520804) (xy 52.497282 -109.557291) (xy 52.445376 -109.587258)
			(xy 52.390003 -109.610194) (xy 52.33211 -109.625707) (xy 52.272688 -109.63353) (xy 52.212752 -109.63353)
			(xy 52.15333 -109.625707) (xy 52.095437 -109.610194) (xy 52.040064 -109.587258) (xy 51.988158 -109.557291)
			(xy 51.940608 -109.520804) (xy 51.898228 -109.478424) (xy 51.861741 -109.430874) (xy 51.831774 -109.378968)
			(xy 51.808838 -109.323595) (xy 51.793325 -109.265702) (xy 51.785502 -109.20628) (xy 51.785012 -109.176312)
			(xy 35.583368 -109.176312) (xy 35.583368 -109.18444) (xy 35.582878 -109.214408) (xy 35.575055 -109.27383)
			(xy 35.559542 -109.331723) (xy 35.536606 -109.387096) (xy 35.506639 -109.439002) (xy 35.470152 -109.486552)
			(xy 35.427772 -109.528932) (xy 35.380222 -109.565419) (xy 35.328316 -109.595386) (xy 35.272943 -109.618322)
			(xy 35.21505 -109.633835) (xy 35.155628 -109.641658) (xy 35.095692 -109.641658) (xy 35.03627 -109.633835)
			(xy 34.978377 -109.618322) (xy 34.923004 -109.595386) (xy 34.871098 -109.565419) (xy 34.823548 -109.528932)
			(xy 34.781168 -109.486552) (xy 34.744681 -109.439002) (xy 34.714714 -109.387096) (xy 34.691778 -109.331723)
			(xy 34.676265 -109.27383) (xy 34.668442 -109.214408) (xy 34.667952 -109.18444) (xy 4.308094 -109.18444)
			(xy 4.308094 -110.977934) (xy 37.31006 -110.977934) (xy 37.31006 -110.114334) (xy 37.31055 -110.084366)
			(xy 37.318373 -110.024944) (xy 37.333886 -109.967051) (xy 37.356822 -109.911678) (xy 37.386789 -109.859772)
			(xy 37.423276 -109.812222) (xy 37.465656 -109.769842) (xy 37.513206 -109.733355) (xy 37.565112 -109.703388)
			(xy 37.620485 -109.680452) (xy 37.678378 -109.664939) (xy 37.7378 -109.657116) (xy 37.797736 -109.657116)
			(xy 37.857158 -109.664939) (xy 37.915051 -109.680452) (xy 37.970424 -109.703388) (xy 38.02233 -109.733355)
			(xy 38.06988 -109.769842) (xy 38.11226 -109.812222) (xy 38.148747 -109.859772) (xy 38.178714 -109.911678)
			(xy 38.20165 -109.967051) (xy 38.217163 -110.024944) (xy 38.224986 -110.084366) (xy 38.225476 -110.114334)
			(xy 38.225476 -110.97641) (xy 53.639212 -110.97641) (xy 53.639212 -110.11281) (xy 53.639702 -110.082842)
			(xy 53.647525 -110.02342) (xy 53.663038 -109.965527) (xy 53.685974 -109.910154) (xy 53.715941 -109.858248)
			(xy 53.752428 -109.810698) (xy 53.794808 -109.768318) (xy 53.842358 -109.731831) (xy 53.894264 -109.701864)
			(xy 53.949637 -109.678928) (xy 54.00753 -109.663415) (xy 54.066952 -109.655592) (xy 54.126888 -109.655592)
			(xy 54.18631 -109.663415) (xy 54.244203 -109.678928) (xy 54.299576 -109.701864) (xy 54.351482 -109.731831)
			(xy 54.399032 -109.768318) (xy 54.441412 -109.810698) (xy 54.477899 -109.858248) (xy 54.507866 -109.910154)
			(xy 54.530802 -109.965527) (xy 54.546315 -110.02342) (xy 54.554138 -110.082842) (xy 54.554628 -110.11281)
			(xy 54.554628 -110.97641) (xy 54.554603 -110.977934) (xy 153.409904 -110.977934) (xy 153.409904 -110.114334)
			(xy 153.410394 -110.08435) (xy 153.418222 -110.024894) (xy 153.433743 -109.966969) (xy 153.456692 -109.911565)
			(xy 153.486676 -109.859631) (xy 153.523182 -109.812055) (xy 153.565587 -109.76965) (xy 153.613163 -109.733144)
			(xy 153.665097 -109.70316) (xy 153.720501 -109.680211) (xy 153.778426 -109.66469) (xy 153.837882 -109.656862)
			(xy 153.89785 -109.656862) (xy 153.957306 -109.66469) (xy 154.015231 -109.680211) (xy 154.070635 -109.70316)
			(xy 154.122569 -109.733144) (xy 154.170145 -109.76965) (xy 154.21255 -109.812055) (xy 154.249056 -109.859631)
			(xy 154.27904 -109.911565) (xy 154.301989 -109.966969) (xy 154.31751 -110.024894) (xy 154.325338 -110.08435)
			(xy 154.325828 -110.114334) (xy 154.325828 -110.97641) (xy 169.739056 -110.97641) (xy 169.739056 -110.11281)
			(xy 169.739546 -110.082826) (xy 169.747374 -110.02337) (xy 169.762895 -109.965445) (xy 169.785844 -109.910041)
			(xy 169.815828 -109.858107) (xy 169.852334 -109.810531) (xy 169.894739 -109.768126) (xy 169.942315 -109.73162)
			(xy 169.994249 -109.701636) (xy 170.049653 -109.678687) (xy 170.107578 -109.663166) (xy 170.167034 -109.655338)
			(xy 170.227002 -109.655338) (xy 170.286458 -109.663166) (xy 170.344383 -109.678687) (xy 170.399787 -109.701636)
			(xy 170.451721 -109.73162) (xy 170.499297 -109.768126) (xy 170.541702 -109.810531) (xy 170.578208 -109.858107)
			(xy 170.608192 -109.910041) (xy 170.631141 -109.965445) (xy 170.646662 -110.02337) (xy 170.65449 -110.082826)
			(xy 170.65498 -110.11281) (xy 170.65498 -110.97641) (xy 170.654955 -110.977934) (xy 269.509748 -110.977934)
			(xy 269.509748 -110.114334) (xy 269.510238 -110.08435) (xy 269.518066 -110.024894) (xy 269.533587 -109.966969)
			(xy 269.556536 -109.911565) (xy 269.58652 -109.859631) (xy 269.623026 -109.812055) (xy 269.665431 -109.76965)
			(xy 269.713007 -109.733144) (xy 269.764941 -109.70316) (xy 269.820345 -109.680211) (xy 269.87827 -109.66469)
			(xy 269.937726 -109.656862) (xy 269.997694 -109.656862) (xy 270.05715 -109.66469) (xy 270.115075 -109.680211)
			(xy 270.170479 -109.70316) (xy 270.222413 -109.733144) (xy 270.269989 -109.76965) (xy 270.312394 -109.812055)
			(xy 270.3489 -109.859631) (xy 270.378884 -109.911565) (xy 270.401833 -109.966969) (xy 270.417354 -110.024894)
			(xy 270.425182 -110.08435) (xy 270.425672 -110.114334) (xy 270.425672 -110.97641) (xy 285.8389 -110.97641)
			(xy 285.8389 -110.11281) (xy 285.83939 -110.082826) (xy 285.847218 -110.02337) (xy 285.862739 -109.965445)
			(xy 285.885688 -109.910041) (xy 285.915672 -109.858107) (xy 285.952178 -109.810531) (xy 285.994583 -109.768126)
			(xy 286.042159 -109.73162) (xy 286.094093 -109.701636) (xy 286.149497 -109.678687) (xy 286.207422 -109.663166)
			(xy 286.266878 -109.655338) (xy 286.326846 -109.655338) (xy 286.386302 -109.663166) (xy 286.444227 -109.678687)
			(xy 286.499631 -109.701636) (xy 286.551565 -109.73162) (xy 286.599141 -109.768126) (xy 286.641546 -109.810531)
			(xy 286.678052 -109.858107) (xy 286.708036 -109.910041) (xy 286.730985 -109.965445) (xy 286.746506 -110.02337)
			(xy 286.754334 -110.082826) (xy 286.754824 -110.11281) (xy 286.754824 -110.97641) (xy 286.754799 -110.977934)
			(xy 385.6101 -110.977934) (xy 385.6101 -110.114334) (xy 385.61059 -110.084366) (xy 385.618413 -110.024944)
			(xy 385.633926 -109.967051) (xy 385.656862 -109.911678) (xy 385.686829 -109.859772) (xy 385.723316 -109.812222)
			(xy 385.765696 -109.769842) (xy 385.813246 -109.733355) (xy 385.865152 -109.703388) (xy 385.920525 -109.680452)
			(xy 385.978418 -109.664939) (xy 386.03784 -109.657116) (xy 386.097776 -109.657116) (xy 386.157198 -109.664939)
			(xy 386.215091 -109.680452) (xy 386.270464 -109.703388) (xy 386.32237 -109.733355) (xy 386.36992 -109.769842)
			(xy 386.4123 -109.812222) (xy 386.448787 -109.859772) (xy 386.478754 -109.911678) (xy 386.50169 -109.967051)
			(xy 386.517203 -110.024944) (xy 386.525026 -110.084366) (xy 386.525516 -110.114334) (xy 386.525516 -110.97641)
			(xy 401.939252 -110.97641) (xy 401.939252 -110.11281) (xy 401.939742 -110.082842) (xy 401.947565 -110.02342)
			(xy 401.963078 -109.965527) (xy 401.986014 -109.910154) (xy 402.015981 -109.858248) (xy 402.052468 -109.810698)
			(xy 402.094848 -109.768318) (xy 402.142398 -109.731831) (xy 402.194304 -109.701864) (xy 402.249677 -109.678928)
			(xy 402.30757 -109.663415) (xy 402.366992 -109.655592) (xy 402.426928 -109.655592) (xy 402.48635 -109.663415)
			(xy 402.544243 -109.678928) (xy 402.599616 -109.701864) (xy 402.651522 -109.731831) (xy 402.699072 -109.768318)
			(xy 402.741452 -109.810698) (xy 402.777939 -109.858248) (xy 402.807906 -109.910154) (xy 402.830842 -109.965527)
			(xy 402.846355 -110.02342) (xy 402.854178 -110.082842) (xy 402.854668 -110.11281) (xy 402.854668 -110.97641)
			(xy 402.854178 -111.006378) (xy 402.846355 -111.0658) (xy 402.830842 -111.123693) (xy 402.807906 -111.179066)
			(xy 402.777939 -111.230972) (xy 402.741452 -111.278522) (xy 402.699072 -111.320902) (xy 402.651522 -111.357389)
			(xy 402.599616 -111.387356) (xy 402.544243 -111.410292) (xy 402.48635 -111.425805) (xy 402.426928 -111.433628)
			(xy 402.366992 -111.433628) (xy 402.30757 -111.425805) (xy 402.249677 -111.410292) (xy 402.194304 -111.387356)
			(xy 402.142398 -111.357389) (xy 402.094848 -111.320902) (xy 402.052468 -111.278522) (xy 402.015981 -111.230972)
			(xy 401.986014 -111.179066) (xy 401.963078 -111.123693) (xy 401.947565 -111.0658) (xy 401.939742 -111.006378)
			(xy 401.939252 -110.97641) (xy 386.525516 -110.97641) (xy 386.525516 -110.977934) (xy 386.525026 -111.007902)
			(xy 386.517203 -111.067324) (xy 386.50169 -111.125217) (xy 386.478754 -111.18059) (xy 386.448787 -111.232496)
			(xy 386.4123 -111.280046) (xy 386.36992 -111.322426) (xy 386.32237 -111.358913) (xy 386.270464 -111.38888)
			(xy 386.215091 -111.411816) (xy 386.157198 -111.427329) (xy 386.097776 -111.435152) (xy 386.03784 -111.435152)
			(xy 385.978418 -111.427329) (xy 385.920525 -111.411816) (xy 385.865152 -111.38888) (xy 385.813246 -111.358913)
			(xy 385.765696 -111.322426) (xy 385.723316 -111.280046) (xy 385.686829 -111.232496) (xy 385.656862 -111.18059)
			(xy 385.633926 -111.125217) (xy 385.618413 -111.067324) (xy 385.61059 -111.007902) (xy 385.6101 -110.977934)
			(xy 286.754799 -110.977934) (xy 286.754334 -111.006394) (xy 286.746506 -111.06585) (xy 286.730985 -111.123775)
			(xy 286.708036 -111.179179) (xy 286.678052 -111.231113) (xy 286.641546 -111.278689) (xy 286.599141 -111.321094)
			(xy 286.551565 -111.3576) (xy 286.499631 -111.387584) (xy 286.444227 -111.410533) (xy 286.386302 -111.426054)
			(xy 286.326846 -111.433882) (xy 286.266878 -111.433882) (xy 286.207422 -111.426054) (xy 286.149497 -111.410533)
			(xy 286.094093 -111.387584) (xy 286.042159 -111.3576) (xy 285.994583 -111.321094) (xy 285.952178 -111.278689)
			(xy 285.915672 -111.231113) (xy 285.885688 -111.179179) (xy 285.862739 -111.123775) (xy 285.847218 -111.06585)
			(xy 285.83939 -111.006394) (xy 285.8389 -110.97641) (xy 270.425672 -110.97641) (xy 270.425672 -110.977934)
			(xy 270.425182 -111.007918) (xy 270.417354 -111.067374) (xy 270.401833 -111.125299) (xy 270.378884 -111.180703)
			(xy 270.3489 -111.232637) (xy 270.312394 -111.280213) (xy 270.269989 -111.322618) (xy 270.222413 -111.359124)
			(xy 270.170479 -111.389108) (xy 270.115075 -111.412057) (xy 270.05715 -111.427578) (xy 269.997694 -111.435406)
			(xy 269.937726 -111.435406) (xy 269.87827 -111.427578) (xy 269.820345 -111.412057) (xy 269.764941 -111.389108)
			(xy 269.713007 -111.359124) (xy 269.665431 -111.322618) (xy 269.623026 -111.280213) (xy 269.58652 -111.232637)
			(xy 269.556536 -111.180703) (xy 269.533587 -111.125299) (xy 269.518066 -111.067374) (xy 269.510238 -111.007918)
			(xy 269.509748 -110.977934) (xy 170.654955 -110.977934) (xy 170.65449 -111.006394) (xy 170.646662 -111.06585)
			(xy 170.631141 -111.123775) (xy 170.608192 -111.179179) (xy 170.578208 -111.231113) (xy 170.541702 -111.278689)
			(xy 170.499297 -111.321094) (xy 170.451721 -111.3576) (xy 170.399787 -111.387584) (xy 170.344383 -111.410533)
			(xy 170.286458 -111.426054) (xy 170.227002 -111.433882) (xy 170.167034 -111.433882) (xy 170.107578 -111.426054)
			(xy 170.049653 -111.410533) (xy 169.994249 -111.387584) (xy 169.942315 -111.3576) (xy 169.894739 -111.321094)
			(xy 169.852334 -111.278689) (xy 169.815828 -111.231113) (xy 169.785844 -111.179179) (xy 169.762895 -111.123775)
			(xy 169.747374 -111.06585) (xy 169.739546 -111.006394) (xy 169.739056 -110.97641) (xy 154.325828 -110.97641)
			(xy 154.325828 -110.977934) (xy 154.325338 -111.007918) (xy 154.31751 -111.067374) (xy 154.301989 -111.125299)
			(xy 154.27904 -111.180703) (xy 154.249056 -111.232637) (xy 154.21255 -111.280213) (xy 154.170145 -111.322618)
			(xy 154.122569 -111.359124) (xy 154.070635 -111.389108) (xy 154.015231 -111.412057) (xy 153.957306 -111.427578)
			(xy 153.89785 -111.435406) (xy 153.837882 -111.435406) (xy 153.778426 -111.427578) (xy 153.720501 -111.412057)
			(xy 153.665097 -111.389108) (xy 153.613163 -111.359124) (xy 153.565587 -111.322618) (xy 153.523182 -111.280213)
			(xy 153.486676 -111.232637) (xy 153.456692 -111.180703) (xy 153.433743 -111.125299) (xy 153.418222 -111.067374)
			(xy 153.410394 -111.007918) (xy 153.409904 -110.977934) (xy 54.554603 -110.977934) (xy 54.554138 -111.006378)
			(xy 54.546315 -111.0658) (xy 54.530802 -111.123693) (xy 54.507866 -111.179066) (xy 54.477899 -111.230972)
			(xy 54.441412 -111.278522) (xy 54.399032 -111.320902) (xy 54.351482 -111.357389) (xy 54.299576 -111.387356)
			(xy 54.244203 -111.410292) (xy 54.18631 -111.425805) (xy 54.126888 -111.433628) (xy 54.066952 -111.433628)
			(xy 54.00753 -111.425805) (xy 53.949637 -111.410292) (xy 53.894264 -111.387356) (xy 53.842358 -111.357389)
			(xy 53.794808 -111.320902) (xy 53.752428 -111.278522) (xy 53.715941 -111.230972) (xy 53.685974 -111.179066)
			(xy 53.663038 -111.123693) (xy 53.647525 -111.0658) (xy 53.639702 -111.006378) (xy 53.639212 -110.97641)
			(xy 38.225476 -110.97641) (xy 38.225476 -110.977934) (xy 38.224986 -111.007902) (xy 38.217163 -111.067324)
			(xy 38.20165 -111.125217) (xy 38.178714 -111.18059) (xy 38.148747 -111.232496) (xy 38.11226 -111.280046)
			(xy 38.06988 -111.322426) (xy 38.02233 -111.358913) (xy 37.970424 -111.38888) (xy 37.915051 -111.411816)
			(xy 37.857158 -111.427329) (xy 37.797736 -111.435152) (xy 37.7378 -111.435152) (xy 37.678378 -111.427329)
			(xy 37.620485 -111.411816) (xy 37.565112 -111.38888) (xy 37.513206 -111.358913) (xy 37.465656 -111.322426)
			(xy 37.423276 -111.280046) (xy 37.386789 -111.232496) (xy 37.356822 -111.18059) (xy 37.333886 -111.125217)
			(xy 37.318373 -111.067324) (xy 37.31055 -111.007902) (xy 37.31006 -110.977934) (xy 4.308094 -110.977934)
			(xy 4.308094 -112.784382) (xy 34.667952 -112.784382) (xy 34.667952 -111.920782) (xy 34.668442 -111.890814)
			(xy 34.676265 -111.831392) (xy 34.691778 -111.773499) (xy 34.714714 -111.718126) (xy 34.744681 -111.66622)
			(xy 34.781168 -111.61867) (xy 34.823548 -111.57629) (xy 34.871098 -111.539803) (xy 34.923004 -111.509836)
			(xy 34.978377 -111.4869) (xy 35.03627 -111.471387) (xy 35.095692 -111.463564) (xy 35.155628 -111.463564)
			(xy 35.21505 -111.471387) (xy 35.272943 -111.4869) (xy 35.328316 -111.509836) (xy 35.380222 -111.539803)
			(xy 35.427772 -111.57629) (xy 35.470152 -111.61867) (xy 35.506639 -111.66622) (xy 35.536606 -111.718126)
			(xy 35.559542 -111.773499) (xy 35.575055 -111.831392) (xy 35.582878 -111.890814) (xy 35.583368 -111.920782)
			(xy 35.583368 -112.776508) (xy 51.785012 -112.776508) (xy 51.785012 -111.912908) (xy 51.785502 -111.88294)
			(xy 51.793325 -111.823518) (xy 51.808838 -111.765625) (xy 51.831774 -111.710252) (xy 51.861741 -111.658346)
			(xy 51.898228 -111.610796) (xy 51.940608 -111.568416) (xy 51.988158 -111.531929) (xy 52.040064 -111.501962)
			(xy 52.095437 -111.479026) (xy 52.15333 -111.463513) (xy 52.212752 -111.45569) (xy 52.272688 -111.45569)
			(xy 52.33211 -111.463513) (xy 52.390003 -111.479026) (xy 52.445376 -111.501962) (xy 52.497282 -111.531929)
			(xy 52.544832 -111.568416) (xy 52.587212 -111.610796) (xy 52.623699 -111.658346) (xy 52.653666 -111.710252)
			(xy 52.676602 -111.765625) (xy 52.692115 -111.823518) (xy 52.699938 -111.88294) (xy 52.700428 -111.912908)
			(xy 52.700428 -112.776508) (xy 52.700299 -112.784382) (xy 150.767796 -112.784382) (xy 150.767796 -111.920782)
			(xy 150.768286 -111.890798) (xy 150.776114 -111.831342) (xy 150.791635 -111.773417) (xy 150.814584 -111.718013)
			(xy 150.844568 -111.666079) (xy 150.881074 -111.618503) (xy 150.923479 -111.576098) (xy 150.971055 -111.539592)
			(xy 151.022989 -111.509608) (xy 151.078393 -111.486659) (xy 151.136318 -111.471138) (xy 151.195774 -111.46331)
			(xy 151.255742 -111.46331) (xy 151.315198 -111.471138) (xy 151.373123 -111.486659) (xy 151.428527 -111.509608)
			(xy 151.480461 -111.539592) (xy 151.528037 -111.576098) (xy 151.570442 -111.618503) (xy 151.606948 -111.666079)
			(xy 151.636932 -111.718013) (xy 151.659881 -111.773417) (xy 151.675402 -111.831342) (xy 151.68323 -111.890798)
			(xy 151.68372 -111.920782) (xy 151.68372 -112.776508) (xy 167.884856 -112.776508) (xy 167.884856 -111.912908)
			(xy 167.885346 -111.882924) (xy 167.893174 -111.823468) (xy 167.908695 -111.765543) (xy 167.931644 -111.710139)
			(xy 167.961628 -111.658205) (xy 167.998134 -111.610629) (xy 168.040539 -111.568224) (xy 168.088115 -111.531718)
			(xy 168.140049 -111.501734) (xy 168.195453 -111.478785) (xy 168.253378 -111.463264) (xy 168.312834 -111.455436)
			(xy 168.372802 -111.455436) (xy 168.432258 -111.463264) (xy 168.490183 -111.478785) (xy 168.545587 -111.501734)
			(xy 168.597521 -111.531718) (xy 168.645097 -111.568224) (xy 168.687502 -111.610629) (xy 168.724008 -111.658205)
			(xy 168.753992 -111.710139) (xy 168.776941 -111.765543) (xy 168.792462 -111.823468) (xy 168.80029 -111.882924)
			(xy 168.80078 -111.912908) (xy 168.80078 -112.776508) (xy 168.800651 -112.784382) (xy 266.86764 -112.784382)
			(xy 266.86764 -111.920782) (xy 266.86813 -111.890798) (xy 266.875958 -111.831342) (xy 266.891479 -111.773417)
			(xy 266.914428 -111.718013) (xy 266.944412 -111.666079) (xy 266.980918 -111.618503) (xy 267.023323 -111.576098)
			(xy 267.070899 -111.539592) (xy 267.122833 -111.509608) (xy 267.178237 -111.486659) (xy 267.236162 -111.471138)
			(xy 267.295618 -111.46331) (xy 267.355586 -111.46331) (xy 267.415042 -111.471138) (xy 267.472967 -111.486659)
			(xy 267.528371 -111.509608) (xy 267.580305 -111.539592) (xy 267.627881 -111.576098) (xy 267.670286 -111.618503)
			(xy 267.706792 -111.666079) (xy 267.736776 -111.718013) (xy 267.759725 -111.773417) (xy 267.775246 -111.831342)
			(xy 267.783074 -111.890798) (xy 267.783564 -111.920782) (xy 267.783564 -112.776508) (xy 283.9847 -112.776508)
			(xy 283.9847 -111.912908) (xy 283.98519 -111.882924) (xy 283.993018 -111.823468) (xy 284.008539 -111.765543)
			(xy 284.031488 -111.710139) (xy 284.061472 -111.658205) (xy 284.097978 -111.610629) (xy 284.140383 -111.568224)
			(xy 284.187959 -111.531718) (xy 284.239893 -111.501734) (xy 284.295297 -111.478785) (xy 284.353222 -111.463264)
			(xy 284.412678 -111.455436) (xy 284.472646 -111.455436) (xy 284.532102 -111.463264) (xy 284.590027 -111.478785)
			(xy 284.645431 -111.501734) (xy 284.697365 -111.531718) (xy 284.744941 -111.568224) (xy 284.787346 -111.610629)
			(xy 284.823852 -111.658205) (xy 284.853836 -111.710139) (xy 284.876785 -111.765543) (xy 284.892306 -111.823468)
			(xy 284.900134 -111.882924) (xy 284.900624 -111.912908) (xy 284.900624 -112.776508) (xy 284.900495 -112.784382)
			(xy 382.967992 -112.784382) (xy 382.967992 -111.920782) (xy 382.968482 -111.890814) (xy 382.976305 -111.831392)
			(xy 382.991818 -111.773499) (xy 383.014754 -111.718126) (xy 383.044721 -111.66622) (xy 383.081208 -111.61867)
			(xy 383.123588 -111.57629) (xy 383.171138 -111.539803) (xy 383.223044 -111.509836) (xy 383.278417 -111.4869)
			(xy 383.33631 -111.471387) (xy 383.395732 -111.463564) (xy 383.455668 -111.463564) (xy 383.51509 -111.471387)
			(xy 383.572983 -111.4869) (xy 383.628356 -111.509836) (xy 383.680262 -111.539803) (xy 383.727812 -111.57629)
			(xy 383.770192 -111.61867) (xy 383.806679 -111.66622) (xy 383.836646 -111.718126) (xy 383.859582 -111.773499)
			(xy 383.875095 -111.831392) (xy 383.882918 -111.890814) (xy 383.883408 -111.920782) (xy 383.883408 -112.776508)
			(xy 400.085052 -112.776508) (xy 400.085052 -111.912908) (xy 400.085542 -111.88294) (xy 400.093365 -111.823518)
			(xy 400.108878 -111.765625) (xy 400.131814 -111.710252) (xy 400.161781 -111.658346) (xy 400.198268 -111.610796)
			(xy 400.240648 -111.568416) (xy 400.288198 -111.531929) (xy 400.340104 -111.501962) (xy 400.395477 -111.479026)
			(xy 400.45337 -111.463513) (xy 400.512792 -111.45569) (xy 400.572728 -111.45569) (xy 400.63215 -111.463513)
			(xy 400.690043 -111.479026) (xy 400.745416 -111.501962) (xy 400.797322 -111.531929) (xy 400.844872 -111.568416)
			(xy 400.887252 -111.610796) (xy 400.923739 -111.658346) (xy 400.953706 -111.710252) (xy 400.976642 -111.765625)
			(xy 400.992155 -111.823518) (xy 400.999978 -111.88294) (xy 401.000468 -111.912908) (xy 401.000468 -112.776508)
			(xy 400.999978 -112.806476) (xy 400.992155 -112.865898) (xy 400.976642 -112.923791) (xy 400.953706 -112.979164)
			(xy 400.923739 -113.03107) (xy 400.887252 -113.07862) (xy 400.844872 -113.121) (xy 400.797322 -113.157487)
			(xy 400.745416 -113.187454) (xy 400.690043 -113.21039) (xy 400.63215 -113.225903) (xy 400.572728 -113.233726)
			(xy 400.512792 -113.233726) (xy 400.45337 -113.225903) (xy 400.395477 -113.21039) (xy 400.340104 -113.187454)
			(xy 400.288198 -113.157487) (xy 400.240648 -113.121) (xy 400.198268 -113.07862) (xy 400.161781 -113.03107)
			(xy 400.131814 -112.979164) (xy 400.108878 -112.923791) (xy 400.093365 -112.865898) (xy 400.085542 -112.806476)
			(xy 400.085052 -112.776508) (xy 383.883408 -112.776508) (xy 383.883408 -112.784382) (xy 383.882918 -112.81435)
			(xy 383.875095 -112.873772) (xy 383.859582 -112.931665) (xy 383.836646 -112.987038) (xy 383.806679 -113.038944)
			(xy 383.770192 -113.086494) (xy 383.727812 -113.128874) (xy 383.680262 -113.165361) (xy 383.628356 -113.195328)
			(xy 383.572983 -113.218264) (xy 383.51509 -113.233777) (xy 383.455668 -113.2416) (xy 383.395732 -113.2416)
			(xy 383.33631 -113.233777) (xy 383.278417 -113.218264) (xy 383.223044 -113.195328) (xy 383.171138 -113.165361)
			(xy 383.123588 -113.128874) (xy 383.081208 -113.086494) (xy 383.044721 -113.038944) (xy 383.014754 -112.987038)
			(xy 382.991818 -112.931665) (xy 382.976305 -112.873772) (xy 382.968482 -112.81435) (xy 382.967992 -112.784382)
			(xy 284.900495 -112.784382) (xy 284.900134 -112.806492) (xy 284.892306 -112.865948) (xy 284.876785 -112.923873)
			(xy 284.853836 -112.979277) (xy 284.823852 -113.031211) (xy 284.787346 -113.078787) (xy 284.744941 -113.121192)
			(xy 284.697365 -113.157698) (xy 284.645431 -113.187682) (xy 284.590027 -113.210631) (xy 284.532102 -113.226152)
			(xy 284.472646 -113.23398) (xy 284.412678 -113.23398) (xy 284.353222 -113.226152) (xy 284.295297 -113.210631)
			(xy 284.239893 -113.187682) (xy 284.187959 -113.157698) (xy 284.140383 -113.121192) (xy 284.097978 -113.078787)
			(xy 284.061472 -113.031211) (xy 284.031488 -112.979277) (xy 284.008539 -112.923873) (xy 283.993018 -112.865948)
			(xy 283.98519 -112.806492) (xy 283.9847 -112.776508) (xy 267.783564 -112.776508) (xy 267.783564 -112.784382)
			(xy 267.783074 -112.814366) (xy 267.775246 -112.873822) (xy 267.759725 -112.931747) (xy 267.736776 -112.987151)
			(xy 267.706792 -113.039085) (xy 267.670286 -113.086661) (xy 267.627881 -113.129066) (xy 267.580305 -113.165572)
			(xy 267.528371 -113.195556) (xy 267.472967 -113.218505) (xy 267.415042 -113.234026) (xy 267.355586 -113.241854)
			(xy 267.295618 -113.241854) (xy 267.236162 -113.234026) (xy 267.178237 -113.218505) (xy 267.122833 -113.195556)
			(xy 267.070899 -113.165572) (xy 267.023323 -113.129066) (xy 266.980918 -113.086661) (xy 266.944412 -113.039085)
			(xy 266.914428 -112.987151) (xy 266.891479 -112.931747) (xy 266.875958 -112.873822) (xy 266.86813 -112.814366)
			(xy 266.86764 -112.784382) (xy 168.800651 -112.784382) (xy 168.80029 -112.806492) (xy 168.792462 -112.865948)
			(xy 168.776941 -112.923873) (xy 168.753992 -112.979277) (xy 168.724008 -113.031211) (xy 168.687502 -113.078787)
			(xy 168.645097 -113.121192) (xy 168.597521 -113.157698) (xy 168.545587 -113.187682) (xy 168.490183 -113.210631)
			(xy 168.432258 -113.226152) (xy 168.372802 -113.23398) (xy 168.312834 -113.23398) (xy 168.253378 -113.226152)
			(xy 168.195453 -113.210631) (xy 168.140049 -113.187682) (xy 168.088115 -113.157698) (xy 168.040539 -113.121192)
			(xy 167.998134 -113.078787) (xy 167.961628 -113.031211) (xy 167.931644 -112.979277) (xy 167.908695 -112.923873)
			(xy 167.893174 -112.865948) (xy 167.885346 -112.806492) (xy 167.884856 -112.776508) (xy 151.68372 -112.776508)
			(xy 151.68372 -112.784382) (xy 151.68323 -112.814366) (xy 151.675402 -112.873822) (xy 151.659881 -112.931747)
			(xy 151.636932 -112.987151) (xy 151.606948 -113.039085) (xy 151.570442 -113.086661) (xy 151.528037 -113.129066)
			(xy 151.480461 -113.165572) (xy 151.428527 -113.195556) (xy 151.373123 -113.218505) (xy 151.315198 -113.234026)
			(xy 151.255742 -113.241854) (xy 151.195774 -113.241854) (xy 151.136318 -113.234026) (xy 151.078393 -113.218505)
			(xy 151.022989 -113.195556) (xy 150.971055 -113.165572) (xy 150.923479 -113.129066) (xy 150.881074 -113.086661)
			(xy 150.844568 -113.039085) (xy 150.814584 -112.987151) (xy 150.791635 -112.931747) (xy 150.776114 -112.873822)
			(xy 150.768286 -112.814366) (xy 150.767796 -112.784382) (xy 52.700299 -112.784382) (xy 52.699938 -112.806476)
			(xy 52.692115 -112.865898) (xy 52.676602 -112.923791) (xy 52.653666 -112.979164) (xy 52.623699 -113.03107)
			(xy 52.587212 -113.07862) (xy 52.544832 -113.121) (xy 52.497282 -113.157487) (xy 52.445376 -113.187454)
			(xy 52.390003 -113.21039) (xy 52.33211 -113.225903) (xy 52.272688 -113.233726) (xy 52.212752 -113.233726)
			(xy 52.15333 -113.225903) (xy 52.095437 -113.21039) (xy 52.040064 -113.187454) (xy 51.988158 -113.157487)
			(xy 51.940608 -113.121) (xy 51.898228 -113.07862) (xy 51.861741 -113.03107) (xy 51.831774 -112.979164)
			(xy 51.808838 -112.923791) (xy 51.793325 -112.865898) (xy 51.785502 -112.806476) (xy 51.785012 -112.776508)
			(xy 35.583368 -112.776508) (xy 35.583368 -112.784382) (xy 35.582878 -112.81435) (xy 35.575055 -112.873772)
			(xy 35.559542 -112.931665) (xy 35.536606 -112.987038) (xy 35.506639 -113.038944) (xy 35.470152 -113.086494)
			(xy 35.427772 -113.128874) (xy 35.380222 -113.165361) (xy 35.328316 -113.195328) (xy 35.272943 -113.218264)
			(xy 35.21505 -113.233777) (xy 35.155628 -113.2416) (xy 35.095692 -113.2416) (xy 35.03627 -113.233777)
			(xy 34.978377 -113.218264) (xy 34.923004 -113.195328) (xy 34.871098 -113.165361) (xy 34.823548 -113.128874)
			(xy 34.781168 -113.086494) (xy 34.744681 -113.038944) (xy 34.714714 -112.987038) (xy 34.691778 -112.931665)
			(xy 34.676265 -112.873772) (xy 34.668442 -112.81435) (xy 34.667952 -112.784382) (xy 4.308094 -112.784382)
			(xy 4.308094 -117.758718) (xy 74.474832 -117.758718) (xy 74.474832 -116.895118) (xy 74.475322 -116.865134)
			(xy 74.48315 -116.805678) (xy 74.498671 -116.747753) (xy 74.52162 -116.692349) (xy 74.551604 -116.640415)
			(xy 74.58811 -116.592839) (xy 74.630515 -116.550434) (xy 74.678091 -116.513928) (xy 74.730025 -116.483944)
			(xy 74.785429 -116.460995) (xy 74.843354 -116.445474) (xy 74.90281 -116.437646) (xy 74.962778 -116.437646)
			(xy 75.022234 -116.445474) (xy 75.080159 -116.460995) (xy 75.135563 -116.483944) (xy 75.187497 -116.513928)
			(xy 75.235073 -116.550434) (xy 75.277478 -116.592839) (xy 75.313984 -116.640415) (xy 75.343968 -116.692349)
			(xy 75.366917 -116.747753) (xy 75.382438 -116.805678) (xy 75.390266 -116.865134) (xy 75.390756 -116.895118)
			(xy 75.390756 -117.758718) (xy 190.574676 -117.758718) (xy 190.574676 -116.895118) (xy 190.575166 -116.865134)
			(xy 190.582994 -116.805678) (xy 190.598515 -116.747753) (xy 190.621464 -116.692349) (xy 190.651448 -116.640415)
			(xy 190.687954 -116.592839) (xy 190.730359 -116.550434) (xy 190.777935 -116.513928) (xy 190.829869 -116.483944)
			(xy 190.885273 -116.460995) (xy 190.943198 -116.445474) (xy 191.002654 -116.437646) (xy 191.062622 -116.437646)
			(xy 191.122078 -116.445474) (xy 191.180003 -116.460995) (xy 191.235407 -116.483944) (xy 191.287341 -116.513928)
			(xy 191.334917 -116.550434) (xy 191.377322 -116.592839) (xy 191.413828 -116.640415) (xy 191.443812 -116.692349)
			(xy 191.466761 -116.747753) (xy 191.482282 -116.805678) (xy 191.49011 -116.865134) (xy 191.4906 -116.895118)
			(xy 191.4906 -117.758718) (xy 306.675028 -117.758718) (xy 306.675028 -116.895118) (xy 306.675518 -116.86515)
			(xy 306.683341 -116.805728) (xy 306.698854 -116.747835) (xy 306.72179 -116.692462) (xy 306.751757 -116.640556)
			(xy 306.788244 -116.593006) (xy 306.830624 -116.550626) (xy 306.878174 -116.514139) (xy 306.93008 -116.484172)
			(xy 306.985453 -116.461236) (xy 307.043346 -116.445723) (xy 307.102768 -116.4379) (xy 307.162704 -116.4379)
			(xy 307.222126 -116.445723) (xy 307.280019 -116.461236) (xy 307.335392 -116.484172) (xy 307.387298 -116.514139)
			(xy 307.434848 -116.550626) (xy 307.477228 -116.593006) (xy 307.513715 -116.640556) (xy 307.543682 -116.692462)
			(xy 307.566618 -116.747835) (xy 307.582131 -116.805728) (xy 307.589954 -116.86515) (xy 307.590444 -116.895118)
			(xy 307.590444 -117.758718) (xy 307.590436 -117.759226) (xy 422.774872 -117.759226) (xy 422.774872 -116.895626)
			(xy 422.775362 -116.865642) (xy 422.78319 -116.806186) (xy 422.798711 -116.748261) (xy 422.82166 -116.692857)
			(xy 422.851644 -116.640923) (xy 422.88815 -116.593347) (xy 422.930555 -116.550942) (xy 422.978131 -116.514436)
			(xy 423.030065 -116.484452) (xy 423.085469 -116.461503) (xy 423.143394 -116.445982) (xy 423.20285 -116.438154)
			(xy 423.262818 -116.438154) (xy 423.322274 -116.445982) (xy 423.380199 -116.461503) (xy 423.435603 -116.484452)
			(xy 423.487537 -116.514436) (xy 423.535113 -116.550942) (xy 423.577518 -116.593347) (xy 423.614024 -116.640923)
			(xy 423.644008 -116.692857) (xy 423.666957 -116.748261) (xy 423.682478 -116.806186) (xy 423.690306 -116.865642)
			(xy 423.690796 -116.895626) (xy 423.690796 -117.759226) (xy 423.690306 -117.78921) (xy 423.682478 -117.848666)
			(xy 423.666957 -117.906591) (xy 423.644008 -117.961995) (xy 423.614024 -118.013929) (xy 423.577518 -118.061505)
			(xy 423.535113 -118.10391) (xy 423.487537 -118.140416) (xy 423.435603 -118.1704) (xy 423.380199 -118.193349)
			(xy 423.322274 -118.20887) (xy 423.262818 -118.216698) (xy 423.20285 -118.216698) (xy 423.143394 -118.20887)
			(xy 423.085469 -118.193349) (xy 423.030065 -118.1704) (xy 422.978131 -118.140416) (xy 422.930555 -118.10391)
			(xy 422.88815 -118.061505) (xy 422.851644 -118.013929) (xy 422.82166 -117.961995) (xy 422.798711 -117.906591)
			(xy 422.78319 -117.848666) (xy 422.775362 -117.78921) (xy 422.774872 -117.759226) (xy 307.590436 -117.759226)
			(xy 307.589954 -117.788686) (xy 307.582131 -117.848108) (xy 307.566618 -117.906001) (xy 307.543682 -117.961374)
			(xy 307.513715 -118.01328) (xy 307.477228 -118.06083) (xy 307.434848 -118.10321) (xy 307.387298 -118.139697)
			(xy 307.335392 -118.169664) (xy 307.280019 -118.1926) (xy 307.222126 -118.208113) (xy 307.162704 -118.215936)
			(xy 307.102768 -118.215936) (xy 307.043346 -118.208113) (xy 306.985453 -118.1926) (xy 306.93008 -118.169664)
			(xy 306.878174 -118.139697) (xy 306.830624 -118.10321) (xy 306.788244 -118.06083) (xy 306.751757 -118.01328)
			(xy 306.72179 -117.961374) (xy 306.698854 -117.906001) (xy 306.683341 -117.848108) (xy 306.675518 -117.788686)
			(xy 306.675028 -117.758718) (xy 191.4906 -117.758718) (xy 191.49011 -117.788702) (xy 191.482282 -117.848158)
			(xy 191.466761 -117.906083) (xy 191.443812 -117.961487) (xy 191.413828 -118.013421) (xy 191.377322 -118.060997)
			(xy 191.334917 -118.103402) (xy 191.287341 -118.139908) (xy 191.235407 -118.169892) (xy 191.180003 -118.192841)
			(xy 191.122078 -118.208362) (xy 191.062622 -118.21619) (xy 191.002654 -118.21619) (xy 190.943198 -118.208362)
			(xy 190.885273 -118.192841) (xy 190.829869 -118.169892) (xy 190.777935 -118.139908) (xy 190.730359 -118.103402)
			(xy 190.687954 -118.060997) (xy 190.651448 -118.013421) (xy 190.621464 -117.961487) (xy 190.598515 -117.906083)
			(xy 190.582994 -117.848158) (xy 190.575166 -117.788702) (xy 190.574676 -117.758718) (xy 75.390756 -117.758718)
			(xy 75.390266 -117.788702) (xy 75.382438 -117.848158) (xy 75.366917 -117.906083) (xy 75.343968 -117.961487)
			(xy 75.313984 -118.013421) (xy 75.277478 -118.060997) (xy 75.235073 -118.103402) (xy 75.187497 -118.139908)
			(xy 75.135563 -118.169892) (xy 75.080159 -118.192841) (xy 75.022234 -118.208362) (xy 74.962778 -118.21619)
			(xy 74.90281 -118.21619) (xy 74.843354 -118.208362) (xy 74.785429 -118.192841) (xy 74.730025 -118.169892)
			(xy 74.678091 -118.139908) (xy 74.630515 -118.103402) (xy 74.58811 -118.060997) (xy 74.551604 -118.013421)
			(xy 74.52162 -117.961487) (xy 74.498671 -117.906083) (xy 74.48315 -117.848158) (xy 74.475322 -117.788702)
			(xy 74.474832 -117.758718) (xy 4.308094 -117.758718) (xy 4.308094 -120.087898) (xy 34.667952 -120.087898)
			(xy 34.667952 -119.224298) (xy 34.668442 -119.19433) (xy 34.676265 -119.134908) (xy 34.691778 -119.077015)
			(xy 34.714714 -119.021642) (xy 34.744681 -118.969736) (xy 34.781168 -118.922186) (xy 34.823548 -118.879806)
			(xy 34.871098 -118.843319) (xy 34.923004 -118.813352) (xy 34.978377 -118.790416) (xy 35.03627 -118.774903)
			(xy 35.095692 -118.76708) (xy 35.155628 -118.76708) (xy 35.21505 -118.774903) (xy 35.272943 -118.790416)
			(xy 35.328316 -118.813352) (xy 35.380222 -118.843319) (xy 35.427772 -118.879806) (xy 35.470152 -118.922186)
			(xy 35.506639 -118.969736) (xy 35.536606 -119.021642) (xy 35.559542 -119.077015) (xy 35.575055 -119.134908)
			(xy 35.582878 -119.19433) (xy 35.583368 -119.224298) (xy 35.583368 -120.086374) (xy 53.639212 -120.086374)
			(xy 53.639212 -119.222774) (xy 53.639702 -119.192806) (xy 53.647525 -119.133384) (xy 53.663038 -119.075491)
			(xy 53.685974 -119.020118) (xy 53.715941 -118.968212) (xy 53.752428 -118.920662) (xy 53.794808 -118.878282)
			(xy 53.842358 -118.841795) (xy 53.894264 -118.811828) (xy 53.949637 -118.788892) (xy 54.00753 -118.773379)
			(xy 54.066952 -118.765556) (xy 54.126888 -118.765556) (xy 54.18631 -118.773379) (xy 54.244203 -118.788892)
			(xy 54.299576 -118.811828) (xy 54.351482 -118.841795) (xy 54.399032 -118.878282) (xy 54.441412 -118.920662)
			(xy 54.477899 -118.968212) (xy 54.507866 -119.020118) (xy 54.530802 -119.075491) (xy 54.546315 -119.133384)
			(xy 54.554138 -119.192806) (xy 54.554628 -119.222774) (xy 54.554628 -119.567198) (xy 66.599308 -119.567198)
			(xy 66.599308 -118.703598) (xy 66.599798 -118.673614) (xy 66.607626 -118.614158) (xy 66.623147 -118.556233)
			(xy 66.646096 -118.500829) (xy 66.67608 -118.448895) (xy 66.712586 -118.401319) (xy 66.754991 -118.358914)
			(xy 66.802567 -118.322408) (xy 66.854501 -118.292424) (xy 66.909905 -118.269475) (xy 66.96783 -118.253954)
			(xy 67.027286 -118.246126) (xy 67.087254 -118.246126) (xy 67.14671 -118.253954) (xy 67.204635 -118.269475)
			(xy 67.260039 -118.292424) (xy 67.311973 -118.322408) (xy 67.359549 -118.358914) (xy 67.401954 -118.401319)
			(xy 67.43846 -118.448895) (xy 67.468444 -118.500829) (xy 67.491393 -118.556233) (xy 67.506914 -118.614158)
			(xy 67.514742 -118.673614) (xy 67.515232 -118.703598) (xy 67.515232 -119.55907) (xy 81.07426 -119.55907)
			(xy 81.07426 -118.69547) (xy 81.07475 -118.665486) (xy 81.082578 -118.60603) (xy 81.098099 -118.548105)
			(xy 81.121048 -118.492701) (xy 81.151032 -118.440767) (xy 81.187538 -118.393191) (xy 81.229943 -118.350786)
			(xy 81.277519 -118.31428) (xy 81.329453 -118.284296) (xy 81.384857 -118.261347) (xy 81.442782 -118.245826)
			(xy 81.502238 -118.237998) (xy 81.562206 -118.237998) (xy 81.621662 -118.245826) (xy 81.679587 -118.261347)
			(xy 81.734991 -118.284296) (xy 81.786925 -118.31428) (xy 81.834501 -118.350786) (xy 81.876906 -118.393191)
			(xy 81.913412 -118.440767) (xy 81.943396 -118.492701) (xy 81.966345 -118.548105) (xy 81.981866 -118.60603)
			(xy 81.989694 -118.665486) (xy 81.990184 -118.69547) (xy 81.990184 -119.55907) (xy 81.989694 -119.589054)
			(xy 81.981866 -119.64851) (xy 81.966345 -119.706435) (xy 81.943396 -119.761839) (xy 81.913412 -119.813773)
			(xy 81.876906 -119.861349) (xy 81.834501 -119.903754) (xy 81.786925 -119.94026) (xy 81.734991 -119.970244)
			(xy 81.679587 -119.993193) (xy 81.621662 -120.008714) (xy 81.562206 -120.016542) (xy 81.502238 -120.016542)
			(xy 81.442782 -120.008714) (xy 81.384857 -119.993193) (xy 81.329453 -119.970244) (xy 81.277519 -119.94026)
			(xy 81.229943 -119.903754) (xy 81.187538 -119.861349) (xy 81.151032 -119.813773) (xy 81.121048 -119.761839)
			(xy 81.098099 -119.706435) (xy 81.082578 -119.64851) (xy 81.07475 -119.589054) (xy 81.07426 -119.55907)
			(xy 67.515232 -119.55907) (xy 67.515232 -119.567198) (xy 67.514742 -119.597182) (xy 67.506914 -119.656638)
			(xy 67.491393 -119.714563) (xy 67.468444 -119.769967) (xy 67.43846 -119.821901) (xy 67.401954 -119.869477)
			(xy 67.359549 -119.911882) (xy 67.311973 -119.948388) (xy 67.260039 -119.978372) (xy 67.204635 -120.001321)
			(xy 67.14671 -120.016842) (xy 67.087254 -120.02467) (xy 67.027286 -120.02467) (xy 66.96783 -120.016842)
			(xy 66.909905 -120.001321) (xy 66.854501 -119.978372) (xy 66.802567 -119.948388) (xy 66.754991 -119.911882)
			(xy 66.712586 -119.869477) (xy 66.67608 -119.821901) (xy 66.646096 -119.769967) (xy 66.623147 -119.714563)
			(xy 66.607626 -119.656638) (xy 66.599798 -119.597182) (xy 66.599308 -119.567198) (xy 54.554628 -119.567198)
			(xy 54.554628 -120.086374) (xy 54.554138 -120.116342) (xy 54.546315 -120.175764) (xy 54.530802 -120.233657)
			(xy 54.507866 -120.28903) (xy 54.477899 -120.340936) (xy 54.441412 -120.388486) (xy 54.399032 -120.430866)
			(xy 54.351482 -120.467353) (xy 54.299576 -120.49732) (xy 54.244203 -120.520256) (xy 54.18631 -120.535769)
			(xy 54.126888 -120.543592) (xy 54.066952 -120.543592) (xy 54.00753 -120.535769) (xy 53.949637 -120.520256)
			(xy 53.894264 -120.49732) (xy 53.842358 -120.467353) (xy 53.794808 -120.430866) (xy 53.752428 -120.388486)
			(xy 53.715941 -120.340936) (xy 53.685974 -120.28903) (xy 53.663038 -120.233657) (xy 53.647525 -120.175764)
			(xy 53.639702 -120.116342) (xy 53.639212 -120.086374) (xy 35.583368 -120.086374) (xy 35.583368 -120.087898)
			(xy 35.582878 -120.117866) (xy 35.575055 -120.177288) (xy 35.559542 -120.235181) (xy 35.536606 -120.290554)
			(xy 35.506639 -120.34246) (xy 35.470152 -120.39001) (xy 35.427772 -120.43239) (xy 35.380222 -120.468877)
			(xy 35.328316 -120.498844) (xy 35.272943 -120.52178) (xy 35.21505 -120.537293) (xy 35.155628 -120.545116)
			(xy 35.095692 -120.545116) (xy 35.03627 -120.537293) (xy 34.978377 -120.52178) (xy 34.923004 -120.498844)
			(xy 34.871098 -120.468877) (xy 34.823548 -120.43239) (xy 34.781168 -120.39001) (xy 34.744681 -120.34246)
			(xy 34.714714 -120.290554) (xy 34.691778 -120.235181) (xy 34.676265 -120.177288) (xy 34.668442 -120.117866)
			(xy 34.667952 -120.087898) (xy 4.308094 -120.087898) (xy 4.308094 -121.894346) (xy 37.31006 -121.894346)
			(xy 37.31006 -121.030746) (xy 37.31055 -121.000778) (xy 37.318373 -120.941356) (xy 37.333886 -120.883463)
			(xy 37.356822 -120.82809) (xy 37.386789 -120.776184) (xy 37.423276 -120.728634) (xy 37.465656 -120.686254)
			(xy 37.513206 -120.649767) (xy 37.565112 -120.6198) (xy 37.620485 -120.596864) (xy 37.678378 -120.581351)
			(xy 37.7378 -120.573528) (xy 37.797736 -120.573528) (xy 37.857158 -120.581351) (xy 37.915051 -120.596864)
			(xy 37.970424 -120.6198) (xy 38.02233 -120.649767) (xy 38.06988 -120.686254) (xy 38.11226 -120.728634)
			(xy 38.148747 -120.776184) (xy 38.178714 -120.82809) (xy 38.20165 -120.883463) (xy 38.217163 -120.941356)
			(xy 38.224986 -121.000778) (xy 38.225476 -121.030746) (xy 38.225476 -121.886472) (xy 51.785012 -121.886472)
			(xy 51.785012 -121.022872) (xy 51.785502 -120.992904) (xy 51.793325 -120.933482) (xy 51.808838 -120.875589)
			(xy 51.831774 -120.820216) (xy 51.861741 -120.76831) (xy 51.898228 -120.72076) (xy 51.940608 -120.67838)
			(xy 51.988158 -120.641893) (xy 52.040064 -120.611926) (xy 52.095437 -120.58899) (xy 52.15333 -120.573477)
			(xy 52.212752 -120.565654) (xy 52.272688 -120.565654) (xy 52.33211 -120.573477) (xy 52.390003 -120.58899)
			(xy 52.445376 -120.611926) (xy 52.497282 -120.641893) (xy 52.544832 -120.67838) (xy 52.587212 -120.72076)
			(xy 52.623699 -120.76831) (xy 52.653666 -120.820216) (xy 52.676602 -120.875589) (xy 52.692115 -120.933482)
			(xy 52.699938 -120.992904) (xy 52.700428 -121.022872) (xy 52.700428 -121.367296) (xy 64.745108 -121.367296)
			(xy 64.745108 -120.503696) (xy 64.745598 -120.473712) (xy 64.753426 -120.414256) (xy 64.768947 -120.356331)
			(xy 64.791896 -120.300927) (xy 64.82188 -120.248993) (xy 64.858386 -120.201417) (xy 64.900791 -120.159012)
			(xy 64.948367 -120.122506) (xy 65.000301 -120.092522) (xy 65.055705 -120.069573) (xy 65.11363 -120.054052)
			(xy 65.173086 -120.046224) (xy 65.233054 -120.046224) (xy 65.29251 -120.054052) (xy 65.350435 -120.069573)
			(xy 65.405839 -120.092522) (xy 65.457773 -120.122506) (xy 65.505349 -120.159012) (xy 65.547754 -120.201417)
			(xy 65.58426 -120.248993) (xy 65.614244 -120.300927) (xy 65.637193 -120.356331) (xy 65.652714 -120.414256)
			(xy 65.660542 -120.473712) (xy 65.661032 -120.503696) (xy 65.661032 -121.365772) (xy 83.716368 -121.365772)
			(xy 83.716368 -120.502172) (xy 83.716858 -120.472188) (xy 83.724686 -120.412732) (xy 83.740207 -120.354807)
			(xy 83.763156 -120.299403) (xy 83.79314 -120.247469) (xy 83.829646 -120.199893) (xy 83.872051 -120.157488)
			(xy 83.919627 -120.120982) (xy 83.971561 -120.090998) (xy 84.026965 -120.068049) (xy 84.08489 -120.052528)
			(xy 84.144346 -120.0447) (xy 84.204314 -120.0447) (xy 84.26377 -120.052528) (xy 84.321695 -120.068049)
			(xy 84.369615 -120.087898) (xy 150.767796 -120.087898) (xy 150.767796 -119.224298) (xy 150.768286 -119.194314)
			(xy 150.776114 -119.134858) (xy 150.791635 -119.076933) (xy 150.814584 -119.021529) (xy 150.844568 -118.969595)
			(xy 150.881074 -118.922019) (xy 150.923479 -118.879614) (xy 150.971055 -118.843108) (xy 151.022989 -118.813124)
			(xy 151.078393 -118.790175) (xy 151.136318 -118.774654) (xy 151.195774 -118.766826) (xy 151.255742 -118.766826)
			(xy 151.315198 -118.774654) (xy 151.373123 -118.790175) (xy 151.428527 -118.813124) (xy 151.480461 -118.843108)
			(xy 151.528037 -118.879614) (xy 151.570442 -118.922019) (xy 151.606948 -118.969595) (xy 151.636932 -119.021529)
			(xy 151.659881 -119.076933) (xy 151.675402 -119.134858) (xy 151.68323 -119.194314) (xy 151.68372 -119.224298)
			(xy 151.68372 -120.086374) (xy 169.739056 -120.086374) (xy 169.739056 -119.222774) (xy 169.739546 -119.19279)
			(xy 169.747374 -119.133334) (xy 169.762895 -119.075409) (xy 169.785844 -119.020005) (xy 169.815828 -118.968071)
			(xy 169.852334 -118.920495) (xy 169.894739 -118.87809) (xy 169.942315 -118.841584) (xy 169.994249 -118.8116)
			(xy 170.049653 -118.788651) (xy 170.107578 -118.77313) (xy 170.167034 -118.765302) (xy 170.227002 -118.765302)
			(xy 170.286458 -118.77313) (xy 170.344383 -118.788651) (xy 170.399787 -118.8116) (xy 170.451721 -118.841584)
			(xy 170.499297 -118.87809) (xy 170.541702 -118.920495) (xy 170.578208 -118.968071) (xy 170.608192 -119.020005)
			(xy 170.631141 -119.075409) (xy 170.646662 -119.133334) (xy 170.65449 -119.19279) (xy 170.65498 -119.222774)
			(xy 170.65498 -119.567198) (xy 182.69966 -119.567198) (xy 182.69966 -118.703598) (xy 182.70015 -118.67363)
			(xy 182.707973 -118.614208) (xy 182.723486 -118.556315) (xy 182.746422 -118.500942) (xy 182.776389 -118.449036)
			(xy 182.812876 -118.401486) (xy 182.855256 -118.359106) (xy 182.902806 -118.322619) (xy 182.954712 -118.292652)
			(xy 183.010085 -118.269716) (xy 183.067978 -118.254203) (xy 183.1274 -118.24638) (xy 183.187336 -118.24638)
			(xy 183.246758 -118.254203) (xy 183.304651 -118.269716) (xy 183.360024 -118.292652) (xy 183.41193 -118.322619)
			(xy 183.45948 -118.359106) (xy 183.50186 -118.401486) (xy 183.538347 -118.449036) (xy 183.568314 -118.500942)
			(xy 183.59125 -118.556315) (xy 183.606763 -118.614208) (xy 183.614586 -118.67363) (xy 183.615076 -118.703598)
			(xy 183.615076 -119.559324) (xy 197.174612 -119.559324) (xy 197.174612 -118.695724) (xy 197.175102 -118.665756)
			(xy 197.182925 -118.606334) (xy 197.198438 -118.548441) (xy 197.221374 -118.493068) (xy 197.251341 -118.441162)
			(xy 197.287828 -118.393612) (xy 197.330208 -118.351232) (xy 197.377758 -118.314745) (xy 197.429664 -118.284778)
			(xy 197.485037 -118.261842) (xy 197.54293 -118.246329) (xy 197.602352 -118.238506) (xy 197.662288 -118.238506)
			(xy 197.72171 -118.246329) (xy 197.779603 -118.261842) (xy 197.834976 -118.284778) (xy 197.886882 -118.314745)
			(xy 197.934432 -118.351232) (xy 197.976812 -118.393612) (xy 198.013299 -118.441162) (xy 198.043266 -118.493068)
			(xy 198.066202 -118.548441) (xy 198.081715 -118.606334) (xy 198.089538 -118.665756) (xy 198.090028 -118.695724)
			(xy 198.090028 -119.559324) (xy 198.089538 -119.589292) (xy 198.081715 -119.648714) (xy 198.066202 -119.706607)
			(xy 198.043266 -119.76198) (xy 198.013299 -119.813886) (xy 197.976812 -119.861436) (xy 197.934432 -119.903816)
			(xy 197.886882 -119.940303) (xy 197.834976 -119.97027) (xy 197.779603 -119.993206) (xy 197.72171 -120.008719)
			(xy 197.662288 -120.016542) (xy 197.602352 -120.016542) (xy 197.54293 -120.008719) (xy 197.485037 -119.993206)
			(xy 197.429664 -119.97027) (xy 197.377758 -119.940303) (xy 197.330208 -119.903816) (xy 197.287828 -119.861436)
			(xy 197.251341 -119.813886) (xy 197.221374 -119.76198) (xy 197.198438 -119.706607) (xy 197.182925 -119.648714)
			(xy 197.175102 -119.589292) (xy 197.174612 -119.559324) (xy 183.615076 -119.559324) (xy 183.615076 -119.567198)
			(xy 183.614586 -119.597166) (xy 183.606763 -119.656588) (xy 183.59125 -119.714481) (xy 183.568314 -119.769854)
			(xy 183.538347 -119.82176) (xy 183.50186 -119.86931) (xy 183.45948 -119.91169) (xy 183.41193 -119.948177)
			(xy 183.360024 -119.978144) (xy 183.304651 -120.00108) (xy 183.246758 -120.016593) (xy 183.187336 -120.024416)
			(xy 183.1274 -120.024416) (xy 183.067978 -120.016593) (xy 183.010085 -120.00108) (xy 182.954712 -119.978144)
			(xy 182.902806 -119.948177) (xy 182.855256 -119.91169) (xy 182.812876 -119.86931) (xy 182.776389 -119.82176)
			(xy 182.746422 -119.769854) (xy 182.723486 -119.714481) (xy 182.707973 -119.656588) (xy 182.70015 -119.597166)
			(xy 182.69966 -119.567198) (xy 170.65498 -119.567198) (xy 170.65498 -120.086374) (xy 170.65449 -120.116358)
			(xy 170.646662 -120.175814) (xy 170.631141 -120.233739) (xy 170.608192 -120.289143) (xy 170.578208 -120.341077)
			(xy 170.541702 -120.388653) (xy 170.499297 -120.431058) (xy 170.451721 -120.467564) (xy 170.399787 -120.497548)
			(xy 170.344383 -120.520497) (xy 170.286458 -120.536018) (xy 170.227002 -120.543846) (xy 170.167034 -120.543846)
			(xy 170.107578 -120.536018) (xy 170.049653 -120.520497) (xy 169.994249 -120.497548) (xy 169.942315 -120.467564)
			(xy 169.894739 -120.431058) (xy 169.852334 -120.388653) (xy 169.815828 -120.341077) (xy 169.785844 -120.289143)
			(xy 169.762895 -120.233739) (xy 169.747374 -120.175814) (xy 169.739546 -120.116358) (xy 169.739056 -120.086374)
			(xy 151.68372 -120.086374) (xy 151.68372 -120.087898) (xy 151.68323 -120.117882) (xy 151.675402 -120.177338)
			(xy 151.659881 -120.235263) (xy 151.636932 -120.290667) (xy 151.606948 -120.342601) (xy 151.570442 -120.390177)
			(xy 151.528037 -120.432582) (xy 151.480461 -120.469088) (xy 151.428527 -120.499072) (xy 151.373123 -120.522021)
			(xy 151.315198 -120.537542) (xy 151.255742 -120.54537) (xy 151.195774 -120.54537) (xy 151.136318 -120.537542)
			(xy 151.078393 -120.522021) (xy 151.022989 -120.499072) (xy 150.971055 -120.469088) (xy 150.923479 -120.432582)
			(xy 150.881074 -120.390177) (xy 150.844568 -120.342601) (xy 150.814584 -120.290667) (xy 150.791635 -120.235263)
			(xy 150.776114 -120.177338) (xy 150.768286 -120.117882) (xy 150.767796 -120.087898) (xy 84.369615 -120.087898)
			(xy 84.377099 -120.090998) (xy 84.429033 -120.120982) (xy 84.476609 -120.157488) (xy 84.519014 -120.199893)
			(xy 84.55552 -120.247469) (xy 84.585504 -120.299403) (xy 84.608453 -120.354807) (xy 84.623974 -120.412732)
			(xy 84.631802 -120.472188) (xy 84.632292 -120.502172) (xy 84.632292 -121.365772) (xy 84.631802 -121.395756)
			(xy 84.623974 -121.455212) (xy 84.608453 -121.513137) (xy 84.585504 -121.568541) (xy 84.55552 -121.620475)
			(xy 84.519014 -121.668051) (xy 84.476609 -121.710456) (xy 84.429033 -121.746962) (xy 84.377099 -121.776946)
			(xy 84.321695 -121.799895) (xy 84.26377 -121.815416) (xy 84.204314 -121.823244) (xy 84.144346 -121.823244)
			(xy 84.08489 -121.815416) (xy 84.026965 -121.799895) (xy 83.971561 -121.776946) (xy 83.919627 -121.746962)
			(xy 83.872051 -121.710456) (xy 83.829646 -121.668051) (xy 83.79314 -121.620475) (xy 83.763156 -121.568541)
			(xy 83.740207 -121.513137) (xy 83.724686 -121.455212) (xy 83.716858 -121.395756) (xy 83.716368 -121.365772)
			(xy 65.661032 -121.365772) (xy 65.661032 -121.367296) (xy 65.660542 -121.39728) (xy 65.652714 -121.456736)
			(xy 65.637193 -121.514661) (xy 65.614244 -121.570065) (xy 65.58426 -121.621999) (xy 65.547754 -121.669575)
			(xy 65.505349 -121.71198) (xy 65.457773 -121.748486) (xy 65.405839 -121.77847) (xy 65.350435 -121.801419)
			(xy 65.29251 -121.81694) (xy 65.233054 -121.824768) (xy 65.173086 -121.824768) (xy 65.11363 -121.81694)
			(xy 65.055705 -121.801419) (xy 65.000301 -121.77847) (xy 64.948367 -121.748486) (xy 64.900791 -121.71198)
			(xy 64.858386 -121.669575) (xy 64.82188 -121.621999) (xy 64.791896 -121.570065) (xy 64.768947 -121.514661)
			(xy 64.753426 -121.456736) (xy 64.745598 -121.39728) (xy 64.745108 -121.367296) (xy 52.700428 -121.367296)
			(xy 52.700428 -121.886472) (xy 52.699938 -121.91644) (xy 52.692115 -121.975862) (xy 52.676602 -122.033755)
			(xy 52.653666 -122.089128) (xy 52.623699 -122.141034) (xy 52.587212 -122.188584) (xy 52.544832 -122.230964)
			(xy 52.497282 -122.267451) (xy 52.445376 -122.297418) (xy 52.390003 -122.320354) (xy 52.33211 -122.335867)
			(xy 52.272688 -122.34369) (xy 52.212752 -122.34369) (xy 52.15333 -122.335867) (xy 52.095437 -122.320354)
			(xy 52.040064 -122.297418) (xy 51.988158 -122.267451) (xy 51.940608 -122.230964) (xy 51.898228 -122.188584)
			(xy 51.861741 -122.141034) (xy 51.831774 -122.089128) (xy 51.808838 -122.033755) (xy 51.793325 -121.975862)
			(xy 51.785502 -121.91644) (xy 51.785012 -121.886472) (xy 38.225476 -121.886472) (xy 38.225476 -121.894346)
			(xy 38.224986 -121.924314) (xy 38.217163 -121.983736) (xy 38.20165 -122.041629) (xy 38.178714 -122.097002)
			(xy 38.148747 -122.148908) (xy 38.11226 -122.196458) (xy 38.06988 -122.238838) (xy 38.02233 -122.275325)
			(xy 37.970424 -122.305292) (xy 37.915051 -122.328228) (xy 37.857158 -122.343741) (xy 37.797736 -122.351564)
			(xy 37.7378 -122.351564) (xy 37.678378 -122.343741) (xy 37.620485 -122.328228) (xy 37.565112 -122.305292)
			(xy 37.513206 -122.275325) (xy 37.465656 -122.238838) (xy 37.423276 -122.196458) (xy 37.386789 -122.148908)
			(xy 37.356822 -122.097002) (xy 37.333886 -122.041629) (xy 37.318373 -121.983736) (xy 37.31055 -121.924314)
			(xy 37.31006 -121.894346) (xy 4.308094 -121.894346) (xy 4.308094 -123.68784) (xy 34.667952 -123.68784)
			(xy 34.667952 -122.82424) (xy 34.668442 -122.794272) (xy 34.676265 -122.73485) (xy 34.691778 -122.676957)
			(xy 34.714714 -122.621584) (xy 34.744681 -122.569678) (xy 34.781168 -122.522128) (xy 34.823548 -122.479748)
			(xy 34.871098 -122.443261) (xy 34.923004 -122.413294) (xy 34.978377 -122.390358) (xy 35.03627 -122.374845)
			(xy 35.095692 -122.367022) (xy 35.155628 -122.367022) (xy 35.21505 -122.374845) (xy 35.272943 -122.390358)
			(xy 35.328316 -122.413294) (xy 35.380222 -122.443261) (xy 35.427772 -122.479748) (xy 35.470152 -122.522128)
			(xy 35.506639 -122.569678) (xy 35.536606 -122.621584) (xy 35.559542 -122.676957) (xy 35.575055 -122.73485)
			(xy 35.582878 -122.794272) (xy 35.583368 -122.82424) (xy 35.583368 -123.686316) (xy 53.639212 -123.686316)
			(xy 53.639212 -122.822716) (xy 53.639702 -122.792748) (xy 53.647525 -122.733326) (xy 53.663038 -122.675433)
			(xy 53.685974 -122.62006) (xy 53.715941 -122.568154) (xy 53.752428 -122.520604) (xy 53.794808 -122.478224)
			(xy 53.842358 -122.441737) (xy 53.894264 -122.41177) (xy 53.949637 -122.388834) (xy 54.00753 -122.373321)
			(xy 54.066952 -122.365498) (xy 54.126888 -122.365498) (xy 54.18631 -122.373321) (xy 54.244203 -122.388834)
			(xy 54.299576 -122.41177) (xy 54.351482 -122.441737) (xy 54.399032 -122.478224) (xy 54.441412 -122.520604)
			(xy 54.477899 -122.568154) (xy 54.507866 -122.62006) (xy 54.530802 -122.675433) (xy 54.546315 -122.733326)
			(xy 54.554138 -122.792748) (xy 54.554628 -122.822716) (xy 54.554628 -123.16714) (xy 66.599308 -123.16714)
			(xy 66.599308 -122.30354) (xy 66.599798 -122.273556) (xy 66.607626 -122.2141) (xy 66.623147 -122.156175)
			(xy 66.646096 -122.100771) (xy 66.67608 -122.048837) (xy 66.712586 -122.001261) (xy 66.754991 -121.958856)
			(xy 66.802567 -121.92235) (xy 66.854501 -121.892366) (xy 66.909905 -121.869417) (xy 66.96783 -121.853896)
			(xy 67.027286 -121.846068) (xy 67.087254 -121.846068) (xy 67.14671 -121.853896) (xy 67.204635 -121.869417)
			(xy 67.260039 -121.892366) (xy 67.311973 -121.92235) (xy 67.359549 -121.958856) (xy 67.401954 -122.001261)
			(xy 67.43846 -122.048837) (xy 67.468444 -122.100771) (xy 67.491393 -122.156175) (xy 67.506914 -122.2141)
			(xy 67.514742 -122.273556) (xy 67.515232 -122.30354) (xy 67.515232 -123.159266) (xy 81.07426 -123.159266)
			(xy 81.07426 -122.295666) (xy 81.07475 -122.265682) (xy 81.082578 -122.206226) (xy 81.098099 -122.148301)
			(xy 81.121048 -122.092897) (xy 81.151032 -122.040963) (xy 81.187538 -121.993387) (xy 81.229943 -121.950982)
			(xy 81.277519 -121.914476) (xy 81.329453 -121.884492) (xy 81.384857 -121.861543) (xy 81.442782 -121.846022)
			(xy 81.502238 -121.838194) (xy 81.562206 -121.838194) (xy 81.621662 -121.846022) (xy 81.679587 -121.861543)
			(xy 81.734991 -121.884492) (xy 81.752059 -121.894346) (xy 153.409904 -121.894346) (xy 153.409904 -121.030746)
			(xy 153.410394 -121.000762) (xy 153.418222 -120.941306) (xy 153.433743 -120.883381) (xy 153.456692 -120.827977)
			(xy 153.486676 -120.776043) (xy 153.523182 -120.728467) (xy 153.565587 -120.686062) (xy 153.613163 -120.649556)
			(xy 153.665097 -120.619572) (xy 153.720501 -120.596623) (xy 153.778426 -120.581102) (xy 153.837882 -120.573274)
			(xy 153.89785 -120.573274) (xy 153.957306 -120.581102) (xy 154.015231 -120.596623) (xy 154.070635 -120.619572)
			(xy 154.122569 -120.649556) (xy 154.170145 -120.686062) (xy 154.21255 -120.728467) (xy 154.249056 -120.776043)
			(xy 154.27904 -120.827977) (xy 154.301989 -120.883381) (xy 154.31751 -120.941306) (xy 154.325338 -121.000762)
			(xy 154.325828 -121.030746) (xy 154.325828 -121.886472) (xy 167.884856 -121.886472) (xy 167.884856 -121.022872)
			(xy 167.885346 -120.992888) (xy 167.893174 -120.933432) (xy 167.908695 -120.875507) (xy 167.931644 -120.820103)
			(xy 167.961628 -120.768169) (xy 167.998134 -120.720593) (xy 168.040539 -120.678188) (xy 168.088115 -120.641682)
			(xy 168.140049 -120.611698) (xy 168.195453 -120.588749) (xy 168.253378 -120.573228) (xy 168.312834 -120.5654)
			(xy 168.372802 -120.5654) (xy 168.432258 -120.573228) (xy 168.490183 -120.588749) (xy 168.545587 -120.611698)
			(xy 168.597521 -120.641682) (xy 168.645097 -120.678188) (xy 168.687502 -120.720593) (xy 168.724008 -120.768169)
			(xy 168.753992 -120.820103) (xy 168.776941 -120.875507) (xy 168.792462 -120.933432) (xy 168.80029 -120.992888)
			(xy 168.80078 -121.022872) (xy 168.80078 -121.367296) (xy 180.84546 -121.367296) (xy 180.84546 -120.503696)
			(xy 180.84595 -120.473728) (xy 180.853773 -120.414306) (xy 180.869286 -120.356413) (xy 180.892222 -120.30104)
			(xy 180.922189 -120.249134) (xy 180.958676 -120.201584) (xy 181.001056 -120.159204) (xy 181.048606 -120.122717)
			(xy 181.100512 -120.09275) (xy 181.155885 -120.069814) (xy 181.213778 -120.054301) (xy 181.2732 -120.046478)
			(xy 181.333136 -120.046478) (xy 181.392558 -120.054301) (xy 181.450451 -120.069814) (xy 181.505824 -120.09275)
			(xy 181.55773 -120.122717) (xy 181.60528 -120.159204) (xy 181.64766 -120.201584) (xy 181.684147 -120.249134)
			(xy 181.714114 -120.30104) (xy 181.73705 -120.356413) (xy 181.752563 -120.414306) (xy 181.760386 -120.473728)
			(xy 181.760876 -120.503696) (xy 181.760876 -121.365772) (xy 199.81672 -121.365772) (xy 199.81672 -120.502172)
			(xy 199.81721 -120.472204) (xy 199.825033 -120.412782) (xy 199.840546 -120.354889) (xy 199.863482 -120.299516)
			(xy 199.893449 -120.24761) (xy 199.929936 -120.20006) (xy 199.972316 -120.15768) (xy 200.019866 -120.121193)
			(xy 200.071772 -120.091226) (xy 200.127145 -120.06829) (xy 200.185038 -120.052777) (xy 200.24446 -120.044954)
			(xy 200.304396 -120.044954) (xy 200.363818 -120.052777) (xy 200.421711 -120.06829) (xy 200.469049 -120.087898)
			(xy 266.86764 -120.087898) (xy 266.86764 -119.224298) (xy 266.86813 -119.194314) (xy 266.875958 -119.134858)
			(xy 266.891479 -119.076933) (xy 266.914428 -119.021529) (xy 266.944412 -118.969595) (xy 266.980918 -118.922019)
			(xy 267.023323 -118.879614) (xy 267.070899 -118.843108) (xy 267.122833 -118.813124) (xy 267.178237 -118.790175)
			(xy 267.236162 -118.774654) (xy 267.295618 -118.766826) (xy 267.355586 -118.766826) (xy 267.415042 -118.774654)
			(xy 267.472967 -118.790175) (xy 267.528371 -118.813124) (xy 267.580305 -118.843108) (xy 267.627881 -118.879614)
			(xy 267.670286 -118.922019) (xy 267.706792 -118.969595) (xy 267.736776 -119.021529) (xy 267.759725 -119.076933)
			(xy 267.775246 -119.134858) (xy 267.783074 -119.194314) (xy 267.783564 -119.224298) (xy 267.783564 -120.086374)
			(xy 285.8389 -120.086374) (xy 285.8389 -119.222774) (xy 285.83939 -119.19279) (xy 285.847218 -119.133334)
			(xy 285.862739 -119.075409) (xy 285.885688 -119.020005) (xy 285.915672 -118.968071) (xy 285.952178 -118.920495)
			(xy 285.994583 -118.87809) (xy 286.042159 -118.841584) (xy 286.094093 -118.8116) (xy 286.149497 -118.788651)
			(xy 286.207422 -118.77313) (xy 286.266878 -118.765302) (xy 286.326846 -118.765302) (xy 286.386302 -118.77313)
			(xy 286.444227 -118.788651) (xy 286.499631 -118.8116) (xy 286.551565 -118.841584) (xy 286.599141 -118.87809)
			(xy 286.641546 -118.920495) (xy 286.678052 -118.968071) (xy 286.708036 -119.020005) (xy 286.730985 -119.075409)
			(xy 286.746506 -119.133334) (xy 286.754334 -119.19279) (xy 286.754824 -119.222774) (xy 286.754824 -119.567198)
			(xy 298.799504 -119.567198) (xy 298.799504 -118.703598) (xy 298.799994 -118.67363) (xy 298.807817 -118.614208)
			(xy 298.82333 -118.556315) (xy 298.846266 -118.500942) (xy 298.876233 -118.449036) (xy 298.91272 -118.401486)
			(xy 298.9551 -118.359106) (xy 299.00265 -118.322619) (xy 299.054556 -118.292652) (xy 299.109929 -118.269716)
			(xy 299.167822 -118.254203) (xy 299.227244 -118.24638) (xy 299.28718 -118.24638) (xy 299.346602 -118.254203)
			(xy 299.404495 -118.269716) (xy 299.459868 -118.292652) (xy 299.511774 -118.322619) (xy 299.559324 -118.359106)
			(xy 299.601704 -118.401486) (xy 299.638191 -118.449036) (xy 299.668158 -118.500942) (xy 299.691094 -118.556315)
			(xy 299.706607 -118.614208) (xy 299.71443 -118.67363) (xy 299.71492 -118.703598) (xy 299.71492 -119.559324)
			(xy 313.274456 -119.559324) (xy 313.274456 -118.695724) (xy 313.274946 -118.665756) (xy 313.282769 -118.606334)
			(xy 313.298282 -118.548441) (xy 313.321218 -118.493068) (xy 313.351185 -118.441162) (xy 313.387672 -118.393612)
			(xy 313.430052 -118.351232) (xy 313.477602 -118.314745) (xy 313.529508 -118.284778) (xy 313.584881 -118.261842)
			(xy 313.642774 -118.246329) (xy 313.702196 -118.238506) (xy 313.762132 -118.238506) (xy 313.821554 -118.246329)
			(xy 313.879447 -118.261842) (xy 313.93482 -118.284778) (xy 313.986726 -118.314745) (xy 314.034276 -118.351232)
			(xy 314.076656 -118.393612) (xy 314.113143 -118.441162) (xy 314.14311 -118.493068) (xy 314.166046 -118.548441)
			(xy 314.181559 -118.606334) (xy 314.189382 -118.665756) (xy 314.189872 -118.695724) (xy 314.189872 -119.559324)
			(xy 314.189382 -119.589292) (xy 314.181559 -119.648714) (xy 314.166046 -119.706607) (xy 314.14311 -119.76198)
			(xy 314.113143 -119.813886) (xy 314.076656 -119.861436) (xy 314.034276 -119.903816) (xy 313.986726 -119.940303)
			(xy 313.93482 -119.97027) (xy 313.879447 -119.993206) (xy 313.821554 -120.008719) (xy 313.762132 -120.016542)
			(xy 313.702196 -120.016542) (xy 313.642774 -120.008719) (xy 313.584881 -119.993206) (xy 313.529508 -119.97027)
			(xy 313.477602 -119.940303) (xy 313.430052 -119.903816) (xy 313.387672 -119.861436) (xy 313.351185 -119.813886)
			(xy 313.321218 -119.76198) (xy 313.298282 -119.706607) (xy 313.282769 -119.648714) (xy 313.274946 -119.589292)
			(xy 313.274456 -119.559324) (xy 299.71492 -119.559324) (xy 299.71492 -119.567198) (xy 299.71443 -119.597166)
			(xy 299.706607 -119.656588) (xy 299.691094 -119.714481) (xy 299.668158 -119.769854) (xy 299.638191 -119.82176)
			(xy 299.601704 -119.86931) (xy 299.559324 -119.91169) (xy 299.511774 -119.948177) (xy 299.459868 -119.978144)
			(xy 299.404495 -120.00108) (xy 299.346602 -120.016593) (xy 299.28718 -120.024416) (xy 299.227244 -120.024416)
			(xy 299.167822 -120.016593) (xy 299.109929 -120.00108) (xy 299.054556 -119.978144) (xy 299.00265 -119.948177)
			(xy 298.9551 -119.91169) (xy 298.91272 -119.86931) (xy 298.876233 -119.82176) (xy 298.846266 -119.769854)
			(xy 298.82333 -119.714481) (xy 298.807817 -119.656588) (xy 298.799994 -119.597166) (xy 298.799504 -119.567198)
			(xy 286.754824 -119.567198) (xy 286.754824 -120.086374) (xy 286.754334 -120.116358) (xy 286.746506 -120.175814)
			(xy 286.730985 -120.233739) (xy 286.708036 -120.289143) (xy 286.678052 -120.341077) (xy 286.641546 -120.388653)
			(xy 286.599141 -120.431058) (xy 286.551565 -120.467564) (xy 286.499631 -120.497548) (xy 286.444227 -120.520497)
			(xy 286.386302 -120.536018) (xy 286.326846 -120.543846) (xy 286.266878 -120.543846) (xy 286.207422 -120.536018)
			(xy 286.149497 -120.520497) (xy 286.094093 -120.497548) (xy 286.042159 -120.467564) (xy 285.994583 -120.431058)
			(xy 285.952178 -120.388653) (xy 285.915672 -120.341077) (xy 285.885688 -120.289143) (xy 285.862739 -120.233739)
			(xy 285.847218 -120.175814) (xy 285.83939 -120.116358) (xy 285.8389 -120.086374) (xy 267.783564 -120.086374)
			(xy 267.783564 -120.087898) (xy 267.783074 -120.117882) (xy 267.775246 -120.177338) (xy 267.759725 -120.235263)
			(xy 267.736776 -120.290667) (xy 267.706792 -120.342601) (xy 267.670286 -120.390177) (xy 267.627881 -120.432582)
			(xy 267.580305 -120.469088) (xy 267.528371 -120.499072) (xy 267.472967 -120.522021) (xy 267.415042 -120.537542)
			(xy 267.355586 -120.54537) (xy 267.295618 -120.54537) (xy 267.236162 -120.537542) (xy 267.178237 -120.522021)
			(xy 267.122833 -120.499072) (xy 267.070899 -120.469088) (xy 267.023323 -120.432582) (xy 266.980918 -120.390177)
			(xy 266.944412 -120.342601) (xy 266.914428 -120.290667) (xy 266.891479 -120.235263) (xy 266.875958 -120.177338)
			(xy 266.86813 -120.117882) (xy 266.86764 -120.087898) (xy 200.469049 -120.087898) (xy 200.477084 -120.091226)
			(xy 200.52899 -120.121193) (xy 200.57654 -120.15768) (xy 200.61892 -120.20006) (xy 200.655407 -120.24761)
			(xy 200.685374 -120.299516) (xy 200.70831 -120.354889) (xy 200.723823 -120.412782) (xy 200.731646 -120.472204)
			(xy 200.732136 -120.502172) (xy 200.732136 -121.365772) (xy 200.731646 -121.39574) (xy 200.723823 -121.455162)
			(xy 200.70831 -121.513055) (xy 200.685374 -121.568428) (xy 200.655407 -121.620334) (xy 200.61892 -121.667884)
			(xy 200.57654 -121.710264) (xy 200.52899 -121.746751) (xy 200.477084 -121.776718) (xy 200.421711 -121.799654)
			(xy 200.363818 -121.815167) (xy 200.304396 -121.82299) (xy 200.24446 -121.82299) (xy 200.185038 -121.815167)
			(xy 200.127145 -121.799654) (xy 200.071772 -121.776718) (xy 200.019866 -121.746751) (xy 199.972316 -121.710264)
			(xy 199.929936 -121.667884) (xy 199.893449 -121.620334) (xy 199.863482 -121.568428) (xy 199.840546 -121.513055)
			(xy 199.825033 -121.455162) (xy 199.81721 -121.39574) (xy 199.81672 -121.365772) (xy 181.760876 -121.365772)
			(xy 181.760876 -121.367296) (xy 181.760386 -121.397264) (xy 181.752563 -121.456686) (xy 181.73705 -121.514579)
			(xy 181.714114 -121.569952) (xy 181.684147 -121.621858) (xy 181.64766 -121.669408) (xy 181.60528 -121.711788)
			(xy 181.55773 -121.748275) (xy 181.505824 -121.778242) (xy 181.450451 -121.801178) (xy 181.392558 -121.816691)
			(xy 181.333136 -121.824514) (xy 181.2732 -121.824514) (xy 181.213778 -121.816691) (xy 181.155885 -121.801178)
			(xy 181.100512 -121.778242) (xy 181.048606 -121.748275) (xy 181.001056 -121.711788) (xy 180.958676 -121.669408)
			(xy 180.922189 -121.621858) (xy 180.892222 -121.569952) (xy 180.869286 -121.514579) (xy 180.853773 -121.456686)
			(xy 180.84595 -121.397264) (xy 180.84546 -121.367296) (xy 168.80078 -121.367296) (xy 168.80078 -121.886472)
			(xy 168.80029 -121.916456) (xy 168.792462 -121.975912) (xy 168.776941 -122.033837) (xy 168.753992 -122.089241)
			(xy 168.724008 -122.141175) (xy 168.687502 -122.188751) (xy 168.645097 -122.231156) (xy 168.597521 -122.267662)
			(xy 168.545587 -122.297646) (xy 168.490183 -122.320595) (xy 168.432258 -122.336116) (xy 168.372802 -122.343944)
			(xy 168.312834 -122.343944) (xy 168.253378 -122.336116) (xy 168.195453 -122.320595) (xy 168.140049 -122.297646)
			(xy 168.088115 -122.267662) (xy 168.040539 -122.231156) (xy 167.998134 -122.188751) (xy 167.961628 -122.141175)
			(xy 167.931644 -122.089241) (xy 167.908695 -122.033837) (xy 167.893174 -121.975912) (xy 167.885346 -121.916456)
			(xy 167.884856 -121.886472) (xy 154.325828 -121.886472) (xy 154.325828 -121.894346) (xy 154.325338 -121.92433)
			(xy 154.31751 -121.983786) (xy 154.301989 -122.041711) (xy 154.27904 -122.097115) (xy 154.249056 -122.149049)
			(xy 154.21255 -122.196625) (xy 154.170145 -122.23903) (xy 154.122569 -122.275536) (xy 154.070635 -122.30552)
			(xy 154.015231 -122.328469) (xy 153.957306 -122.34399) (xy 153.89785 -122.351818) (xy 153.837882 -122.351818)
			(xy 153.778426 -122.34399) (xy 153.720501 -122.328469) (xy 153.665097 -122.30552) (xy 153.613163 -122.275536)
			(xy 153.565587 -122.23903) (xy 153.523182 -122.196625) (xy 153.486676 -122.149049) (xy 153.456692 -122.097115)
			(xy 153.433743 -122.041711) (xy 153.418222 -121.983786) (xy 153.410394 -121.92433) (xy 153.409904 -121.894346)
			(xy 81.752059 -121.894346) (xy 81.786925 -121.914476) (xy 81.834501 -121.950982) (xy 81.876906 -121.993387)
			(xy 81.913412 -122.040963) (xy 81.943396 -122.092897) (xy 81.966345 -122.148301) (xy 81.981866 -122.206226)
			(xy 81.989694 -122.265682) (xy 81.990184 -122.295666) (xy 81.990184 -123.159266) (xy 81.989694 -123.18925)
			(xy 81.981866 -123.248706) (xy 81.966345 -123.306631) (xy 81.943396 -123.362035) (xy 81.913412 -123.413969)
			(xy 81.876906 -123.461545) (xy 81.834501 -123.50395) (xy 81.786925 -123.540456) (xy 81.734991 -123.57044)
			(xy 81.679587 -123.593389) (xy 81.621662 -123.60891) (xy 81.562206 -123.616738) (xy 81.502238 -123.616738)
			(xy 81.442782 -123.60891) (xy 81.384857 -123.593389) (xy 81.329453 -123.57044) (xy 81.277519 -123.540456)
			(xy 81.229943 -123.50395) (xy 81.187538 -123.461545) (xy 81.151032 -123.413969) (xy 81.121048 -123.362035)
			(xy 81.098099 -123.306631) (xy 81.082578 -123.248706) (xy 81.07475 -123.18925) (xy 81.07426 -123.159266)
			(xy 67.515232 -123.159266) (xy 67.515232 -123.16714) (xy 67.514742 -123.197124) (xy 67.506914 -123.25658)
			(xy 67.491393 -123.314505) (xy 67.468444 -123.369909) (xy 67.43846 -123.421843) (xy 67.401954 -123.469419)
			(xy 67.359549 -123.511824) (xy 67.311973 -123.54833) (xy 67.260039 -123.578314) (xy 67.204635 -123.601263)
			(xy 67.14671 -123.616784) (xy 67.087254 -123.624612) (xy 67.027286 -123.624612) (xy 66.96783 -123.616784)
			(xy 66.909905 -123.601263) (xy 66.854501 -123.578314) (xy 66.802567 -123.54833) (xy 66.754991 -123.511824)
			(xy 66.712586 -123.469419) (xy 66.67608 -123.421843) (xy 66.646096 -123.369909) (xy 66.623147 -123.314505)
			(xy 66.607626 -123.25658) (xy 66.599798 -123.197124) (xy 66.599308 -123.16714) (xy 54.554628 -123.16714)
			(xy 54.554628 -123.686316) (xy 54.554138 -123.716284) (xy 54.546315 -123.775706) (xy 54.530802 -123.833599)
			(xy 54.507866 -123.888972) (xy 54.477899 -123.940878) (xy 54.441412 -123.988428) (xy 54.399032 -124.030808)
			(xy 54.351482 -124.067295) (xy 54.299576 -124.097262) (xy 54.244203 -124.120198) (xy 54.18631 -124.135711)
			(xy 54.126888 -124.143534) (xy 54.066952 -124.143534) (xy 54.00753 -124.135711) (xy 53.949637 -124.120198)
			(xy 53.894264 -124.097262) (xy 53.842358 -124.067295) (xy 53.794808 -124.030808) (xy 53.752428 -123.988428)
			(xy 53.715941 -123.940878) (xy 53.685974 -123.888972) (xy 53.663038 -123.833599) (xy 53.647525 -123.775706)
			(xy 53.639702 -123.716284) (xy 53.639212 -123.686316) (xy 35.583368 -123.686316) (xy 35.583368 -123.68784)
			(xy 35.582878 -123.717808) (xy 35.575055 -123.77723) (xy 35.559542 -123.835123) (xy 35.536606 -123.890496)
			(xy 35.506639 -123.942402) (xy 35.470152 -123.989952) (xy 35.427772 -124.032332) (xy 35.380222 -124.068819)
			(xy 35.328316 -124.098786) (xy 35.272943 -124.121722) (xy 35.21505 -124.137235) (xy 35.155628 -124.145058)
			(xy 35.095692 -124.145058) (xy 35.03627 -124.137235) (xy 34.978377 -124.121722) (xy 34.923004 -124.098786)
			(xy 34.871098 -124.068819) (xy 34.823548 -124.032332) (xy 34.781168 -123.989952) (xy 34.744681 -123.942402)
			(xy 34.714714 -123.890496) (xy 34.691778 -123.835123) (xy 34.676265 -123.77723) (xy 34.668442 -123.717808)
			(xy 34.667952 -123.68784) (xy 4.308094 -123.68784) (xy 4.308094 -125.494542) (xy 37.31006 -125.494542)
			(xy 37.31006 -124.630942) (xy 37.31055 -124.600974) (xy 37.318373 -124.541552) (xy 37.333886 -124.483659)
			(xy 37.356822 -124.428286) (xy 37.386789 -124.37638) (xy 37.423276 -124.32883) (xy 37.465656 -124.28645)
			(xy 37.513206 -124.249963) (xy 37.565112 -124.219996) (xy 37.620485 -124.19706) (xy 37.678378 -124.181547)
			(xy 37.7378 -124.173724) (xy 37.797736 -124.173724) (xy 37.857158 -124.181547) (xy 37.915051 -124.19706)
			(xy 37.970424 -124.219996) (xy 38.02233 -124.249963) (xy 38.06988 -124.28645) (xy 38.11226 -124.32883)
			(xy 38.148747 -124.37638) (xy 38.178714 -124.428286) (xy 38.20165 -124.483659) (xy 38.217163 -124.541552)
			(xy 38.224986 -124.600974) (xy 38.225476 -124.630942) (xy 38.225476 -125.486414) (xy 51.785012 -125.486414)
			(xy 51.785012 -124.622814) (xy 51.785502 -124.592846) (xy 51.793325 -124.533424) (xy 51.808838 -124.475531)
			(xy 51.831774 -124.420158) (xy 51.861741 -124.368252) (xy 51.898228 -124.320702) (xy 51.940608 -124.278322)
			(xy 51.988158 -124.241835) (xy 52.040064 -124.211868) (xy 52.095437 -124.188932) (xy 52.15333 -124.173419)
			(xy 52.212752 -124.165596) (xy 52.272688 -124.165596) (xy 52.33211 -124.173419) (xy 52.390003 -124.188932)
			(xy 52.445376 -124.211868) (xy 52.497282 -124.241835) (xy 52.544832 -124.278322) (xy 52.587212 -124.320702)
			(xy 52.623699 -124.368252) (xy 52.653666 -124.420158) (xy 52.676602 -124.475531) (xy 52.692115 -124.533424)
			(xy 52.699938 -124.592846) (xy 52.700428 -124.622814) (xy 52.700428 -124.967238) (xy 64.745108 -124.967238)
			(xy 64.745108 -124.103638) (xy 64.745598 -124.073654) (xy 64.753426 -124.014198) (xy 64.768947 -123.956273)
			(xy 64.791896 -123.900869) (xy 64.82188 -123.848935) (xy 64.858386 -123.801359) (xy 64.900791 -123.758954)
			(xy 64.948367 -123.722448) (xy 65.000301 -123.692464) (xy 65.055705 -123.669515) (xy 65.11363 -123.653994)
			(xy 65.173086 -123.646166) (xy 65.233054 -123.646166) (xy 65.29251 -123.653994) (xy 65.350435 -123.669515)
			(xy 65.405839 -123.692464) (xy 65.457773 -123.722448) (xy 65.505349 -123.758954) (xy 65.547754 -123.801359)
			(xy 65.58426 -123.848935) (xy 65.614244 -123.900869) (xy 65.637193 -123.956273) (xy 65.652714 -124.014198)
			(xy 65.660542 -124.073654) (xy 65.661032 -124.103638) (xy 65.661032 -124.965714) (xy 83.716368 -124.965714)
			(xy 83.716368 -124.102114) (xy 83.716858 -124.07213) (xy 83.724686 -124.012674) (xy 83.740207 -123.954749)
			(xy 83.763156 -123.899345) (xy 83.79314 -123.847411) (xy 83.829646 -123.799835) (xy 83.872051 -123.75743)
			(xy 83.919627 -123.720924) (xy 83.971561 -123.69094) (xy 84.026965 -123.667991) (xy 84.08489 -123.65247)
			(xy 84.144346 -123.644642) (xy 84.204314 -123.644642) (xy 84.26377 -123.65247) (xy 84.321695 -123.667991)
			(xy 84.369615 -123.68784) (xy 150.767796 -123.68784) (xy 150.767796 -122.82424) (xy 150.768286 -122.794256)
			(xy 150.776114 -122.7348) (xy 150.791635 -122.676875) (xy 150.814584 -122.621471) (xy 150.844568 -122.569537)
			(xy 150.881074 -122.521961) (xy 150.923479 -122.479556) (xy 150.971055 -122.44305) (xy 151.022989 -122.413066)
			(xy 151.078393 -122.390117) (xy 151.136318 -122.374596) (xy 151.195774 -122.366768) (xy 151.255742 -122.366768)
			(xy 151.315198 -122.374596) (xy 151.373123 -122.390117) (xy 151.428527 -122.413066) (xy 151.480461 -122.44305)
			(xy 151.528037 -122.479556) (xy 151.570442 -122.521961) (xy 151.606948 -122.569537) (xy 151.636932 -122.621471)
			(xy 151.659881 -122.676875) (xy 151.675402 -122.7348) (xy 151.68323 -122.794256) (xy 151.68372 -122.82424)
			(xy 151.68372 -123.686316) (xy 169.739056 -123.686316) (xy 169.739056 -122.822716) (xy 169.739546 -122.792732)
			(xy 169.747374 -122.733276) (xy 169.762895 -122.675351) (xy 169.785844 -122.619947) (xy 169.815828 -122.568013)
			(xy 169.852334 -122.520437) (xy 169.894739 -122.478032) (xy 169.942315 -122.441526) (xy 169.994249 -122.411542)
			(xy 170.049653 -122.388593) (xy 170.107578 -122.373072) (xy 170.167034 -122.365244) (xy 170.227002 -122.365244)
			(xy 170.286458 -122.373072) (xy 170.344383 -122.388593) (xy 170.399787 -122.411542) (xy 170.451721 -122.441526)
			(xy 170.499297 -122.478032) (xy 170.541702 -122.520437) (xy 170.578208 -122.568013) (xy 170.608192 -122.619947)
			(xy 170.631141 -122.675351) (xy 170.646662 -122.733276) (xy 170.65449 -122.792732) (xy 170.65498 -122.822716)
			(xy 170.65498 -123.16714) (xy 182.69966 -123.16714) (xy 182.69966 -122.30354) (xy 182.70015 -122.273572)
			(xy 182.707973 -122.21415) (xy 182.723486 -122.156257) (xy 182.746422 -122.100884) (xy 182.776389 -122.048978)
			(xy 182.812876 -122.001428) (xy 182.855256 -121.959048) (xy 182.902806 -121.922561) (xy 182.954712 -121.892594)
			(xy 183.010085 -121.869658) (xy 183.067978 -121.854145) (xy 183.1274 -121.846322) (xy 183.187336 -121.846322)
			(xy 183.246758 -121.854145) (xy 183.304651 -121.869658) (xy 183.360024 -121.892594) (xy 183.41193 -121.922561)
			(xy 183.45948 -121.959048) (xy 183.50186 -122.001428) (xy 183.538347 -122.048978) (xy 183.568314 -122.100884)
			(xy 183.59125 -122.156257) (xy 183.606763 -122.21415) (xy 183.614586 -122.273572) (xy 183.615076 -122.30354)
			(xy 183.615076 -123.159266) (xy 197.174612 -123.159266) (xy 197.174612 -122.295666) (xy 197.175102 -122.265698)
			(xy 197.182925 -122.206276) (xy 197.198438 -122.148383) (xy 197.221374 -122.09301) (xy 197.251341 -122.041104)
			(xy 197.287828 -121.993554) (xy 197.330208 -121.951174) (xy 197.377758 -121.914687) (xy 197.429664 -121.88472)
			(xy 197.485037 -121.861784) (xy 197.54293 -121.846271) (xy 197.602352 -121.838448) (xy 197.662288 -121.838448)
			(xy 197.72171 -121.846271) (xy 197.779603 -121.861784) (xy 197.834976 -121.88472) (xy 197.851649 -121.894346)
			(xy 269.509748 -121.894346) (xy 269.509748 -121.030746) (xy 269.510238 -121.000762) (xy 269.518066 -120.941306)
			(xy 269.533587 -120.883381) (xy 269.556536 -120.827977) (xy 269.58652 -120.776043) (xy 269.623026 -120.728467)
			(xy 269.665431 -120.686062) (xy 269.713007 -120.649556) (xy 269.764941 -120.619572) (xy 269.820345 -120.596623)
			(xy 269.87827 -120.581102) (xy 269.937726 -120.573274) (xy 269.997694 -120.573274) (xy 270.05715 -120.581102)
			(xy 270.115075 -120.596623) (xy 270.170479 -120.619572) (xy 270.222413 -120.649556) (xy 270.269989 -120.686062)
			(xy 270.312394 -120.728467) (xy 270.3489 -120.776043) (xy 270.378884 -120.827977) (xy 270.401833 -120.883381)
			(xy 270.417354 -120.941306) (xy 270.425182 -121.000762) (xy 270.425672 -121.030746) (xy 270.425672 -121.886472)
			(xy 283.9847 -121.886472) (xy 283.9847 -121.022872) (xy 283.98519 -120.992888) (xy 283.993018 -120.933432)
			(xy 284.008539 -120.875507) (xy 284.031488 -120.820103) (xy 284.061472 -120.768169) (xy 284.097978 -120.720593)
			(xy 284.140383 -120.678188) (xy 284.187959 -120.641682) (xy 284.239893 -120.611698) (xy 284.295297 -120.588749)
			(xy 284.353222 -120.573228) (xy 284.412678 -120.5654) (xy 284.472646 -120.5654) (xy 284.532102 -120.573228)
			(xy 284.590027 -120.588749) (xy 284.645431 -120.611698) (xy 284.697365 -120.641682) (xy 284.744941 -120.678188)
			(xy 284.787346 -120.720593) (xy 284.823852 -120.768169) (xy 284.853836 -120.820103) (xy 284.876785 -120.875507)
			(xy 284.892306 -120.933432) (xy 284.900134 -120.992888) (xy 284.900624 -121.022872) (xy 284.900624 -121.367296)
			(xy 296.945304 -121.367296) (xy 296.945304 -120.503696) (xy 296.945794 -120.473728) (xy 296.953617 -120.414306)
			(xy 296.96913 -120.356413) (xy 296.992066 -120.30104) (xy 297.022033 -120.249134) (xy 297.05852 -120.201584)
			(xy 297.1009 -120.159204) (xy 297.14845 -120.122717) (xy 297.200356 -120.09275) (xy 297.255729 -120.069814)
			(xy 297.313622 -120.054301) (xy 297.373044 -120.046478) (xy 297.43298 -120.046478) (xy 297.492402 -120.054301)
			(xy 297.550295 -120.069814) (xy 297.605668 -120.09275) (xy 297.657574 -120.122717) (xy 297.705124 -120.159204)
			(xy 297.747504 -120.201584) (xy 297.783991 -120.249134) (xy 297.813958 -120.30104) (xy 297.836894 -120.356413)
			(xy 297.852407 -120.414306) (xy 297.86023 -120.473728) (xy 297.86072 -120.503696) (xy 297.86072 -121.365772)
			(xy 315.916564 -121.365772) (xy 315.916564 -120.502172) (xy 315.917054 -120.472204) (xy 315.924877 -120.412782)
			(xy 315.94039 -120.354889) (xy 315.963326 -120.299516) (xy 315.993293 -120.24761) (xy 316.02978 -120.20006)
			(xy 316.07216 -120.15768) (xy 316.11971 -120.121193) (xy 316.171616 -120.091226) (xy 316.226989 -120.06829)
			(xy 316.284882 -120.052777) (xy 316.344304 -120.044954) (xy 316.40424 -120.044954) (xy 316.463662 -120.052777)
			(xy 316.521555 -120.06829) (xy 316.568893 -120.087898) (xy 382.967992 -120.087898) (xy 382.967992 -119.224298)
			(xy 382.968482 -119.19433) (xy 382.976305 -119.134908) (xy 382.991818 -119.077015) (xy 383.014754 -119.021642)
			(xy 383.044721 -118.969736) (xy 383.081208 -118.922186) (xy 383.123588 -118.879806) (xy 383.171138 -118.843319)
			(xy 383.223044 -118.813352) (xy 383.278417 -118.790416) (xy 383.33631 -118.774903) (xy 383.395732 -118.76708)
			(xy 383.455668 -118.76708) (xy 383.51509 -118.774903) (xy 383.572983 -118.790416) (xy 383.628356 -118.813352)
			(xy 383.680262 -118.843319) (xy 383.727812 -118.879806) (xy 383.770192 -118.922186) (xy 383.806679 -118.969736)
			(xy 383.836646 -119.021642) (xy 383.859582 -119.077015) (xy 383.875095 -119.134908) (xy 383.882918 -119.19433)
			(xy 383.883408 -119.224298) (xy 383.883408 -120.086374) (xy 401.939252 -120.086374) (xy 401.939252 -119.222774)
			(xy 401.939742 -119.192806) (xy 401.947565 -119.133384) (xy 401.963078 -119.075491) (xy 401.986014 -119.020118)
			(xy 402.015981 -118.968212) (xy 402.052468 -118.920662) (xy 402.094848 -118.878282) (xy 402.142398 -118.841795)
			(xy 402.194304 -118.811828) (xy 402.249677 -118.788892) (xy 402.30757 -118.773379) (xy 402.366992 -118.765556)
			(xy 402.426928 -118.765556) (xy 402.48635 -118.773379) (xy 402.544243 -118.788892) (xy 402.599616 -118.811828)
			(xy 402.651522 -118.841795) (xy 402.699072 -118.878282) (xy 402.741452 -118.920662) (xy 402.777939 -118.968212)
			(xy 402.807906 -119.020118) (xy 402.830842 -119.075491) (xy 402.846355 -119.133384) (xy 402.854178 -119.192806)
			(xy 402.854668 -119.222774) (xy 402.854668 -119.567198) (xy 414.899348 -119.567198) (xy 414.899348 -118.703598)
			(xy 414.899838 -118.673614) (xy 414.907666 -118.614158) (xy 414.923187 -118.556233) (xy 414.946136 -118.500829)
			(xy 414.97612 -118.448895) (xy 415.012626 -118.401319) (xy 415.055031 -118.358914) (xy 415.102607 -118.322408)
			(xy 415.154541 -118.292424) (xy 415.209945 -118.269475) (xy 415.26787 -118.253954) (xy 415.327326 -118.246126)
			(xy 415.387294 -118.246126) (xy 415.44675 -118.253954) (xy 415.504675 -118.269475) (xy 415.560079 -118.292424)
			(xy 415.612013 -118.322408) (xy 415.659589 -118.358914) (xy 415.701994 -118.401319) (xy 415.7385 -118.448895)
			(xy 415.768484 -118.500829) (xy 415.791433 -118.556233) (xy 415.806954 -118.614158) (xy 415.814782 -118.673614)
			(xy 415.815272 -118.703598) (xy 415.815272 -119.559324) (xy 429.3743 -119.559324) (xy 429.3743 -118.695724)
			(xy 429.37479 -118.66574) (xy 429.382618 -118.606284) (xy 429.398139 -118.548359) (xy 429.421088 -118.492955)
			(xy 429.451072 -118.441021) (xy 429.487578 -118.393445) (xy 429.529983 -118.35104) (xy 429.577559 -118.314534)
			(xy 429.629493 -118.28455) (xy 429.684897 -118.261601) (xy 429.742822 -118.24608) (xy 429.802278 -118.238252)
			(xy 429.862246 -118.238252) (xy 429.921702 -118.24608) (xy 429.979627 -118.261601) (xy 430.035031 -118.28455)
			(xy 430.086965 -118.314534) (xy 430.134541 -118.35104) (xy 430.176946 -118.393445) (xy 430.213452 -118.441021)
			(xy 430.243436 -118.492955) (xy 430.266385 -118.548359) (xy 430.281906 -118.606284) (xy 430.289734 -118.66574)
			(xy 430.290224 -118.695724) (xy 430.290224 -119.559324) (xy 430.289734 -119.589308) (xy 430.281906 -119.648764)
			(xy 430.266385 -119.706689) (xy 430.243436 -119.762093) (xy 430.213452 -119.814027) (xy 430.176946 -119.861603)
			(xy 430.134541 -119.904008) (xy 430.086965 -119.940514) (xy 430.035031 -119.970498) (xy 429.979627 -119.993447)
			(xy 429.921702 -120.008968) (xy 429.862246 -120.016796) (xy 429.802278 -120.016796) (xy 429.742822 -120.008968)
			(xy 429.684897 -119.993447) (xy 429.629493 -119.970498) (xy 429.577559 -119.940514) (xy 429.529983 -119.904008)
			(xy 429.487578 -119.861603) (xy 429.451072 -119.814027) (xy 429.421088 -119.762093) (xy 429.398139 -119.706689)
			(xy 429.382618 -119.648764) (xy 429.37479 -119.589308) (xy 429.3743 -119.559324) (xy 415.815272 -119.559324)
			(xy 415.815272 -119.567198) (xy 415.814782 -119.597182) (xy 415.806954 -119.656638) (xy 415.791433 -119.714563)
			(xy 415.768484 -119.769967) (xy 415.7385 -119.821901) (xy 415.701994 -119.869477) (xy 415.659589 -119.911882)
			(xy 415.612013 -119.948388) (xy 415.560079 -119.978372) (xy 415.504675 -120.001321) (xy 415.44675 -120.016842)
			(xy 415.387294 -120.02467) (xy 415.327326 -120.02467) (xy 415.26787 -120.016842) (xy 415.209945 -120.001321)
			(xy 415.154541 -119.978372) (xy 415.102607 -119.948388) (xy 415.055031 -119.911882) (xy 415.012626 -119.869477)
			(xy 414.97612 -119.821901) (xy 414.946136 -119.769967) (xy 414.923187 -119.714563) (xy 414.907666 -119.656638)
			(xy 414.899838 -119.597182) (xy 414.899348 -119.567198) (xy 402.854668 -119.567198) (xy 402.854668 -120.086374)
			(xy 402.854178 -120.116342) (xy 402.846355 -120.175764) (xy 402.830842 -120.233657) (xy 402.807906 -120.28903)
			(xy 402.777939 -120.340936) (xy 402.741452 -120.388486) (xy 402.699072 -120.430866) (xy 402.651522 -120.467353)
			(xy 402.599616 -120.49732) (xy 402.544243 -120.520256) (xy 402.48635 -120.535769) (xy 402.426928 -120.543592)
			(xy 402.366992 -120.543592) (xy 402.30757 -120.535769) (xy 402.249677 -120.520256) (xy 402.194304 -120.49732)
			(xy 402.142398 -120.467353) (xy 402.094848 -120.430866) (xy 402.052468 -120.388486) (xy 402.015981 -120.340936)
			(xy 401.986014 -120.28903) (xy 401.963078 -120.233657) (xy 401.947565 -120.175764) (xy 401.939742 -120.116342)
			(xy 401.939252 -120.086374) (xy 383.883408 -120.086374) (xy 383.883408 -120.087898) (xy 383.882918 -120.117866)
			(xy 383.875095 -120.177288) (xy 383.859582 -120.235181) (xy 383.836646 -120.290554) (xy 383.806679 -120.34246)
			(xy 383.770192 -120.39001) (xy 383.727812 -120.43239) (xy 383.680262 -120.468877) (xy 383.628356 -120.498844)
			(xy 383.572983 -120.52178) (xy 383.51509 -120.537293) (xy 383.455668 -120.545116) (xy 383.395732 -120.545116)
			(xy 383.33631 -120.537293) (xy 383.278417 -120.52178) (xy 383.223044 -120.498844) (xy 383.171138 -120.468877)
			(xy 383.123588 -120.43239) (xy 383.081208 -120.39001) (xy 383.044721 -120.34246) (xy 383.014754 -120.290554)
			(xy 382.991818 -120.235181) (xy 382.976305 -120.177288) (xy 382.968482 -120.117866) (xy 382.967992 -120.087898)
			(xy 316.568893 -120.087898) (xy 316.576928 -120.091226) (xy 316.628834 -120.121193) (xy 316.676384 -120.15768)
			(xy 316.718764 -120.20006) (xy 316.755251 -120.24761) (xy 316.785218 -120.299516) (xy 316.808154 -120.354889)
			(xy 316.823667 -120.412782) (xy 316.83149 -120.472204) (xy 316.83198 -120.502172) (xy 316.83198 -121.365772)
			(xy 316.83149 -121.39574) (xy 316.823667 -121.455162) (xy 316.808154 -121.513055) (xy 316.785218 -121.568428)
			(xy 316.755251 -121.620334) (xy 316.718764 -121.667884) (xy 316.676384 -121.710264) (xy 316.628834 -121.746751)
			(xy 316.576928 -121.776718) (xy 316.521555 -121.799654) (xy 316.463662 -121.815167) (xy 316.40424 -121.82299)
			(xy 316.344304 -121.82299) (xy 316.284882 -121.815167) (xy 316.226989 -121.799654) (xy 316.171616 -121.776718)
			(xy 316.11971 -121.746751) (xy 316.07216 -121.710264) (xy 316.02978 -121.667884) (xy 315.993293 -121.620334)
			(xy 315.963326 -121.568428) (xy 315.94039 -121.513055) (xy 315.924877 -121.455162) (xy 315.917054 -121.39574)
			(xy 315.916564 -121.365772) (xy 297.86072 -121.365772) (xy 297.86072 -121.367296) (xy 297.86023 -121.397264)
			(xy 297.852407 -121.456686) (xy 297.836894 -121.514579) (xy 297.813958 -121.569952) (xy 297.783991 -121.621858)
			(xy 297.747504 -121.669408) (xy 297.705124 -121.711788) (xy 297.657574 -121.748275) (xy 297.605668 -121.778242)
			(xy 297.550295 -121.801178) (xy 297.492402 -121.816691) (xy 297.43298 -121.824514) (xy 297.373044 -121.824514)
			(xy 297.313622 -121.816691) (xy 297.255729 -121.801178) (xy 297.200356 -121.778242) (xy 297.14845 -121.748275)
			(xy 297.1009 -121.711788) (xy 297.05852 -121.669408) (xy 297.022033 -121.621858) (xy 296.992066 -121.569952)
			(xy 296.96913 -121.514579) (xy 296.953617 -121.456686) (xy 296.945794 -121.397264) (xy 296.945304 -121.367296)
			(xy 284.900624 -121.367296) (xy 284.900624 -121.886472) (xy 284.900134 -121.916456) (xy 284.892306 -121.975912)
			(xy 284.876785 -122.033837) (xy 284.853836 -122.089241) (xy 284.823852 -122.141175) (xy 284.787346 -122.188751)
			(xy 284.744941 -122.231156) (xy 284.697365 -122.267662) (xy 284.645431 -122.297646) (xy 284.590027 -122.320595)
			(xy 284.532102 -122.336116) (xy 284.472646 -122.343944) (xy 284.412678 -122.343944) (xy 284.353222 -122.336116)
			(xy 284.295297 -122.320595) (xy 284.239893 -122.297646) (xy 284.187959 -122.267662) (xy 284.140383 -122.231156)
			(xy 284.097978 -122.188751) (xy 284.061472 -122.141175) (xy 284.031488 -122.089241) (xy 284.008539 -122.033837)
			(xy 283.993018 -121.975912) (xy 283.98519 -121.916456) (xy 283.9847 -121.886472) (xy 270.425672 -121.886472)
			(xy 270.425672 -121.894346) (xy 270.425182 -121.92433) (xy 270.417354 -121.983786) (xy 270.401833 -122.041711)
			(xy 270.378884 -122.097115) (xy 270.3489 -122.149049) (xy 270.312394 -122.196625) (xy 270.269989 -122.23903)
			(xy 270.222413 -122.275536) (xy 270.170479 -122.30552) (xy 270.115075 -122.328469) (xy 270.05715 -122.34399)
			(xy 269.997694 -122.351818) (xy 269.937726 -122.351818) (xy 269.87827 -122.34399) (xy 269.820345 -122.328469)
			(xy 269.764941 -122.30552) (xy 269.713007 -122.275536) (xy 269.665431 -122.23903) (xy 269.623026 -122.196625)
			(xy 269.58652 -122.149049) (xy 269.556536 -122.097115) (xy 269.533587 -122.041711) (xy 269.518066 -121.983786)
			(xy 269.510238 -121.92433) (xy 269.509748 -121.894346) (xy 197.851649 -121.894346) (xy 197.886882 -121.914687)
			(xy 197.934432 -121.951174) (xy 197.976812 -121.993554) (xy 198.013299 -122.041104) (xy 198.043266 -122.09301)
			(xy 198.066202 -122.148383) (xy 198.081715 -122.206276) (xy 198.089538 -122.265698) (xy 198.090028 -122.295666)
			(xy 198.090028 -123.159266) (xy 198.089538 -123.189234) (xy 198.081715 -123.248656) (xy 198.066202 -123.306549)
			(xy 198.043266 -123.361922) (xy 198.013299 -123.413828) (xy 197.976812 -123.461378) (xy 197.934432 -123.503758)
			(xy 197.886882 -123.540245) (xy 197.834976 -123.570212) (xy 197.779603 -123.593148) (xy 197.72171 -123.608661)
			(xy 197.662288 -123.616484) (xy 197.602352 -123.616484) (xy 197.54293 -123.608661) (xy 197.485037 -123.593148)
			(xy 197.429664 -123.570212) (xy 197.377758 -123.540245) (xy 197.330208 -123.503758) (xy 197.287828 -123.461378)
			(xy 197.251341 -123.413828) (xy 197.221374 -123.361922) (xy 197.198438 -123.306549) (xy 197.182925 -123.248656)
			(xy 197.175102 -123.189234) (xy 197.174612 -123.159266) (xy 183.615076 -123.159266) (xy 183.615076 -123.16714)
			(xy 183.614586 -123.197108) (xy 183.606763 -123.25653) (xy 183.59125 -123.314423) (xy 183.568314 -123.369796)
			(xy 183.538347 -123.421702) (xy 183.50186 -123.469252) (xy 183.45948 -123.511632) (xy 183.41193 -123.548119)
			(xy 183.360024 -123.578086) (xy 183.304651 -123.601022) (xy 183.246758 -123.616535) (xy 183.187336 -123.624358)
			(xy 183.1274 -123.624358) (xy 183.067978 -123.616535) (xy 183.010085 -123.601022) (xy 182.954712 -123.578086)
			(xy 182.902806 -123.548119) (xy 182.855256 -123.511632) (xy 182.812876 -123.469252) (xy 182.776389 -123.421702)
			(xy 182.746422 -123.369796) (xy 182.723486 -123.314423) (xy 182.707973 -123.25653) (xy 182.70015 -123.197108)
			(xy 182.69966 -123.16714) (xy 170.65498 -123.16714) (xy 170.65498 -123.686316) (xy 170.65449 -123.7163)
			(xy 170.646662 -123.775756) (xy 170.631141 -123.833681) (xy 170.608192 -123.889085) (xy 170.578208 -123.941019)
			(xy 170.541702 -123.988595) (xy 170.499297 -124.031) (xy 170.451721 -124.067506) (xy 170.399787 -124.09749)
			(xy 170.344383 -124.120439) (xy 170.286458 -124.13596) (xy 170.227002 -124.143788) (xy 170.167034 -124.143788)
			(xy 170.107578 -124.13596) (xy 170.049653 -124.120439) (xy 169.994249 -124.09749) (xy 169.942315 -124.067506)
			(xy 169.894739 -124.031) (xy 169.852334 -123.988595) (xy 169.815828 -123.941019) (xy 169.785844 -123.889085)
			(xy 169.762895 -123.833681) (xy 169.747374 -123.775756) (xy 169.739546 -123.7163) (xy 169.739056 -123.686316)
			(xy 151.68372 -123.686316) (xy 151.68372 -123.68784) (xy 151.68323 -123.717824) (xy 151.675402 -123.77728)
			(xy 151.659881 -123.835205) (xy 151.636932 -123.890609) (xy 151.606948 -123.942543) (xy 151.570442 -123.990119)
			(xy 151.528037 -124.032524) (xy 151.480461 -124.06903) (xy 151.428527 -124.099014) (xy 151.373123 -124.121963)
			(xy 151.315198 -124.137484) (xy 151.255742 -124.145312) (xy 151.195774 -124.145312) (xy 151.136318 -124.137484)
			(xy 151.078393 -124.121963) (xy 151.022989 -124.099014) (xy 150.971055 -124.06903) (xy 150.923479 -124.032524)
			(xy 150.881074 -123.990119) (xy 150.844568 -123.942543) (xy 150.814584 -123.890609) (xy 150.791635 -123.835205)
			(xy 150.776114 -123.77728) (xy 150.768286 -123.717824) (xy 150.767796 -123.68784) (xy 84.369615 -123.68784)
			(xy 84.377099 -123.69094) (xy 84.429033 -123.720924) (xy 84.476609 -123.75743) (xy 84.519014 -123.799835)
			(xy 84.55552 -123.847411) (xy 84.585504 -123.899345) (xy 84.608453 -123.954749) (xy 84.623974 -124.012674)
			(xy 84.631802 -124.07213) (xy 84.632292 -124.102114) (xy 84.632292 -124.965714) (xy 84.631802 -124.995698)
			(xy 84.623974 -125.055154) (xy 84.608453 -125.113079) (xy 84.585504 -125.168483) (xy 84.55552 -125.220417)
			(xy 84.519014 -125.267993) (xy 84.476609 -125.310398) (xy 84.429033 -125.346904) (xy 84.377099 -125.376888)
			(xy 84.321695 -125.399837) (xy 84.26377 -125.415358) (xy 84.204314 -125.423186) (xy 84.144346 -125.423186)
			(xy 84.08489 -125.415358) (xy 84.026965 -125.399837) (xy 83.971561 -125.376888) (xy 83.919627 -125.346904)
			(xy 83.872051 -125.310398) (xy 83.829646 -125.267993) (xy 83.79314 -125.220417) (xy 83.763156 -125.168483)
			(xy 83.740207 -125.113079) (xy 83.724686 -125.055154) (xy 83.716858 -124.995698) (xy 83.716368 -124.965714)
			(xy 65.661032 -124.965714) (xy 65.661032 -124.967238) (xy 65.660542 -124.997222) (xy 65.652714 -125.056678)
			(xy 65.637193 -125.114603) (xy 65.614244 -125.170007) (xy 65.58426 -125.221941) (xy 65.547754 -125.269517)
			(xy 65.505349 -125.311922) (xy 65.457773 -125.348428) (xy 65.405839 -125.378412) (xy 65.350435 -125.401361)
			(xy 65.29251 -125.416882) (xy 65.233054 -125.42471) (xy 65.173086 -125.42471) (xy 65.11363 -125.416882)
			(xy 65.055705 -125.401361) (xy 65.000301 -125.378412) (xy 64.948367 -125.348428) (xy 64.900791 -125.311922)
			(xy 64.858386 -125.269517) (xy 64.82188 -125.221941) (xy 64.791896 -125.170007) (xy 64.768947 -125.114603)
			(xy 64.753426 -125.056678) (xy 64.745598 -124.997222) (xy 64.745108 -124.967238) (xy 52.700428 -124.967238)
			(xy 52.700428 -125.486414) (xy 52.700295 -125.494542) (xy 153.409904 -125.494542) (xy 153.409904 -124.630942)
			(xy 153.410394 -124.600958) (xy 153.418222 -124.541502) (xy 153.433743 -124.483577) (xy 153.456692 -124.428173)
			(xy 153.486676 -124.376239) (xy 153.523182 -124.328663) (xy 153.565587 -124.286258) (xy 153.613163 -124.249752)
			(xy 153.665097 -124.219768) (xy 153.720501 -124.196819) (xy 153.778426 -124.181298) (xy 153.837882 -124.17347)
			(xy 153.89785 -124.17347) (xy 153.957306 -124.181298) (xy 154.015231 -124.196819) (xy 154.070635 -124.219768)
			(xy 154.122569 -124.249752) (xy 154.170145 -124.286258) (xy 154.21255 -124.328663) (xy 154.249056 -124.376239)
			(xy 154.27904 -124.428173) (xy 154.301989 -124.483577) (xy 154.31751 -124.541502) (xy 154.325338 -124.600958)
			(xy 154.325828 -124.630942) (xy 154.325828 -125.486414) (xy 167.884856 -125.486414) (xy 167.884856 -124.622814)
			(xy 167.885346 -124.59283) (xy 167.893174 -124.533374) (xy 167.908695 -124.475449) (xy 167.931644 -124.420045)
			(xy 167.961628 -124.368111) (xy 167.998134 -124.320535) (xy 168.040539 -124.27813) (xy 168.088115 -124.241624)
			(xy 168.140049 -124.21164) (xy 168.195453 -124.188691) (xy 168.253378 -124.17317) (xy 168.312834 -124.165342)
			(xy 168.372802 -124.165342) (xy 168.432258 -124.17317) (xy 168.490183 -124.188691) (xy 168.545587 -124.21164)
			(xy 168.597521 -124.241624) (xy 168.645097 -124.27813) (xy 168.687502 -124.320535) (xy 168.724008 -124.368111)
			(xy 168.753992 -124.420045) (xy 168.776941 -124.475449) (xy 168.792462 -124.533374) (xy 168.80029 -124.59283)
			(xy 168.80078 -124.622814) (xy 168.80078 -124.967238) (xy 180.84546 -124.967238) (xy 180.84546 -124.103638)
			(xy 180.84595 -124.07367) (xy 180.853773 -124.014248) (xy 180.869286 -123.956355) (xy 180.892222 -123.900982)
			(xy 180.922189 -123.849076) (xy 180.958676 -123.801526) (xy 181.001056 -123.759146) (xy 181.048606 -123.722659)
			(xy 181.100512 -123.692692) (xy 181.155885 -123.669756) (xy 181.213778 -123.654243) (xy 181.2732 -123.64642)
			(xy 181.333136 -123.64642) (xy 181.392558 -123.654243) (xy 181.450451 -123.669756) (xy 181.505824 -123.692692)
			(xy 181.55773 -123.722659) (xy 181.60528 -123.759146) (xy 181.64766 -123.801526) (xy 181.684147 -123.849076)
			(xy 181.714114 -123.900982) (xy 181.73705 -123.956355) (xy 181.752563 -124.014248) (xy 181.760386 -124.07367)
			(xy 181.760876 -124.103638) (xy 181.760876 -124.965714) (xy 199.81672 -124.965714) (xy 199.81672 -124.102114)
			(xy 199.81721 -124.072146) (xy 199.825033 -124.012724) (xy 199.840546 -123.954831) (xy 199.863482 -123.899458)
			(xy 199.893449 -123.847552) (xy 199.929936 -123.800002) (xy 199.972316 -123.757622) (xy 200.019866 -123.721135)
			(xy 200.071772 -123.691168) (xy 200.127145 -123.668232) (xy 200.185038 -123.652719) (xy 200.24446 -123.644896)
			(xy 200.304396 -123.644896) (xy 200.363818 -123.652719) (xy 200.421711 -123.668232) (xy 200.469049 -123.68784)
			(xy 266.86764 -123.68784) (xy 266.86764 -122.82424) (xy 266.86813 -122.794256) (xy 266.875958 -122.7348)
			(xy 266.891479 -122.676875) (xy 266.914428 -122.621471) (xy 266.944412 -122.569537) (xy 266.980918 -122.521961)
			(xy 267.023323 -122.479556) (xy 267.070899 -122.44305) (xy 267.122833 -122.413066) (xy 267.178237 -122.390117)
			(xy 267.236162 -122.374596) (xy 267.295618 -122.366768) (xy 267.355586 -122.366768) (xy 267.415042 -122.374596)
			(xy 267.472967 -122.390117) (xy 267.528371 -122.413066) (xy 267.580305 -122.44305) (xy 267.627881 -122.479556)
			(xy 267.670286 -122.521961) (xy 267.706792 -122.569537) (xy 267.736776 -122.621471) (xy 267.759725 -122.676875)
			(xy 267.775246 -122.7348) (xy 267.783074 -122.794256) (xy 267.783564 -122.82424) (xy 267.783564 -123.686316)
			(xy 285.8389 -123.686316) (xy 285.8389 -122.822716) (xy 285.83939 -122.792732) (xy 285.847218 -122.733276)
			(xy 285.862739 -122.675351) (xy 285.885688 -122.619947) (xy 285.915672 -122.568013) (xy 285.952178 -122.520437)
			(xy 285.994583 -122.478032) (xy 286.042159 -122.441526) (xy 286.094093 -122.411542) (xy 286.149497 -122.388593)
			(xy 286.207422 -122.373072) (xy 286.266878 -122.365244) (xy 286.326846 -122.365244) (xy 286.386302 -122.373072)
			(xy 286.444227 -122.388593) (xy 286.499631 -122.411542) (xy 286.551565 -122.441526) (xy 286.599141 -122.478032)
			(xy 286.641546 -122.520437) (xy 286.678052 -122.568013) (xy 286.708036 -122.619947) (xy 286.730985 -122.675351)
			(xy 286.746506 -122.733276) (xy 286.754334 -122.792732) (xy 286.754824 -122.822716) (xy 286.754824 -123.16714)
			(xy 298.799504 -123.16714) (xy 298.799504 -122.30354) (xy 298.799994 -122.273572) (xy 298.807817 -122.21415)
			(xy 298.82333 -122.156257) (xy 298.846266 -122.100884) (xy 298.876233 -122.048978) (xy 298.91272 -122.001428)
			(xy 298.9551 -121.959048) (xy 299.00265 -121.922561) (xy 299.054556 -121.892594) (xy 299.109929 -121.869658)
			(xy 299.167822 -121.854145) (xy 299.227244 -121.846322) (xy 299.28718 -121.846322) (xy 299.346602 -121.854145)
			(xy 299.404495 -121.869658) (xy 299.459868 -121.892594) (xy 299.511774 -121.922561) (xy 299.559324 -121.959048)
			(xy 299.601704 -122.001428) (xy 299.638191 -122.048978) (xy 299.668158 -122.100884) (xy 299.691094 -122.156257)
			(xy 299.706607 -122.21415) (xy 299.71443 -122.273572) (xy 299.71492 -122.30354) (xy 299.71492 -123.159266)
			(xy 313.274456 -123.159266) (xy 313.274456 -122.295666) (xy 313.274946 -122.265698) (xy 313.282769 -122.206276)
			(xy 313.298282 -122.148383) (xy 313.321218 -122.09301) (xy 313.351185 -122.041104) (xy 313.387672 -121.993554)
			(xy 313.430052 -121.951174) (xy 313.477602 -121.914687) (xy 313.529508 -121.88472) (xy 313.584881 -121.861784)
			(xy 313.642774 -121.846271) (xy 313.702196 -121.838448) (xy 313.762132 -121.838448) (xy 313.821554 -121.846271)
			(xy 313.879447 -121.861784) (xy 313.93482 -121.88472) (xy 313.951493 -121.894346) (xy 385.6101 -121.894346)
			(xy 385.6101 -121.030746) (xy 385.61059 -121.000778) (xy 385.618413 -120.941356) (xy 385.633926 -120.883463)
			(xy 385.656862 -120.82809) (xy 385.686829 -120.776184) (xy 385.723316 -120.728634) (xy 385.765696 -120.686254)
			(xy 385.813246 -120.649767) (xy 385.865152 -120.6198) (xy 385.920525 -120.596864) (xy 385.978418 -120.581351)
			(xy 386.03784 -120.573528) (xy 386.097776 -120.573528) (xy 386.157198 -120.581351) (xy 386.215091 -120.596864)
			(xy 386.270464 -120.6198) (xy 386.32237 -120.649767) (xy 386.36992 -120.686254) (xy 386.4123 -120.728634)
			(xy 386.448787 -120.776184) (xy 386.478754 -120.82809) (xy 386.50169 -120.883463) (xy 386.517203 -120.941356)
			(xy 386.525026 -121.000778) (xy 386.525516 -121.030746) (xy 386.525516 -121.886472) (xy 400.085052 -121.886472)
			(xy 400.085052 -121.022872) (xy 400.085542 -120.992904) (xy 400.093365 -120.933482) (xy 400.108878 -120.875589)
			(xy 400.131814 -120.820216) (xy 400.161781 -120.76831) (xy 400.198268 -120.72076) (xy 400.240648 -120.67838)
			(xy 400.288198 -120.641893) (xy 400.340104 -120.611926) (xy 400.395477 -120.58899) (xy 400.45337 -120.573477)
			(xy 400.512792 -120.565654) (xy 400.572728 -120.565654) (xy 400.63215 -120.573477) (xy 400.690043 -120.58899)
			(xy 400.745416 -120.611926) (xy 400.797322 -120.641893) (xy 400.844872 -120.67838) (xy 400.887252 -120.72076)
			(xy 400.923739 -120.76831) (xy 400.953706 -120.820216) (xy 400.976642 -120.875589) (xy 400.992155 -120.933482)
			(xy 400.999978 -120.992904) (xy 401.000468 -121.022872) (xy 401.000468 -121.367296) (xy 413.045148 -121.367296)
			(xy 413.045148 -120.503696) (xy 413.045638 -120.473712) (xy 413.053466 -120.414256) (xy 413.068987 -120.356331)
			(xy 413.091936 -120.300927) (xy 413.12192 -120.248993) (xy 413.158426 -120.201417) (xy 413.200831 -120.159012)
			(xy 413.248407 -120.122506) (xy 413.300341 -120.092522) (xy 413.355745 -120.069573) (xy 413.41367 -120.054052)
			(xy 413.473126 -120.046224) (xy 413.533094 -120.046224) (xy 413.59255 -120.054052) (xy 413.650475 -120.069573)
			(xy 413.705879 -120.092522) (xy 413.757813 -120.122506) (xy 413.805389 -120.159012) (xy 413.847794 -120.201417)
			(xy 413.8843 -120.248993) (xy 413.914284 -120.300927) (xy 413.937233 -120.356331) (xy 413.952754 -120.414256)
			(xy 413.960582 -120.473712) (xy 413.961072 -120.503696) (xy 413.961072 -121.365772) (xy 432.016408 -121.365772)
			(xy 432.016408 -120.502172) (xy 432.016898 -120.472188) (xy 432.024726 -120.412732) (xy 432.040247 -120.354807)
			(xy 432.063196 -120.299403) (xy 432.09318 -120.247469) (xy 432.129686 -120.199893) (xy 432.172091 -120.157488)
			(xy 432.219667 -120.120982) (xy 432.271601 -120.090998) (xy 432.327005 -120.068049) (xy 432.38493 -120.052528)
			(xy 432.444386 -120.0447) (xy 432.504354 -120.0447) (xy 432.56381 -120.052528) (xy 432.621735 -120.068049)
			(xy 432.677139 -120.090998) (xy 432.729073 -120.120982) (xy 432.776649 -120.157488) (xy 432.819054 -120.199893)
			(xy 432.85556 -120.247469) (xy 432.885544 -120.299403) (xy 432.908493 -120.354807) (xy 432.924014 -120.412732)
			(xy 432.931842 -120.472188) (xy 432.932332 -120.502172) (xy 432.932332 -121.365772) (xy 432.931842 -121.395756)
			(xy 432.924014 -121.455212) (xy 432.908493 -121.513137) (xy 432.885544 -121.568541) (xy 432.85556 -121.620475)
			(xy 432.819054 -121.668051) (xy 432.776649 -121.710456) (xy 432.729073 -121.746962) (xy 432.677139 -121.776946)
			(xy 432.621735 -121.799895) (xy 432.56381 -121.815416) (xy 432.504354 -121.823244) (xy 432.444386 -121.823244)
			(xy 432.38493 -121.815416) (xy 432.327005 -121.799895) (xy 432.271601 -121.776946) (xy 432.219667 -121.746962)
			(xy 432.172091 -121.710456) (xy 432.129686 -121.668051) (xy 432.09318 -121.620475) (xy 432.063196 -121.568541)
			(xy 432.040247 -121.513137) (xy 432.024726 -121.455212) (xy 432.016898 -121.395756) (xy 432.016408 -121.365772)
			(xy 413.961072 -121.365772) (xy 413.961072 -121.367296) (xy 413.960582 -121.39728) (xy 413.952754 -121.456736)
			(xy 413.937233 -121.514661) (xy 413.914284 -121.570065) (xy 413.8843 -121.621999) (xy 413.847794 -121.669575)
			(xy 413.805389 -121.71198) (xy 413.757813 -121.748486) (xy 413.705879 -121.77847) (xy 413.650475 -121.801419)
			(xy 413.59255 -121.81694) (xy 413.533094 -121.824768) (xy 413.473126 -121.824768) (xy 413.41367 -121.81694)
			(xy 413.355745 -121.801419) (xy 413.300341 -121.77847) (xy 413.248407 -121.748486) (xy 413.200831 -121.71198)
			(xy 413.158426 -121.669575) (xy 413.12192 -121.621999) (xy 413.091936 -121.570065) (xy 413.068987 -121.514661)
			(xy 413.053466 -121.456736) (xy 413.045638 -121.39728) (xy 413.045148 -121.367296) (xy 401.000468 -121.367296)
			(xy 401.000468 -121.886472) (xy 400.999978 -121.91644) (xy 400.992155 -121.975862) (xy 400.976642 -122.033755)
			(xy 400.953706 -122.089128) (xy 400.923739 -122.141034) (xy 400.887252 -122.188584) (xy 400.844872 -122.230964)
			(xy 400.797322 -122.267451) (xy 400.745416 -122.297418) (xy 400.690043 -122.320354) (xy 400.63215 -122.335867)
			(xy 400.572728 -122.34369) (xy 400.512792 -122.34369) (xy 400.45337 -122.335867) (xy 400.395477 -122.320354)
			(xy 400.340104 -122.297418) (xy 400.288198 -122.267451) (xy 400.240648 -122.230964) (xy 400.198268 -122.188584)
			(xy 400.161781 -122.141034) (xy 400.131814 -122.089128) (xy 400.108878 -122.033755) (xy 400.093365 -121.975862)
			(xy 400.085542 -121.91644) (xy 400.085052 -121.886472) (xy 386.525516 -121.886472) (xy 386.525516 -121.894346)
			(xy 386.525026 -121.924314) (xy 386.517203 -121.983736) (xy 386.50169 -122.041629) (xy 386.478754 -122.097002)
			(xy 386.448787 -122.148908) (xy 386.4123 -122.196458) (xy 386.36992 -122.238838) (xy 386.32237 -122.275325)
			(xy 386.270464 -122.305292) (xy 386.215091 -122.328228) (xy 386.157198 -122.343741) (xy 386.097776 -122.351564)
			(xy 386.03784 -122.351564) (xy 385.978418 -122.343741) (xy 385.920525 -122.328228) (xy 385.865152 -122.305292)
			(xy 385.813246 -122.275325) (xy 385.765696 -122.238838) (xy 385.723316 -122.196458) (xy 385.686829 -122.148908)
			(xy 385.656862 -122.097002) (xy 385.633926 -122.041629) (xy 385.618413 -121.983736) (xy 385.61059 -121.924314)
			(xy 385.6101 -121.894346) (xy 313.951493 -121.894346) (xy 313.986726 -121.914687) (xy 314.034276 -121.951174)
			(xy 314.076656 -121.993554) (xy 314.113143 -122.041104) (xy 314.14311 -122.09301) (xy 314.166046 -122.148383)
			(xy 314.181559 -122.206276) (xy 314.189382 -122.265698) (xy 314.189872 -122.295666) (xy 314.189872 -123.159266)
			(xy 314.189382 -123.189234) (xy 314.181559 -123.248656) (xy 314.166046 -123.306549) (xy 314.14311 -123.361922)
			(xy 314.113143 -123.413828) (xy 314.076656 -123.461378) (xy 314.034276 -123.503758) (xy 313.986726 -123.540245)
			(xy 313.93482 -123.570212) (xy 313.879447 -123.593148) (xy 313.821554 -123.608661) (xy 313.762132 -123.616484)
			(xy 313.702196 -123.616484) (xy 313.642774 -123.608661) (xy 313.584881 -123.593148) (xy 313.529508 -123.570212)
			(xy 313.477602 -123.540245) (xy 313.430052 -123.503758) (xy 313.387672 -123.461378) (xy 313.351185 -123.413828)
			(xy 313.321218 -123.361922) (xy 313.298282 -123.306549) (xy 313.282769 -123.248656) (xy 313.274946 -123.189234)
			(xy 313.274456 -123.159266) (xy 299.71492 -123.159266) (xy 299.71492 -123.16714) (xy 299.71443 -123.197108)
			(xy 299.706607 -123.25653) (xy 299.691094 -123.314423) (xy 299.668158 -123.369796) (xy 299.638191 -123.421702)
			(xy 299.601704 -123.469252) (xy 299.559324 -123.511632) (xy 299.511774 -123.548119) (xy 299.459868 -123.578086)
			(xy 299.404495 -123.601022) (xy 299.346602 -123.616535) (xy 299.28718 -123.624358) (xy 299.227244 -123.624358)
			(xy 299.167822 -123.616535) (xy 299.109929 -123.601022) (xy 299.054556 -123.578086) (xy 299.00265 -123.548119)
			(xy 298.9551 -123.511632) (xy 298.91272 -123.469252) (xy 298.876233 -123.421702) (xy 298.846266 -123.369796)
			(xy 298.82333 -123.314423) (xy 298.807817 -123.25653) (xy 298.799994 -123.197108) (xy 298.799504 -123.16714)
			(xy 286.754824 -123.16714) (xy 286.754824 -123.686316) (xy 286.754334 -123.7163) (xy 286.746506 -123.775756)
			(xy 286.730985 -123.833681) (xy 286.708036 -123.889085) (xy 286.678052 -123.941019) (xy 286.641546 -123.988595)
			(xy 286.599141 -124.031) (xy 286.551565 -124.067506) (xy 286.499631 -124.09749) (xy 286.444227 -124.120439)
			(xy 286.386302 -124.13596) (xy 286.326846 -124.143788) (xy 286.266878 -124.143788) (xy 286.207422 -124.13596)
			(xy 286.149497 -124.120439) (xy 286.094093 -124.09749) (xy 286.042159 -124.067506) (xy 285.994583 -124.031)
			(xy 285.952178 -123.988595) (xy 285.915672 -123.941019) (xy 285.885688 -123.889085) (xy 285.862739 -123.833681)
			(xy 285.847218 -123.775756) (xy 285.83939 -123.7163) (xy 285.8389 -123.686316) (xy 267.783564 -123.686316)
			(xy 267.783564 -123.68784) (xy 267.783074 -123.717824) (xy 267.775246 -123.77728) (xy 267.759725 -123.835205)
			(xy 267.736776 -123.890609) (xy 267.706792 -123.942543) (xy 267.670286 -123.990119) (xy 267.627881 -124.032524)
			(xy 267.580305 -124.06903) (xy 267.528371 -124.099014) (xy 267.472967 -124.121963) (xy 267.415042 -124.137484)
			(xy 267.355586 -124.145312) (xy 267.295618 -124.145312) (xy 267.236162 -124.137484) (xy 267.178237 -124.121963)
			(xy 267.122833 -124.099014) (xy 267.070899 -124.06903) (xy 267.023323 -124.032524) (xy 266.980918 -123.990119)
			(xy 266.944412 -123.942543) (xy 266.914428 -123.890609) (xy 266.891479 -123.835205) (xy 266.875958 -123.77728)
			(xy 266.86813 -123.717824) (xy 266.86764 -123.68784) (xy 200.469049 -123.68784) (xy 200.477084 -123.691168)
			(xy 200.52899 -123.721135) (xy 200.57654 -123.757622) (xy 200.61892 -123.800002) (xy 200.655407 -123.847552)
			(xy 200.685374 -123.899458) (xy 200.70831 -123.954831) (xy 200.723823 -124.012724) (xy 200.731646 -124.072146)
			(xy 200.732136 -124.102114) (xy 200.732136 -124.965714) (xy 200.731646 -124.995682) (xy 200.723823 -125.055104)
			(xy 200.70831 -125.112997) (xy 200.685374 -125.16837) (xy 200.655407 -125.220276) (xy 200.61892 -125.267826)
			(xy 200.57654 -125.310206) (xy 200.52899 -125.346693) (xy 200.477084 -125.37666) (xy 200.421711 -125.399596)
			(xy 200.363818 -125.415109) (xy 200.304396 -125.422932) (xy 200.24446 -125.422932) (xy 200.185038 -125.415109)
			(xy 200.127145 -125.399596) (xy 200.071772 -125.37666) (xy 200.019866 -125.346693) (xy 199.972316 -125.310206)
			(xy 199.929936 -125.267826) (xy 199.893449 -125.220276) (xy 199.863482 -125.16837) (xy 199.840546 -125.112997)
			(xy 199.825033 -125.055104) (xy 199.81721 -124.995682) (xy 199.81672 -124.965714) (xy 181.760876 -124.965714)
			(xy 181.760876 -124.967238) (xy 181.760386 -124.997206) (xy 181.752563 -125.056628) (xy 181.73705 -125.114521)
			(xy 181.714114 -125.169894) (xy 181.684147 -125.2218) (xy 181.64766 -125.26935) (xy 181.60528 -125.31173)
			(xy 181.55773 -125.348217) (xy 181.505824 -125.378184) (xy 181.450451 -125.40112) (xy 181.392558 -125.416633)
			(xy 181.333136 -125.424456) (xy 181.2732 -125.424456) (xy 181.213778 -125.416633) (xy 181.155885 -125.40112)
			(xy 181.100512 -125.378184) (xy 181.048606 -125.348217) (xy 181.001056 -125.31173) (xy 180.958676 -125.26935)
			(xy 180.922189 -125.2218) (xy 180.892222 -125.169894) (xy 180.869286 -125.114521) (xy 180.853773 -125.056628)
			(xy 180.84595 -124.997206) (xy 180.84546 -124.967238) (xy 168.80078 -124.967238) (xy 168.80078 -125.486414)
			(xy 168.800647 -125.494542) (xy 269.509748 -125.494542) (xy 269.509748 -124.630942) (xy 269.510238 -124.600958)
			(xy 269.518066 -124.541502) (xy 269.533587 -124.483577) (xy 269.556536 -124.428173) (xy 269.58652 -124.376239)
			(xy 269.623026 -124.328663) (xy 269.665431 -124.286258) (xy 269.713007 -124.249752) (xy 269.764941 -124.219768)
			(xy 269.820345 -124.196819) (xy 269.87827 -124.181298) (xy 269.937726 -124.17347) (xy 269.997694 -124.17347)
			(xy 270.05715 -124.181298) (xy 270.115075 -124.196819) (xy 270.170479 -124.219768) (xy 270.222413 -124.249752)
			(xy 270.269989 -124.286258) (xy 270.312394 -124.328663) (xy 270.3489 -124.376239) (xy 270.378884 -124.428173)
			(xy 270.401833 -124.483577) (xy 270.417354 -124.541502) (xy 270.425182 -124.600958) (xy 270.425672 -124.630942)
			(xy 270.425672 -125.486414) (xy 283.9847 -125.486414) (xy 283.9847 -124.622814) (xy 283.98519 -124.59283)
			(xy 283.993018 -124.533374) (xy 284.008539 -124.475449) (xy 284.031488 -124.420045) (xy 284.061472 -124.368111)
			(xy 284.097978 -124.320535) (xy 284.140383 -124.27813) (xy 284.187959 -124.241624) (xy 284.239893 -124.21164)
			(xy 284.295297 -124.188691) (xy 284.353222 -124.17317) (xy 284.412678 -124.165342) (xy 284.472646 -124.165342)
			(xy 284.532102 -124.17317) (xy 284.590027 -124.188691) (xy 284.645431 -124.21164) (xy 284.697365 -124.241624)
			(xy 284.744941 -124.27813) (xy 284.787346 -124.320535) (xy 284.823852 -124.368111) (xy 284.853836 -124.420045)
			(xy 284.876785 -124.475449) (xy 284.892306 -124.533374) (xy 284.900134 -124.59283) (xy 284.900624 -124.622814)
			(xy 284.900624 -124.967238) (xy 296.945304 -124.967238) (xy 296.945304 -124.103638) (xy 296.945794 -124.07367)
			(xy 296.953617 -124.014248) (xy 296.96913 -123.956355) (xy 296.992066 -123.900982) (xy 297.022033 -123.849076)
			(xy 297.05852 -123.801526) (xy 297.1009 -123.759146) (xy 297.14845 -123.722659) (xy 297.200356 -123.692692)
			(xy 297.255729 -123.669756) (xy 297.313622 -123.654243) (xy 297.373044 -123.64642) (xy 297.43298 -123.64642)
			(xy 297.492402 -123.654243) (xy 297.550295 -123.669756) (xy 297.605668 -123.692692) (xy 297.657574 -123.722659)
			(xy 297.705124 -123.759146) (xy 297.747504 -123.801526) (xy 297.783991 -123.849076) (xy 297.813958 -123.900982)
			(xy 297.836894 -123.956355) (xy 297.852407 -124.014248) (xy 297.86023 -124.07367) (xy 297.86072 -124.103638)
			(xy 297.86072 -124.965714) (xy 315.916564 -124.965714) (xy 315.916564 -124.102114) (xy 315.917054 -124.072146)
			(xy 315.924877 -124.012724) (xy 315.94039 -123.954831) (xy 315.963326 -123.899458) (xy 315.993293 -123.847552)
			(xy 316.02978 -123.800002) (xy 316.07216 -123.757622) (xy 316.11971 -123.721135) (xy 316.171616 -123.691168)
			(xy 316.226989 -123.668232) (xy 316.284882 -123.652719) (xy 316.344304 -123.644896) (xy 316.40424 -123.644896)
			(xy 316.463662 -123.652719) (xy 316.521555 -123.668232) (xy 316.568893 -123.68784) (xy 382.967992 -123.68784)
			(xy 382.967992 -122.82424) (xy 382.968482 -122.794272) (xy 382.976305 -122.73485) (xy 382.991818 -122.676957)
			(xy 383.014754 -122.621584) (xy 383.044721 -122.569678) (xy 383.081208 -122.522128) (xy 383.123588 -122.479748)
			(xy 383.171138 -122.443261) (xy 383.223044 -122.413294) (xy 383.278417 -122.390358) (xy 383.33631 -122.374845)
			(xy 383.395732 -122.367022) (xy 383.455668 -122.367022) (xy 383.51509 -122.374845) (xy 383.572983 -122.390358)
			(xy 383.628356 -122.413294) (xy 383.680262 -122.443261) (xy 383.727812 -122.479748) (xy 383.770192 -122.522128)
			(xy 383.806679 -122.569678) (xy 383.836646 -122.621584) (xy 383.859582 -122.676957) (xy 383.875095 -122.73485)
			(xy 383.882918 -122.794272) (xy 383.883408 -122.82424) (xy 383.883408 -123.686316) (xy 401.939252 -123.686316)
			(xy 401.939252 -122.822716) (xy 401.939742 -122.792748) (xy 401.947565 -122.733326) (xy 401.963078 -122.675433)
			(xy 401.986014 -122.62006) (xy 402.015981 -122.568154) (xy 402.052468 -122.520604) (xy 402.094848 -122.478224)
			(xy 402.142398 -122.441737) (xy 402.194304 -122.41177) (xy 402.249677 -122.388834) (xy 402.30757 -122.373321)
			(xy 402.366992 -122.365498) (xy 402.426928 -122.365498) (xy 402.48635 -122.373321) (xy 402.544243 -122.388834)
			(xy 402.599616 -122.41177) (xy 402.651522 -122.441737) (xy 402.699072 -122.478224) (xy 402.741452 -122.520604)
			(xy 402.777939 -122.568154) (xy 402.807906 -122.62006) (xy 402.830842 -122.675433) (xy 402.846355 -122.733326)
			(xy 402.854178 -122.792748) (xy 402.854668 -122.822716) (xy 402.854668 -123.16714) (xy 414.899348 -123.16714)
			(xy 414.899348 -122.30354) (xy 414.899838 -122.273556) (xy 414.907666 -122.2141) (xy 414.923187 -122.156175)
			(xy 414.946136 -122.100771) (xy 414.97612 -122.048837) (xy 415.012626 -122.001261) (xy 415.055031 -121.958856)
			(xy 415.102607 -121.92235) (xy 415.154541 -121.892366) (xy 415.209945 -121.869417) (xy 415.26787 -121.853896)
			(xy 415.327326 -121.846068) (xy 415.387294 -121.846068) (xy 415.44675 -121.853896) (xy 415.504675 -121.869417)
			(xy 415.560079 -121.892366) (xy 415.612013 -121.92235) (xy 415.659589 -121.958856) (xy 415.701994 -122.001261)
			(xy 415.7385 -122.048837) (xy 415.768484 -122.100771) (xy 415.791433 -122.156175) (xy 415.806954 -122.2141)
			(xy 415.814782 -122.273556) (xy 415.815272 -122.30354) (xy 415.815272 -123.159266) (xy 429.3743 -123.159266)
			(xy 429.3743 -122.295666) (xy 429.37479 -122.265682) (xy 429.382618 -122.206226) (xy 429.398139 -122.148301)
			(xy 429.421088 -122.092897) (xy 429.451072 -122.040963) (xy 429.487578 -121.993387) (xy 429.529983 -121.950982)
			(xy 429.577559 -121.914476) (xy 429.629493 -121.884492) (xy 429.684897 -121.861543) (xy 429.742822 -121.846022)
			(xy 429.802278 -121.838194) (xy 429.862246 -121.838194) (xy 429.921702 -121.846022) (xy 429.979627 -121.861543)
			(xy 430.035031 -121.884492) (xy 430.086965 -121.914476) (xy 430.134541 -121.950982) (xy 430.176946 -121.993387)
			(xy 430.213452 -122.040963) (xy 430.243436 -122.092897) (xy 430.266385 -122.148301) (xy 430.281906 -122.206226)
			(xy 430.289734 -122.265682) (xy 430.290224 -122.295666) (xy 430.290224 -123.159266) (xy 430.289734 -123.18925)
			(xy 430.281906 -123.248706) (xy 430.266385 -123.306631) (xy 430.243436 -123.362035) (xy 430.213452 -123.413969)
			(xy 430.176946 -123.461545) (xy 430.134541 -123.50395) (xy 430.086965 -123.540456) (xy 430.035031 -123.57044)
			(xy 429.979627 -123.593389) (xy 429.921702 -123.60891) (xy 429.862246 -123.616738) (xy 429.802278 -123.616738)
			(xy 429.742822 -123.60891) (xy 429.684897 -123.593389) (xy 429.629493 -123.57044) (xy 429.577559 -123.540456)
			(xy 429.529983 -123.50395) (xy 429.487578 -123.461545) (xy 429.451072 -123.413969) (xy 429.421088 -123.362035)
			(xy 429.398139 -123.306631) (xy 429.382618 -123.248706) (xy 429.37479 -123.18925) (xy 429.3743 -123.159266)
			(xy 415.815272 -123.159266) (xy 415.815272 -123.16714) (xy 415.814782 -123.197124) (xy 415.806954 -123.25658)
			(xy 415.791433 -123.314505) (xy 415.768484 -123.369909) (xy 415.7385 -123.421843) (xy 415.701994 -123.469419)
			(xy 415.659589 -123.511824) (xy 415.612013 -123.54833) (xy 415.560079 -123.578314) (xy 415.504675 -123.601263)
			(xy 415.44675 -123.616784) (xy 415.387294 -123.624612) (xy 415.327326 -123.624612) (xy 415.26787 -123.616784)
			(xy 415.209945 -123.601263) (xy 415.154541 -123.578314) (xy 415.102607 -123.54833) (xy 415.055031 -123.511824)
			(xy 415.012626 -123.469419) (xy 414.97612 -123.421843) (xy 414.946136 -123.369909) (xy 414.923187 -123.314505)
			(xy 414.907666 -123.25658) (xy 414.899838 -123.197124) (xy 414.899348 -123.16714) (xy 402.854668 -123.16714)
			(xy 402.854668 -123.686316) (xy 402.854178 -123.716284) (xy 402.846355 -123.775706) (xy 402.830842 -123.833599)
			(xy 402.807906 -123.888972) (xy 402.777939 -123.940878) (xy 402.741452 -123.988428) (xy 402.699072 -124.030808)
			(xy 402.651522 -124.067295) (xy 402.599616 -124.097262) (xy 402.544243 -124.120198) (xy 402.48635 -124.135711)
			(xy 402.426928 -124.143534) (xy 402.366992 -124.143534) (xy 402.30757 -124.135711) (xy 402.249677 -124.120198)
			(xy 402.194304 -124.097262) (xy 402.142398 -124.067295) (xy 402.094848 -124.030808) (xy 402.052468 -123.988428)
			(xy 402.015981 -123.940878) (xy 401.986014 -123.888972) (xy 401.963078 -123.833599) (xy 401.947565 -123.775706)
			(xy 401.939742 -123.716284) (xy 401.939252 -123.686316) (xy 383.883408 -123.686316) (xy 383.883408 -123.68784)
			(xy 383.882918 -123.717808) (xy 383.875095 -123.77723) (xy 383.859582 -123.835123) (xy 383.836646 -123.890496)
			(xy 383.806679 -123.942402) (xy 383.770192 -123.989952) (xy 383.727812 -124.032332) (xy 383.680262 -124.068819)
			(xy 383.628356 -124.098786) (xy 383.572983 -124.121722) (xy 383.51509 -124.137235) (xy 383.455668 -124.145058)
			(xy 383.395732 -124.145058) (xy 383.33631 -124.137235) (xy 383.278417 -124.121722) (xy 383.223044 -124.098786)
			(xy 383.171138 -124.068819) (xy 383.123588 -124.032332) (xy 383.081208 -123.989952) (xy 383.044721 -123.942402)
			(xy 383.014754 -123.890496) (xy 382.991818 -123.835123) (xy 382.976305 -123.77723) (xy 382.968482 -123.717808)
			(xy 382.967992 -123.68784) (xy 316.568893 -123.68784) (xy 316.576928 -123.691168) (xy 316.628834 -123.721135)
			(xy 316.676384 -123.757622) (xy 316.718764 -123.800002) (xy 316.755251 -123.847552) (xy 316.785218 -123.899458)
			(xy 316.808154 -123.954831) (xy 316.823667 -124.012724) (xy 316.83149 -124.072146) (xy 316.83198 -124.102114)
			(xy 316.83198 -124.965714) (xy 316.83149 -124.995682) (xy 316.823667 -125.055104) (xy 316.808154 -125.112997)
			(xy 316.785218 -125.16837) (xy 316.755251 -125.220276) (xy 316.718764 -125.267826) (xy 316.676384 -125.310206)
			(xy 316.628834 -125.346693) (xy 316.576928 -125.37666) (xy 316.521555 -125.399596) (xy 316.463662 -125.415109)
			(xy 316.40424 -125.422932) (xy 316.344304 -125.422932) (xy 316.284882 -125.415109) (xy 316.226989 -125.399596)
			(xy 316.171616 -125.37666) (xy 316.11971 -125.346693) (xy 316.07216 -125.310206) (xy 316.02978 -125.267826)
			(xy 315.993293 -125.220276) (xy 315.963326 -125.16837) (xy 315.94039 -125.112997) (xy 315.924877 -125.055104)
			(xy 315.917054 -124.995682) (xy 315.916564 -124.965714) (xy 297.86072 -124.965714) (xy 297.86072 -124.967238)
			(xy 297.86023 -124.997206) (xy 297.852407 -125.056628) (xy 297.836894 -125.114521) (xy 297.813958 -125.169894)
			(xy 297.783991 -125.2218) (xy 297.747504 -125.26935) (xy 297.705124 -125.31173) (xy 297.657574 -125.348217)
			(xy 297.605668 -125.378184) (xy 297.550295 -125.40112) (xy 297.492402 -125.416633) (xy 297.43298 -125.424456)
			(xy 297.373044 -125.424456) (xy 297.313622 -125.416633) (xy 297.255729 -125.40112) (xy 297.200356 -125.378184)
			(xy 297.14845 -125.348217) (xy 297.1009 -125.31173) (xy 297.05852 -125.26935) (xy 297.022033 -125.2218)
			(xy 296.992066 -125.169894) (xy 296.96913 -125.114521) (xy 296.953617 -125.056628) (xy 296.945794 -124.997206)
			(xy 296.945304 -124.967238) (xy 284.900624 -124.967238) (xy 284.900624 -125.486414) (xy 284.900491 -125.494542)
			(xy 385.6101 -125.494542) (xy 385.6101 -124.630942) (xy 385.61059 -124.600974) (xy 385.618413 -124.541552)
			(xy 385.633926 -124.483659) (xy 385.656862 -124.428286) (xy 385.686829 -124.37638) (xy 385.723316 -124.32883)
			(xy 385.765696 -124.28645) (xy 385.813246 -124.249963) (xy 385.865152 -124.219996) (xy 385.920525 -124.19706)
			(xy 385.978418 -124.181547) (xy 386.03784 -124.173724) (xy 386.097776 -124.173724) (xy 386.157198 -124.181547)
			(xy 386.215091 -124.19706) (xy 386.270464 -124.219996) (xy 386.32237 -124.249963) (xy 386.36992 -124.28645)
			(xy 386.4123 -124.32883) (xy 386.448787 -124.37638) (xy 386.478754 -124.428286) (xy 386.50169 -124.483659)
			(xy 386.517203 -124.541552) (xy 386.525026 -124.600974) (xy 386.525516 -124.630942) (xy 386.525516 -125.486414)
			(xy 400.085052 -125.486414) (xy 400.085052 -124.622814) (xy 400.085542 -124.592846) (xy 400.093365 -124.533424)
			(xy 400.108878 -124.475531) (xy 400.131814 -124.420158) (xy 400.161781 -124.368252) (xy 400.198268 -124.320702)
			(xy 400.240648 -124.278322) (xy 400.288198 -124.241835) (xy 400.340104 -124.211868) (xy 400.395477 -124.188932)
			(xy 400.45337 -124.173419) (xy 400.512792 -124.165596) (xy 400.572728 -124.165596) (xy 400.63215 -124.173419)
			(xy 400.690043 -124.188932) (xy 400.745416 -124.211868) (xy 400.797322 -124.241835) (xy 400.844872 -124.278322)
			(xy 400.887252 -124.320702) (xy 400.923739 -124.368252) (xy 400.953706 -124.420158) (xy 400.976642 -124.475531)
			(xy 400.992155 -124.533424) (xy 400.999978 -124.592846) (xy 401.000468 -124.622814) (xy 401.000468 -124.967238)
			(xy 413.045148 -124.967238) (xy 413.045148 -124.103638) (xy 413.045638 -124.073654) (xy 413.053466 -124.014198)
			(xy 413.068987 -123.956273) (xy 413.091936 -123.900869) (xy 413.12192 -123.848935) (xy 413.158426 -123.801359)
			(xy 413.200831 -123.758954) (xy 413.248407 -123.722448) (xy 413.300341 -123.692464) (xy 413.355745 -123.669515)
			(xy 413.41367 -123.653994) (xy 413.473126 -123.646166) (xy 413.533094 -123.646166) (xy 413.59255 -123.653994)
			(xy 413.650475 -123.669515) (xy 413.705879 -123.692464) (xy 413.757813 -123.722448) (xy 413.805389 -123.758954)
			(xy 413.847794 -123.801359) (xy 413.8843 -123.848935) (xy 413.914284 -123.900869) (xy 413.937233 -123.956273)
			(xy 413.952754 -124.014198) (xy 413.960582 -124.073654) (xy 413.961072 -124.103638) (xy 413.961072 -124.965714)
			(xy 432.016408 -124.965714) (xy 432.016408 -124.102114) (xy 432.016898 -124.07213) (xy 432.024726 -124.012674)
			(xy 432.040247 -123.954749) (xy 432.063196 -123.899345) (xy 432.09318 -123.847411) (xy 432.129686 -123.799835)
			(xy 432.172091 -123.75743) (xy 432.219667 -123.720924) (xy 432.271601 -123.69094) (xy 432.327005 -123.667991)
			(xy 432.38493 -123.65247) (xy 432.444386 -123.644642) (xy 432.504354 -123.644642) (xy 432.56381 -123.65247)
			(xy 432.621735 -123.667991) (xy 432.677139 -123.69094) (xy 432.729073 -123.720924) (xy 432.776649 -123.75743)
			(xy 432.819054 -123.799835) (xy 432.85556 -123.847411) (xy 432.885544 -123.899345) (xy 432.908493 -123.954749)
			(xy 432.924014 -124.012674) (xy 432.931842 -124.07213) (xy 432.932332 -124.102114) (xy 432.932332 -124.965714)
			(xy 432.931842 -124.995698) (xy 432.924014 -125.055154) (xy 432.908493 -125.113079) (xy 432.885544 -125.168483)
			(xy 432.85556 -125.220417) (xy 432.819054 -125.267993) (xy 432.776649 -125.310398) (xy 432.729073 -125.346904)
			(xy 432.677139 -125.376888) (xy 432.621735 -125.399837) (xy 432.56381 -125.415358) (xy 432.504354 -125.423186)
			(xy 432.444386 -125.423186) (xy 432.38493 -125.415358) (xy 432.327005 -125.399837) (xy 432.271601 -125.376888)
			(xy 432.219667 -125.346904) (xy 432.172091 -125.310398) (xy 432.129686 -125.267993) (xy 432.09318 -125.220417)
			(xy 432.063196 -125.168483) (xy 432.040247 -125.113079) (xy 432.024726 -125.055154) (xy 432.016898 -124.995698)
			(xy 432.016408 -124.965714) (xy 413.961072 -124.965714) (xy 413.961072 -124.967238) (xy 413.960582 -124.997222)
			(xy 413.952754 -125.056678) (xy 413.937233 -125.114603) (xy 413.914284 -125.170007) (xy 413.8843 -125.221941)
			(xy 413.847794 -125.269517) (xy 413.805389 -125.311922) (xy 413.757813 -125.348428) (xy 413.705879 -125.378412)
			(xy 413.650475 -125.401361) (xy 413.59255 -125.416882) (xy 413.533094 -125.42471) (xy 413.473126 -125.42471)
			(xy 413.41367 -125.416882) (xy 413.355745 -125.401361) (xy 413.300341 -125.378412) (xy 413.248407 -125.348428)
			(xy 413.200831 -125.311922) (xy 413.158426 -125.269517) (xy 413.12192 -125.221941) (xy 413.091936 -125.170007)
			(xy 413.068987 -125.114603) (xy 413.053466 -125.056678) (xy 413.045638 -124.997222) (xy 413.045148 -124.967238)
			(xy 401.000468 -124.967238) (xy 401.000468 -125.486414) (xy 400.999978 -125.516382) (xy 400.992155 -125.575804)
			(xy 400.976642 -125.633697) (xy 400.953706 -125.68907) (xy 400.923739 -125.740976) (xy 400.887252 -125.788526)
			(xy 400.844872 -125.830906) (xy 400.797322 -125.867393) (xy 400.745416 -125.89736) (xy 400.690043 -125.920296)
			(xy 400.63215 -125.935809) (xy 400.572728 -125.943632) (xy 400.512792 -125.943632) (xy 400.45337 -125.935809)
			(xy 400.395477 -125.920296) (xy 400.340104 -125.89736) (xy 400.288198 -125.867393) (xy 400.240648 -125.830906)
			(xy 400.198268 -125.788526) (xy 400.161781 -125.740976) (xy 400.131814 -125.68907) (xy 400.108878 -125.633697)
			(xy 400.093365 -125.575804) (xy 400.085542 -125.516382) (xy 400.085052 -125.486414) (xy 386.525516 -125.486414)
			(xy 386.525516 -125.494542) (xy 386.525026 -125.52451) (xy 386.517203 -125.583932) (xy 386.50169 -125.641825)
			(xy 386.478754 -125.697198) (xy 386.448787 -125.749104) (xy 386.4123 -125.796654) (xy 386.36992 -125.839034)
			(xy 386.32237 -125.875521) (xy 386.270464 -125.905488) (xy 386.215091 -125.928424) (xy 386.157198 -125.943937)
			(xy 386.097776 -125.95176) (xy 386.03784 -125.95176) (xy 385.978418 -125.943937) (xy 385.920525 -125.928424)
			(xy 385.865152 -125.905488) (xy 385.813246 -125.875521) (xy 385.765696 -125.839034) (xy 385.723316 -125.796654)
			(xy 385.686829 -125.749104) (xy 385.656862 -125.697198) (xy 385.633926 -125.641825) (xy 385.618413 -125.583932)
			(xy 385.61059 -125.52451) (xy 385.6101 -125.494542) (xy 284.900491 -125.494542) (xy 284.900134 -125.516398)
			(xy 284.892306 -125.575854) (xy 284.876785 -125.633779) (xy 284.853836 -125.689183) (xy 284.823852 -125.741117)
			(xy 284.787346 -125.788693) (xy 284.744941 -125.831098) (xy 284.697365 -125.867604) (xy 284.645431 -125.897588)
			(xy 284.590027 -125.920537) (xy 284.532102 -125.936058) (xy 284.472646 -125.943886) (xy 284.412678 -125.943886)
			(xy 284.353222 -125.936058) (xy 284.295297 -125.920537) (xy 284.239893 -125.897588) (xy 284.187959 -125.867604)
			(xy 284.140383 -125.831098) (xy 284.097978 -125.788693) (xy 284.061472 -125.741117) (xy 284.031488 -125.689183)
			(xy 284.008539 -125.633779) (xy 283.993018 -125.575854) (xy 283.98519 -125.516398) (xy 283.9847 -125.486414)
			(xy 270.425672 -125.486414) (xy 270.425672 -125.494542) (xy 270.425182 -125.524526) (xy 270.417354 -125.583982)
			(xy 270.401833 -125.641907) (xy 270.378884 -125.697311) (xy 270.3489 -125.749245) (xy 270.312394 -125.796821)
			(xy 270.269989 -125.839226) (xy 270.222413 -125.875732) (xy 270.170479 -125.905716) (xy 270.115075 -125.928665)
			(xy 270.05715 -125.944186) (xy 269.997694 -125.952014) (xy 269.937726 -125.952014) (xy 269.87827 -125.944186)
			(xy 269.820345 -125.928665) (xy 269.764941 -125.905716) (xy 269.713007 -125.875732) (xy 269.665431 -125.839226)
			(xy 269.623026 -125.796821) (xy 269.58652 -125.749245) (xy 269.556536 -125.697311) (xy 269.533587 -125.641907)
			(xy 269.518066 -125.583982) (xy 269.510238 -125.524526) (xy 269.509748 -125.494542) (xy 168.800647 -125.494542)
			(xy 168.80029 -125.516398) (xy 168.792462 -125.575854) (xy 168.776941 -125.633779) (xy 168.753992 -125.689183)
			(xy 168.724008 -125.741117) (xy 168.687502 -125.788693) (xy 168.645097 -125.831098) (xy 168.597521 -125.867604)
			(xy 168.545587 -125.897588) (xy 168.490183 -125.920537) (xy 168.432258 -125.936058) (xy 168.372802 -125.943886)
			(xy 168.312834 -125.943886) (xy 168.253378 -125.936058) (xy 168.195453 -125.920537) (xy 168.140049 -125.897588)
			(xy 168.088115 -125.867604) (xy 168.040539 -125.831098) (xy 167.998134 -125.788693) (xy 167.961628 -125.741117)
			(xy 167.931644 -125.689183) (xy 167.908695 -125.633779) (xy 167.893174 -125.575854) (xy 167.885346 -125.516398)
			(xy 167.884856 -125.486414) (xy 154.325828 -125.486414) (xy 154.325828 -125.494542) (xy 154.325338 -125.524526)
			(xy 154.31751 -125.583982) (xy 154.301989 -125.641907) (xy 154.27904 -125.697311) (xy 154.249056 -125.749245)
			(xy 154.21255 -125.796821) (xy 154.170145 -125.839226) (xy 154.122569 -125.875732) (xy 154.070635 -125.905716)
			(xy 154.015231 -125.928665) (xy 153.957306 -125.944186) (xy 153.89785 -125.952014) (xy 153.837882 -125.952014)
			(xy 153.778426 -125.944186) (xy 153.720501 -125.928665) (xy 153.665097 -125.905716) (xy 153.613163 -125.875732)
			(xy 153.565587 -125.839226) (xy 153.523182 -125.796821) (xy 153.486676 -125.749245) (xy 153.456692 -125.697311)
			(xy 153.433743 -125.641907) (xy 153.418222 -125.583982) (xy 153.410394 -125.524526) (xy 153.409904 -125.494542)
			(xy 52.700295 -125.494542) (xy 52.699938 -125.516382) (xy 52.692115 -125.575804) (xy 52.676602 -125.633697)
			(xy 52.653666 -125.68907) (xy 52.623699 -125.740976) (xy 52.587212 -125.788526) (xy 52.544832 -125.830906)
			(xy 52.497282 -125.867393) (xy 52.445376 -125.89736) (xy 52.390003 -125.920296) (xy 52.33211 -125.935809)
			(xy 52.272688 -125.943632) (xy 52.212752 -125.943632) (xy 52.15333 -125.935809) (xy 52.095437 -125.920296)
			(xy 52.040064 -125.89736) (xy 51.988158 -125.867393) (xy 51.940608 -125.830906) (xy 51.898228 -125.788526)
			(xy 51.861741 -125.740976) (xy 51.831774 -125.68907) (xy 51.808838 -125.633697) (xy 51.793325 -125.575804)
			(xy 51.785502 -125.516382) (xy 51.785012 -125.486414) (xy 38.225476 -125.486414) (xy 38.225476 -125.494542)
			(xy 38.224986 -125.52451) (xy 38.217163 -125.583932) (xy 38.20165 -125.641825) (xy 38.178714 -125.697198)
			(xy 38.148747 -125.749104) (xy 38.11226 -125.796654) (xy 38.06988 -125.839034) (xy 38.02233 -125.875521)
			(xy 37.970424 -125.905488) (xy 37.915051 -125.928424) (xy 37.857158 -125.943937) (xy 37.797736 -125.95176)
			(xy 37.7378 -125.95176) (xy 37.678378 -125.943937) (xy 37.620485 -125.928424) (xy 37.565112 -125.905488)
			(xy 37.513206 -125.875521) (xy 37.465656 -125.839034) (xy 37.423276 -125.796654) (xy 37.386789 -125.749104)
			(xy 37.356822 -125.697198) (xy 37.333886 -125.641825) (xy 37.318373 -125.583932) (xy 37.31055 -125.52451)
			(xy 37.31006 -125.494542) (xy 4.308094 -125.494542) (xy 4.308094 -131.297934) (xy 34.667952 -131.297934)
			(xy 34.667952 -130.434334) (xy 34.668442 -130.404366) (xy 34.676265 -130.344944) (xy 34.691778 -130.287051)
			(xy 34.714714 -130.231678) (xy 34.744681 -130.179772) (xy 34.781168 -130.132222) (xy 34.823548 -130.089842)
			(xy 34.871098 -130.053355) (xy 34.923004 -130.023388) (xy 34.978377 -130.000452) (xy 35.03627 -129.984939)
			(xy 35.095692 -129.977116) (xy 35.155628 -129.977116) (xy 35.21505 -129.984939) (xy 35.272943 -130.000452)
			(xy 35.328316 -130.023388) (xy 35.380222 -130.053355) (xy 35.427772 -130.089842) (xy 35.470152 -130.132222)
			(xy 35.506639 -130.179772) (xy 35.536606 -130.231678) (xy 35.559542 -130.287051) (xy 35.575055 -130.344944)
			(xy 35.582878 -130.404366) (xy 35.583368 -130.434334) (xy 35.583368 -131.29641) (xy 53.639212 -131.29641)
			(xy 53.639212 -130.43281) (xy 53.639702 -130.402842) (xy 53.647525 -130.34342) (xy 53.663038 -130.285527)
			(xy 53.685974 -130.230154) (xy 53.715941 -130.178248) (xy 53.752428 -130.130698) (xy 53.794808 -130.088318)
			(xy 53.842358 -130.051831) (xy 53.894264 -130.021864) (xy 53.949637 -129.998928) (xy 54.00753 -129.983415)
			(xy 54.066952 -129.975592) (xy 54.126888 -129.975592) (xy 54.18631 -129.983415) (xy 54.244203 -129.998928)
			(xy 54.299576 -130.021864) (xy 54.351482 -130.051831) (xy 54.399032 -130.088318) (xy 54.441412 -130.130698)
			(xy 54.477899 -130.178248) (xy 54.507866 -130.230154) (xy 54.530802 -130.285527) (xy 54.546315 -130.34342)
			(xy 54.554138 -130.402842) (xy 54.554628 -130.43281) (xy 54.554628 -130.777234) (xy 66.599308 -130.777234)
			(xy 66.599308 -129.913634) (xy 66.599798 -129.88365) (xy 66.607626 -129.824194) (xy 66.623147 -129.766269)
			(xy 66.646096 -129.710865) (xy 66.67608 -129.658931) (xy 66.712586 -129.611355) (xy 66.754991 -129.56895)
			(xy 66.802567 -129.532444) (xy 66.854501 -129.50246) (xy 66.909905 -129.479511) (xy 66.96783 -129.46399)
			(xy 67.027286 -129.456162) (xy 67.087254 -129.456162) (xy 67.14671 -129.46399) (xy 67.204635 -129.479511)
			(xy 67.260039 -129.50246) (xy 67.311973 -129.532444) (xy 67.359549 -129.56895) (xy 67.401954 -129.611355)
			(xy 67.43846 -129.658931) (xy 67.468444 -129.710865) (xy 67.491393 -129.766269) (xy 67.506914 -129.824194)
			(xy 67.514742 -129.88365) (xy 67.515232 -129.913634) (xy 67.515232 -130.769106) (xy 81.07426 -130.769106)
			(xy 81.07426 -129.905506) (xy 81.07475 -129.875522) (xy 81.082578 -129.816066) (xy 81.098099 -129.758141)
			(xy 81.121048 -129.702737) (xy 81.151032 -129.650803) (xy 81.187538 -129.603227) (xy 81.229943 -129.560822)
			(xy 81.277519 -129.524316) (xy 81.329453 -129.494332) (xy 81.384857 -129.471383) (xy 81.442782 -129.455862)
			(xy 81.502238 -129.448034) (xy 81.562206 -129.448034) (xy 81.621662 -129.455862) (xy 81.679587 -129.471383)
			(xy 81.734991 -129.494332) (xy 81.786925 -129.524316) (xy 81.834501 -129.560822) (xy 81.876906 -129.603227)
			(xy 81.913412 -129.650803) (xy 81.943396 -129.702737) (xy 81.966345 -129.758141) (xy 81.981866 -129.816066)
			(xy 81.989694 -129.875522) (xy 81.990184 -129.905506) (xy 81.990184 -130.769106) (xy 81.989694 -130.79909)
			(xy 81.981866 -130.858546) (xy 81.966345 -130.916471) (xy 81.943396 -130.971875) (xy 81.913412 -131.023809)
			(xy 81.876906 -131.071385) (xy 81.834501 -131.11379) (xy 81.786925 -131.150296) (xy 81.734991 -131.18028)
			(xy 81.679587 -131.203229) (xy 81.621662 -131.21875) (xy 81.562206 -131.226578) (xy 81.502238 -131.226578)
			(xy 81.442782 -131.21875) (xy 81.384857 -131.203229) (xy 81.329453 -131.18028) (xy 81.277519 -131.150296)
			(xy 81.229943 -131.11379) (xy 81.187538 -131.071385) (xy 81.151032 -131.023809) (xy 81.121048 -130.971875)
			(xy 81.098099 -130.916471) (xy 81.082578 -130.858546) (xy 81.07475 -130.79909) (xy 81.07426 -130.769106)
			(xy 67.515232 -130.769106) (xy 67.515232 -130.777234) (xy 67.514742 -130.807218) (xy 67.506914 -130.866674)
			(xy 67.491393 -130.924599) (xy 67.468444 -130.980003) (xy 67.43846 -131.031937) (xy 67.401954 -131.079513)
			(xy 67.359549 -131.121918) (xy 67.311973 -131.158424) (xy 67.260039 -131.188408) (xy 67.204635 -131.211357)
			(xy 67.14671 -131.226878) (xy 67.087254 -131.234706) (xy 67.027286 -131.234706) (xy 66.96783 -131.226878)
			(xy 66.909905 -131.211357) (xy 66.854501 -131.188408) (xy 66.802567 -131.158424) (xy 66.754991 -131.121918)
			(xy 66.712586 -131.079513) (xy 66.67608 -131.031937) (xy 66.646096 -130.980003) (xy 66.623147 -130.924599)
			(xy 66.607626 -130.866674) (xy 66.599798 -130.807218) (xy 66.599308 -130.777234) (xy 54.554628 -130.777234)
			(xy 54.554628 -131.29641) (xy 54.554138 -131.326378) (xy 54.546315 -131.3858) (xy 54.530802 -131.443693)
			(xy 54.507866 -131.499066) (xy 54.477899 -131.550972) (xy 54.441412 -131.598522) (xy 54.399032 -131.640902)
			(xy 54.351482 -131.677389) (xy 54.299576 -131.707356) (xy 54.244203 -131.730292) (xy 54.18631 -131.745805)
			(xy 54.126888 -131.753628) (xy 54.066952 -131.753628) (xy 54.00753 -131.745805) (xy 53.949637 -131.730292)
			(xy 53.894264 -131.707356) (xy 53.842358 -131.677389) (xy 53.794808 -131.640902) (xy 53.752428 -131.598522)
			(xy 53.715941 -131.550972) (xy 53.685974 -131.499066) (xy 53.663038 -131.443693) (xy 53.647525 -131.3858)
			(xy 53.639702 -131.326378) (xy 53.639212 -131.29641) (xy 35.583368 -131.29641) (xy 35.583368 -131.297934)
			(xy 35.582878 -131.327902) (xy 35.575055 -131.387324) (xy 35.559542 -131.445217) (xy 35.536606 -131.50059)
			(xy 35.506639 -131.552496) (xy 35.470152 -131.600046) (xy 35.427772 -131.642426) (xy 35.380222 -131.678913)
			(xy 35.328316 -131.70888) (xy 35.272943 -131.731816) (xy 35.21505 -131.747329) (xy 35.155628 -131.755152)
			(xy 35.095692 -131.755152) (xy 35.03627 -131.747329) (xy 34.978377 -131.731816) (xy 34.923004 -131.70888)
			(xy 34.871098 -131.678913) (xy 34.823548 -131.642426) (xy 34.781168 -131.600046) (xy 34.744681 -131.552496)
			(xy 34.714714 -131.50059) (xy 34.691778 -131.445217) (xy 34.676265 -131.387324) (xy 34.668442 -131.327902)
			(xy 34.667952 -131.297934) (xy 4.308094 -131.297934) (xy 4.308094 -133.104382) (xy 37.31006 -133.104382)
			(xy 37.31006 -132.240782) (xy 37.31055 -132.210814) (xy 37.318373 -132.151392) (xy 37.333886 -132.093499)
			(xy 37.356822 -132.038126) (xy 37.386789 -131.98622) (xy 37.423276 -131.93867) (xy 37.465656 -131.89629)
			(xy 37.513206 -131.859803) (xy 37.565112 -131.829836) (xy 37.620485 -131.8069) (xy 37.678378 -131.791387)
			(xy 37.7378 -131.783564) (xy 37.797736 -131.783564) (xy 37.857158 -131.791387) (xy 37.915051 -131.8069)
			(xy 37.970424 -131.829836) (xy 38.02233 -131.859803) (xy 38.06988 -131.89629) (xy 38.11226 -131.93867)
			(xy 38.148747 -131.98622) (xy 38.178714 -132.038126) (xy 38.20165 -132.093499) (xy 38.217163 -132.151392)
			(xy 38.224986 -132.210814) (xy 38.225476 -132.240782) (xy 38.225476 -133.096508) (xy 51.785012 -133.096508)
			(xy 51.785012 -132.232908) (xy 51.785502 -132.20294) (xy 51.793325 -132.143518) (xy 51.808838 -132.085625)
			(xy 51.831774 -132.030252) (xy 51.861741 -131.978346) (xy 51.898228 -131.930796) (xy 51.940608 -131.888416)
			(xy 51.988158 -131.851929) (xy 52.040064 -131.821962) (xy 52.095437 -131.799026) (xy 52.15333 -131.783513)
			(xy 52.212752 -131.77569) (xy 52.272688 -131.77569) (xy 52.33211 -131.783513) (xy 52.390003 -131.799026)
			(xy 52.445376 -131.821962) (xy 52.497282 -131.851929) (xy 52.544832 -131.888416) (xy 52.587212 -131.930796)
			(xy 52.623699 -131.978346) (xy 52.653666 -132.030252) (xy 52.676602 -132.085625) (xy 52.692115 -132.143518)
			(xy 52.699938 -132.20294) (xy 52.700428 -132.232908) (xy 52.700428 -132.577332) (xy 64.745108 -132.577332)
			(xy 64.745108 -131.713732) (xy 64.745598 -131.683748) (xy 64.753426 -131.624292) (xy 64.768947 -131.566367)
			(xy 64.791896 -131.510963) (xy 64.82188 -131.459029) (xy 64.858386 -131.411453) (xy 64.900791 -131.369048)
			(xy 64.948367 -131.332542) (xy 65.000301 -131.302558) (xy 65.055705 -131.279609) (xy 65.11363 -131.264088)
			(xy 65.173086 -131.25626) (xy 65.233054 -131.25626) (xy 65.29251 -131.264088) (xy 65.350435 -131.279609)
			(xy 65.405839 -131.302558) (xy 65.457773 -131.332542) (xy 65.505349 -131.369048) (xy 65.547754 -131.411453)
			(xy 65.58426 -131.459029) (xy 65.614244 -131.510963) (xy 65.637193 -131.566367) (xy 65.652714 -131.624292)
			(xy 65.660542 -131.683748) (xy 65.661032 -131.713732) (xy 65.661032 -132.575808) (xy 83.716368 -132.575808)
			(xy 83.716368 -131.712208) (xy 83.716858 -131.682224) (xy 83.724686 -131.622768) (xy 83.740207 -131.564843)
			(xy 83.763156 -131.509439) (xy 83.79314 -131.457505) (xy 83.829646 -131.409929) (xy 83.872051 -131.367524)
			(xy 83.919627 -131.331018) (xy 83.971561 -131.301034) (xy 84.026965 -131.278085) (xy 84.08489 -131.262564)
			(xy 84.144346 -131.254736) (xy 84.204314 -131.254736) (xy 84.26377 -131.262564) (xy 84.321695 -131.278085)
			(xy 84.369615 -131.297934) (xy 150.767796 -131.297934) (xy 150.767796 -130.434334) (xy 150.768286 -130.40435)
			(xy 150.776114 -130.344894) (xy 150.791635 -130.286969) (xy 150.814584 -130.231565) (xy 150.844568 -130.179631)
			(xy 150.881074 -130.132055) (xy 150.923479 -130.08965) (xy 150.971055 -130.053144) (xy 151.022989 -130.02316)
			(xy 151.078393 -130.000211) (xy 151.136318 -129.98469) (xy 151.195774 -129.976862) (xy 151.255742 -129.976862)
			(xy 151.315198 -129.98469) (xy 151.373123 -130.000211) (xy 151.428527 -130.02316) (xy 151.480461 -130.053144)
			(xy 151.528037 -130.08965) (xy 151.570442 -130.132055) (xy 151.606948 -130.179631) (xy 151.636932 -130.231565)
			(xy 151.659881 -130.286969) (xy 151.675402 -130.344894) (xy 151.68323 -130.40435) (xy 151.68372 -130.434334)
			(xy 151.68372 -131.29641) (xy 169.739056 -131.29641) (xy 169.739056 -130.43281) (xy 169.739546 -130.402826)
			(xy 169.747374 -130.34337) (xy 169.762895 -130.285445) (xy 169.785844 -130.230041) (xy 169.815828 -130.178107)
			(xy 169.852334 -130.130531) (xy 169.894739 -130.088126) (xy 169.942315 -130.05162) (xy 169.994249 -130.021636)
			(xy 170.049653 -129.998687) (xy 170.107578 -129.983166) (xy 170.167034 -129.975338) (xy 170.227002 -129.975338)
			(xy 170.286458 -129.983166) (xy 170.344383 -129.998687) (xy 170.399787 -130.021636) (xy 170.451721 -130.05162)
			(xy 170.499297 -130.088126) (xy 170.541702 -130.130531) (xy 170.578208 -130.178107) (xy 170.608192 -130.230041)
			(xy 170.631141 -130.285445) (xy 170.646662 -130.34337) (xy 170.65449 -130.402826) (xy 170.65498 -130.43281)
			(xy 170.65498 -130.777234) (xy 182.69966 -130.777234) (xy 182.69966 -129.913634) (xy 182.70015 -129.883666)
			(xy 182.707973 -129.824244) (xy 182.723486 -129.766351) (xy 182.746422 -129.710978) (xy 182.776389 -129.659072)
			(xy 182.812876 -129.611522) (xy 182.855256 -129.569142) (xy 182.902806 -129.532655) (xy 182.954712 -129.502688)
			(xy 183.010085 -129.479752) (xy 183.067978 -129.464239) (xy 183.1274 -129.456416) (xy 183.187336 -129.456416)
			(xy 183.246758 -129.464239) (xy 183.304651 -129.479752) (xy 183.360024 -129.502688) (xy 183.41193 -129.532655)
			(xy 183.45948 -129.569142) (xy 183.50186 -129.611522) (xy 183.538347 -129.659072) (xy 183.568314 -129.710978)
			(xy 183.59125 -129.766351) (xy 183.606763 -129.824244) (xy 183.614586 -129.883666) (xy 183.615076 -129.913634)
			(xy 183.615076 -130.769106) (xy 197.174612 -130.769106) (xy 197.174612 -129.905506) (xy 197.175102 -129.875538)
			(xy 197.182925 -129.816116) (xy 197.198438 -129.758223) (xy 197.221374 -129.70285) (xy 197.251341 -129.650944)
			(xy 197.287828 -129.603394) (xy 197.330208 -129.561014) (xy 197.377758 -129.524527) (xy 197.429664 -129.49456)
			(xy 197.485037 -129.471624) (xy 197.54293 -129.456111) (xy 197.602352 -129.448288) (xy 197.662288 -129.448288)
			(xy 197.72171 -129.456111) (xy 197.779603 -129.471624) (xy 197.834976 -129.49456) (xy 197.886882 -129.524527)
			(xy 197.934432 -129.561014) (xy 197.976812 -129.603394) (xy 198.013299 -129.650944) (xy 198.043266 -129.70285)
			(xy 198.066202 -129.758223) (xy 198.081715 -129.816116) (xy 198.089538 -129.875538) (xy 198.090028 -129.905506)
			(xy 198.090028 -130.769106) (xy 198.089538 -130.799074) (xy 198.081715 -130.858496) (xy 198.066202 -130.916389)
			(xy 198.043266 -130.971762) (xy 198.013299 -131.023668) (xy 197.976812 -131.071218) (xy 197.934432 -131.113598)
			(xy 197.886882 -131.150085) (xy 197.834976 -131.180052) (xy 197.779603 -131.202988) (xy 197.72171 -131.218501)
			(xy 197.662288 -131.226324) (xy 197.602352 -131.226324) (xy 197.54293 -131.218501) (xy 197.485037 -131.202988)
			(xy 197.429664 -131.180052) (xy 197.377758 -131.150085) (xy 197.330208 -131.113598) (xy 197.287828 -131.071218)
			(xy 197.251341 -131.023668) (xy 197.221374 -130.971762) (xy 197.198438 -130.916389) (xy 197.182925 -130.858496)
			(xy 197.175102 -130.799074) (xy 197.174612 -130.769106) (xy 183.615076 -130.769106) (xy 183.615076 -130.777234)
			(xy 183.614586 -130.807202) (xy 183.606763 -130.866624) (xy 183.59125 -130.924517) (xy 183.568314 -130.97989)
			(xy 183.538347 -131.031796) (xy 183.50186 -131.079346) (xy 183.45948 -131.121726) (xy 183.41193 -131.158213)
			(xy 183.360024 -131.18818) (xy 183.304651 -131.211116) (xy 183.246758 -131.226629) (xy 183.187336 -131.234452)
			(xy 183.1274 -131.234452) (xy 183.067978 -131.226629) (xy 183.010085 -131.211116) (xy 182.954712 -131.18818)
			(xy 182.902806 -131.158213) (xy 182.855256 -131.121726) (xy 182.812876 -131.079346) (xy 182.776389 -131.031796)
			(xy 182.746422 -130.97989) (xy 182.723486 -130.924517) (xy 182.707973 -130.866624) (xy 182.70015 -130.807202)
			(xy 182.69966 -130.777234) (xy 170.65498 -130.777234) (xy 170.65498 -131.29641) (xy 170.65449 -131.326394)
			(xy 170.646662 -131.38585) (xy 170.631141 -131.443775) (xy 170.608192 -131.499179) (xy 170.578208 -131.551113)
			(xy 170.541702 -131.598689) (xy 170.499297 -131.641094) (xy 170.451721 -131.6776) (xy 170.399787 -131.707584)
			(xy 170.344383 -131.730533) (xy 170.286458 -131.746054) (xy 170.227002 -131.753882) (xy 170.167034 -131.753882)
			(xy 170.107578 -131.746054) (xy 170.049653 -131.730533) (xy 169.994249 -131.707584) (xy 169.942315 -131.6776)
			(xy 169.894739 -131.641094) (xy 169.852334 -131.598689) (xy 169.815828 -131.551113) (xy 169.785844 -131.499179)
			(xy 169.762895 -131.443775) (xy 169.747374 -131.38585) (xy 169.739546 -131.326394) (xy 169.739056 -131.29641)
			(xy 151.68372 -131.29641) (xy 151.68372 -131.297934) (xy 151.68323 -131.327918) (xy 151.675402 -131.387374)
			(xy 151.659881 -131.445299) (xy 151.636932 -131.500703) (xy 151.606948 -131.552637) (xy 151.570442 -131.600213)
			(xy 151.528037 -131.642618) (xy 151.480461 -131.679124) (xy 151.428527 -131.709108) (xy 151.373123 -131.732057)
			(xy 151.315198 -131.747578) (xy 151.255742 -131.755406) (xy 151.195774 -131.755406) (xy 151.136318 -131.747578)
			(xy 151.078393 -131.732057) (xy 151.022989 -131.709108) (xy 150.971055 -131.679124) (xy 150.923479 -131.642618)
			(xy 150.881074 -131.600213) (xy 150.844568 -131.552637) (xy 150.814584 -131.500703) (xy 150.791635 -131.445299)
			(xy 150.776114 -131.387374) (xy 150.768286 -131.327918) (xy 150.767796 -131.297934) (xy 84.369615 -131.297934)
			(xy 84.377099 -131.301034) (xy 84.429033 -131.331018) (xy 84.476609 -131.367524) (xy 84.519014 -131.409929)
			(xy 84.55552 -131.457505) (xy 84.585504 -131.509439) (xy 84.608453 -131.564843) (xy 84.623974 -131.622768)
			(xy 84.631802 -131.682224) (xy 84.632292 -131.712208) (xy 84.632292 -132.575808) (xy 84.631802 -132.605792)
			(xy 84.623974 -132.665248) (xy 84.608453 -132.723173) (xy 84.585504 -132.778577) (xy 84.55552 -132.830511)
			(xy 84.519014 -132.878087) (xy 84.476609 -132.920492) (xy 84.429033 -132.956998) (xy 84.377099 -132.986982)
			(xy 84.321695 -133.009931) (xy 84.26377 -133.025452) (xy 84.204314 -133.03328) (xy 84.144346 -133.03328)
			(xy 84.08489 -133.025452) (xy 84.026965 -133.009931) (xy 83.971561 -132.986982) (xy 83.919627 -132.956998)
			(xy 83.872051 -132.920492) (xy 83.829646 -132.878087) (xy 83.79314 -132.830511) (xy 83.763156 -132.778577)
			(xy 83.740207 -132.723173) (xy 83.724686 -132.665248) (xy 83.716858 -132.605792) (xy 83.716368 -132.575808)
			(xy 65.661032 -132.575808) (xy 65.661032 -132.577332) (xy 65.660542 -132.607316) (xy 65.652714 -132.666772)
			(xy 65.637193 -132.724697) (xy 65.614244 -132.780101) (xy 65.58426 -132.832035) (xy 65.547754 -132.879611)
			(xy 65.505349 -132.922016) (xy 65.457773 -132.958522) (xy 65.405839 -132.988506) (xy 65.350435 -133.011455)
			(xy 65.29251 -133.026976) (xy 65.233054 -133.034804) (xy 65.173086 -133.034804) (xy 65.11363 -133.026976)
			(xy 65.055705 -133.011455) (xy 65.000301 -132.988506) (xy 64.948367 -132.958522) (xy 64.900791 -132.922016)
			(xy 64.858386 -132.879611) (xy 64.82188 -132.832035) (xy 64.791896 -132.780101) (xy 64.768947 -132.724697)
			(xy 64.753426 -132.666772) (xy 64.745598 -132.607316) (xy 64.745108 -132.577332) (xy 52.700428 -132.577332)
			(xy 52.700428 -133.096508) (xy 52.699938 -133.126476) (xy 52.692115 -133.185898) (xy 52.676602 -133.243791)
			(xy 52.653666 -133.299164) (xy 52.623699 -133.35107) (xy 52.587212 -133.39862) (xy 52.544832 -133.441)
			(xy 52.497282 -133.477487) (xy 52.445376 -133.507454) (xy 52.390003 -133.53039) (xy 52.33211 -133.545903)
			(xy 52.272688 -133.553726) (xy 52.212752 -133.553726) (xy 52.15333 -133.545903) (xy 52.095437 -133.53039)
			(xy 52.040064 -133.507454) (xy 51.988158 -133.477487) (xy 51.940608 -133.441) (xy 51.898228 -133.39862)
			(xy 51.861741 -133.35107) (xy 51.831774 -133.299164) (xy 51.808838 -133.243791) (xy 51.793325 -133.185898)
			(xy 51.785502 -133.126476) (xy 51.785012 -133.096508) (xy 38.225476 -133.096508) (xy 38.225476 -133.104382)
			(xy 38.224986 -133.13435) (xy 38.217163 -133.193772) (xy 38.20165 -133.251665) (xy 38.178714 -133.307038)
			(xy 38.148747 -133.358944) (xy 38.11226 -133.406494) (xy 38.06988 -133.448874) (xy 38.02233 -133.485361)
			(xy 37.970424 -133.515328) (xy 37.915051 -133.538264) (xy 37.857158 -133.553777) (xy 37.797736 -133.5616)
			(xy 37.7378 -133.5616) (xy 37.678378 -133.553777) (xy 37.620485 -133.538264) (xy 37.565112 -133.515328)
			(xy 37.513206 -133.485361) (xy 37.465656 -133.448874) (xy 37.423276 -133.406494) (xy 37.386789 -133.358944)
			(xy 37.356822 -133.307038) (xy 37.333886 -133.251665) (xy 37.318373 -133.193772) (xy 37.31055 -133.13435)
			(xy 37.31006 -133.104382) (xy 4.308094 -133.104382) (xy 4.308094 -134.897876) (xy 34.667952 -134.897876)
			(xy 34.667952 -134.034276) (xy 34.668442 -134.004308) (xy 34.676265 -133.944886) (xy 34.691778 -133.886993)
			(xy 34.714714 -133.83162) (xy 34.744681 -133.779714) (xy 34.781168 -133.732164) (xy 34.823548 -133.689784)
			(xy 34.871098 -133.653297) (xy 34.923004 -133.62333) (xy 34.978377 -133.600394) (xy 35.03627 -133.584881)
			(xy 35.095692 -133.577058) (xy 35.155628 -133.577058) (xy 35.21505 -133.584881) (xy 35.272943 -133.600394)
			(xy 35.328316 -133.62333) (xy 35.380222 -133.653297) (xy 35.427772 -133.689784) (xy 35.470152 -133.732164)
			(xy 35.506639 -133.779714) (xy 35.536606 -133.83162) (xy 35.559542 -133.886993) (xy 35.575055 -133.944886)
			(xy 35.582878 -134.004308) (xy 35.583368 -134.034276) (xy 35.583368 -134.896352) (xy 53.639212 -134.896352)
			(xy 53.639212 -134.032752) (xy 53.639702 -134.002784) (xy 53.647525 -133.943362) (xy 53.663038 -133.885469)
			(xy 53.685974 -133.830096) (xy 53.715941 -133.77819) (xy 53.752428 -133.73064) (xy 53.794808 -133.68826)
			(xy 53.842358 -133.651773) (xy 53.894264 -133.621806) (xy 53.949637 -133.59887) (xy 54.00753 -133.583357)
			(xy 54.066952 -133.575534) (xy 54.126888 -133.575534) (xy 54.18631 -133.583357) (xy 54.244203 -133.59887)
			(xy 54.299576 -133.621806) (xy 54.351482 -133.651773) (xy 54.399032 -133.68826) (xy 54.441412 -133.73064)
			(xy 54.477899 -133.77819) (xy 54.507866 -133.830096) (xy 54.530802 -133.885469) (xy 54.546315 -133.943362)
			(xy 54.554138 -134.002784) (xy 54.554628 -134.032752) (xy 54.554628 -134.377176) (xy 66.599308 -134.377176)
			(xy 66.599308 -133.513576) (xy 66.599798 -133.483592) (xy 66.607626 -133.424136) (xy 66.623147 -133.366211)
			(xy 66.646096 -133.310807) (xy 66.67608 -133.258873) (xy 66.712586 -133.211297) (xy 66.754991 -133.168892)
			(xy 66.802567 -133.132386) (xy 66.854501 -133.102402) (xy 66.909905 -133.079453) (xy 66.96783 -133.063932)
			(xy 67.027286 -133.056104) (xy 67.087254 -133.056104) (xy 67.14671 -133.063932) (xy 67.204635 -133.079453)
			(xy 67.260039 -133.102402) (xy 67.311973 -133.132386) (xy 67.359549 -133.168892) (xy 67.401954 -133.211297)
			(xy 67.43846 -133.258873) (xy 67.468444 -133.310807) (xy 67.491393 -133.366211) (xy 67.506914 -133.424136)
			(xy 67.514742 -133.483592) (xy 67.515232 -133.513576) (xy 67.515232 -134.369302) (xy 81.07426 -134.369302)
			(xy 81.07426 -133.505702) (xy 81.07475 -133.475718) (xy 81.082578 -133.416262) (xy 81.098099 -133.358337)
			(xy 81.121048 -133.302933) (xy 81.151032 -133.250999) (xy 81.187538 -133.203423) (xy 81.229943 -133.161018)
			(xy 81.277519 -133.124512) (xy 81.329453 -133.094528) (xy 81.384857 -133.071579) (xy 81.442782 -133.056058)
			(xy 81.502238 -133.04823) (xy 81.562206 -133.04823) (xy 81.621662 -133.056058) (xy 81.679587 -133.071579)
			(xy 81.734991 -133.094528) (xy 81.752059 -133.104382) (xy 153.409904 -133.104382) (xy 153.409904 -132.240782)
			(xy 153.410394 -132.210798) (xy 153.418222 -132.151342) (xy 153.433743 -132.093417) (xy 153.456692 -132.038013)
			(xy 153.486676 -131.986079) (xy 153.523182 -131.938503) (xy 153.565587 -131.896098) (xy 153.613163 -131.859592)
			(xy 153.665097 -131.829608) (xy 153.720501 -131.806659) (xy 153.778426 -131.791138) (xy 153.837882 -131.78331)
			(xy 153.89785 -131.78331) (xy 153.957306 -131.791138) (xy 154.015231 -131.806659) (xy 154.070635 -131.829608)
			(xy 154.122569 -131.859592) (xy 154.170145 -131.896098) (xy 154.21255 -131.938503) (xy 154.249056 -131.986079)
			(xy 154.27904 -132.038013) (xy 154.301989 -132.093417) (xy 154.31751 -132.151342) (xy 154.325338 -132.210798)
			(xy 154.325828 -132.240782) (xy 154.325828 -133.096508) (xy 167.884856 -133.096508) (xy 167.884856 -132.232908)
			(xy 167.885346 -132.202924) (xy 167.893174 -132.143468) (xy 167.908695 -132.085543) (xy 167.931644 -132.030139)
			(xy 167.961628 -131.978205) (xy 167.998134 -131.930629) (xy 168.040539 -131.888224) (xy 168.088115 -131.851718)
			(xy 168.140049 -131.821734) (xy 168.195453 -131.798785) (xy 168.253378 -131.783264) (xy 168.312834 -131.775436)
			(xy 168.372802 -131.775436) (xy 168.432258 -131.783264) (xy 168.490183 -131.798785) (xy 168.545587 -131.821734)
			(xy 168.597521 -131.851718) (xy 168.645097 -131.888224) (xy 168.687502 -131.930629) (xy 168.724008 -131.978205)
			(xy 168.753992 -132.030139) (xy 168.776941 -132.085543) (xy 168.792462 -132.143468) (xy 168.80029 -132.202924)
			(xy 168.80078 -132.232908) (xy 168.80078 -132.577332) (xy 180.84546 -132.577332) (xy 180.84546 -131.713732)
			(xy 180.84595 -131.683764) (xy 180.853773 -131.624342) (xy 180.869286 -131.566449) (xy 180.892222 -131.511076)
			(xy 180.922189 -131.45917) (xy 180.958676 -131.41162) (xy 181.001056 -131.36924) (xy 181.048606 -131.332753)
			(xy 181.100512 -131.302786) (xy 181.155885 -131.27985) (xy 181.213778 -131.264337) (xy 181.2732 -131.256514)
			(xy 181.333136 -131.256514) (xy 181.392558 -131.264337) (xy 181.450451 -131.27985) (xy 181.505824 -131.302786)
			(xy 181.55773 -131.332753) (xy 181.60528 -131.36924) (xy 181.64766 -131.41162) (xy 181.684147 -131.45917)
			(xy 181.714114 -131.511076) (xy 181.73705 -131.566449) (xy 181.752563 -131.624342) (xy 181.760386 -131.683764)
			(xy 181.760876 -131.713732) (xy 181.760876 -132.575808) (xy 199.81672 -132.575808) (xy 199.81672 -131.712208)
			(xy 199.81721 -131.68224) (xy 199.825033 -131.622818) (xy 199.840546 -131.564925) (xy 199.863482 -131.509552)
			(xy 199.893449 -131.457646) (xy 199.929936 -131.410096) (xy 199.972316 -131.367716) (xy 200.019866 -131.331229)
			(xy 200.071772 -131.301262) (xy 200.127145 -131.278326) (xy 200.185038 -131.262813) (xy 200.24446 -131.25499)
			(xy 200.304396 -131.25499) (xy 200.363818 -131.262813) (xy 200.421711 -131.278326) (xy 200.469049 -131.297934)
			(xy 266.86764 -131.297934) (xy 266.86764 -130.434334) (xy 266.86813 -130.40435) (xy 266.875958 -130.344894)
			(xy 266.891479 -130.286969) (xy 266.914428 -130.231565) (xy 266.944412 -130.179631) (xy 266.980918 -130.132055)
			(xy 267.023323 -130.08965) (xy 267.070899 -130.053144) (xy 267.122833 -130.02316) (xy 267.178237 -130.000211)
			(xy 267.236162 -129.98469) (xy 267.295618 -129.976862) (xy 267.355586 -129.976862) (xy 267.415042 -129.98469)
			(xy 267.472967 -130.000211) (xy 267.528371 -130.02316) (xy 267.580305 -130.053144) (xy 267.627881 -130.08965)
			(xy 267.670286 -130.132055) (xy 267.706792 -130.179631) (xy 267.736776 -130.231565) (xy 267.759725 -130.286969)
			(xy 267.775246 -130.344894) (xy 267.783074 -130.40435) (xy 267.783564 -130.434334) (xy 267.783564 -131.29641)
			(xy 285.8389 -131.29641) (xy 285.8389 -130.43281) (xy 285.83939 -130.402826) (xy 285.847218 -130.34337)
			(xy 285.862739 -130.285445) (xy 285.885688 -130.230041) (xy 285.915672 -130.178107) (xy 285.952178 -130.130531)
			(xy 285.994583 -130.088126) (xy 286.042159 -130.05162) (xy 286.094093 -130.021636) (xy 286.149497 -129.998687)
			(xy 286.207422 -129.983166) (xy 286.266878 -129.975338) (xy 286.326846 -129.975338) (xy 286.386302 -129.983166)
			(xy 286.444227 -129.998687) (xy 286.499631 -130.021636) (xy 286.551565 -130.05162) (xy 286.599141 -130.088126)
			(xy 286.641546 -130.130531) (xy 286.678052 -130.178107) (xy 286.708036 -130.230041) (xy 286.730985 -130.285445)
			(xy 286.746506 -130.34337) (xy 286.754334 -130.402826) (xy 286.754824 -130.43281) (xy 286.754824 -130.777234)
			(xy 298.799504 -130.777234) (xy 298.799504 -129.913634) (xy 298.799994 -129.883666) (xy 298.807817 -129.824244)
			(xy 298.82333 -129.766351) (xy 298.846266 -129.710978) (xy 298.876233 -129.659072) (xy 298.91272 -129.611522)
			(xy 298.9551 -129.569142) (xy 299.00265 -129.532655) (xy 299.054556 -129.502688) (xy 299.109929 -129.479752)
			(xy 299.167822 -129.464239) (xy 299.227244 -129.456416) (xy 299.28718 -129.456416) (xy 299.346602 -129.464239)
			(xy 299.404495 -129.479752) (xy 299.459868 -129.502688) (xy 299.511774 -129.532655) (xy 299.559324 -129.569142)
			(xy 299.601704 -129.611522) (xy 299.638191 -129.659072) (xy 299.668158 -129.710978) (xy 299.691094 -129.766351)
			(xy 299.706607 -129.824244) (xy 299.71443 -129.883666) (xy 299.71492 -129.913634) (xy 299.71492 -130.769106)
			(xy 313.274456 -130.769106) (xy 313.274456 -129.905506) (xy 313.274946 -129.875538) (xy 313.282769 -129.816116)
			(xy 313.298282 -129.758223) (xy 313.321218 -129.70285) (xy 313.351185 -129.650944) (xy 313.387672 -129.603394)
			(xy 313.430052 -129.561014) (xy 313.477602 -129.524527) (xy 313.529508 -129.49456) (xy 313.584881 -129.471624)
			(xy 313.642774 -129.456111) (xy 313.702196 -129.448288) (xy 313.762132 -129.448288) (xy 313.821554 -129.456111)
			(xy 313.879447 -129.471624) (xy 313.93482 -129.49456) (xy 313.986726 -129.524527) (xy 314.034276 -129.561014)
			(xy 314.076656 -129.603394) (xy 314.113143 -129.650944) (xy 314.14311 -129.70285) (xy 314.166046 -129.758223)
			(xy 314.181559 -129.816116) (xy 314.189382 -129.875538) (xy 314.189872 -129.905506) (xy 314.189872 -130.769106)
			(xy 314.189382 -130.799074) (xy 314.181559 -130.858496) (xy 314.166046 -130.916389) (xy 314.14311 -130.971762)
			(xy 314.113143 -131.023668) (xy 314.076656 -131.071218) (xy 314.034276 -131.113598) (xy 313.986726 -131.150085)
			(xy 313.93482 -131.180052) (xy 313.879447 -131.202988) (xy 313.821554 -131.218501) (xy 313.762132 -131.226324)
			(xy 313.702196 -131.226324) (xy 313.642774 -131.218501) (xy 313.584881 -131.202988) (xy 313.529508 -131.180052)
			(xy 313.477602 -131.150085) (xy 313.430052 -131.113598) (xy 313.387672 -131.071218) (xy 313.351185 -131.023668)
			(xy 313.321218 -130.971762) (xy 313.298282 -130.916389) (xy 313.282769 -130.858496) (xy 313.274946 -130.799074)
			(xy 313.274456 -130.769106) (xy 299.71492 -130.769106) (xy 299.71492 -130.777234) (xy 299.71443 -130.807202)
			(xy 299.706607 -130.866624) (xy 299.691094 -130.924517) (xy 299.668158 -130.97989) (xy 299.638191 -131.031796)
			(xy 299.601704 -131.079346) (xy 299.559324 -131.121726) (xy 299.511774 -131.158213) (xy 299.459868 -131.18818)
			(xy 299.404495 -131.211116) (xy 299.346602 -131.226629) (xy 299.28718 -131.234452) (xy 299.227244 -131.234452)
			(xy 299.167822 -131.226629) (xy 299.109929 -131.211116) (xy 299.054556 -131.18818) (xy 299.00265 -131.158213)
			(xy 298.9551 -131.121726) (xy 298.91272 -131.079346) (xy 298.876233 -131.031796) (xy 298.846266 -130.97989)
			(xy 298.82333 -130.924517) (xy 298.807817 -130.866624) (xy 298.799994 -130.807202) (xy 298.799504 -130.777234)
			(xy 286.754824 -130.777234) (xy 286.754824 -131.29641) (xy 286.754334 -131.326394) (xy 286.746506 -131.38585)
			(xy 286.730985 -131.443775) (xy 286.708036 -131.499179) (xy 286.678052 -131.551113) (xy 286.641546 -131.598689)
			(xy 286.599141 -131.641094) (xy 286.551565 -131.6776) (xy 286.499631 -131.707584) (xy 286.444227 -131.730533)
			(xy 286.386302 -131.746054) (xy 286.326846 -131.753882) (xy 286.266878 -131.753882) (xy 286.207422 -131.746054)
			(xy 286.149497 -131.730533) (xy 286.094093 -131.707584) (xy 286.042159 -131.6776) (xy 285.994583 -131.641094)
			(xy 285.952178 -131.598689) (xy 285.915672 -131.551113) (xy 285.885688 -131.499179) (xy 285.862739 -131.443775)
			(xy 285.847218 -131.38585) (xy 285.83939 -131.326394) (xy 285.8389 -131.29641) (xy 267.783564 -131.29641)
			(xy 267.783564 -131.297934) (xy 267.783074 -131.327918) (xy 267.775246 -131.387374) (xy 267.759725 -131.445299)
			(xy 267.736776 -131.500703) (xy 267.706792 -131.552637) (xy 267.670286 -131.600213) (xy 267.627881 -131.642618)
			(xy 267.580305 -131.679124) (xy 267.528371 -131.709108) (xy 267.472967 -131.732057) (xy 267.415042 -131.747578)
			(xy 267.355586 -131.755406) (xy 267.295618 -131.755406) (xy 267.236162 -131.747578) (xy 267.178237 -131.732057)
			(xy 267.122833 -131.709108) (xy 267.070899 -131.679124) (xy 267.023323 -131.642618) (xy 266.980918 -131.600213)
			(xy 266.944412 -131.552637) (xy 266.914428 -131.500703) (xy 266.891479 -131.445299) (xy 266.875958 -131.387374)
			(xy 266.86813 -131.327918) (xy 266.86764 -131.297934) (xy 200.469049 -131.297934) (xy 200.477084 -131.301262)
			(xy 200.52899 -131.331229) (xy 200.57654 -131.367716) (xy 200.61892 -131.410096) (xy 200.655407 -131.457646)
			(xy 200.685374 -131.509552) (xy 200.70831 -131.564925) (xy 200.723823 -131.622818) (xy 200.731646 -131.68224)
			(xy 200.732136 -131.712208) (xy 200.732136 -132.575808) (xy 200.731646 -132.605776) (xy 200.723823 -132.665198)
			(xy 200.70831 -132.723091) (xy 200.685374 -132.778464) (xy 200.655407 -132.83037) (xy 200.61892 -132.87792)
			(xy 200.57654 -132.9203) (xy 200.52899 -132.956787) (xy 200.477084 -132.986754) (xy 200.421711 -133.00969)
			(xy 200.363818 -133.025203) (xy 200.304396 -133.033026) (xy 200.24446 -133.033026) (xy 200.185038 -133.025203)
			(xy 200.127145 -133.00969) (xy 200.071772 -132.986754) (xy 200.019866 -132.956787) (xy 199.972316 -132.9203)
			(xy 199.929936 -132.87792) (xy 199.893449 -132.83037) (xy 199.863482 -132.778464) (xy 199.840546 -132.723091)
			(xy 199.825033 -132.665198) (xy 199.81721 -132.605776) (xy 199.81672 -132.575808) (xy 181.760876 -132.575808)
			(xy 181.760876 -132.577332) (xy 181.760386 -132.6073) (xy 181.752563 -132.666722) (xy 181.73705 -132.724615)
			(xy 181.714114 -132.779988) (xy 181.684147 -132.831894) (xy 181.64766 -132.879444) (xy 181.60528 -132.921824)
			(xy 181.55773 -132.958311) (xy 181.505824 -132.988278) (xy 181.450451 -133.011214) (xy 181.392558 -133.026727)
			(xy 181.333136 -133.03455) (xy 181.2732 -133.03455) (xy 181.213778 -133.026727) (xy 181.155885 -133.011214)
			(xy 181.100512 -132.988278) (xy 181.048606 -132.958311) (xy 181.001056 -132.921824) (xy 180.958676 -132.879444)
			(xy 180.922189 -132.831894) (xy 180.892222 -132.779988) (xy 180.869286 -132.724615) (xy 180.853773 -132.666722)
			(xy 180.84595 -132.6073) (xy 180.84546 -132.577332) (xy 168.80078 -132.577332) (xy 168.80078 -133.096508)
			(xy 168.80029 -133.126492) (xy 168.792462 -133.185948) (xy 168.776941 -133.243873) (xy 168.753992 -133.299277)
			(xy 168.724008 -133.351211) (xy 168.687502 -133.398787) (xy 168.645097 -133.441192) (xy 168.597521 -133.477698)
			(xy 168.545587 -133.507682) (xy 168.490183 -133.530631) (xy 168.432258 -133.546152) (xy 168.372802 -133.55398)
			(xy 168.312834 -133.55398) (xy 168.253378 -133.546152) (xy 168.195453 -133.530631) (xy 168.140049 -133.507682)
			(xy 168.088115 -133.477698) (xy 168.040539 -133.441192) (xy 167.998134 -133.398787) (xy 167.961628 -133.351211)
			(xy 167.931644 -133.299277) (xy 167.908695 -133.243873) (xy 167.893174 -133.185948) (xy 167.885346 -133.126492)
			(xy 167.884856 -133.096508) (xy 154.325828 -133.096508) (xy 154.325828 -133.104382) (xy 154.325338 -133.134366)
			(xy 154.31751 -133.193822) (xy 154.301989 -133.251747) (xy 154.27904 -133.307151) (xy 154.249056 -133.359085)
			(xy 154.21255 -133.406661) (xy 154.170145 -133.449066) (xy 154.122569 -133.485572) (xy 154.070635 -133.515556)
			(xy 154.015231 -133.538505) (xy 153.957306 -133.554026) (xy 153.89785 -133.561854) (xy 153.837882 -133.561854)
			(xy 153.778426 -133.554026) (xy 153.720501 -133.538505) (xy 153.665097 -133.515556) (xy 153.613163 -133.485572)
			(xy 153.565587 -133.449066) (xy 153.523182 -133.406661) (xy 153.486676 -133.359085) (xy 153.456692 -133.307151)
			(xy 153.433743 -133.251747) (xy 153.418222 -133.193822) (xy 153.410394 -133.134366) (xy 153.409904 -133.104382)
			(xy 81.752059 -133.104382) (xy 81.786925 -133.124512) (xy 81.834501 -133.161018) (xy 81.876906 -133.203423)
			(xy 81.913412 -133.250999) (xy 81.943396 -133.302933) (xy 81.966345 -133.358337) (xy 81.981866 -133.416262)
			(xy 81.989694 -133.475718) (xy 81.990184 -133.505702) (xy 81.990184 -134.369302) (xy 81.989694 -134.399286)
			(xy 81.981866 -134.458742) (xy 81.966345 -134.516667) (xy 81.943396 -134.572071) (xy 81.913412 -134.624005)
			(xy 81.876906 -134.671581) (xy 81.834501 -134.713986) (xy 81.786925 -134.750492) (xy 81.734991 -134.780476)
			(xy 81.679587 -134.803425) (xy 81.621662 -134.818946) (xy 81.562206 -134.826774) (xy 81.502238 -134.826774)
			(xy 81.442782 -134.818946) (xy 81.384857 -134.803425) (xy 81.329453 -134.780476) (xy 81.277519 -134.750492)
			(xy 81.229943 -134.713986) (xy 81.187538 -134.671581) (xy 81.151032 -134.624005) (xy 81.121048 -134.572071)
			(xy 81.098099 -134.516667) (xy 81.082578 -134.458742) (xy 81.07475 -134.399286) (xy 81.07426 -134.369302)
			(xy 67.515232 -134.369302) (xy 67.515232 -134.377176) (xy 67.514742 -134.40716) (xy 67.506914 -134.466616)
			(xy 67.491393 -134.524541) (xy 67.468444 -134.579945) (xy 67.43846 -134.631879) (xy 67.401954 -134.679455)
			(xy 67.359549 -134.72186) (xy 67.311973 -134.758366) (xy 67.260039 -134.78835) (xy 67.204635 -134.811299)
			(xy 67.14671 -134.82682) (xy 67.087254 -134.834648) (xy 67.027286 -134.834648) (xy 66.96783 -134.82682)
			(xy 66.909905 -134.811299) (xy 66.854501 -134.78835) (xy 66.802567 -134.758366) (xy 66.754991 -134.72186)
			(xy 66.712586 -134.679455) (xy 66.67608 -134.631879) (xy 66.646096 -134.579945) (xy 66.623147 -134.524541)
			(xy 66.607626 -134.466616) (xy 66.599798 -134.40716) (xy 66.599308 -134.377176) (xy 54.554628 -134.377176)
			(xy 54.554628 -134.896352) (xy 54.554138 -134.92632) (xy 54.546315 -134.985742) (xy 54.530802 -135.043635)
			(xy 54.507866 -135.099008) (xy 54.477899 -135.150914) (xy 54.441412 -135.198464) (xy 54.399032 -135.240844)
			(xy 54.351482 -135.277331) (xy 54.299576 -135.307298) (xy 54.244203 -135.330234) (xy 54.18631 -135.345747)
			(xy 54.126888 -135.35357) (xy 54.066952 -135.35357) (xy 54.00753 -135.345747) (xy 53.949637 -135.330234)
			(xy 53.894264 -135.307298) (xy 53.842358 -135.277331) (xy 53.794808 -135.240844) (xy 53.752428 -135.198464)
			(xy 53.715941 -135.150914) (xy 53.685974 -135.099008) (xy 53.663038 -135.043635) (xy 53.647525 -134.985742)
			(xy 53.639702 -134.92632) (xy 53.639212 -134.896352) (xy 35.583368 -134.896352) (xy 35.583368 -134.897876)
			(xy 35.582878 -134.927844) (xy 35.575055 -134.987266) (xy 35.559542 -135.045159) (xy 35.536606 -135.100532)
			(xy 35.506639 -135.152438) (xy 35.470152 -135.199988) (xy 35.427772 -135.242368) (xy 35.380222 -135.278855)
			(xy 35.328316 -135.308822) (xy 35.272943 -135.331758) (xy 35.21505 -135.347271) (xy 35.155628 -135.355094)
			(xy 35.095692 -135.355094) (xy 35.03627 -135.347271) (xy 34.978377 -135.331758) (xy 34.923004 -135.308822)
			(xy 34.871098 -135.278855) (xy 34.823548 -135.242368) (xy 34.781168 -135.199988) (xy 34.744681 -135.152438)
			(xy 34.714714 -135.100532) (xy 34.691778 -135.045159) (xy 34.676265 -134.987266) (xy 34.668442 -134.927844)
			(xy 34.667952 -134.897876) (xy 4.308094 -134.897876) (xy 4.308094 -136.704324) (xy 37.31006 -136.704324)
			(xy 37.31006 -135.840724) (xy 37.31055 -135.810756) (xy 37.318373 -135.751334) (xy 37.333886 -135.693441)
			(xy 37.356822 -135.638068) (xy 37.386789 -135.586162) (xy 37.423276 -135.538612) (xy 37.465656 -135.496232)
			(xy 37.513206 -135.459745) (xy 37.565112 -135.429778) (xy 37.620485 -135.406842) (xy 37.678378 -135.391329)
			(xy 37.7378 -135.383506) (xy 37.797736 -135.383506) (xy 37.857158 -135.391329) (xy 37.915051 -135.406842)
			(xy 37.970424 -135.429778) (xy 38.02233 -135.459745) (xy 38.06988 -135.496232) (xy 38.11226 -135.538612)
			(xy 38.148747 -135.586162) (xy 38.178714 -135.638068) (xy 38.20165 -135.693441) (xy 38.217163 -135.751334)
			(xy 38.224986 -135.810756) (xy 38.225476 -135.840724) (xy 38.225476 -136.69645) (xy 51.785012 -136.69645)
			(xy 51.785012 -135.83285) (xy 51.785502 -135.802882) (xy 51.793325 -135.74346) (xy 51.808838 -135.685567)
			(xy 51.831774 -135.630194) (xy 51.861741 -135.578288) (xy 51.898228 -135.530738) (xy 51.940608 -135.488358)
			(xy 51.988158 -135.451871) (xy 52.040064 -135.421904) (xy 52.095437 -135.398968) (xy 52.15333 -135.383455)
			(xy 52.212752 -135.375632) (xy 52.272688 -135.375632) (xy 52.33211 -135.383455) (xy 52.390003 -135.398968)
			(xy 52.445376 -135.421904) (xy 52.497282 -135.451871) (xy 52.544832 -135.488358) (xy 52.587212 -135.530738)
			(xy 52.623699 -135.578288) (xy 52.653666 -135.630194) (xy 52.676602 -135.685567) (xy 52.692115 -135.74346)
			(xy 52.699938 -135.802882) (xy 52.700428 -135.83285) (xy 52.700428 -136.177274) (xy 64.745108 -136.177274)
			(xy 64.745108 -135.313674) (xy 64.745598 -135.28369) (xy 64.753426 -135.224234) (xy 64.768947 -135.166309)
			(xy 64.791896 -135.110905) (xy 64.82188 -135.058971) (xy 64.858386 -135.011395) (xy 64.900791 -134.96899)
			(xy 64.948367 -134.932484) (xy 65.000301 -134.9025) (xy 65.055705 -134.879551) (xy 65.11363 -134.86403)
			(xy 65.173086 -134.856202) (xy 65.233054 -134.856202) (xy 65.29251 -134.86403) (xy 65.350435 -134.879551)
			(xy 65.405839 -134.9025) (xy 65.457773 -134.932484) (xy 65.505349 -134.96899) (xy 65.547754 -135.011395)
			(xy 65.58426 -135.058971) (xy 65.614244 -135.110905) (xy 65.637193 -135.166309) (xy 65.652714 -135.224234)
			(xy 65.660542 -135.28369) (xy 65.661032 -135.313674) (xy 65.661032 -136.17575) (xy 83.716368 -136.17575)
			(xy 83.716368 -135.31215) (xy 83.716858 -135.282166) (xy 83.724686 -135.22271) (xy 83.740207 -135.164785)
			(xy 83.763156 -135.109381) (xy 83.79314 -135.057447) (xy 83.829646 -135.009871) (xy 83.872051 -134.967466)
			(xy 83.919627 -134.93096) (xy 83.971561 -134.900976) (xy 84.026965 -134.878027) (xy 84.08489 -134.862506)
			(xy 84.144346 -134.854678) (xy 84.204314 -134.854678) (xy 84.26377 -134.862506) (xy 84.321695 -134.878027)
			(xy 84.369615 -134.897876) (xy 150.767796 -134.897876) (xy 150.767796 -134.034276) (xy 150.768286 -134.004292)
			(xy 150.776114 -133.944836) (xy 150.791635 -133.886911) (xy 150.814584 -133.831507) (xy 150.844568 -133.779573)
			(xy 150.881074 -133.731997) (xy 150.923479 -133.689592) (xy 150.971055 -133.653086) (xy 151.022989 -133.623102)
			(xy 151.078393 -133.600153) (xy 151.136318 -133.584632) (xy 151.195774 -133.576804) (xy 151.255742 -133.576804)
			(xy 151.315198 -133.584632) (xy 151.373123 -133.600153) (xy 151.428527 -133.623102) (xy 151.480461 -133.653086)
			(xy 151.528037 -133.689592) (xy 151.570442 -133.731997) (xy 151.606948 -133.779573) (xy 151.636932 -133.831507)
			(xy 151.659881 -133.886911) (xy 151.675402 -133.944836) (xy 151.68323 -134.004292) (xy 151.68372 -134.034276)
			(xy 151.68372 -134.896352) (xy 169.739056 -134.896352) (xy 169.739056 -134.032752) (xy 169.739546 -134.002768)
			(xy 169.747374 -133.943312) (xy 169.762895 -133.885387) (xy 169.785844 -133.829983) (xy 169.815828 -133.778049)
			(xy 169.852334 -133.730473) (xy 169.894739 -133.688068) (xy 169.942315 -133.651562) (xy 169.994249 -133.621578)
			(xy 170.049653 -133.598629) (xy 170.107578 -133.583108) (xy 170.167034 -133.57528) (xy 170.227002 -133.57528)
			(xy 170.286458 -133.583108) (xy 170.344383 -133.598629) (xy 170.399787 -133.621578) (xy 170.451721 -133.651562)
			(xy 170.499297 -133.688068) (xy 170.541702 -133.730473) (xy 170.578208 -133.778049) (xy 170.608192 -133.829983)
			(xy 170.631141 -133.885387) (xy 170.646662 -133.943312) (xy 170.65449 -134.002768) (xy 170.65498 -134.032752)
			(xy 170.65498 -134.377176) (xy 182.69966 -134.377176) (xy 182.69966 -133.513576) (xy 182.70015 -133.483608)
			(xy 182.707973 -133.424186) (xy 182.723486 -133.366293) (xy 182.746422 -133.31092) (xy 182.776389 -133.259014)
			(xy 182.812876 -133.211464) (xy 182.855256 -133.169084) (xy 182.902806 -133.132597) (xy 182.954712 -133.10263)
			(xy 183.010085 -133.079694) (xy 183.067978 -133.064181) (xy 183.1274 -133.056358) (xy 183.187336 -133.056358)
			(xy 183.246758 -133.064181) (xy 183.304651 -133.079694) (xy 183.360024 -133.10263) (xy 183.41193 -133.132597)
			(xy 183.45948 -133.169084) (xy 183.50186 -133.211464) (xy 183.538347 -133.259014) (xy 183.568314 -133.31092)
			(xy 183.59125 -133.366293) (xy 183.606763 -133.424186) (xy 183.614586 -133.483608) (xy 183.615076 -133.513576)
			(xy 183.615076 -134.369302) (xy 197.174612 -134.369302) (xy 197.174612 -133.505702) (xy 197.175102 -133.475734)
			(xy 197.182925 -133.416312) (xy 197.198438 -133.358419) (xy 197.221374 -133.303046) (xy 197.251341 -133.25114)
			(xy 197.287828 -133.20359) (xy 197.330208 -133.16121) (xy 197.377758 -133.124723) (xy 197.429664 -133.094756)
			(xy 197.485037 -133.07182) (xy 197.54293 -133.056307) (xy 197.602352 -133.048484) (xy 197.662288 -133.048484)
			(xy 197.72171 -133.056307) (xy 197.779603 -133.07182) (xy 197.834976 -133.094756) (xy 197.851649 -133.104382)
			(xy 269.509748 -133.104382) (xy 269.509748 -132.240782) (xy 269.510238 -132.210798) (xy 269.518066 -132.151342)
			(xy 269.533587 -132.093417) (xy 269.556536 -132.038013) (xy 269.58652 -131.986079) (xy 269.623026 -131.938503)
			(xy 269.665431 -131.896098) (xy 269.713007 -131.859592) (xy 269.764941 -131.829608) (xy 269.820345 -131.806659)
			(xy 269.87827 -131.791138) (xy 269.937726 -131.78331) (xy 269.997694 -131.78331) (xy 270.05715 -131.791138)
			(xy 270.115075 -131.806659) (xy 270.170479 -131.829608) (xy 270.222413 -131.859592) (xy 270.269989 -131.896098)
			(xy 270.312394 -131.938503) (xy 270.3489 -131.986079) (xy 270.378884 -132.038013) (xy 270.401833 -132.093417)
			(xy 270.417354 -132.151342) (xy 270.425182 -132.210798) (xy 270.425672 -132.240782) (xy 270.425672 -133.096508)
			(xy 283.9847 -133.096508) (xy 283.9847 -132.232908) (xy 283.98519 -132.202924) (xy 283.993018 -132.143468)
			(xy 284.008539 -132.085543) (xy 284.031488 -132.030139) (xy 284.061472 -131.978205) (xy 284.097978 -131.930629)
			(xy 284.140383 -131.888224) (xy 284.187959 -131.851718) (xy 284.239893 -131.821734) (xy 284.295297 -131.798785)
			(xy 284.353222 -131.783264) (xy 284.412678 -131.775436) (xy 284.472646 -131.775436) (xy 284.532102 -131.783264)
			(xy 284.590027 -131.798785) (xy 284.645431 -131.821734) (xy 284.697365 -131.851718) (xy 284.744941 -131.888224)
			(xy 284.787346 -131.930629) (xy 284.823852 -131.978205) (xy 284.853836 -132.030139) (xy 284.876785 -132.085543)
			(xy 284.892306 -132.143468) (xy 284.900134 -132.202924) (xy 284.900624 -132.232908) (xy 284.900624 -132.577332)
			(xy 296.945304 -132.577332) (xy 296.945304 -131.713732) (xy 296.945794 -131.683764) (xy 296.953617 -131.624342)
			(xy 296.96913 -131.566449) (xy 296.992066 -131.511076) (xy 297.022033 -131.45917) (xy 297.05852 -131.41162)
			(xy 297.1009 -131.36924) (xy 297.14845 -131.332753) (xy 297.200356 -131.302786) (xy 297.255729 -131.27985)
			(xy 297.313622 -131.264337) (xy 297.373044 -131.256514) (xy 297.43298 -131.256514) (xy 297.492402 -131.264337)
			(xy 297.550295 -131.27985) (xy 297.605668 -131.302786) (xy 297.657574 -131.332753) (xy 297.705124 -131.36924)
			(xy 297.747504 -131.41162) (xy 297.783991 -131.45917) (xy 297.813958 -131.511076) (xy 297.836894 -131.566449)
			(xy 297.852407 -131.624342) (xy 297.86023 -131.683764) (xy 297.86072 -131.713732) (xy 297.86072 -132.575808)
			(xy 315.916564 -132.575808) (xy 315.916564 -131.712208) (xy 315.917054 -131.68224) (xy 315.924877 -131.622818)
			(xy 315.94039 -131.564925) (xy 315.963326 -131.509552) (xy 315.993293 -131.457646) (xy 316.02978 -131.410096)
			(xy 316.07216 -131.367716) (xy 316.11971 -131.331229) (xy 316.171616 -131.301262) (xy 316.226989 -131.278326)
			(xy 316.284882 -131.262813) (xy 316.344304 -131.25499) (xy 316.40424 -131.25499) (xy 316.463662 -131.262813)
			(xy 316.521555 -131.278326) (xy 316.568893 -131.297934) (xy 382.967992 -131.297934) (xy 382.967992 -130.434334)
			(xy 382.968482 -130.404366) (xy 382.976305 -130.344944) (xy 382.991818 -130.287051) (xy 383.014754 -130.231678)
			(xy 383.044721 -130.179772) (xy 383.081208 -130.132222) (xy 383.123588 -130.089842) (xy 383.171138 -130.053355)
			(xy 383.223044 -130.023388) (xy 383.278417 -130.000452) (xy 383.33631 -129.984939) (xy 383.395732 -129.977116)
			(xy 383.455668 -129.977116) (xy 383.51509 -129.984939) (xy 383.572983 -130.000452) (xy 383.628356 -130.023388)
			(xy 383.680262 -130.053355) (xy 383.727812 -130.089842) (xy 383.770192 -130.132222) (xy 383.806679 -130.179772)
			(xy 383.836646 -130.231678) (xy 383.859582 -130.287051) (xy 383.875095 -130.344944) (xy 383.882918 -130.404366)
			(xy 383.883408 -130.434334) (xy 383.883408 -131.29641) (xy 401.939252 -131.29641) (xy 401.939252 -130.43281)
			(xy 401.939742 -130.402842) (xy 401.947565 -130.34342) (xy 401.963078 -130.285527) (xy 401.986014 -130.230154)
			(xy 402.015981 -130.178248) (xy 402.052468 -130.130698) (xy 402.094848 -130.088318) (xy 402.142398 -130.051831)
			(xy 402.194304 -130.021864) (xy 402.249677 -129.998928) (xy 402.30757 -129.983415) (xy 402.366992 -129.975592)
			(xy 402.426928 -129.975592) (xy 402.48635 -129.983415) (xy 402.544243 -129.998928) (xy 402.599616 -130.021864)
			(xy 402.651522 -130.051831) (xy 402.699072 -130.088318) (xy 402.741452 -130.130698) (xy 402.777939 -130.178248)
			(xy 402.807906 -130.230154) (xy 402.830842 -130.285527) (xy 402.846355 -130.34342) (xy 402.854178 -130.402842)
			(xy 402.854668 -130.43281) (xy 402.854668 -130.777234) (xy 414.899348 -130.777234) (xy 414.899348 -129.913634)
			(xy 414.899838 -129.88365) (xy 414.907666 -129.824194) (xy 414.923187 -129.766269) (xy 414.946136 -129.710865)
			(xy 414.97612 -129.658931) (xy 415.012626 -129.611355) (xy 415.055031 -129.56895) (xy 415.102607 -129.532444)
			(xy 415.154541 -129.50246) (xy 415.209945 -129.479511) (xy 415.26787 -129.46399) (xy 415.327326 -129.456162)
			(xy 415.387294 -129.456162) (xy 415.44675 -129.46399) (xy 415.504675 -129.479511) (xy 415.560079 -129.50246)
			(xy 415.612013 -129.532444) (xy 415.659589 -129.56895) (xy 415.701994 -129.611355) (xy 415.7385 -129.658931)
			(xy 415.768484 -129.710865) (xy 415.791433 -129.766269) (xy 415.806954 -129.824194) (xy 415.814782 -129.88365)
			(xy 415.815272 -129.913634) (xy 415.815272 -130.769106) (xy 429.3743 -130.769106) (xy 429.3743 -129.905506)
			(xy 429.37479 -129.875522) (xy 429.382618 -129.816066) (xy 429.398139 -129.758141) (xy 429.421088 -129.702737)
			(xy 429.451072 -129.650803) (xy 429.487578 -129.603227) (xy 429.529983 -129.560822) (xy 429.577559 -129.524316)
			(xy 429.629493 -129.494332) (xy 429.684897 -129.471383) (xy 429.742822 -129.455862) (xy 429.802278 -129.448034)
			(xy 429.862246 -129.448034) (xy 429.921702 -129.455862) (xy 429.979627 -129.471383) (xy 430.035031 -129.494332)
			(xy 430.086965 -129.524316) (xy 430.134541 -129.560822) (xy 430.176946 -129.603227) (xy 430.213452 -129.650803)
			(xy 430.243436 -129.702737) (xy 430.266385 -129.758141) (xy 430.281906 -129.816066) (xy 430.289734 -129.875522)
			(xy 430.290224 -129.905506) (xy 430.290224 -130.769106) (xy 430.289734 -130.79909) (xy 430.281906 -130.858546)
			(xy 430.266385 -130.916471) (xy 430.243436 -130.971875) (xy 430.213452 -131.023809) (xy 430.176946 -131.071385)
			(xy 430.134541 -131.11379) (xy 430.086965 -131.150296) (xy 430.035031 -131.18028) (xy 429.979627 -131.203229)
			(xy 429.921702 -131.21875) (xy 429.862246 -131.226578) (xy 429.802278 -131.226578) (xy 429.742822 -131.21875)
			(xy 429.684897 -131.203229) (xy 429.629493 -131.18028) (xy 429.577559 -131.150296) (xy 429.529983 -131.11379)
			(xy 429.487578 -131.071385) (xy 429.451072 -131.023809) (xy 429.421088 -130.971875) (xy 429.398139 -130.916471)
			(xy 429.382618 -130.858546) (xy 429.37479 -130.79909) (xy 429.3743 -130.769106) (xy 415.815272 -130.769106)
			(xy 415.815272 -130.777234) (xy 415.814782 -130.807218) (xy 415.806954 -130.866674) (xy 415.791433 -130.924599)
			(xy 415.768484 -130.980003) (xy 415.7385 -131.031937) (xy 415.701994 -131.079513) (xy 415.659589 -131.121918)
			(xy 415.612013 -131.158424) (xy 415.560079 -131.188408) (xy 415.504675 -131.211357) (xy 415.44675 -131.226878)
			(xy 415.387294 -131.234706) (xy 415.327326 -131.234706) (xy 415.26787 -131.226878) (xy 415.209945 -131.211357)
			(xy 415.154541 -131.188408) (xy 415.102607 -131.158424) (xy 415.055031 -131.121918) (xy 415.012626 -131.079513)
			(xy 414.97612 -131.031937) (xy 414.946136 -130.980003) (xy 414.923187 -130.924599) (xy 414.907666 -130.866674)
			(xy 414.899838 -130.807218) (xy 414.899348 -130.777234) (xy 402.854668 -130.777234) (xy 402.854668 -131.29641)
			(xy 402.854178 -131.326378) (xy 402.846355 -131.3858) (xy 402.830842 -131.443693) (xy 402.807906 -131.499066)
			(xy 402.777939 -131.550972) (xy 402.741452 -131.598522) (xy 402.699072 -131.640902) (xy 402.651522 -131.677389)
			(xy 402.599616 -131.707356) (xy 402.544243 -131.730292) (xy 402.48635 -131.745805) (xy 402.426928 -131.753628)
			(xy 402.366992 -131.753628) (xy 402.30757 -131.745805) (xy 402.249677 -131.730292) (xy 402.194304 -131.707356)
			(xy 402.142398 -131.677389) (xy 402.094848 -131.640902) (xy 402.052468 -131.598522) (xy 402.015981 -131.550972)
			(xy 401.986014 -131.499066) (xy 401.963078 -131.443693) (xy 401.947565 -131.3858) (xy 401.939742 -131.326378)
			(xy 401.939252 -131.29641) (xy 383.883408 -131.29641) (xy 383.883408 -131.297934) (xy 383.882918 -131.327902)
			(xy 383.875095 -131.387324) (xy 383.859582 -131.445217) (xy 383.836646 -131.50059) (xy 383.806679 -131.552496)
			(xy 383.770192 -131.600046) (xy 383.727812 -131.642426) (xy 383.680262 -131.678913) (xy 383.628356 -131.70888)
			(xy 383.572983 -131.731816) (xy 383.51509 -131.747329) (xy 383.455668 -131.755152) (xy 383.395732 -131.755152)
			(xy 383.33631 -131.747329) (xy 383.278417 -131.731816) (xy 383.223044 -131.70888) (xy 383.171138 -131.678913)
			(xy 383.123588 -131.642426) (xy 383.081208 -131.600046) (xy 383.044721 -131.552496) (xy 383.014754 -131.50059)
			(xy 382.991818 -131.445217) (xy 382.976305 -131.387324) (xy 382.968482 -131.327902) (xy 382.967992 -131.297934)
			(xy 316.568893 -131.297934) (xy 316.576928 -131.301262) (xy 316.628834 -131.331229) (xy 316.676384 -131.367716)
			(xy 316.718764 -131.410096) (xy 316.755251 -131.457646) (xy 316.785218 -131.509552) (xy 316.808154 -131.564925)
			(xy 316.823667 -131.622818) (xy 316.83149 -131.68224) (xy 316.83198 -131.712208) (xy 316.83198 -132.575808)
			(xy 316.83149 -132.605776) (xy 316.823667 -132.665198) (xy 316.808154 -132.723091) (xy 316.785218 -132.778464)
			(xy 316.755251 -132.83037) (xy 316.718764 -132.87792) (xy 316.676384 -132.9203) (xy 316.628834 -132.956787)
			(xy 316.576928 -132.986754) (xy 316.521555 -133.00969) (xy 316.463662 -133.025203) (xy 316.40424 -133.033026)
			(xy 316.344304 -133.033026) (xy 316.284882 -133.025203) (xy 316.226989 -133.00969) (xy 316.171616 -132.986754)
			(xy 316.11971 -132.956787) (xy 316.07216 -132.9203) (xy 316.02978 -132.87792) (xy 315.993293 -132.83037)
			(xy 315.963326 -132.778464) (xy 315.94039 -132.723091) (xy 315.924877 -132.665198) (xy 315.917054 -132.605776)
			(xy 315.916564 -132.575808) (xy 297.86072 -132.575808) (xy 297.86072 -132.577332) (xy 297.86023 -132.6073)
			(xy 297.852407 -132.666722) (xy 297.836894 -132.724615) (xy 297.813958 -132.779988) (xy 297.783991 -132.831894)
			(xy 297.747504 -132.879444) (xy 297.705124 -132.921824) (xy 297.657574 -132.958311) (xy 297.605668 -132.988278)
			(xy 297.550295 -133.011214) (xy 297.492402 -133.026727) (xy 297.43298 -133.03455) (xy 297.373044 -133.03455)
			(xy 297.313622 -133.026727) (xy 297.255729 -133.011214) (xy 297.200356 -132.988278) (xy 297.14845 -132.958311)
			(xy 297.1009 -132.921824) (xy 297.05852 -132.879444) (xy 297.022033 -132.831894) (xy 296.992066 -132.779988)
			(xy 296.96913 -132.724615) (xy 296.953617 -132.666722) (xy 296.945794 -132.6073) (xy 296.945304 -132.577332)
			(xy 284.900624 -132.577332) (xy 284.900624 -133.096508) (xy 284.900134 -133.126492) (xy 284.892306 -133.185948)
			(xy 284.876785 -133.243873) (xy 284.853836 -133.299277) (xy 284.823852 -133.351211) (xy 284.787346 -133.398787)
			(xy 284.744941 -133.441192) (xy 284.697365 -133.477698) (xy 284.645431 -133.507682) (xy 284.590027 -133.530631)
			(xy 284.532102 -133.546152) (xy 284.472646 -133.55398) (xy 284.412678 -133.55398) (xy 284.353222 -133.546152)
			(xy 284.295297 -133.530631) (xy 284.239893 -133.507682) (xy 284.187959 -133.477698) (xy 284.140383 -133.441192)
			(xy 284.097978 -133.398787) (xy 284.061472 -133.351211) (xy 284.031488 -133.299277) (xy 284.008539 -133.243873)
			(xy 283.993018 -133.185948) (xy 283.98519 -133.126492) (xy 283.9847 -133.096508) (xy 270.425672 -133.096508)
			(xy 270.425672 -133.104382) (xy 270.425182 -133.134366) (xy 270.417354 -133.193822) (xy 270.401833 -133.251747)
			(xy 270.378884 -133.307151) (xy 270.3489 -133.359085) (xy 270.312394 -133.406661) (xy 270.269989 -133.449066)
			(xy 270.222413 -133.485572) (xy 270.170479 -133.515556) (xy 270.115075 -133.538505) (xy 270.05715 -133.554026)
			(xy 269.997694 -133.561854) (xy 269.937726 -133.561854) (xy 269.87827 -133.554026) (xy 269.820345 -133.538505)
			(xy 269.764941 -133.515556) (xy 269.713007 -133.485572) (xy 269.665431 -133.449066) (xy 269.623026 -133.406661)
			(xy 269.58652 -133.359085) (xy 269.556536 -133.307151) (xy 269.533587 -133.251747) (xy 269.518066 -133.193822)
			(xy 269.510238 -133.134366) (xy 269.509748 -133.104382) (xy 197.851649 -133.104382) (xy 197.886882 -133.124723)
			(xy 197.934432 -133.16121) (xy 197.976812 -133.20359) (xy 198.013299 -133.25114) (xy 198.043266 -133.303046)
			(xy 198.066202 -133.358419) (xy 198.081715 -133.416312) (xy 198.089538 -133.475734) (xy 198.090028 -133.505702)
			(xy 198.090028 -134.369302) (xy 198.089538 -134.39927) (xy 198.081715 -134.458692) (xy 198.066202 -134.516585)
			(xy 198.043266 -134.571958) (xy 198.013299 -134.623864) (xy 197.976812 -134.671414) (xy 197.934432 -134.713794)
			(xy 197.886882 -134.750281) (xy 197.834976 -134.780248) (xy 197.779603 -134.803184) (xy 197.72171 -134.818697)
			(xy 197.662288 -134.82652) (xy 197.602352 -134.82652) (xy 197.54293 -134.818697) (xy 197.485037 -134.803184)
			(xy 197.429664 -134.780248) (xy 197.377758 -134.750281) (xy 197.330208 -134.713794) (xy 197.287828 -134.671414)
			(xy 197.251341 -134.623864) (xy 197.221374 -134.571958) (xy 197.198438 -134.516585) (xy 197.182925 -134.458692)
			(xy 197.175102 -134.39927) (xy 197.174612 -134.369302) (xy 183.615076 -134.369302) (xy 183.615076 -134.377176)
			(xy 183.614586 -134.407144) (xy 183.606763 -134.466566) (xy 183.59125 -134.524459) (xy 183.568314 -134.579832)
			(xy 183.538347 -134.631738) (xy 183.50186 -134.679288) (xy 183.45948 -134.721668) (xy 183.41193 -134.758155)
			(xy 183.360024 -134.788122) (xy 183.304651 -134.811058) (xy 183.246758 -134.826571) (xy 183.187336 -134.834394)
			(xy 183.1274 -134.834394) (xy 183.067978 -134.826571) (xy 183.010085 -134.811058) (xy 182.954712 -134.788122)
			(xy 182.902806 -134.758155) (xy 182.855256 -134.721668) (xy 182.812876 -134.679288) (xy 182.776389 -134.631738)
			(xy 182.746422 -134.579832) (xy 182.723486 -134.524459) (xy 182.707973 -134.466566) (xy 182.70015 -134.407144)
			(xy 182.69966 -134.377176) (xy 170.65498 -134.377176) (xy 170.65498 -134.896352) (xy 170.65449 -134.926336)
			(xy 170.646662 -134.985792) (xy 170.631141 -135.043717) (xy 170.608192 -135.099121) (xy 170.578208 -135.151055)
			(xy 170.541702 -135.198631) (xy 170.499297 -135.241036) (xy 170.451721 -135.277542) (xy 170.399787 -135.307526)
			(xy 170.344383 -135.330475) (xy 170.286458 -135.345996) (xy 170.227002 -135.353824) (xy 170.167034 -135.353824)
			(xy 170.107578 -135.345996) (xy 170.049653 -135.330475) (xy 169.994249 -135.307526) (xy 169.942315 -135.277542)
			(xy 169.894739 -135.241036) (xy 169.852334 -135.198631) (xy 169.815828 -135.151055) (xy 169.785844 -135.099121)
			(xy 169.762895 -135.043717) (xy 169.747374 -134.985792) (xy 169.739546 -134.926336) (xy 169.739056 -134.896352)
			(xy 151.68372 -134.896352) (xy 151.68372 -134.897876) (xy 151.68323 -134.92786) (xy 151.675402 -134.987316)
			(xy 151.659881 -135.045241) (xy 151.636932 -135.100645) (xy 151.606948 -135.152579) (xy 151.570442 -135.200155)
			(xy 151.528037 -135.24256) (xy 151.480461 -135.279066) (xy 151.428527 -135.30905) (xy 151.373123 -135.331999)
			(xy 151.315198 -135.34752) (xy 151.255742 -135.355348) (xy 151.195774 -135.355348) (xy 151.136318 -135.34752)
			(xy 151.078393 -135.331999) (xy 151.022989 -135.30905) (xy 150.971055 -135.279066) (xy 150.923479 -135.24256)
			(xy 150.881074 -135.200155) (xy 150.844568 -135.152579) (xy 150.814584 -135.100645) (xy 150.791635 -135.045241)
			(xy 150.776114 -134.987316) (xy 150.768286 -134.92786) (xy 150.767796 -134.897876) (xy 84.369615 -134.897876)
			(xy 84.377099 -134.900976) (xy 84.429033 -134.93096) (xy 84.476609 -134.967466) (xy 84.519014 -135.009871)
			(xy 84.55552 -135.057447) (xy 84.585504 -135.109381) (xy 84.608453 -135.164785) (xy 84.623974 -135.22271)
			(xy 84.631802 -135.282166) (xy 84.632292 -135.31215) (xy 84.632292 -136.17575) (xy 84.631802 -136.205734)
			(xy 84.623974 -136.26519) (xy 84.608453 -136.323115) (xy 84.585504 -136.378519) (xy 84.55552 -136.430453)
			(xy 84.519014 -136.478029) (xy 84.476609 -136.520434) (xy 84.429033 -136.55694) (xy 84.377099 -136.586924)
			(xy 84.321695 -136.609873) (xy 84.26377 -136.625394) (xy 84.204314 -136.633222) (xy 84.144346 -136.633222)
			(xy 84.08489 -136.625394) (xy 84.026965 -136.609873) (xy 83.971561 -136.586924) (xy 83.919627 -136.55694)
			(xy 83.872051 -136.520434) (xy 83.829646 -136.478029) (xy 83.79314 -136.430453) (xy 83.763156 -136.378519)
			(xy 83.740207 -136.323115) (xy 83.724686 -136.26519) (xy 83.716858 -136.205734) (xy 83.716368 -136.17575)
			(xy 65.661032 -136.17575) (xy 65.661032 -136.177274) (xy 65.660542 -136.207258) (xy 65.652714 -136.266714)
			(xy 65.637193 -136.324639) (xy 65.614244 -136.380043) (xy 65.58426 -136.431977) (xy 65.547754 -136.479553)
			(xy 65.505349 -136.521958) (xy 65.457773 -136.558464) (xy 65.405839 -136.588448) (xy 65.350435 -136.611397)
			(xy 65.29251 -136.626918) (xy 65.233054 -136.634746) (xy 65.173086 -136.634746) (xy 65.11363 -136.626918)
			(xy 65.055705 -136.611397) (xy 65.000301 -136.588448) (xy 64.948367 -136.558464) (xy 64.900791 -136.521958)
			(xy 64.858386 -136.479553) (xy 64.82188 -136.431977) (xy 64.791896 -136.380043) (xy 64.768947 -136.324639)
			(xy 64.753426 -136.266714) (xy 64.745598 -136.207258) (xy 64.745108 -136.177274) (xy 52.700428 -136.177274)
			(xy 52.700428 -136.69645) (xy 52.700299 -136.704324) (xy 153.409904 -136.704324) (xy 153.409904 -135.840724)
			(xy 153.410394 -135.81074) (xy 153.418222 -135.751284) (xy 153.433743 -135.693359) (xy 153.456692 -135.637955)
			(xy 153.486676 -135.586021) (xy 153.523182 -135.538445) (xy 153.565587 -135.49604) (xy 153.613163 -135.459534)
			(xy 153.665097 -135.42955) (xy 153.720501 -135.406601) (xy 153.778426 -135.39108) (xy 153.837882 -135.383252)
			(xy 153.89785 -135.383252) (xy 153.957306 -135.39108) (xy 154.015231 -135.406601) (xy 154.070635 -135.42955)
			(xy 154.122569 -135.459534) (xy 154.170145 -135.49604) (xy 154.21255 -135.538445) (xy 154.249056 -135.586021)
			(xy 154.27904 -135.637955) (xy 154.301989 -135.693359) (xy 154.31751 -135.751284) (xy 154.325338 -135.81074)
			(xy 154.325828 -135.840724) (xy 154.325828 -136.69645) (xy 167.884856 -136.69645) (xy 167.884856 -135.83285)
			(xy 167.885346 -135.802866) (xy 167.893174 -135.74341) (xy 167.908695 -135.685485) (xy 167.931644 -135.630081)
			(xy 167.961628 -135.578147) (xy 167.998134 -135.530571) (xy 168.040539 -135.488166) (xy 168.088115 -135.45166)
			(xy 168.140049 -135.421676) (xy 168.195453 -135.398727) (xy 168.253378 -135.383206) (xy 168.312834 -135.375378)
			(xy 168.372802 -135.375378) (xy 168.432258 -135.383206) (xy 168.490183 -135.398727) (xy 168.545587 -135.421676)
			(xy 168.597521 -135.45166) (xy 168.645097 -135.488166) (xy 168.687502 -135.530571) (xy 168.724008 -135.578147)
			(xy 168.753992 -135.630081) (xy 168.776941 -135.685485) (xy 168.792462 -135.74341) (xy 168.80029 -135.802866)
			(xy 168.80078 -135.83285) (xy 168.80078 -136.177274) (xy 180.84546 -136.177274) (xy 180.84546 -135.313674)
			(xy 180.84595 -135.283706) (xy 180.853773 -135.224284) (xy 180.869286 -135.166391) (xy 180.892222 -135.111018)
			(xy 180.922189 -135.059112) (xy 180.958676 -135.011562) (xy 181.001056 -134.969182) (xy 181.048606 -134.932695)
			(xy 181.100512 -134.902728) (xy 181.155885 -134.879792) (xy 181.213778 -134.864279) (xy 181.2732 -134.856456)
			(xy 181.333136 -134.856456) (xy 181.392558 -134.864279) (xy 181.450451 -134.879792) (xy 181.505824 -134.902728)
			(xy 181.55773 -134.932695) (xy 181.60528 -134.969182) (xy 181.64766 -135.011562) (xy 181.684147 -135.059112)
			(xy 181.714114 -135.111018) (xy 181.73705 -135.166391) (xy 181.752563 -135.224284) (xy 181.760386 -135.283706)
			(xy 181.760876 -135.313674) (xy 181.760876 -136.17575) (xy 199.81672 -136.17575) (xy 199.81672 -135.31215)
			(xy 199.81721 -135.282182) (xy 199.825033 -135.22276) (xy 199.840546 -135.164867) (xy 199.863482 -135.109494)
			(xy 199.893449 -135.057588) (xy 199.929936 -135.010038) (xy 199.972316 -134.967658) (xy 200.019866 -134.931171)
			(xy 200.071772 -134.901204) (xy 200.127145 -134.878268) (xy 200.185038 -134.862755) (xy 200.24446 -134.854932)
			(xy 200.304396 -134.854932) (xy 200.363818 -134.862755) (xy 200.421711 -134.878268) (xy 200.469049 -134.897876)
			(xy 266.86764 -134.897876) (xy 266.86764 -134.034276) (xy 266.86813 -134.004292) (xy 266.875958 -133.944836)
			(xy 266.891479 -133.886911) (xy 266.914428 -133.831507) (xy 266.944412 -133.779573) (xy 266.980918 -133.731997)
			(xy 267.023323 -133.689592) (xy 267.070899 -133.653086) (xy 267.122833 -133.623102) (xy 267.178237 -133.600153)
			(xy 267.236162 -133.584632) (xy 267.295618 -133.576804) (xy 267.355586 -133.576804) (xy 267.415042 -133.584632)
			(xy 267.472967 -133.600153) (xy 267.528371 -133.623102) (xy 267.580305 -133.653086) (xy 267.627881 -133.689592)
			(xy 267.670286 -133.731997) (xy 267.706792 -133.779573) (xy 267.736776 -133.831507) (xy 267.759725 -133.886911)
			(xy 267.775246 -133.944836) (xy 267.783074 -134.004292) (xy 267.783564 -134.034276) (xy 267.783564 -134.896352)
			(xy 285.8389 -134.896352) (xy 285.8389 -134.032752) (xy 285.83939 -134.002768) (xy 285.847218 -133.943312)
			(xy 285.862739 -133.885387) (xy 285.885688 -133.829983) (xy 285.915672 -133.778049) (xy 285.952178 -133.730473)
			(xy 285.994583 -133.688068) (xy 286.042159 -133.651562) (xy 286.094093 -133.621578) (xy 286.149497 -133.598629)
			(xy 286.207422 -133.583108) (xy 286.266878 -133.57528) (xy 286.326846 -133.57528) (xy 286.386302 -133.583108)
			(xy 286.444227 -133.598629) (xy 286.499631 -133.621578) (xy 286.551565 -133.651562) (xy 286.599141 -133.688068)
			(xy 286.641546 -133.730473) (xy 286.678052 -133.778049) (xy 286.708036 -133.829983) (xy 286.730985 -133.885387)
			(xy 286.746506 -133.943312) (xy 286.754334 -134.002768) (xy 286.754824 -134.032752) (xy 286.754824 -134.377176)
			(xy 298.799504 -134.377176) (xy 298.799504 -133.513576) (xy 298.799994 -133.483608) (xy 298.807817 -133.424186)
			(xy 298.82333 -133.366293) (xy 298.846266 -133.31092) (xy 298.876233 -133.259014) (xy 298.91272 -133.211464)
			(xy 298.9551 -133.169084) (xy 299.00265 -133.132597) (xy 299.054556 -133.10263) (xy 299.109929 -133.079694)
			(xy 299.167822 -133.064181) (xy 299.227244 -133.056358) (xy 299.28718 -133.056358) (xy 299.346602 -133.064181)
			(xy 299.404495 -133.079694) (xy 299.459868 -133.10263) (xy 299.511774 -133.132597) (xy 299.559324 -133.169084)
			(xy 299.601704 -133.211464) (xy 299.638191 -133.259014) (xy 299.668158 -133.31092) (xy 299.691094 -133.366293)
			(xy 299.706607 -133.424186) (xy 299.71443 -133.483608) (xy 299.71492 -133.513576) (xy 299.71492 -134.369302)
			(xy 313.274456 -134.369302) (xy 313.274456 -133.505702) (xy 313.274946 -133.475734) (xy 313.282769 -133.416312)
			(xy 313.298282 -133.358419) (xy 313.321218 -133.303046) (xy 313.351185 -133.25114) (xy 313.387672 -133.20359)
			(xy 313.430052 -133.16121) (xy 313.477602 -133.124723) (xy 313.529508 -133.094756) (xy 313.584881 -133.07182)
			(xy 313.642774 -133.056307) (xy 313.702196 -133.048484) (xy 313.762132 -133.048484) (xy 313.821554 -133.056307)
			(xy 313.879447 -133.07182) (xy 313.93482 -133.094756) (xy 313.951493 -133.104382) (xy 385.6101 -133.104382)
			(xy 385.6101 -132.240782) (xy 385.61059 -132.210814) (xy 385.618413 -132.151392) (xy 385.633926 -132.093499)
			(xy 385.656862 -132.038126) (xy 385.686829 -131.98622) (xy 385.723316 -131.93867) (xy 385.765696 -131.89629)
			(xy 385.813246 -131.859803) (xy 385.865152 -131.829836) (xy 385.920525 -131.8069) (xy 385.978418 -131.791387)
			(xy 386.03784 -131.783564) (xy 386.097776 -131.783564) (xy 386.157198 -131.791387) (xy 386.215091 -131.8069)
			(xy 386.270464 -131.829836) (xy 386.32237 -131.859803) (xy 386.36992 -131.89629) (xy 386.4123 -131.93867)
			(xy 386.448787 -131.98622) (xy 386.478754 -132.038126) (xy 386.50169 -132.093499) (xy 386.517203 -132.151392)
			(xy 386.525026 -132.210814) (xy 386.525516 -132.240782) (xy 386.525516 -133.096508) (xy 400.085052 -133.096508)
			(xy 400.085052 -132.232908) (xy 400.085542 -132.20294) (xy 400.093365 -132.143518) (xy 400.108878 -132.085625)
			(xy 400.131814 -132.030252) (xy 400.161781 -131.978346) (xy 400.198268 -131.930796) (xy 400.240648 -131.888416)
			(xy 400.288198 -131.851929) (xy 400.340104 -131.821962) (xy 400.395477 -131.799026) (xy 400.45337 -131.783513)
			(xy 400.512792 -131.77569) (xy 400.572728 -131.77569) (xy 400.63215 -131.783513) (xy 400.690043 -131.799026)
			(xy 400.745416 -131.821962) (xy 400.797322 -131.851929) (xy 400.844872 -131.888416) (xy 400.887252 -131.930796)
			(xy 400.923739 -131.978346) (xy 400.953706 -132.030252) (xy 400.976642 -132.085625) (xy 400.992155 -132.143518)
			(xy 400.999978 -132.20294) (xy 401.000468 -132.232908) (xy 401.000468 -132.577332) (xy 413.045148 -132.577332)
			(xy 413.045148 -131.713732) (xy 413.045638 -131.683748) (xy 413.053466 -131.624292) (xy 413.068987 -131.566367)
			(xy 413.091936 -131.510963) (xy 413.12192 -131.459029) (xy 413.158426 -131.411453) (xy 413.200831 -131.369048)
			(xy 413.248407 -131.332542) (xy 413.300341 -131.302558) (xy 413.355745 -131.279609) (xy 413.41367 -131.264088)
			(xy 413.473126 -131.25626) (xy 413.533094 -131.25626) (xy 413.59255 -131.264088) (xy 413.650475 -131.279609)
			(xy 413.705879 -131.302558) (xy 413.757813 -131.332542) (xy 413.805389 -131.369048) (xy 413.847794 -131.411453)
			(xy 413.8843 -131.459029) (xy 413.914284 -131.510963) (xy 413.937233 -131.566367) (xy 413.952754 -131.624292)
			(xy 413.960582 -131.683748) (xy 413.961072 -131.713732) (xy 413.961072 -132.575808) (xy 432.016408 -132.575808)
			(xy 432.016408 -131.712208) (xy 432.016898 -131.682224) (xy 432.024726 -131.622768) (xy 432.040247 -131.564843)
			(xy 432.063196 -131.509439) (xy 432.09318 -131.457505) (xy 432.129686 -131.409929) (xy 432.172091 -131.367524)
			(xy 432.219667 -131.331018) (xy 432.271601 -131.301034) (xy 432.327005 -131.278085) (xy 432.38493 -131.262564)
			(xy 432.444386 -131.254736) (xy 432.504354 -131.254736) (xy 432.56381 -131.262564) (xy 432.621735 -131.278085)
			(xy 432.677139 -131.301034) (xy 432.729073 -131.331018) (xy 432.776649 -131.367524) (xy 432.819054 -131.409929)
			(xy 432.85556 -131.457505) (xy 432.885544 -131.509439) (xy 432.908493 -131.564843) (xy 432.924014 -131.622768)
			(xy 432.931842 -131.682224) (xy 432.932332 -131.712208) (xy 432.932332 -132.575808) (xy 432.931842 -132.605792)
			(xy 432.924014 -132.665248) (xy 432.908493 -132.723173) (xy 432.885544 -132.778577) (xy 432.85556 -132.830511)
			(xy 432.819054 -132.878087) (xy 432.776649 -132.920492) (xy 432.729073 -132.956998) (xy 432.677139 -132.986982)
			(xy 432.621735 -133.009931) (xy 432.56381 -133.025452) (xy 432.504354 -133.03328) (xy 432.444386 -133.03328)
			(xy 432.38493 -133.025452) (xy 432.327005 -133.009931) (xy 432.271601 -132.986982) (xy 432.219667 -132.956998)
			(xy 432.172091 -132.920492) (xy 432.129686 -132.878087) (xy 432.09318 -132.830511) (xy 432.063196 -132.778577)
			(xy 432.040247 -132.723173) (xy 432.024726 -132.665248) (xy 432.016898 -132.605792) (xy 432.016408 -132.575808)
			(xy 413.961072 -132.575808) (xy 413.961072 -132.577332) (xy 413.960582 -132.607316) (xy 413.952754 -132.666772)
			(xy 413.937233 -132.724697) (xy 413.914284 -132.780101) (xy 413.8843 -132.832035) (xy 413.847794 -132.879611)
			(xy 413.805389 -132.922016) (xy 413.757813 -132.958522) (xy 413.705879 -132.988506) (xy 413.650475 -133.011455)
			(xy 413.59255 -133.026976) (xy 413.533094 -133.034804) (xy 413.473126 -133.034804) (xy 413.41367 -133.026976)
			(xy 413.355745 -133.011455) (xy 413.300341 -132.988506) (xy 413.248407 -132.958522) (xy 413.200831 -132.922016)
			(xy 413.158426 -132.879611) (xy 413.12192 -132.832035) (xy 413.091936 -132.780101) (xy 413.068987 -132.724697)
			(xy 413.053466 -132.666772) (xy 413.045638 -132.607316) (xy 413.045148 -132.577332) (xy 401.000468 -132.577332)
			(xy 401.000468 -133.096508) (xy 400.999978 -133.126476) (xy 400.992155 -133.185898) (xy 400.976642 -133.243791)
			(xy 400.953706 -133.299164) (xy 400.923739 -133.35107) (xy 400.887252 -133.39862) (xy 400.844872 -133.441)
			(xy 400.797322 -133.477487) (xy 400.745416 -133.507454) (xy 400.690043 -133.53039) (xy 400.63215 -133.545903)
			(xy 400.572728 -133.553726) (xy 400.512792 -133.553726) (xy 400.45337 -133.545903) (xy 400.395477 -133.53039)
			(xy 400.340104 -133.507454) (xy 400.288198 -133.477487) (xy 400.240648 -133.441) (xy 400.198268 -133.39862)
			(xy 400.161781 -133.35107) (xy 400.131814 -133.299164) (xy 400.108878 -133.243791) (xy 400.093365 -133.185898)
			(xy 400.085542 -133.126476) (xy 400.085052 -133.096508) (xy 386.525516 -133.096508) (xy 386.525516 -133.104382)
			(xy 386.525026 -133.13435) (xy 386.517203 -133.193772) (xy 386.50169 -133.251665) (xy 386.478754 -133.307038)
			(xy 386.448787 -133.358944) (xy 386.4123 -133.406494) (xy 386.36992 -133.448874) (xy 386.32237 -133.485361)
			(xy 386.270464 -133.515328) (xy 386.215091 -133.538264) (xy 386.157198 -133.553777) (xy 386.097776 -133.5616)
			(xy 386.03784 -133.5616) (xy 385.978418 -133.553777) (xy 385.920525 -133.538264) (xy 385.865152 -133.515328)
			(xy 385.813246 -133.485361) (xy 385.765696 -133.448874) (xy 385.723316 -133.406494) (xy 385.686829 -133.358944)
			(xy 385.656862 -133.307038) (xy 385.633926 -133.251665) (xy 385.618413 -133.193772) (xy 385.61059 -133.13435)
			(xy 385.6101 -133.104382) (xy 313.951493 -133.104382) (xy 313.986726 -133.124723) (xy 314.034276 -133.16121)
			(xy 314.076656 -133.20359) (xy 314.113143 -133.25114) (xy 314.14311 -133.303046) (xy 314.166046 -133.358419)
			(xy 314.181559 -133.416312) (xy 314.189382 -133.475734) (xy 314.189872 -133.505702) (xy 314.189872 -134.369302)
			(xy 314.189382 -134.39927) (xy 314.181559 -134.458692) (xy 314.166046 -134.516585) (xy 314.14311 -134.571958)
			(xy 314.113143 -134.623864) (xy 314.076656 -134.671414) (xy 314.034276 -134.713794) (xy 313.986726 -134.750281)
			(xy 313.93482 -134.780248) (xy 313.879447 -134.803184) (xy 313.821554 -134.818697) (xy 313.762132 -134.82652)
			(xy 313.702196 -134.82652) (xy 313.642774 -134.818697) (xy 313.584881 -134.803184) (xy 313.529508 -134.780248)
			(xy 313.477602 -134.750281) (xy 313.430052 -134.713794) (xy 313.387672 -134.671414) (xy 313.351185 -134.623864)
			(xy 313.321218 -134.571958) (xy 313.298282 -134.516585) (xy 313.282769 -134.458692) (xy 313.274946 -134.39927)
			(xy 313.274456 -134.369302) (xy 299.71492 -134.369302) (xy 299.71492 -134.377176) (xy 299.71443 -134.407144)
			(xy 299.706607 -134.466566) (xy 299.691094 -134.524459) (xy 299.668158 -134.579832) (xy 299.638191 -134.631738)
			(xy 299.601704 -134.679288) (xy 299.559324 -134.721668) (xy 299.511774 -134.758155) (xy 299.459868 -134.788122)
			(xy 299.404495 -134.811058) (xy 299.346602 -134.826571) (xy 299.28718 -134.834394) (xy 299.227244 -134.834394)
			(xy 299.167822 -134.826571) (xy 299.109929 -134.811058) (xy 299.054556 -134.788122) (xy 299.00265 -134.758155)
			(xy 298.9551 -134.721668) (xy 298.91272 -134.679288) (xy 298.876233 -134.631738) (xy 298.846266 -134.579832)
			(xy 298.82333 -134.524459) (xy 298.807817 -134.466566) (xy 298.799994 -134.407144) (xy 298.799504 -134.377176)
			(xy 286.754824 -134.377176) (xy 286.754824 -134.896352) (xy 286.754334 -134.926336) (xy 286.746506 -134.985792)
			(xy 286.730985 -135.043717) (xy 286.708036 -135.099121) (xy 286.678052 -135.151055) (xy 286.641546 -135.198631)
			(xy 286.599141 -135.241036) (xy 286.551565 -135.277542) (xy 286.499631 -135.307526) (xy 286.444227 -135.330475)
			(xy 286.386302 -135.345996) (xy 286.326846 -135.353824) (xy 286.266878 -135.353824) (xy 286.207422 -135.345996)
			(xy 286.149497 -135.330475) (xy 286.094093 -135.307526) (xy 286.042159 -135.277542) (xy 285.994583 -135.241036)
			(xy 285.952178 -135.198631) (xy 285.915672 -135.151055) (xy 285.885688 -135.099121) (xy 285.862739 -135.043717)
			(xy 285.847218 -134.985792) (xy 285.83939 -134.926336) (xy 285.8389 -134.896352) (xy 267.783564 -134.896352)
			(xy 267.783564 -134.897876) (xy 267.783074 -134.92786) (xy 267.775246 -134.987316) (xy 267.759725 -135.045241)
			(xy 267.736776 -135.100645) (xy 267.706792 -135.152579) (xy 267.670286 -135.200155) (xy 267.627881 -135.24256)
			(xy 267.580305 -135.279066) (xy 267.528371 -135.30905) (xy 267.472967 -135.331999) (xy 267.415042 -135.34752)
			(xy 267.355586 -135.355348) (xy 267.295618 -135.355348) (xy 267.236162 -135.34752) (xy 267.178237 -135.331999)
			(xy 267.122833 -135.30905) (xy 267.070899 -135.279066) (xy 267.023323 -135.24256) (xy 266.980918 -135.200155)
			(xy 266.944412 -135.152579) (xy 266.914428 -135.100645) (xy 266.891479 -135.045241) (xy 266.875958 -134.987316)
			(xy 266.86813 -134.92786) (xy 266.86764 -134.897876) (xy 200.469049 -134.897876) (xy 200.477084 -134.901204)
			(xy 200.52899 -134.931171) (xy 200.57654 -134.967658) (xy 200.61892 -135.010038) (xy 200.655407 -135.057588)
			(xy 200.685374 -135.109494) (xy 200.70831 -135.164867) (xy 200.723823 -135.22276) (xy 200.731646 -135.282182)
			(xy 200.732136 -135.31215) (xy 200.732136 -136.17575) (xy 200.731646 -136.205718) (xy 200.723823 -136.26514)
			(xy 200.70831 -136.323033) (xy 200.685374 -136.378406) (xy 200.655407 -136.430312) (xy 200.61892 -136.477862)
			(xy 200.57654 -136.520242) (xy 200.52899 -136.556729) (xy 200.477084 -136.586696) (xy 200.421711 -136.609632)
			(xy 200.363818 -136.625145) (xy 200.304396 -136.632968) (xy 200.24446 -136.632968) (xy 200.185038 -136.625145)
			(xy 200.127145 -136.609632) (xy 200.071772 -136.586696) (xy 200.019866 -136.556729) (xy 199.972316 -136.520242)
			(xy 199.929936 -136.477862) (xy 199.893449 -136.430312) (xy 199.863482 -136.378406) (xy 199.840546 -136.323033)
			(xy 199.825033 -136.26514) (xy 199.81721 -136.205718) (xy 199.81672 -136.17575) (xy 181.760876 -136.17575)
			(xy 181.760876 -136.177274) (xy 181.760386 -136.207242) (xy 181.752563 -136.266664) (xy 181.73705 -136.324557)
			(xy 181.714114 -136.37993) (xy 181.684147 -136.431836) (xy 181.64766 -136.479386) (xy 181.60528 -136.521766)
			(xy 181.55773 -136.558253) (xy 181.505824 -136.58822) (xy 181.450451 -136.611156) (xy 181.392558 -136.626669)
			(xy 181.333136 -136.634492) (xy 181.2732 -136.634492) (xy 181.213778 -136.626669) (xy 181.155885 -136.611156)
			(xy 181.100512 -136.58822) (xy 181.048606 -136.558253) (xy 181.001056 -136.521766) (xy 180.958676 -136.479386)
			(xy 180.922189 -136.431836) (xy 180.892222 -136.37993) (xy 180.869286 -136.324557) (xy 180.853773 -136.266664)
			(xy 180.84595 -136.207242) (xy 180.84546 -136.177274) (xy 168.80078 -136.177274) (xy 168.80078 -136.69645)
			(xy 168.800651 -136.704324) (xy 269.509748 -136.704324) (xy 269.509748 -135.840724) (xy 269.510238 -135.81074)
			(xy 269.518066 -135.751284) (xy 269.533587 -135.693359) (xy 269.556536 -135.637955) (xy 269.58652 -135.586021)
			(xy 269.623026 -135.538445) (xy 269.665431 -135.49604) (xy 269.713007 -135.459534) (xy 269.764941 -135.42955)
			(xy 269.820345 -135.406601) (xy 269.87827 -135.39108) (xy 269.937726 -135.383252) (xy 269.997694 -135.383252)
			(xy 270.05715 -135.39108) (xy 270.115075 -135.406601) (xy 270.170479 -135.42955) (xy 270.222413 -135.459534)
			(xy 270.269989 -135.49604) (xy 270.312394 -135.538445) (xy 270.3489 -135.586021) (xy 270.378884 -135.637955)
			(xy 270.401833 -135.693359) (xy 270.417354 -135.751284) (xy 270.425182 -135.81074) (xy 270.425672 -135.840724)
			(xy 270.425672 -136.69645) (xy 283.9847 -136.69645) (xy 283.9847 -135.83285) (xy 283.98519 -135.802866)
			(xy 283.993018 -135.74341) (xy 284.008539 -135.685485) (xy 284.031488 -135.630081) (xy 284.061472 -135.578147)
			(xy 284.097978 -135.530571) (xy 284.140383 -135.488166) (xy 284.187959 -135.45166) (xy 284.239893 -135.421676)
			(xy 284.295297 -135.398727) (xy 284.353222 -135.383206) (xy 284.412678 -135.375378) (xy 284.472646 -135.375378)
			(xy 284.532102 -135.383206) (xy 284.590027 -135.398727) (xy 284.645431 -135.421676) (xy 284.697365 -135.45166)
			(xy 284.744941 -135.488166) (xy 284.787346 -135.530571) (xy 284.823852 -135.578147) (xy 284.853836 -135.630081)
			(xy 284.876785 -135.685485) (xy 284.892306 -135.74341) (xy 284.900134 -135.802866) (xy 284.900624 -135.83285)
			(xy 284.900624 -136.177274) (xy 296.945304 -136.177274) (xy 296.945304 -135.313674) (xy 296.945794 -135.283706)
			(xy 296.953617 -135.224284) (xy 296.96913 -135.166391) (xy 296.992066 -135.111018) (xy 297.022033 -135.059112)
			(xy 297.05852 -135.011562) (xy 297.1009 -134.969182) (xy 297.14845 -134.932695) (xy 297.200356 -134.902728)
			(xy 297.255729 -134.879792) (xy 297.313622 -134.864279) (xy 297.373044 -134.856456) (xy 297.43298 -134.856456)
			(xy 297.492402 -134.864279) (xy 297.550295 -134.879792) (xy 297.605668 -134.902728) (xy 297.657574 -134.932695)
			(xy 297.705124 -134.969182) (xy 297.747504 -135.011562) (xy 297.783991 -135.059112) (xy 297.813958 -135.111018)
			(xy 297.836894 -135.166391) (xy 297.852407 -135.224284) (xy 297.86023 -135.283706) (xy 297.86072 -135.313674)
			(xy 297.86072 -136.17575) (xy 315.916564 -136.17575) (xy 315.916564 -135.31215) (xy 315.917054 -135.282182)
			(xy 315.924877 -135.22276) (xy 315.94039 -135.164867) (xy 315.963326 -135.109494) (xy 315.993293 -135.057588)
			(xy 316.02978 -135.010038) (xy 316.07216 -134.967658) (xy 316.11971 -134.931171) (xy 316.171616 -134.901204)
			(xy 316.226989 -134.878268) (xy 316.284882 -134.862755) (xy 316.344304 -134.854932) (xy 316.40424 -134.854932)
			(xy 316.463662 -134.862755) (xy 316.521555 -134.878268) (xy 316.568893 -134.897876) (xy 382.967992 -134.897876)
			(xy 382.967992 -134.034276) (xy 382.968482 -134.004308) (xy 382.976305 -133.944886) (xy 382.991818 -133.886993)
			(xy 383.014754 -133.83162) (xy 383.044721 -133.779714) (xy 383.081208 -133.732164) (xy 383.123588 -133.689784)
			(xy 383.171138 -133.653297) (xy 383.223044 -133.62333) (xy 383.278417 -133.600394) (xy 383.33631 -133.584881)
			(xy 383.395732 -133.577058) (xy 383.455668 -133.577058) (xy 383.51509 -133.584881) (xy 383.572983 -133.600394)
			(xy 383.628356 -133.62333) (xy 383.680262 -133.653297) (xy 383.727812 -133.689784) (xy 383.770192 -133.732164)
			(xy 383.806679 -133.779714) (xy 383.836646 -133.83162) (xy 383.859582 -133.886993) (xy 383.875095 -133.944886)
			(xy 383.882918 -134.004308) (xy 383.883408 -134.034276) (xy 383.883408 -134.896352) (xy 401.939252 -134.896352)
			(xy 401.939252 -134.032752) (xy 401.939742 -134.002784) (xy 401.947565 -133.943362) (xy 401.963078 -133.885469)
			(xy 401.986014 -133.830096) (xy 402.015981 -133.77819) (xy 402.052468 -133.73064) (xy 402.094848 -133.68826)
			(xy 402.142398 -133.651773) (xy 402.194304 -133.621806) (xy 402.249677 -133.59887) (xy 402.30757 -133.583357)
			(xy 402.366992 -133.575534) (xy 402.426928 -133.575534) (xy 402.48635 -133.583357) (xy 402.544243 -133.59887)
			(xy 402.599616 -133.621806) (xy 402.651522 -133.651773) (xy 402.699072 -133.68826) (xy 402.741452 -133.73064)
			(xy 402.777939 -133.77819) (xy 402.807906 -133.830096) (xy 402.830842 -133.885469) (xy 402.846355 -133.943362)
			(xy 402.854178 -134.002784) (xy 402.854668 -134.032752) (xy 402.854668 -134.377176) (xy 414.899348 -134.377176)
			(xy 414.899348 -133.513576) (xy 414.899838 -133.483592) (xy 414.907666 -133.424136) (xy 414.923187 -133.366211)
			(xy 414.946136 -133.310807) (xy 414.97612 -133.258873) (xy 415.012626 -133.211297) (xy 415.055031 -133.168892)
			(xy 415.102607 -133.132386) (xy 415.154541 -133.102402) (xy 415.209945 -133.079453) (xy 415.26787 -133.063932)
			(xy 415.327326 -133.056104) (xy 415.387294 -133.056104) (xy 415.44675 -133.063932) (xy 415.504675 -133.079453)
			(xy 415.560079 -133.102402) (xy 415.612013 -133.132386) (xy 415.659589 -133.168892) (xy 415.701994 -133.211297)
			(xy 415.7385 -133.258873) (xy 415.768484 -133.310807) (xy 415.791433 -133.366211) (xy 415.806954 -133.424136)
			(xy 415.814782 -133.483592) (xy 415.815272 -133.513576) (xy 415.815272 -134.369302) (xy 429.3743 -134.369302)
			(xy 429.3743 -133.505702) (xy 429.37479 -133.475718) (xy 429.382618 -133.416262) (xy 429.398139 -133.358337)
			(xy 429.421088 -133.302933) (xy 429.451072 -133.250999) (xy 429.487578 -133.203423) (xy 429.529983 -133.161018)
			(xy 429.577559 -133.124512) (xy 429.629493 -133.094528) (xy 429.684897 -133.071579) (xy 429.742822 -133.056058)
			(xy 429.802278 -133.04823) (xy 429.862246 -133.04823) (xy 429.921702 -133.056058) (xy 429.979627 -133.071579)
			(xy 430.035031 -133.094528) (xy 430.086965 -133.124512) (xy 430.134541 -133.161018) (xy 430.176946 -133.203423)
			(xy 430.213452 -133.250999) (xy 430.243436 -133.302933) (xy 430.266385 -133.358337) (xy 430.281906 -133.416262)
			(xy 430.289734 -133.475718) (xy 430.290224 -133.505702) (xy 430.290224 -134.369302) (xy 430.289734 -134.399286)
			(xy 430.281906 -134.458742) (xy 430.266385 -134.516667) (xy 430.243436 -134.572071) (xy 430.213452 -134.624005)
			(xy 430.176946 -134.671581) (xy 430.134541 -134.713986) (xy 430.086965 -134.750492) (xy 430.035031 -134.780476)
			(xy 429.979627 -134.803425) (xy 429.921702 -134.818946) (xy 429.862246 -134.826774) (xy 429.802278 -134.826774)
			(xy 429.742822 -134.818946) (xy 429.684897 -134.803425) (xy 429.629493 -134.780476) (xy 429.577559 -134.750492)
			(xy 429.529983 -134.713986) (xy 429.487578 -134.671581) (xy 429.451072 -134.624005) (xy 429.421088 -134.572071)
			(xy 429.398139 -134.516667) (xy 429.382618 -134.458742) (xy 429.37479 -134.399286) (xy 429.3743 -134.369302)
			(xy 415.815272 -134.369302) (xy 415.815272 -134.377176) (xy 415.814782 -134.40716) (xy 415.806954 -134.466616)
			(xy 415.791433 -134.524541) (xy 415.768484 -134.579945) (xy 415.7385 -134.631879) (xy 415.701994 -134.679455)
			(xy 415.659589 -134.72186) (xy 415.612013 -134.758366) (xy 415.560079 -134.78835) (xy 415.504675 -134.811299)
			(xy 415.44675 -134.82682) (xy 415.387294 -134.834648) (xy 415.327326 -134.834648) (xy 415.26787 -134.82682)
			(xy 415.209945 -134.811299) (xy 415.154541 -134.78835) (xy 415.102607 -134.758366) (xy 415.055031 -134.72186)
			(xy 415.012626 -134.679455) (xy 414.97612 -134.631879) (xy 414.946136 -134.579945) (xy 414.923187 -134.524541)
			(xy 414.907666 -134.466616) (xy 414.899838 -134.40716) (xy 414.899348 -134.377176) (xy 402.854668 -134.377176)
			(xy 402.854668 -134.896352) (xy 402.854178 -134.92632) (xy 402.846355 -134.985742) (xy 402.830842 -135.043635)
			(xy 402.807906 -135.099008) (xy 402.777939 -135.150914) (xy 402.741452 -135.198464) (xy 402.699072 -135.240844)
			(xy 402.651522 -135.277331) (xy 402.599616 -135.307298) (xy 402.544243 -135.330234) (xy 402.48635 -135.345747)
			(xy 402.426928 -135.35357) (xy 402.366992 -135.35357) (xy 402.30757 -135.345747) (xy 402.249677 -135.330234)
			(xy 402.194304 -135.307298) (xy 402.142398 -135.277331) (xy 402.094848 -135.240844) (xy 402.052468 -135.198464)
			(xy 402.015981 -135.150914) (xy 401.986014 -135.099008) (xy 401.963078 -135.043635) (xy 401.947565 -134.985742)
			(xy 401.939742 -134.92632) (xy 401.939252 -134.896352) (xy 383.883408 -134.896352) (xy 383.883408 -134.897876)
			(xy 383.882918 -134.927844) (xy 383.875095 -134.987266) (xy 383.859582 -135.045159) (xy 383.836646 -135.100532)
			(xy 383.806679 -135.152438) (xy 383.770192 -135.199988) (xy 383.727812 -135.242368) (xy 383.680262 -135.278855)
			(xy 383.628356 -135.308822) (xy 383.572983 -135.331758) (xy 383.51509 -135.347271) (xy 383.455668 -135.355094)
			(xy 383.395732 -135.355094) (xy 383.33631 -135.347271) (xy 383.278417 -135.331758) (xy 383.223044 -135.308822)
			(xy 383.171138 -135.278855) (xy 383.123588 -135.242368) (xy 383.081208 -135.199988) (xy 383.044721 -135.152438)
			(xy 383.014754 -135.100532) (xy 382.991818 -135.045159) (xy 382.976305 -134.987266) (xy 382.968482 -134.927844)
			(xy 382.967992 -134.897876) (xy 316.568893 -134.897876) (xy 316.576928 -134.901204) (xy 316.628834 -134.931171)
			(xy 316.676384 -134.967658) (xy 316.718764 -135.010038) (xy 316.755251 -135.057588) (xy 316.785218 -135.109494)
			(xy 316.808154 -135.164867) (xy 316.823667 -135.22276) (xy 316.83149 -135.282182) (xy 316.83198 -135.31215)
			(xy 316.83198 -136.17575) (xy 316.83149 -136.205718) (xy 316.823667 -136.26514) (xy 316.808154 -136.323033)
			(xy 316.785218 -136.378406) (xy 316.755251 -136.430312) (xy 316.718764 -136.477862) (xy 316.676384 -136.520242)
			(xy 316.628834 -136.556729) (xy 316.576928 -136.586696) (xy 316.521555 -136.609632) (xy 316.463662 -136.625145)
			(xy 316.40424 -136.632968) (xy 316.344304 -136.632968) (xy 316.284882 -136.625145) (xy 316.226989 -136.609632)
			(xy 316.171616 -136.586696) (xy 316.11971 -136.556729) (xy 316.07216 -136.520242) (xy 316.02978 -136.477862)
			(xy 315.993293 -136.430312) (xy 315.963326 -136.378406) (xy 315.94039 -136.323033) (xy 315.924877 -136.26514)
			(xy 315.917054 -136.205718) (xy 315.916564 -136.17575) (xy 297.86072 -136.17575) (xy 297.86072 -136.177274)
			(xy 297.86023 -136.207242) (xy 297.852407 -136.266664) (xy 297.836894 -136.324557) (xy 297.813958 -136.37993)
			(xy 297.783991 -136.431836) (xy 297.747504 -136.479386) (xy 297.705124 -136.521766) (xy 297.657574 -136.558253)
			(xy 297.605668 -136.58822) (xy 297.550295 -136.611156) (xy 297.492402 -136.626669) (xy 297.43298 -136.634492)
			(xy 297.373044 -136.634492) (xy 297.313622 -136.626669) (xy 297.255729 -136.611156) (xy 297.200356 -136.58822)
			(xy 297.14845 -136.558253) (xy 297.1009 -136.521766) (xy 297.05852 -136.479386) (xy 297.022033 -136.431836)
			(xy 296.992066 -136.37993) (xy 296.96913 -136.324557) (xy 296.953617 -136.266664) (xy 296.945794 -136.207242)
			(xy 296.945304 -136.177274) (xy 284.900624 -136.177274) (xy 284.900624 -136.69645) (xy 284.900495 -136.704324)
			(xy 385.6101 -136.704324) (xy 385.6101 -135.840724) (xy 385.61059 -135.810756) (xy 385.618413 -135.751334)
			(xy 385.633926 -135.693441) (xy 385.656862 -135.638068) (xy 385.686829 -135.586162) (xy 385.723316 -135.538612)
			(xy 385.765696 -135.496232) (xy 385.813246 -135.459745) (xy 385.865152 -135.429778) (xy 385.920525 -135.406842)
			(xy 385.978418 -135.391329) (xy 386.03784 -135.383506) (xy 386.097776 -135.383506) (xy 386.157198 -135.391329)
			(xy 386.215091 -135.406842) (xy 386.270464 -135.429778) (xy 386.32237 -135.459745) (xy 386.36992 -135.496232)
			(xy 386.4123 -135.538612) (xy 386.448787 -135.586162) (xy 386.478754 -135.638068) (xy 386.50169 -135.693441)
			(xy 386.517203 -135.751334) (xy 386.525026 -135.810756) (xy 386.525516 -135.840724) (xy 386.525516 -136.69645)
			(xy 400.085052 -136.69645) (xy 400.085052 -135.83285) (xy 400.085542 -135.802882) (xy 400.093365 -135.74346)
			(xy 400.108878 -135.685567) (xy 400.131814 -135.630194) (xy 400.161781 -135.578288) (xy 400.198268 -135.530738)
			(xy 400.240648 -135.488358) (xy 400.288198 -135.451871) (xy 400.340104 -135.421904) (xy 400.395477 -135.398968)
			(xy 400.45337 -135.383455) (xy 400.512792 -135.375632) (xy 400.572728 -135.375632) (xy 400.63215 -135.383455)
			(xy 400.690043 -135.398968) (xy 400.745416 -135.421904) (xy 400.797322 -135.451871) (xy 400.844872 -135.488358)
			(xy 400.887252 -135.530738) (xy 400.923739 -135.578288) (xy 400.953706 -135.630194) (xy 400.976642 -135.685567)
			(xy 400.992155 -135.74346) (xy 400.999978 -135.802882) (xy 401.000468 -135.83285) (xy 401.000468 -136.177274)
			(xy 413.045148 -136.177274) (xy 413.045148 -135.313674) (xy 413.045638 -135.28369) (xy 413.053466 -135.224234)
			(xy 413.068987 -135.166309) (xy 413.091936 -135.110905) (xy 413.12192 -135.058971) (xy 413.158426 -135.011395)
			(xy 413.200831 -134.96899) (xy 413.248407 -134.932484) (xy 413.300341 -134.9025) (xy 413.355745 -134.879551)
			(xy 413.41367 -134.86403) (xy 413.473126 -134.856202) (xy 413.533094 -134.856202) (xy 413.59255 -134.86403)
			(xy 413.650475 -134.879551) (xy 413.705879 -134.9025) (xy 413.757813 -134.932484) (xy 413.805389 -134.96899)
			(xy 413.847794 -135.011395) (xy 413.8843 -135.058971) (xy 413.914284 -135.110905) (xy 413.937233 -135.166309)
			(xy 413.952754 -135.224234) (xy 413.960582 -135.28369) (xy 413.961072 -135.313674) (xy 413.961072 -136.17575)
			(xy 432.016408 -136.17575) (xy 432.016408 -135.31215) (xy 432.016898 -135.282166) (xy 432.024726 -135.22271)
			(xy 432.040247 -135.164785) (xy 432.063196 -135.109381) (xy 432.09318 -135.057447) (xy 432.129686 -135.009871)
			(xy 432.172091 -134.967466) (xy 432.219667 -134.93096) (xy 432.271601 -134.900976) (xy 432.327005 -134.878027)
			(xy 432.38493 -134.862506) (xy 432.444386 -134.854678) (xy 432.504354 -134.854678) (xy 432.56381 -134.862506)
			(xy 432.621735 -134.878027) (xy 432.677139 -134.900976) (xy 432.729073 -134.93096) (xy 432.776649 -134.967466)
			(xy 432.819054 -135.009871) (xy 432.85556 -135.057447) (xy 432.885544 -135.109381) (xy 432.908493 -135.164785)
			(xy 432.924014 -135.22271) (xy 432.931842 -135.282166) (xy 432.932332 -135.31215) (xy 432.932332 -136.17575)
			(xy 432.931842 -136.205734) (xy 432.924014 -136.26519) (xy 432.908493 -136.323115) (xy 432.885544 -136.378519)
			(xy 432.85556 -136.430453) (xy 432.819054 -136.478029) (xy 432.776649 -136.520434) (xy 432.729073 -136.55694)
			(xy 432.677139 -136.586924) (xy 432.621735 -136.609873) (xy 432.56381 -136.625394) (xy 432.504354 -136.633222)
			(xy 432.444386 -136.633222) (xy 432.38493 -136.625394) (xy 432.327005 -136.609873) (xy 432.271601 -136.586924)
			(xy 432.219667 -136.55694) (xy 432.172091 -136.520434) (xy 432.129686 -136.478029) (xy 432.09318 -136.430453)
			(xy 432.063196 -136.378519) (xy 432.040247 -136.323115) (xy 432.024726 -136.26519) (xy 432.016898 -136.205734)
			(xy 432.016408 -136.17575) (xy 413.961072 -136.17575) (xy 413.961072 -136.177274) (xy 413.960582 -136.207258)
			(xy 413.952754 -136.266714) (xy 413.937233 -136.324639) (xy 413.914284 -136.380043) (xy 413.8843 -136.431977)
			(xy 413.847794 -136.479553) (xy 413.805389 -136.521958) (xy 413.757813 -136.558464) (xy 413.705879 -136.588448)
			(xy 413.650475 -136.611397) (xy 413.59255 -136.626918) (xy 413.533094 -136.634746) (xy 413.473126 -136.634746)
			(xy 413.41367 -136.626918) (xy 413.355745 -136.611397) (xy 413.300341 -136.588448) (xy 413.248407 -136.558464)
			(xy 413.200831 -136.521958) (xy 413.158426 -136.479553) (xy 413.12192 -136.431977) (xy 413.091936 -136.380043)
			(xy 413.068987 -136.324639) (xy 413.053466 -136.266714) (xy 413.045638 -136.207258) (xy 413.045148 -136.177274)
			(xy 401.000468 -136.177274) (xy 401.000468 -136.69645) (xy 400.999978 -136.726418) (xy 400.992155 -136.78584)
			(xy 400.976642 -136.843733) (xy 400.953706 -136.899106) (xy 400.923739 -136.951012) (xy 400.887252 -136.998562)
			(xy 400.844872 -137.040942) (xy 400.797322 -137.077429) (xy 400.745416 -137.107396) (xy 400.690043 -137.130332)
			(xy 400.63215 -137.145845) (xy 400.572728 -137.153668) (xy 400.512792 -137.153668) (xy 400.45337 -137.145845)
			(xy 400.395477 -137.130332) (xy 400.340104 -137.107396) (xy 400.288198 -137.077429) (xy 400.240648 -137.040942)
			(xy 400.198268 -136.998562) (xy 400.161781 -136.951012) (xy 400.131814 -136.899106) (xy 400.108878 -136.843733)
			(xy 400.093365 -136.78584) (xy 400.085542 -136.726418) (xy 400.085052 -136.69645) (xy 386.525516 -136.69645)
			(xy 386.525516 -136.704324) (xy 386.525026 -136.734292) (xy 386.517203 -136.793714) (xy 386.50169 -136.851607)
			(xy 386.478754 -136.90698) (xy 386.448787 -136.958886) (xy 386.4123 -137.006436) (xy 386.36992 -137.048816)
			(xy 386.32237 -137.085303) (xy 386.270464 -137.11527) (xy 386.215091 -137.138206) (xy 386.157198 -137.153719)
			(xy 386.097776 -137.161542) (xy 386.03784 -137.161542) (xy 385.978418 -137.153719) (xy 385.920525 -137.138206)
			(xy 385.865152 -137.11527) (xy 385.813246 -137.085303) (xy 385.765696 -137.048816) (xy 385.723316 -137.006436)
			(xy 385.686829 -136.958886) (xy 385.656862 -136.90698) (xy 385.633926 -136.851607) (xy 385.618413 -136.793714)
			(xy 385.61059 -136.734292) (xy 385.6101 -136.704324) (xy 284.900495 -136.704324) (xy 284.900134 -136.726434)
			(xy 284.892306 -136.78589) (xy 284.876785 -136.843815) (xy 284.853836 -136.899219) (xy 284.823852 -136.951153)
			(xy 284.787346 -136.998729) (xy 284.744941 -137.041134) (xy 284.697365 -137.07764) (xy 284.645431 -137.107624)
			(xy 284.590027 -137.130573) (xy 284.532102 -137.146094) (xy 284.472646 -137.153922) (xy 284.412678 -137.153922)
			(xy 284.353222 -137.146094) (xy 284.295297 -137.130573) (xy 284.239893 -137.107624) (xy 284.187959 -137.07764)
			(xy 284.140383 -137.041134) (xy 284.097978 -136.998729) (xy 284.061472 -136.951153) (xy 284.031488 -136.899219)
			(xy 284.008539 -136.843815) (xy 283.993018 -136.78589) (xy 283.98519 -136.726434) (xy 283.9847 -136.69645)
			(xy 270.425672 -136.69645) (xy 270.425672 -136.704324) (xy 270.425182 -136.734308) (xy 270.417354 -136.793764)
			(xy 270.401833 -136.851689) (xy 270.378884 -136.907093) (xy 270.3489 -136.959027) (xy 270.312394 -137.006603)
			(xy 270.269989 -137.049008) (xy 270.222413 -137.085514) (xy 270.170479 -137.115498) (xy 270.115075 -137.138447)
			(xy 270.05715 -137.153968) (xy 269.997694 -137.161796) (xy 269.937726 -137.161796) (xy 269.87827 -137.153968)
			(xy 269.820345 -137.138447) (xy 269.764941 -137.115498) (xy 269.713007 -137.085514) (xy 269.665431 -137.049008)
			(xy 269.623026 -137.006603) (xy 269.58652 -136.959027) (xy 269.556536 -136.907093) (xy 269.533587 -136.851689)
			(xy 269.518066 -136.793764) (xy 269.510238 -136.734308) (xy 269.509748 -136.704324) (xy 168.800651 -136.704324)
			(xy 168.80029 -136.726434) (xy 168.792462 -136.78589) (xy 168.776941 -136.843815) (xy 168.753992 -136.899219)
			(xy 168.724008 -136.951153) (xy 168.687502 -136.998729) (xy 168.645097 -137.041134) (xy 168.597521 -137.07764)
			(xy 168.545587 -137.107624) (xy 168.490183 -137.130573) (xy 168.432258 -137.146094) (xy 168.372802 -137.153922)
			(xy 168.312834 -137.153922) (xy 168.253378 -137.146094) (xy 168.195453 -137.130573) (xy 168.140049 -137.107624)
			(xy 168.088115 -137.07764) (xy 168.040539 -137.041134) (xy 167.998134 -136.998729) (xy 167.961628 -136.951153)
			(xy 167.931644 -136.899219) (xy 167.908695 -136.843815) (xy 167.893174 -136.78589) (xy 167.885346 -136.726434)
			(xy 167.884856 -136.69645) (xy 154.325828 -136.69645) (xy 154.325828 -136.704324) (xy 154.325338 -136.734308)
			(xy 154.31751 -136.793764) (xy 154.301989 -136.851689) (xy 154.27904 -136.907093) (xy 154.249056 -136.959027)
			(xy 154.21255 -137.006603) (xy 154.170145 -137.049008) (xy 154.122569 -137.085514) (xy 154.070635 -137.115498)
			(xy 154.015231 -137.138447) (xy 153.957306 -137.153968) (xy 153.89785 -137.161796) (xy 153.837882 -137.161796)
			(xy 153.778426 -137.153968) (xy 153.720501 -137.138447) (xy 153.665097 -137.115498) (xy 153.613163 -137.085514)
			(xy 153.565587 -137.049008) (xy 153.523182 -137.006603) (xy 153.486676 -136.959027) (xy 153.456692 -136.907093)
			(xy 153.433743 -136.851689) (xy 153.418222 -136.793764) (xy 153.410394 -136.734308) (xy 153.409904 -136.704324)
			(xy 52.700299 -136.704324) (xy 52.699938 -136.726418) (xy 52.692115 -136.78584) (xy 52.676602 -136.843733)
			(xy 52.653666 -136.899106) (xy 52.623699 -136.951012) (xy 52.587212 -136.998562) (xy 52.544832 -137.040942)
			(xy 52.497282 -137.077429) (xy 52.445376 -137.107396) (xy 52.390003 -137.130332) (xy 52.33211 -137.145845)
			(xy 52.272688 -137.153668) (xy 52.212752 -137.153668) (xy 52.15333 -137.145845) (xy 52.095437 -137.130332)
			(xy 52.040064 -137.107396) (xy 51.988158 -137.077429) (xy 51.940608 -137.040942) (xy 51.898228 -136.998562)
			(xy 51.861741 -136.951012) (xy 51.831774 -136.899106) (xy 51.808838 -136.843733) (xy 51.793325 -136.78584)
			(xy 51.785502 -136.726418) (xy 51.785012 -136.69645) (xy 38.225476 -136.69645) (xy 38.225476 -136.704324)
			(xy 38.224986 -136.734292) (xy 38.217163 -136.793714) (xy 38.20165 -136.851607) (xy 38.178714 -136.90698)
			(xy 38.148747 -136.958886) (xy 38.11226 -137.006436) (xy 38.06988 -137.048816) (xy 38.02233 -137.085303)
			(xy 37.970424 -137.11527) (xy 37.915051 -137.138206) (xy 37.857158 -137.153719) (xy 37.797736 -137.161542)
			(xy 37.7378 -137.161542) (xy 37.678378 -137.153719) (xy 37.620485 -137.138206) (xy 37.565112 -137.11527)
			(xy 37.513206 -137.085303) (xy 37.465656 -137.048816) (xy 37.423276 -137.006436) (xy 37.386789 -136.958886)
			(xy 37.356822 -136.90698) (xy 37.333886 -136.851607) (xy 37.318373 -136.793714) (xy 37.31055 -136.734292)
			(xy 37.31006 -136.704324) (xy 4.308094 -136.704324) (xy 4.308094 -138.496548) (xy 43.97248 -138.496548)
			(xy 43.97248 -137.632948) (xy 43.97297 -137.602964) (xy 43.980798 -137.543508) (xy 43.996319 -137.485583)
			(xy 44.019268 -137.430179) (xy 44.049252 -137.378245) (xy 44.085758 -137.330669) (xy 44.128163 -137.288264)
			(xy 44.175739 -137.251758) (xy 44.227673 -137.221774) (xy 44.283077 -137.198825) (xy 44.341002 -137.183304)
			(xy 44.400458 -137.175476) (xy 44.460426 -137.175476) (xy 44.519882 -137.183304) (xy 44.577807 -137.198825)
			(xy 44.633211 -137.221774) (xy 44.685145 -137.251758) (xy 44.732721 -137.288264) (xy 44.775126 -137.330669)
			(xy 44.811632 -137.378245) (xy 44.841616 -137.430179) (xy 44.864565 -137.485583) (xy 44.880086 -137.543508)
			(xy 44.887914 -137.602964) (xy 44.888404 -137.632948) (xy 44.888404 -138.496548) (xy 160.072324 -138.496548)
			(xy 160.072324 -137.632948) (xy 160.072814 -137.602964) (xy 160.080642 -137.543508) (xy 160.096163 -137.485583)
			(xy 160.119112 -137.430179) (xy 160.149096 -137.378245) (xy 160.185602 -137.330669) (xy 160.228007 -137.288264)
			(xy 160.275583 -137.251758) (xy 160.327517 -137.221774) (xy 160.382921 -137.198825) (xy 160.440846 -137.183304)
			(xy 160.500302 -137.175476) (xy 160.56027 -137.175476) (xy 160.619726 -137.183304) (xy 160.677651 -137.198825)
			(xy 160.733055 -137.221774) (xy 160.784989 -137.251758) (xy 160.832565 -137.288264) (xy 160.87497 -137.330669)
			(xy 160.911476 -137.378245) (xy 160.94146 -137.430179) (xy 160.964409 -137.485583) (xy 160.97993 -137.543508)
			(xy 160.987758 -137.602964) (xy 160.988248 -137.632948) (xy 160.988248 -138.496548) (xy 276.172676 -138.496548)
			(xy 276.172676 -137.632948) (xy 276.173166 -137.60298) (xy 276.180989 -137.543558) (xy 276.196502 -137.485665)
			(xy 276.219438 -137.430292) (xy 276.249405 -137.378386) (xy 276.285892 -137.330836) (xy 276.328272 -137.288456)
			(xy 276.375822 -137.251969) (xy 276.427728 -137.222002) (xy 276.483101 -137.199066) (xy 276.540994 -137.183553)
			(xy 276.600416 -137.17573) (xy 276.660352 -137.17573) (xy 276.719774 -137.183553) (xy 276.777667 -137.199066)
			(xy 276.83304 -137.222002) (xy 276.884946 -137.251969) (xy 276.932496 -137.288456) (xy 276.974876 -137.330836)
			(xy 277.011363 -137.378386) (xy 277.04133 -137.430292) (xy 277.064266 -137.485665) (xy 277.079779 -137.543558)
			(xy 277.087602 -137.60298) (xy 277.088092 -137.632948) (xy 277.088092 -138.496548) (xy 277.088084 -138.497056)
			(xy 392.27252 -138.497056) (xy 392.27252 -137.633456) (xy 392.27301 -137.603472) (xy 392.280838 -137.544016)
			(xy 392.296359 -137.486091) (xy 392.319308 -137.430687) (xy 392.349292 -137.378753) (xy 392.385798 -137.331177)
			(xy 392.428203 -137.288772) (xy 392.475779 -137.252266) (xy 392.527713 -137.222282) (xy 392.583117 -137.199333)
			(xy 392.641042 -137.183812) (xy 392.700498 -137.175984) (xy 392.760466 -137.175984) (xy 392.819922 -137.183812)
			(xy 392.877847 -137.199333) (xy 392.933251 -137.222282) (xy 392.985185 -137.252266) (xy 393.032761 -137.288772)
			(xy 393.075166 -137.331177) (xy 393.111672 -137.378753) (xy 393.141656 -137.430687) (xy 393.164605 -137.486091)
			(xy 393.180126 -137.544016) (xy 393.187954 -137.603472) (xy 393.188444 -137.633456) (xy 393.188444 -138.497056)
			(xy 393.187954 -138.52704) (xy 393.180126 -138.586496) (xy 393.164605 -138.644421) (xy 393.141656 -138.699825)
			(xy 393.111672 -138.751759) (xy 393.075166 -138.799335) (xy 393.032761 -138.84174) (xy 392.985185 -138.878246)
			(xy 392.933251 -138.90823) (xy 392.877847 -138.931179) (xy 392.819922 -138.9467) (xy 392.760466 -138.954528)
			(xy 392.700498 -138.954528) (xy 392.641042 -138.9467) (xy 392.583117 -138.931179) (xy 392.527713 -138.90823)
			(xy 392.475779 -138.878246) (xy 392.428203 -138.84174) (xy 392.385798 -138.799335) (xy 392.349292 -138.751759)
			(xy 392.319308 -138.699825) (xy 392.296359 -138.644421) (xy 392.280838 -138.586496) (xy 392.27301 -138.52704)
			(xy 392.27252 -138.497056) (xy 277.088084 -138.497056) (xy 277.087602 -138.526516) (xy 277.079779 -138.585938)
			(xy 277.064266 -138.643831) (xy 277.04133 -138.699204) (xy 277.011363 -138.75111) (xy 276.974876 -138.79866)
			(xy 276.932496 -138.84104) (xy 276.884946 -138.877527) (xy 276.83304 -138.907494) (xy 276.777667 -138.93043)
			(xy 276.719774 -138.945943) (xy 276.660352 -138.953766) (xy 276.600416 -138.953766) (xy 276.540994 -138.945943)
			(xy 276.483101 -138.93043) (xy 276.427728 -138.907494) (xy 276.375822 -138.877527) (xy 276.328272 -138.84104)
			(xy 276.285892 -138.79866) (xy 276.249405 -138.75111) (xy 276.219438 -138.699204) (xy 276.196502 -138.643831)
			(xy 276.180989 -138.585938) (xy 276.173166 -138.526516) (xy 276.172676 -138.496548) (xy 160.988248 -138.496548)
			(xy 160.987758 -138.526532) (xy 160.97993 -138.585988) (xy 160.964409 -138.643913) (xy 160.94146 -138.699317)
			(xy 160.911476 -138.751251) (xy 160.87497 -138.798827) (xy 160.832565 -138.841232) (xy 160.784989 -138.877738)
			(xy 160.733055 -138.907722) (xy 160.677651 -138.930671) (xy 160.619726 -138.946192) (xy 160.56027 -138.95402)
			(xy 160.500302 -138.95402) (xy 160.440846 -138.946192) (xy 160.382921 -138.930671) (xy 160.327517 -138.907722)
			(xy 160.275583 -138.877738) (xy 160.228007 -138.841232) (xy 160.185602 -138.798827) (xy 160.149096 -138.751251)
			(xy 160.119112 -138.699317) (xy 160.096163 -138.643913) (xy 160.080642 -138.585988) (xy 160.072814 -138.526532)
			(xy 160.072324 -138.496548) (xy 44.888404 -138.496548) (xy 44.887914 -138.526532) (xy 44.880086 -138.585988)
			(xy 44.864565 -138.643913) (xy 44.841616 -138.699317) (xy 44.811632 -138.751251) (xy 44.775126 -138.798827)
			(xy 44.732721 -138.841232) (xy 44.685145 -138.877738) (xy 44.633211 -138.907722) (xy 44.577807 -138.930671)
			(xy 44.519882 -138.946192) (xy 44.460426 -138.95402) (xy 44.400458 -138.95402) (xy 44.341002 -138.946192)
			(xy 44.283077 -138.930671) (xy 44.227673 -138.907722) (xy 44.175739 -138.877738) (xy 44.128163 -138.841232)
			(xy 44.085758 -138.798827) (xy 44.049252 -138.751251) (xy 44.019268 -138.699317) (xy 43.996319 -138.643913)
			(xy 43.980798 -138.585988) (xy 43.97297 -138.526532) (xy 43.97248 -138.496548) (xy 4.308094 -138.496548)
			(xy 4.308094 -143.48714) (xy 66.599308 -143.48714) (xy 66.599308 -142.62354) (xy 66.599798 -142.593556)
			(xy 66.607626 -142.5341) (xy 66.623147 -142.476175) (xy 66.646096 -142.420771) (xy 66.67608 -142.368837)
			(xy 66.712586 -142.321261) (xy 66.754991 -142.278856) (xy 66.802567 -142.24235) (xy 66.854501 -142.212366)
			(xy 66.909905 -142.189417) (xy 66.96783 -142.173896) (xy 67.027286 -142.166068) (xy 67.087254 -142.166068)
			(xy 67.14671 -142.173896) (xy 67.204635 -142.189417) (xy 67.260039 -142.212366) (xy 67.311973 -142.24235)
			(xy 67.359549 -142.278856) (xy 67.401954 -142.321261) (xy 67.43846 -142.368837) (xy 67.468444 -142.420771)
			(xy 67.491393 -142.476175) (xy 67.506914 -142.5341) (xy 67.514742 -142.593556) (xy 67.515232 -142.62354)
			(xy 67.515232 -143.479266) (xy 81.07426 -143.479266) (xy 81.07426 -142.615666) (xy 81.07475 -142.585682)
			(xy 81.082578 -142.526226) (xy 81.098099 -142.468301) (xy 81.121048 -142.412897) (xy 81.151032 -142.360963)
			(xy 81.187538 -142.313387) (xy 81.229943 -142.270982) (xy 81.277519 -142.234476) (xy 81.329453 -142.204492)
			(xy 81.384857 -142.181543) (xy 81.442782 -142.166022) (xy 81.502238 -142.158194) (xy 81.562206 -142.158194)
			(xy 81.621662 -142.166022) (xy 81.679587 -142.181543) (xy 81.734991 -142.204492) (xy 81.786925 -142.234476)
			(xy 81.834501 -142.270982) (xy 81.876906 -142.313387) (xy 81.913412 -142.360963) (xy 81.943396 -142.412897)
			(xy 81.966345 -142.468301) (xy 81.981866 -142.526226) (xy 81.989694 -142.585682) (xy 81.990184 -142.615666)
			(xy 81.990184 -143.479266) (xy 81.990055 -143.48714) (xy 182.69966 -143.48714) (xy 182.69966 -142.62354)
			(xy 182.70015 -142.593572) (xy 182.707973 -142.53415) (xy 182.723486 -142.476257) (xy 182.746422 -142.420884)
			(xy 182.776389 -142.368978) (xy 182.812876 -142.321428) (xy 182.855256 -142.279048) (xy 182.902806 -142.242561)
			(xy 182.954712 -142.212594) (xy 183.010085 -142.189658) (xy 183.067978 -142.174145) (xy 183.1274 -142.166322)
			(xy 183.187336 -142.166322) (xy 183.246758 -142.174145) (xy 183.304651 -142.189658) (xy 183.360024 -142.212594)
			(xy 183.41193 -142.242561) (xy 183.45948 -142.279048) (xy 183.50186 -142.321428) (xy 183.538347 -142.368978)
			(xy 183.568314 -142.420884) (xy 183.59125 -142.476257) (xy 183.606763 -142.53415) (xy 183.614586 -142.593572)
			(xy 183.615076 -142.62354) (xy 183.615076 -143.479266) (xy 197.174612 -143.479266) (xy 197.174612 -142.615666)
			(xy 197.175102 -142.585698) (xy 197.182925 -142.526276) (xy 197.198438 -142.468383) (xy 197.221374 -142.41301)
			(xy 197.251341 -142.361104) (xy 197.287828 -142.313554) (xy 197.330208 -142.271174) (xy 197.377758 -142.234687)
			(xy 197.429664 -142.20472) (xy 197.485037 -142.181784) (xy 197.54293 -142.166271) (xy 197.602352 -142.158448)
			(xy 197.662288 -142.158448) (xy 197.72171 -142.166271) (xy 197.779603 -142.181784) (xy 197.834976 -142.20472)
			(xy 197.886882 -142.234687) (xy 197.934432 -142.271174) (xy 197.976812 -142.313554) (xy 198.013299 -142.361104)
			(xy 198.043266 -142.41301) (xy 198.066202 -142.468383) (xy 198.081715 -142.526276) (xy 198.089538 -142.585698)
			(xy 198.090028 -142.615666) (xy 198.090028 -143.479266) (xy 198.089899 -143.48714) (xy 298.799504 -143.48714)
			(xy 298.799504 -142.62354) (xy 298.799994 -142.593572) (xy 298.807817 -142.53415) (xy 298.82333 -142.476257)
			(xy 298.846266 -142.420884) (xy 298.876233 -142.368978) (xy 298.91272 -142.321428) (xy 298.9551 -142.279048)
			(xy 299.00265 -142.242561) (xy 299.054556 -142.212594) (xy 299.109929 -142.189658) (xy 299.167822 -142.174145)
			(xy 299.227244 -142.166322) (xy 299.28718 -142.166322) (xy 299.346602 -142.174145) (xy 299.404495 -142.189658)
			(xy 299.459868 -142.212594) (xy 299.511774 -142.242561) (xy 299.559324 -142.279048) (xy 299.601704 -142.321428)
			(xy 299.638191 -142.368978) (xy 299.668158 -142.420884) (xy 299.691094 -142.476257) (xy 299.706607 -142.53415)
			(xy 299.71443 -142.593572) (xy 299.71492 -142.62354) (xy 299.71492 -143.479266) (xy 313.274456 -143.479266)
			(xy 313.274456 -142.615666) (xy 313.274946 -142.585698) (xy 313.282769 -142.526276) (xy 313.298282 -142.468383)
			(xy 313.321218 -142.41301) (xy 313.351185 -142.361104) (xy 313.387672 -142.313554) (xy 313.430052 -142.271174)
			(xy 313.477602 -142.234687) (xy 313.529508 -142.20472) (xy 313.584881 -142.181784) (xy 313.642774 -142.166271)
			(xy 313.702196 -142.158448) (xy 313.762132 -142.158448) (xy 313.821554 -142.166271) (xy 313.879447 -142.181784)
			(xy 313.93482 -142.20472) (xy 313.986726 -142.234687) (xy 314.034276 -142.271174) (xy 314.076656 -142.313554)
			(xy 314.113143 -142.361104) (xy 314.14311 -142.41301) (xy 314.166046 -142.468383) (xy 314.181559 -142.526276)
			(xy 314.189382 -142.585698) (xy 314.189872 -142.615666) (xy 314.189872 -143.479266) (xy 314.189743 -143.48714)
			(xy 414.899348 -143.48714) (xy 414.899348 -142.62354) (xy 414.899838 -142.593556) (xy 414.907666 -142.5341)
			(xy 414.923187 -142.476175) (xy 414.946136 -142.420771) (xy 414.97612 -142.368837) (xy 415.012626 -142.321261)
			(xy 415.055031 -142.278856) (xy 415.102607 -142.24235) (xy 415.154541 -142.212366) (xy 415.209945 -142.189417)
			(xy 415.26787 -142.173896) (xy 415.327326 -142.166068) (xy 415.387294 -142.166068) (xy 415.44675 -142.173896)
			(xy 415.504675 -142.189417) (xy 415.560079 -142.212366) (xy 415.612013 -142.24235) (xy 415.659589 -142.278856)
			(xy 415.701994 -142.321261) (xy 415.7385 -142.368837) (xy 415.768484 -142.420771) (xy 415.791433 -142.476175)
			(xy 415.806954 -142.5341) (xy 415.814782 -142.593556) (xy 415.815272 -142.62354) (xy 415.815272 -143.479266)
			(xy 429.3743 -143.479266) (xy 429.3743 -142.615666) (xy 429.37479 -142.585682) (xy 429.382618 -142.526226)
			(xy 429.398139 -142.468301) (xy 429.421088 -142.412897) (xy 429.451072 -142.360963) (xy 429.487578 -142.313387)
			(xy 429.529983 -142.270982) (xy 429.577559 -142.234476) (xy 429.629493 -142.204492) (xy 429.684897 -142.181543)
			(xy 429.742822 -142.166022) (xy 429.802278 -142.158194) (xy 429.862246 -142.158194) (xy 429.921702 -142.166022)
			(xy 429.979627 -142.181543) (xy 430.035031 -142.204492) (xy 430.086965 -142.234476) (xy 430.134541 -142.270982)
			(xy 430.176946 -142.313387) (xy 430.213452 -142.360963) (xy 430.243436 -142.412897) (xy 430.266385 -142.468301)
			(xy 430.281906 -142.526226) (xy 430.289734 -142.585682) (xy 430.290224 -142.615666) (xy 430.290224 -143.479266)
			(xy 430.289734 -143.50925) (xy 430.281906 -143.568706) (xy 430.266385 -143.626631) (xy 430.243436 -143.682035)
			(xy 430.213452 -143.733969) (xy 430.176946 -143.781545) (xy 430.134541 -143.82395) (xy 430.086965 -143.860456)
			(xy 430.035031 -143.89044) (xy 429.979627 -143.913389) (xy 429.921702 -143.92891) (xy 429.862246 -143.936738)
			(xy 429.802278 -143.936738) (xy 429.742822 -143.92891) (xy 429.684897 -143.913389) (xy 429.629493 -143.89044)
			(xy 429.577559 -143.860456) (xy 429.529983 -143.82395) (xy 429.487578 -143.781545) (xy 429.451072 -143.733969)
			(xy 429.421088 -143.682035) (xy 429.398139 -143.626631) (xy 429.382618 -143.568706) (xy 429.37479 -143.50925)
			(xy 429.3743 -143.479266) (xy 415.815272 -143.479266) (xy 415.815272 -143.48714) (xy 415.814782 -143.517124)
			(xy 415.806954 -143.57658) (xy 415.791433 -143.634505) (xy 415.768484 -143.689909) (xy 415.7385 -143.741843)
			(xy 415.701994 -143.789419) (xy 415.659589 -143.831824) (xy 415.612013 -143.86833) (xy 415.560079 -143.898314)
			(xy 415.504675 -143.921263) (xy 415.44675 -143.936784) (xy 415.387294 -143.944612) (xy 415.327326 -143.944612)
			(xy 415.26787 -143.936784) (xy 415.209945 -143.921263) (xy 415.154541 -143.898314) (xy 415.102607 -143.86833)
			(xy 415.055031 -143.831824) (xy 415.012626 -143.789419) (xy 414.97612 -143.741843) (xy 414.946136 -143.689909)
			(xy 414.923187 -143.634505) (xy 414.907666 -143.57658) (xy 414.899838 -143.517124) (xy 414.899348 -143.48714)
			(xy 314.189743 -143.48714) (xy 314.189382 -143.509234) (xy 314.181559 -143.568656) (xy 314.166046 -143.626549)
			(xy 314.14311 -143.681922) (xy 314.113143 -143.733828) (xy 314.076656 -143.781378) (xy 314.034276 -143.823758)
			(xy 313.986726 -143.860245) (xy 313.93482 -143.890212) (xy 313.879447 -143.913148) (xy 313.821554 -143.928661)
			(xy 313.762132 -143.936484) (xy 313.702196 -143.936484) (xy 313.642774 -143.928661) (xy 313.584881 -143.913148)
			(xy 313.529508 -143.890212) (xy 313.477602 -143.860245) (xy 313.430052 -143.823758) (xy 313.387672 -143.781378)
			(xy 313.351185 -143.733828) (xy 313.321218 -143.681922) (xy 313.298282 -143.626549) (xy 313.282769 -143.568656)
			(xy 313.274946 -143.509234) (xy 313.274456 -143.479266) (xy 299.71492 -143.479266) (xy 299.71492 -143.48714)
			(xy 299.71443 -143.517108) (xy 299.706607 -143.57653) (xy 299.691094 -143.634423) (xy 299.668158 -143.689796)
			(xy 299.638191 -143.741702) (xy 299.601704 -143.789252) (xy 299.559324 -143.831632) (xy 299.511774 -143.868119)
			(xy 299.459868 -143.898086) (xy 299.404495 -143.921022) (xy 299.346602 -143.936535) (xy 299.28718 -143.944358)
			(xy 299.227244 -143.944358) (xy 299.167822 -143.936535) (xy 299.109929 -143.921022) (xy 299.054556 -143.898086)
			(xy 299.00265 -143.868119) (xy 298.9551 -143.831632) (xy 298.91272 -143.789252) (xy 298.876233 -143.741702)
			(xy 298.846266 -143.689796) (xy 298.82333 -143.634423) (xy 298.807817 -143.57653) (xy 298.799994 -143.517108)
			(xy 298.799504 -143.48714) (xy 198.089899 -143.48714) (xy 198.089538 -143.509234) (xy 198.081715 -143.568656)
			(xy 198.066202 -143.626549) (xy 198.043266 -143.681922) (xy 198.013299 -143.733828) (xy 197.976812 -143.781378)
			(xy 197.934432 -143.823758) (xy 197.886882 -143.860245) (xy 197.834976 -143.890212) (xy 197.779603 -143.913148)
			(xy 197.72171 -143.928661) (xy 197.662288 -143.936484) (xy 197.602352 -143.936484) (xy 197.54293 -143.928661)
			(xy 197.485037 -143.913148) (xy 197.429664 -143.890212) (xy 197.377758 -143.860245) (xy 197.330208 -143.823758)
			(xy 197.287828 -143.781378) (xy 197.251341 -143.733828) (xy 197.221374 -143.681922) (xy 197.198438 -143.626549)
			(xy 197.182925 -143.568656) (xy 197.175102 -143.509234) (xy 197.174612 -143.479266) (xy 183.615076 -143.479266)
			(xy 183.615076 -143.48714) (xy 183.614586 -143.517108) (xy 183.606763 -143.57653) (xy 183.59125 -143.634423)
			(xy 183.568314 -143.689796) (xy 183.538347 -143.741702) (xy 183.50186 -143.789252) (xy 183.45948 -143.831632)
			(xy 183.41193 -143.868119) (xy 183.360024 -143.898086) (xy 183.304651 -143.921022) (xy 183.246758 -143.936535)
			(xy 183.187336 -143.944358) (xy 183.1274 -143.944358) (xy 183.067978 -143.936535) (xy 183.010085 -143.921022)
			(xy 182.954712 -143.898086) (xy 182.902806 -143.868119) (xy 182.855256 -143.831632) (xy 182.812876 -143.789252)
			(xy 182.776389 -143.741702) (xy 182.746422 -143.689796) (xy 182.723486 -143.634423) (xy 182.707973 -143.57653)
			(xy 182.70015 -143.517108) (xy 182.69966 -143.48714) (xy 81.990055 -143.48714) (xy 81.989694 -143.50925)
			(xy 81.981866 -143.568706) (xy 81.966345 -143.626631) (xy 81.943396 -143.682035) (xy 81.913412 -143.733969)
			(xy 81.876906 -143.781545) (xy 81.834501 -143.82395) (xy 81.786925 -143.860456) (xy 81.734991 -143.89044)
			(xy 81.679587 -143.913389) (xy 81.621662 -143.92891) (xy 81.562206 -143.936738) (xy 81.502238 -143.936738)
			(xy 81.442782 -143.92891) (xy 81.384857 -143.913389) (xy 81.329453 -143.89044) (xy 81.277519 -143.860456)
			(xy 81.229943 -143.82395) (xy 81.187538 -143.781545) (xy 81.151032 -143.733969) (xy 81.121048 -143.682035)
			(xy 81.098099 -143.626631) (xy 81.082578 -143.568706) (xy 81.07475 -143.50925) (xy 81.07426 -143.479266)
			(xy 67.515232 -143.479266) (xy 67.515232 -143.48714) (xy 67.514742 -143.517124) (xy 67.506914 -143.57658)
			(xy 67.491393 -143.634505) (xy 67.468444 -143.689909) (xy 67.43846 -143.741843) (xy 67.401954 -143.789419)
			(xy 67.359549 -143.831824) (xy 67.311973 -143.86833) (xy 67.260039 -143.898314) (xy 67.204635 -143.921263)
			(xy 67.14671 -143.936784) (xy 67.087254 -143.944612) (xy 67.027286 -143.944612) (xy 66.96783 -143.936784)
			(xy 66.909905 -143.921263) (xy 66.854501 -143.898314) (xy 66.802567 -143.86833) (xy 66.754991 -143.831824)
			(xy 66.712586 -143.789419) (xy 66.67608 -143.741843) (xy 66.646096 -143.689909) (xy 66.623147 -143.634505)
			(xy 66.607626 -143.57658) (xy 66.599798 -143.517124) (xy 66.599308 -143.48714) (xy 4.308094 -143.48714)
			(xy 4.308094 -145.287238) (xy 64.745108 -145.287238) (xy 64.745108 -144.423638) (xy 64.745598 -144.393654)
			(xy 64.753426 -144.334198) (xy 64.768947 -144.276273) (xy 64.791896 -144.220869) (xy 64.82188 -144.168935)
			(xy 64.858386 -144.121359) (xy 64.900791 -144.078954) (xy 64.948367 -144.042448) (xy 65.000301 -144.012464)
			(xy 65.055705 -143.989515) (xy 65.11363 -143.973994) (xy 65.173086 -143.966166) (xy 65.233054 -143.966166)
			(xy 65.29251 -143.973994) (xy 65.350435 -143.989515) (xy 65.405839 -144.012464) (xy 65.457773 -144.042448)
			(xy 65.505349 -144.078954) (xy 65.547754 -144.121359) (xy 65.58426 -144.168935) (xy 65.614244 -144.220869)
			(xy 65.637193 -144.276273) (xy 65.652714 -144.334198) (xy 65.660542 -144.393654) (xy 65.661032 -144.423638)
			(xy 65.661032 -145.285714) (xy 83.716368 -145.285714) (xy 83.716368 -144.422114) (xy 83.716858 -144.39213)
			(xy 83.724686 -144.332674) (xy 83.740207 -144.274749) (xy 83.763156 -144.219345) (xy 83.79314 -144.167411)
			(xy 83.829646 -144.119835) (xy 83.872051 -144.07743) (xy 83.919627 -144.040924) (xy 83.971561 -144.01094)
			(xy 84.026965 -143.987991) (xy 84.08489 -143.97247) (xy 84.144346 -143.964642) (xy 84.204314 -143.964642)
			(xy 84.26377 -143.97247) (xy 84.321695 -143.987991) (xy 84.377099 -144.01094) (xy 84.429033 -144.040924)
			(xy 84.476609 -144.07743) (xy 84.519014 -144.119835) (xy 84.55552 -144.167411) (xy 84.585504 -144.219345)
			(xy 84.608453 -144.274749) (xy 84.623974 -144.332674) (xy 84.631802 -144.39213) (xy 84.632292 -144.422114)
			(xy 84.632292 -145.285714) (xy 84.632267 -145.287238) (xy 180.84546 -145.287238) (xy 180.84546 -144.423638)
			(xy 180.84595 -144.39367) (xy 180.853773 -144.334248) (xy 180.869286 -144.276355) (xy 180.892222 -144.220982)
			(xy 180.922189 -144.169076) (xy 180.958676 -144.121526) (xy 181.001056 -144.079146) (xy 181.048606 -144.042659)
			(xy 181.100512 -144.012692) (xy 181.155885 -143.989756) (xy 181.213778 -143.974243) (xy 181.2732 -143.96642)
			(xy 181.333136 -143.96642) (xy 181.392558 -143.974243) (xy 181.450451 -143.989756) (xy 181.505824 -144.012692)
			(xy 181.55773 -144.042659) (xy 181.60528 -144.079146) (xy 181.64766 -144.121526) (xy 181.684147 -144.169076)
			(xy 181.714114 -144.220982) (xy 181.73705 -144.276355) (xy 181.752563 -144.334248) (xy 181.760386 -144.39367)
			(xy 181.760876 -144.423638) (xy 181.760876 -145.285714) (xy 199.81672 -145.285714) (xy 199.81672 -144.422114)
			(xy 199.81721 -144.392146) (xy 199.825033 -144.332724) (xy 199.840546 -144.274831) (xy 199.863482 -144.219458)
			(xy 199.893449 -144.167552) (xy 199.929936 -144.120002) (xy 199.972316 -144.077622) (xy 200.019866 -144.041135)
			(xy 200.071772 -144.011168) (xy 200.127145 -143.988232) (xy 200.185038 -143.972719) (xy 200.24446 -143.964896)
			(xy 200.304396 -143.964896) (xy 200.363818 -143.972719) (xy 200.421711 -143.988232) (xy 200.477084 -144.011168)
			(xy 200.52899 -144.041135) (xy 200.57654 -144.077622) (xy 200.61892 -144.120002) (xy 200.655407 -144.167552)
			(xy 200.685374 -144.219458) (xy 200.70831 -144.274831) (xy 200.723823 -144.332724) (xy 200.731646 -144.392146)
			(xy 200.732136 -144.422114) (xy 200.732136 -145.285714) (xy 200.732111 -145.287238) (xy 296.945304 -145.287238)
			(xy 296.945304 -144.423638) (xy 296.945794 -144.39367) (xy 296.953617 -144.334248) (xy 296.96913 -144.276355)
			(xy 296.992066 -144.220982) (xy 297.022033 -144.169076) (xy 297.05852 -144.121526) (xy 297.1009 -144.079146)
			(xy 297.14845 -144.042659) (xy 297.200356 -144.012692) (xy 297.255729 -143.989756) (xy 297.313622 -143.974243)
			(xy 297.373044 -143.96642) (xy 297.43298 -143.96642) (xy 297.492402 -143.974243) (xy 297.550295 -143.989756)
			(xy 297.605668 -144.012692) (xy 297.657574 -144.042659) (xy 297.705124 -144.079146) (xy 297.747504 -144.121526)
			(xy 297.783991 -144.169076) (xy 297.813958 -144.220982) (xy 297.836894 -144.276355) (xy 297.852407 -144.334248)
			(xy 297.86023 -144.39367) (xy 297.86072 -144.423638) (xy 297.86072 -145.285714) (xy 315.916564 -145.285714)
			(xy 315.916564 -144.422114) (xy 315.917054 -144.392146) (xy 315.924877 -144.332724) (xy 315.94039 -144.274831)
			(xy 315.963326 -144.219458) (xy 315.993293 -144.167552) (xy 316.02978 -144.120002) (xy 316.07216 -144.077622)
			(xy 316.11971 -144.041135) (xy 316.171616 -144.011168) (xy 316.226989 -143.988232) (xy 316.284882 -143.972719)
			(xy 316.344304 -143.964896) (xy 316.40424 -143.964896) (xy 316.463662 -143.972719) (xy 316.521555 -143.988232)
			(xy 316.576928 -144.011168) (xy 316.628834 -144.041135) (xy 316.676384 -144.077622) (xy 316.718764 -144.120002)
			(xy 316.755251 -144.167552) (xy 316.785218 -144.219458) (xy 316.808154 -144.274831) (xy 316.823667 -144.332724)
			(xy 316.83149 -144.392146) (xy 316.83198 -144.422114) (xy 316.83198 -145.285714) (xy 316.831955 -145.287238)
			(xy 413.045148 -145.287238) (xy 413.045148 -144.423638) (xy 413.045638 -144.393654) (xy 413.053466 -144.334198)
			(xy 413.068987 -144.276273) (xy 413.091936 -144.220869) (xy 413.12192 -144.168935) (xy 413.158426 -144.121359)
			(xy 413.200831 -144.078954) (xy 413.248407 -144.042448) (xy 413.300341 -144.012464) (xy 413.355745 -143.989515)
			(xy 413.41367 -143.973994) (xy 413.473126 -143.966166) (xy 413.533094 -143.966166) (xy 413.59255 -143.973994)
			(xy 413.650475 -143.989515) (xy 413.705879 -144.012464) (xy 413.757813 -144.042448) (xy 413.805389 -144.078954)
			(xy 413.847794 -144.121359) (xy 413.8843 -144.168935) (xy 413.914284 -144.220869) (xy 413.937233 -144.276273)
			(xy 413.952754 -144.334198) (xy 413.960582 -144.393654) (xy 413.961072 -144.423638) (xy 413.961072 -145.285714)
			(xy 432.016408 -145.285714) (xy 432.016408 -144.422114) (xy 432.016898 -144.39213) (xy 432.024726 -144.332674)
			(xy 432.040247 -144.274749) (xy 432.063196 -144.219345) (xy 432.09318 -144.167411) (xy 432.129686 -144.119835)
			(xy 432.172091 -144.07743) (xy 432.219667 -144.040924) (xy 432.271601 -144.01094) (xy 432.327005 -143.987991)
			(xy 432.38493 -143.97247) (xy 432.444386 -143.964642) (xy 432.504354 -143.964642) (xy 432.56381 -143.97247)
			(xy 432.621735 -143.987991) (xy 432.677139 -144.01094) (xy 432.729073 -144.040924) (xy 432.776649 -144.07743)
			(xy 432.819054 -144.119835) (xy 432.85556 -144.167411) (xy 432.885544 -144.219345) (xy 432.908493 -144.274749)
			(xy 432.924014 -144.332674) (xy 432.931842 -144.39213) (xy 432.932332 -144.422114) (xy 432.932332 -145.285714)
			(xy 432.931842 -145.315698) (xy 432.924014 -145.375154) (xy 432.908493 -145.433079) (xy 432.885544 -145.488483)
			(xy 432.85556 -145.540417) (xy 432.819054 -145.587993) (xy 432.776649 -145.630398) (xy 432.729073 -145.666904)
			(xy 432.677139 -145.696888) (xy 432.621735 -145.719837) (xy 432.56381 -145.735358) (xy 432.504354 -145.743186)
			(xy 432.444386 -145.743186) (xy 432.38493 -145.735358) (xy 432.327005 -145.719837) (xy 432.271601 -145.696888)
			(xy 432.219667 -145.666904) (xy 432.172091 -145.630398) (xy 432.129686 -145.587993) (xy 432.09318 -145.540417)
			(xy 432.063196 -145.488483) (xy 432.040247 -145.433079) (xy 432.024726 -145.375154) (xy 432.016898 -145.315698)
			(xy 432.016408 -145.285714) (xy 413.961072 -145.285714) (xy 413.961072 -145.287238) (xy 413.960582 -145.317222)
			(xy 413.952754 -145.376678) (xy 413.937233 -145.434603) (xy 413.914284 -145.490007) (xy 413.8843 -145.541941)
			(xy 413.847794 -145.589517) (xy 413.805389 -145.631922) (xy 413.757813 -145.668428) (xy 413.705879 -145.698412)
			(xy 413.650475 -145.721361) (xy 413.59255 -145.736882) (xy 413.533094 -145.74471) (xy 413.473126 -145.74471)
			(xy 413.41367 -145.736882) (xy 413.355745 -145.721361) (xy 413.300341 -145.698412) (xy 413.248407 -145.668428)
			(xy 413.200831 -145.631922) (xy 413.158426 -145.589517) (xy 413.12192 -145.541941) (xy 413.091936 -145.490007)
			(xy 413.068987 -145.434603) (xy 413.053466 -145.376678) (xy 413.045638 -145.317222) (xy 413.045148 -145.287238)
			(xy 316.831955 -145.287238) (xy 316.83149 -145.315682) (xy 316.823667 -145.375104) (xy 316.808154 -145.432997)
			(xy 316.785218 -145.48837) (xy 316.755251 -145.540276) (xy 316.718764 -145.587826) (xy 316.676384 -145.630206)
			(xy 316.628834 -145.666693) (xy 316.576928 -145.69666) (xy 316.521555 -145.719596) (xy 316.463662 -145.735109)
			(xy 316.40424 -145.742932) (xy 316.344304 -145.742932) (xy 316.284882 -145.735109) (xy 316.226989 -145.719596)
			(xy 316.171616 -145.69666) (xy 316.11971 -145.666693) (xy 316.07216 -145.630206) (xy 316.02978 -145.587826)
			(xy 315.993293 -145.540276) (xy 315.963326 -145.48837) (xy 315.94039 -145.432997) (xy 315.924877 -145.375104)
			(xy 315.917054 -145.315682) (xy 315.916564 -145.285714) (xy 297.86072 -145.285714) (xy 297.86072 -145.287238)
			(xy 297.86023 -145.317206) (xy 297.852407 -145.376628) (xy 297.836894 -145.434521) (xy 297.813958 -145.489894)
			(xy 297.783991 -145.5418) (xy 297.747504 -145.58935) (xy 297.705124 -145.63173) (xy 297.657574 -145.668217)
			(xy 297.605668 -145.698184) (xy 297.550295 -145.72112) (xy 297.492402 -145.736633) (xy 297.43298 -145.744456)
			(xy 297.373044 -145.744456) (xy 297.313622 -145.736633) (xy 297.255729 -145.72112) (xy 297.200356 -145.698184)
			(xy 297.14845 -145.668217) (xy 297.1009 -145.63173) (xy 297.05852 -145.58935) (xy 297.022033 -145.5418)
			(xy 296.992066 -145.489894) (xy 296.96913 -145.434521) (xy 296.953617 -145.376628) (xy 296.945794 -145.317206)
			(xy 296.945304 -145.287238) (xy 200.732111 -145.287238) (xy 200.731646 -145.315682) (xy 200.723823 -145.375104)
			(xy 200.70831 -145.432997) (xy 200.685374 -145.48837) (xy 200.655407 -145.540276) (xy 200.61892 -145.587826)
			(xy 200.57654 -145.630206) (xy 200.52899 -145.666693) (xy 200.477084 -145.69666) (xy 200.421711 -145.719596)
			(xy 200.363818 -145.735109) (xy 200.304396 -145.742932) (xy 200.24446 -145.742932) (xy 200.185038 -145.735109)
			(xy 200.127145 -145.719596) (xy 200.071772 -145.69666) (xy 200.019866 -145.666693) (xy 199.972316 -145.630206)
			(xy 199.929936 -145.587826) (xy 199.893449 -145.540276) (xy 199.863482 -145.48837) (xy 199.840546 -145.432997)
			(xy 199.825033 -145.375104) (xy 199.81721 -145.315682) (xy 199.81672 -145.285714) (xy 181.760876 -145.285714)
			(xy 181.760876 -145.287238) (xy 181.760386 -145.317206) (xy 181.752563 -145.376628) (xy 181.73705 -145.434521)
			(xy 181.714114 -145.489894) (xy 181.684147 -145.5418) (xy 181.64766 -145.58935) (xy 181.60528 -145.63173)
			(xy 181.55773 -145.668217) (xy 181.505824 -145.698184) (xy 181.450451 -145.72112) (xy 181.392558 -145.736633)
			(xy 181.333136 -145.744456) (xy 181.2732 -145.744456) (xy 181.213778 -145.736633) (xy 181.155885 -145.72112)
			(xy 181.100512 -145.698184) (xy 181.048606 -145.668217) (xy 181.001056 -145.63173) (xy 180.958676 -145.58935)
			(xy 180.922189 -145.5418) (xy 180.892222 -145.489894) (xy 180.869286 -145.434521) (xy 180.853773 -145.376628)
			(xy 180.84595 -145.317206) (xy 180.84546 -145.287238) (xy 84.632267 -145.287238) (xy 84.631802 -145.315698)
			(xy 84.623974 -145.375154) (xy 84.608453 -145.433079) (xy 84.585504 -145.488483) (xy 84.55552 -145.540417)
			(xy 84.519014 -145.587993) (xy 84.476609 -145.630398) (xy 84.429033 -145.666904) (xy 84.377099 -145.696888)
			(xy 84.321695 -145.719837) (xy 84.26377 -145.735358) (xy 84.204314 -145.743186) (xy 84.144346 -145.743186)
			(xy 84.08489 -145.735358) (xy 84.026965 -145.719837) (xy 83.971561 -145.696888) (xy 83.919627 -145.666904)
			(xy 83.872051 -145.630398) (xy 83.829646 -145.587993) (xy 83.79314 -145.540417) (xy 83.763156 -145.488483)
			(xy 83.740207 -145.433079) (xy 83.724686 -145.375154) (xy 83.716858 -145.315698) (xy 83.716368 -145.285714)
			(xy 65.661032 -145.285714) (xy 65.661032 -145.287238) (xy 65.660542 -145.317222) (xy 65.652714 -145.376678)
			(xy 65.637193 -145.434603) (xy 65.614244 -145.490007) (xy 65.58426 -145.541941) (xy 65.547754 -145.589517)
			(xy 65.505349 -145.631922) (xy 65.457773 -145.668428) (xy 65.405839 -145.698412) (xy 65.350435 -145.721361)
			(xy 65.29251 -145.736882) (xy 65.233054 -145.74471) (xy 65.173086 -145.74471) (xy 65.11363 -145.736882)
			(xy 65.055705 -145.721361) (xy 65.000301 -145.698412) (xy 64.948367 -145.668428) (xy 64.900791 -145.631922)
			(xy 64.858386 -145.589517) (xy 64.82188 -145.541941) (xy 64.791896 -145.490007) (xy 64.768947 -145.434603)
			(xy 64.753426 -145.376678) (xy 64.745598 -145.317222) (xy 64.745108 -145.287238) (xy 4.308094 -145.287238)
			(xy 4.308094 -147.087336) (xy 66.599308 -147.087336) (xy 66.599308 -146.223736) (xy 66.599798 -146.193752)
			(xy 66.607626 -146.134296) (xy 66.623147 -146.076371) (xy 66.646096 -146.020967) (xy 66.67608 -145.969033)
			(xy 66.712586 -145.921457) (xy 66.754991 -145.879052) (xy 66.802567 -145.842546) (xy 66.854501 -145.812562)
			(xy 66.909905 -145.789613) (xy 66.96783 -145.774092) (xy 67.027286 -145.766264) (xy 67.087254 -145.766264)
			(xy 67.14671 -145.774092) (xy 67.204635 -145.789613) (xy 67.260039 -145.812562) (xy 67.311973 -145.842546)
			(xy 67.359549 -145.879052) (xy 67.401954 -145.921457) (xy 67.43846 -145.969033) (xy 67.468444 -146.020967)
			(xy 67.491393 -146.076371) (xy 67.506914 -146.134296) (xy 67.514742 -146.193752) (xy 67.515232 -146.223736)
			(xy 67.515232 -147.079208) (xy 81.07426 -147.079208) (xy 81.07426 -146.215608) (xy 81.07475 -146.185624)
			(xy 81.082578 -146.126168) (xy 81.098099 -146.068243) (xy 81.121048 -146.012839) (xy 81.151032 -145.960905)
			(xy 81.187538 -145.913329) (xy 81.229943 -145.870924) (xy 81.277519 -145.834418) (xy 81.329453 -145.804434)
			(xy 81.384857 -145.781485) (xy 81.442782 -145.765964) (xy 81.502238 -145.758136) (xy 81.562206 -145.758136)
			(xy 81.621662 -145.765964) (xy 81.679587 -145.781485) (xy 81.734991 -145.804434) (xy 81.786925 -145.834418)
			(xy 81.834501 -145.870924) (xy 81.876906 -145.913329) (xy 81.913412 -145.960905) (xy 81.943396 -146.012839)
			(xy 81.966345 -146.068243) (xy 81.981866 -146.126168) (xy 81.989694 -146.185624) (xy 81.990184 -146.215608)
			(xy 81.990184 -147.079208) (xy 81.990051 -147.087336) (xy 182.69966 -147.087336) (xy 182.69966 -146.223736)
			(xy 182.70015 -146.193768) (xy 182.707973 -146.134346) (xy 182.723486 -146.076453) (xy 182.746422 -146.02108)
			(xy 182.776389 -145.969174) (xy 182.812876 -145.921624) (xy 182.855256 -145.879244) (xy 182.902806 -145.842757)
			(xy 182.954712 -145.81279) (xy 183.010085 -145.789854) (xy 183.067978 -145.774341) (xy 183.1274 -145.766518)
			(xy 183.187336 -145.766518) (xy 183.246758 -145.774341) (xy 183.304651 -145.789854) (xy 183.360024 -145.81279)
			(xy 183.41193 -145.842757) (xy 183.45948 -145.879244) (xy 183.50186 -145.921624) (xy 183.538347 -145.969174)
			(xy 183.568314 -146.02108) (xy 183.59125 -146.076453) (xy 183.606763 -146.134346) (xy 183.614586 -146.193768)
			(xy 183.615076 -146.223736) (xy 183.615076 -147.079208) (xy 197.174612 -147.079208) (xy 197.174612 -146.215608)
			(xy 197.175102 -146.18564) (xy 197.182925 -146.126218) (xy 197.198438 -146.068325) (xy 197.221374 -146.012952)
			(xy 197.251341 -145.961046) (xy 197.287828 -145.913496) (xy 197.330208 -145.871116) (xy 197.377758 -145.834629)
			(xy 197.429664 -145.804662) (xy 197.485037 -145.781726) (xy 197.54293 -145.766213) (xy 197.602352 -145.75839)
			(xy 197.662288 -145.75839) (xy 197.72171 -145.766213) (xy 197.779603 -145.781726) (xy 197.834976 -145.804662)
			(xy 197.886882 -145.834629) (xy 197.934432 -145.871116) (xy 197.976812 -145.913496) (xy 198.013299 -145.961046)
			(xy 198.043266 -146.012952) (xy 198.066202 -146.068325) (xy 198.081715 -146.126218) (xy 198.089538 -146.18564)
			(xy 198.090028 -146.215608) (xy 198.090028 -147.079208) (xy 198.089895 -147.087336) (xy 298.799504 -147.087336)
			(xy 298.799504 -146.223736) (xy 298.799994 -146.193768) (xy 298.807817 -146.134346) (xy 298.82333 -146.076453)
			(xy 298.846266 -146.02108) (xy 298.876233 -145.969174) (xy 298.91272 -145.921624) (xy 298.9551 -145.879244)
			(xy 299.00265 -145.842757) (xy 299.054556 -145.81279) (xy 299.109929 -145.789854) (xy 299.167822 -145.774341)
			(xy 299.227244 -145.766518) (xy 299.28718 -145.766518) (xy 299.346602 -145.774341) (xy 299.404495 -145.789854)
			(xy 299.459868 -145.81279) (xy 299.511774 -145.842757) (xy 299.559324 -145.879244) (xy 299.601704 -145.921624)
			(xy 299.638191 -145.969174) (xy 299.668158 -146.02108) (xy 299.691094 -146.076453) (xy 299.706607 -146.134346)
			(xy 299.71443 -146.193768) (xy 299.71492 -146.223736) (xy 299.71492 -147.079208) (xy 313.274456 -147.079208)
			(xy 313.274456 -146.215608) (xy 313.274946 -146.18564) (xy 313.282769 -146.126218) (xy 313.298282 -146.068325)
			(xy 313.321218 -146.012952) (xy 313.351185 -145.961046) (xy 313.387672 -145.913496) (xy 313.430052 -145.871116)
			(xy 313.477602 -145.834629) (xy 313.529508 -145.804662) (xy 313.584881 -145.781726) (xy 313.642774 -145.766213)
			(xy 313.702196 -145.75839) (xy 313.762132 -145.75839) (xy 313.821554 -145.766213) (xy 313.879447 -145.781726)
			(xy 313.93482 -145.804662) (xy 313.986726 -145.834629) (xy 314.034276 -145.871116) (xy 314.076656 -145.913496)
			(xy 314.113143 -145.961046) (xy 314.14311 -146.012952) (xy 314.166046 -146.068325) (xy 314.181559 -146.126218)
			(xy 314.189382 -146.18564) (xy 314.189872 -146.215608) (xy 314.189872 -147.079208) (xy 314.189739 -147.087336)
			(xy 414.899348 -147.087336) (xy 414.899348 -146.223736) (xy 414.899838 -146.193752) (xy 414.907666 -146.134296)
			(xy 414.923187 -146.076371) (xy 414.946136 -146.020967) (xy 414.97612 -145.969033) (xy 415.012626 -145.921457)
			(xy 415.055031 -145.879052) (xy 415.102607 -145.842546) (xy 415.154541 -145.812562) (xy 415.209945 -145.789613)
			(xy 415.26787 -145.774092) (xy 415.327326 -145.766264) (xy 415.387294 -145.766264) (xy 415.44675 -145.774092)
			(xy 415.504675 -145.789613) (xy 415.560079 -145.812562) (xy 415.612013 -145.842546) (xy 415.659589 -145.879052)
			(xy 415.701994 -145.921457) (xy 415.7385 -145.969033) (xy 415.768484 -146.020967) (xy 415.791433 -146.076371)
			(xy 415.806954 -146.134296) (xy 415.814782 -146.193752) (xy 415.815272 -146.223736) (xy 415.815272 -147.079208)
			(xy 429.3743 -147.079208) (xy 429.3743 -146.215608) (xy 429.37479 -146.185624) (xy 429.382618 -146.126168)
			(xy 429.398139 -146.068243) (xy 429.421088 -146.012839) (xy 429.451072 -145.960905) (xy 429.487578 -145.913329)
			(xy 429.529983 -145.870924) (xy 429.577559 -145.834418) (xy 429.629493 -145.804434) (xy 429.684897 -145.781485)
			(xy 429.742822 -145.765964) (xy 429.802278 -145.758136) (xy 429.862246 -145.758136) (xy 429.921702 -145.765964)
			(xy 429.979627 -145.781485) (xy 430.035031 -145.804434) (xy 430.086965 -145.834418) (xy 430.134541 -145.870924)
			(xy 430.176946 -145.913329) (xy 430.213452 -145.960905) (xy 430.243436 -146.012839) (xy 430.266385 -146.068243)
			(xy 430.281906 -146.126168) (xy 430.289734 -146.185624) (xy 430.290224 -146.215608) (xy 430.290224 -147.079208)
			(xy 430.289734 -147.109192) (xy 430.281906 -147.168648) (xy 430.266385 -147.226573) (xy 430.243436 -147.281977)
			(xy 430.213452 -147.333911) (xy 430.176946 -147.381487) (xy 430.134541 -147.423892) (xy 430.086965 -147.460398)
			(xy 430.035031 -147.490382) (xy 429.979627 -147.513331) (xy 429.921702 -147.528852) (xy 429.862246 -147.53668)
			(xy 429.802278 -147.53668) (xy 429.742822 -147.528852) (xy 429.684897 -147.513331) (xy 429.629493 -147.490382)
			(xy 429.577559 -147.460398) (xy 429.529983 -147.423892) (xy 429.487578 -147.381487) (xy 429.451072 -147.333911)
			(xy 429.421088 -147.281977) (xy 429.398139 -147.226573) (xy 429.382618 -147.168648) (xy 429.37479 -147.109192)
			(xy 429.3743 -147.079208) (xy 415.815272 -147.079208) (xy 415.815272 -147.087336) (xy 415.814782 -147.11732)
			(xy 415.806954 -147.176776) (xy 415.791433 -147.234701) (xy 415.768484 -147.290105) (xy 415.7385 -147.342039)
			(xy 415.701994 -147.389615) (xy 415.659589 -147.43202) (xy 415.612013 -147.468526) (xy 415.560079 -147.49851)
			(xy 415.504675 -147.521459) (xy 415.44675 -147.53698) (xy 415.387294 -147.544808) (xy 415.327326 -147.544808)
			(xy 415.26787 -147.53698) (xy 415.209945 -147.521459) (xy 415.154541 -147.49851) (xy 415.102607 -147.468526)
			(xy 415.055031 -147.43202) (xy 415.012626 -147.389615) (xy 414.97612 -147.342039) (xy 414.946136 -147.290105)
			(xy 414.923187 -147.234701) (xy 414.907666 -147.176776) (xy 414.899838 -147.11732) (xy 414.899348 -147.087336)
			(xy 314.189739 -147.087336) (xy 314.189382 -147.109176) (xy 314.181559 -147.168598) (xy 314.166046 -147.226491)
			(xy 314.14311 -147.281864) (xy 314.113143 -147.33377) (xy 314.076656 -147.38132) (xy 314.034276 -147.4237)
			(xy 313.986726 -147.460187) (xy 313.93482 -147.490154) (xy 313.879447 -147.51309) (xy 313.821554 -147.528603)
			(xy 313.762132 -147.536426) (xy 313.702196 -147.536426) (xy 313.642774 -147.528603) (xy 313.584881 -147.51309)
			(xy 313.529508 -147.490154) (xy 313.477602 -147.460187) (xy 313.430052 -147.4237) (xy 313.387672 -147.38132)
			(xy 313.351185 -147.33377) (xy 313.321218 -147.281864) (xy 313.298282 -147.226491) (xy 313.282769 -147.168598)
			(xy 313.274946 -147.109176) (xy 313.274456 -147.079208) (xy 299.71492 -147.079208) (xy 299.71492 -147.087336)
			(xy 299.71443 -147.117304) (xy 299.706607 -147.176726) (xy 299.691094 -147.234619) (xy 299.668158 -147.289992)
			(xy 299.638191 -147.341898) (xy 299.601704 -147.389448) (xy 299.559324 -147.431828) (xy 299.511774 -147.468315)
			(xy 299.459868 -147.498282) (xy 299.404495 -147.521218) (xy 299.346602 -147.536731) (xy 299.28718 -147.544554)
			(xy 299.227244 -147.544554) (xy 299.167822 -147.536731) (xy 299.109929 -147.521218) (xy 299.054556 -147.498282)
			(xy 299.00265 -147.468315) (xy 298.9551 -147.431828) (xy 298.91272 -147.389448) (xy 298.876233 -147.341898)
			(xy 298.846266 -147.289992) (xy 298.82333 -147.234619) (xy 298.807817 -147.176726) (xy 298.799994 -147.117304)
			(xy 298.799504 -147.087336) (xy 198.089895 -147.087336) (xy 198.089538 -147.109176) (xy 198.081715 -147.168598)
			(xy 198.066202 -147.226491) (xy 198.043266 -147.281864) (xy 198.013299 -147.33377) (xy 197.976812 -147.38132)
			(xy 197.934432 -147.4237) (xy 197.886882 -147.460187) (xy 197.834976 -147.490154) (xy 197.779603 -147.51309)
			(xy 197.72171 -147.528603) (xy 197.662288 -147.536426) (xy 197.602352 -147.536426) (xy 197.54293 -147.528603)
			(xy 197.485037 -147.51309) (xy 197.429664 -147.490154) (xy 197.377758 -147.460187) (xy 197.330208 -147.4237)
			(xy 197.287828 -147.38132) (xy 197.251341 -147.33377) (xy 197.221374 -147.281864) (xy 197.198438 -147.226491)
			(xy 197.182925 -147.168598) (xy 197.175102 -147.109176) (xy 197.174612 -147.079208) (xy 183.615076 -147.079208)
			(xy 183.615076 -147.087336) (xy 183.614586 -147.117304) (xy 183.606763 -147.176726) (xy 183.59125 -147.234619)
			(xy 183.568314 -147.289992) (xy 183.538347 -147.341898) (xy 183.50186 -147.389448) (xy 183.45948 -147.431828)
			(xy 183.41193 -147.468315) (xy 183.360024 -147.498282) (xy 183.304651 -147.521218) (xy 183.246758 -147.536731)
			(xy 183.187336 -147.544554) (xy 183.1274 -147.544554) (xy 183.067978 -147.536731) (xy 183.010085 -147.521218)
			(xy 182.954712 -147.498282) (xy 182.902806 -147.468315) (xy 182.855256 -147.431828) (xy 182.812876 -147.389448)
			(xy 182.776389 -147.341898) (xy 182.746422 -147.289992) (xy 182.723486 -147.234619) (xy 182.707973 -147.176726)
			(xy 182.70015 -147.117304) (xy 182.69966 -147.087336) (xy 81.990051 -147.087336) (xy 81.989694 -147.109192)
			(xy 81.981866 -147.168648) (xy 81.966345 -147.226573) (xy 81.943396 -147.281977) (xy 81.913412 -147.333911)
			(xy 81.876906 -147.381487) (xy 81.834501 -147.423892) (xy 81.786925 -147.460398) (xy 81.734991 -147.490382)
			(xy 81.679587 -147.513331) (xy 81.621662 -147.528852) (xy 81.562206 -147.53668) (xy 81.502238 -147.53668)
			(xy 81.442782 -147.528852) (xy 81.384857 -147.513331) (xy 81.329453 -147.490382) (xy 81.277519 -147.460398)
			(xy 81.229943 -147.423892) (xy 81.187538 -147.381487) (xy 81.151032 -147.333911) (xy 81.121048 -147.281977)
			(xy 81.098099 -147.226573) (xy 81.082578 -147.168648) (xy 81.07475 -147.109192) (xy 81.07426 -147.079208)
			(xy 67.515232 -147.079208) (xy 67.515232 -147.087336) (xy 67.514742 -147.11732) (xy 67.506914 -147.176776)
			(xy 67.491393 -147.234701) (xy 67.468444 -147.290105) (xy 67.43846 -147.342039) (xy 67.401954 -147.389615)
			(xy 67.359549 -147.43202) (xy 67.311973 -147.468526) (xy 67.260039 -147.49851) (xy 67.204635 -147.521459)
			(xy 67.14671 -147.53698) (xy 67.087254 -147.544808) (xy 67.027286 -147.544808) (xy 66.96783 -147.53698)
			(xy 66.909905 -147.521459) (xy 66.854501 -147.49851) (xy 66.802567 -147.468526) (xy 66.754991 -147.43202)
			(xy 66.712586 -147.389615) (xy 66.67608 -147.342039) (xy 66.646096 -147.290105) (xy 66.623147 -147.234701)
			(xy 66.607626 -147.176776) (xy 66.599798 -147.11732) (xy 66.599308 -147.087336) (xy 4.308094 -147.087336)
			(xy 4.308094 -148.887434) (xy 64.745108 -148.887434) (xy 64.745108 -148.023834) (xy 64.745598 -147.99385)
			(xy 64.753426 -147.934394) (xy 64.768947 -147.876469) (xy 64.791896 -147.821065) (xy 64.82188 -147.769131)
			(xy 64.858386 -147.721555) (xy 64.900791 -147.67915) (xy 64.948367 -147.642644) (xy 65.000301 -147.61266)
			(xy 65.055705 -147.589711) (xy 65.11363 -147.57419) (xy 65.173086 -147.566362) (xy 65.233054 -147.566362)
			(xy 65.29251 -147.57419) (xy 65.350435 -147.589711) (xy 65.405839 -147.61266) (xy 65.457773 -147.642644)
			(xy 65.505349 -147.67915) (xy 65.547754 -147.721555) (xy 65.58426 -147.769131) (xy 65.614244 -147.821065)
			(xy 65.637193 -147.876469) (xy 65.652714 -147.934394) (xy 65.660542 -147.99385) (xy 65.661032 -148.023834)
			(xy 65.661032 -148.88591) (xy 83.716368 -148.88591) (xy 83.716368 -148.02231) (xy 83.716858 -147.992326)
			(xy 83.724686 -147.93287) (xy 83.740207 -147.874945) (xy 83.763156 -147.819541) (xy 83.79314 -147.767607)
			(xy 83.829646 -147.720031) (xy 83.872051 -147.677626) (xy 83.919627 -147.64112) (xy 83.971561 -147.611136)
			(xy 84.026965 -147.588187) (xy 84.08489 -147.572666) (xy 84.144346 -147.564838) (xy 84.204314 -147.564838)
			(xy 84.26377 -147.572666) (xy 84.321695 -147.588187) (xy 84.377099 -147.611136) (xy 84.429033 -147.64112)
			(xy 84.476609 -147.677626) (xy 84.519014 -147.720031) (xy 84.55552 -147.767607) (xy 84.585504 -147.819541)
			(xy 84.608453 -147.874945) (xy 84.623974 -147.93287) (xy 84.631802 -147.992326) (xy 84.632292 -148.02231)
			(xy 84.632292 -148.88591) (xy 84.632267 -148.887434) (xy 180.84546 -148.887434) (xy 180.84546 -148.023834)
			(xy 180.84595 -147.993866) (xy 180.853773 -147.934444) (xy 180.869286 -147.876551) (xy 180.892222 -147.821178)
			(xy 180.922189 -147.769272) (xy 180.958676 -147.721722) (xy 181.001056 -147.679342) (xy 181.048606 -147.642855)
			(xy 181.100512 -147.612888) (xy 181.155885 -147.589952) (xy 181.213778 -147.574439) (xy 181.2732 -147.566616)
			(xy 181.333136 -147.566616) (xy 181.392558 -147.574439) (xy 181.450451 -147.589952) (xy 181.505824 -147.612888)
			(xy 181.55773 -147.642855) (xy 181.60528 -147.679342) (xy 181.64766 -147.721722) (xy 181.684147 -147.769272)
			(xy 181.714114 -147.821178) (xy 181.73705 -147.876551) (xy 181.752563 -147.934444) (xy 181.760386 -147.993866)
			(xy 181.760876 -148.023834) (xy 181.760876 -148.88591) (xy 199.81672 -148.88591) (xy 199.81672 -148.02231)
			(xy 199.81721 -147.992342) (xy 199.825033 -147.93292) (xy 199.840546 -147.875027) (xy 199.863482 -147.819654)
			(xy 199.893449 -147.767748) (xy 199.929936 -147.720198) (xy 199.972316 -147.677818) (xy 200.019866 -147.641331)
			(xy 200.071772 -147.611364) (xy 200.127145 -147.588428) (xy 200.185038 -147.572915) (xy 200.24446 -147.565092)
			(xy 200.304396 -147.565092) (xy 200.363818 -147.572915) (xy 200.421711 -147.588428) (xy 200.477084 -147.611364)
			(xy 200.52899 -147.641331) (xy 200.57654 -147.677818) (xy 200.61892 -147.720198) (xy 200.655407 -147.767748)
			(xy 200.685374 -147.819654) (xy 200.70831 -147.875027) (xy 200.723823 -147.93292) (xy 200.731646 -147.992342)
			(xy 200.732136 -148.02231) (xy 200.732136 -148.88591) (xy 200.731646 -148.915878) (xy 200.723823 -148.9753)
			(xy 200.70831 -149.033193) (xy 200.685374 -149.088566) (xy 200.655407 -149.140472) (xy 200.61892 -149.188022)
			(xy 200.57654 -149.230402) (xy 200.52899 -149.266889) (xy 200.477084 -149.296856) (xy 200.421711 -149.319792)
			(xy 200.363818 -149.335305) (xy 200.304396 -149.343128) (xy 200.24446 -149.343128) (xy 200.185038 -149.335305)
			(xy 200.127145 -149.319792) (xy 200.071772 -149.296856) (xy 200.019866 -149.266889) (xy 199.972316 -149.230402)
			(xy 199.929936 -149.188022) (xy 199.893449 -149.140472) (xy 199.863482 -149.088566) (xy 199.840546 -149.033193)
			(xy 199.825033 -148.9753) (xy 199.81721 -148.915878) (xy 199.81672 -148.88591) (xy 181.760876 -148.88591)
			(xy 181.760876 -148.887434) (xy 181.760386 -148.917402) (xy 181.752563 -148.976824) (xy 181.73705 -149.034717)
			(xy 181.714114 -149.09009) (xy 181.684147 -149.141996) (xy 181.64766 -149.189546) (xy 181.60528 -149.231926)
			(xy 181.55773 -149.268413) (xy 181.505824 -149.29838) (xy 181.450451 -149.321316) (xy 181.392558 -149.336829)
			(xy 181.333136 -149.344652) (xy 181.2732 -149.344652) (xy 181.213778 -149.336829) (xy 181.155885 -149.321316)
			(xy 181.100512 -149.29838) (xy 181.048606 -149.268413) (xy 181.001056 -149.231926) (xy 180.958676 -149.189546)
			(xy 180.922189 -149.141996) (xy 180.892222 -149.09009) (xy 180.869286 -149.034717) (xy 180.853773 -148.976824)
			(xy 180.84595 -148.917402) (xy 180.84546 -148.887434) (xy 84.632267 -148.887434) (xy 84.631802 -148.915894)
			(xy 84.623974 -148.97535) (xy 84.608453 -149.033275) (xy 84.585504 -149.088679) (xy 84.55552 -149.140613)
			(xy 84.519014 -149.188189) (xy 84.476609 -149.230594) (xy 84.429033 -149.2671) (xy 84.377099 -149.297084)
			(xy 84.321695 -149.320033) (xy 84.26377 -149.335554) (xy 84.204314 -149.343382) (xy 84.144346 -149.343382)
			(xy 84.08489 -149.335554) (xy 84.026965 -149.320033) (xy 83.971561 -149.297084) (xy 83.919627 -149.2671)
			(xy 83.872051 -149.230594) (xy 83.829646 -149.188189) (xy 83.79314 -149.140613) (xy 83.763156 -149.088679)
			(xy 83.740207 -149.033275) (xy 83.724686 -148.97535) (xy 83.716858 -148.915894) (xy 83.716368 -148.88591)
			(xy 65.661032 -148.88591) (xy 65.661032 -148.887434) (xy 65.660542 -148.917418) (xy 65.652714 -148.976874)
			(xy 65.637193 -149.034799) (xy 65.614244 -149.090203) (xy 65.58426 -149.142137) (xy 65.547754 -149.189713)
			(xy 65.505349 -149.232118) (xy 65.457773 -149.268624) (xy 65.405839 -149.298608) (xy 65.350435 -149.321557)
			(xy 65.29251 -149.337078) (xy 65.233054 -149.344906) (xy 65.173086 -149.344906) (xy 65.11363 -149.337078)
			(xy 65.055705 -149.321557) (xy 65.000301 -149.298608) (xy 64.948367 -149.268624) (xy 64.900791 -149.232118)
			(xy 64.858386 -149.189713) (xy 64.82188 -149.142137) (xy 64.791896 -149.090203) (xy 64.768947 -149.034799)
			(xy 64.753426 -148.976874) (xy 64.745598 -148.917418) (xy 64.745108 -148.887434) (xy 4.308094 -148.887434)
			(xy 4.308094 -150.687278) (xy 66.599308 -150.687278) (xy 66.599308 -149.823678) (xy 66.599798 -149.793694)
			(xy 66.607626 -149.734238) (xy 66.623147 -149.676313) (xy 66.646096 -149.620909) (xy 66.67608 -149.568975)
			(xy 66.712586 -149.521399) (xy 66.754991 -149.478994) (xy 66.802567 -149.442488) (xy 66.854501 -149.412504)
			(xy 66.909905 -149.389555) (xy 66.96783 -149.374034) (xy 67.027286 -149.366206) (xy 67.087254 -149.366206)
			(xy 67.14671 -149.374034) (xy 67.204635 -149.389555) (xy 67.260039 -149.412504) (xy 67.311973 -149.442488)
			(xy 67.359549 -149.478994) (xy 67.401954 -149.521399) (xy 67.43846 -149.568975) (xy 67.468444 -149.620909)
			(xy 67.491393 -149.676313) (xy 67.506914 -149.734238) (xy 67.514742 -149.793694) (xy 67.515232 -149.823678)
			(xy 67.515232 -150.67915) (xy 81.07426 -150.67915) (xy 81.07426 -149.81555) (xy 81.07475 -149.785566)
			(xy 81.082578 -149.72611) (xy 81.098099 -149.668185) (xy 81.121048 -149.612781) (xy 81.151032 -149.560847)
			(xy 81.187538 -149.513271) (xy 81.229943 -149.470866) (xy 81.277519 -149.43436) (xy 81.329453 -149.404376)
			(xy 81.384857 -149.381427) (xy 81.442782 -149.365906) (xy 81.502238 -149.358078) (xy 81.562206 -149.358078)
			(xy 81.621662 -149.365906) (xy 81.679587 -149.381427) (xy 81.734991 -149.404376) (xy 81.786925 -149.43436)
			(xy 81.834501 -149.470866) (xy 81.876906 -149.513271) (xy 81.913412 -149.560847) (xy 81.943396 -149.612781)
			(xy 81.966345 -149.668185) (xy 81.981866 -149.72611) (xy 81.989694 -149.785566) (xy 81.990184 -149.81555)
			(xy 81.990184 -150.67915) (xy 81.990051 -150.687278) (xy 182.69966 -150.687278) (xy 182.69966 -149.823678)
			(xy 182.70015 -149.79371) (xy 182.707973 -149.734288) (xy 182.723486 -149.676395) (xy 182.746422 -149.621022)
			(xy 182.776389 -149.569116) (xy 182.812876 -149.521566) (xy 182.855256 -149.479186) (xy 182.902806 -149.442699)
			(xy 182.954712 -149.412732) (xy 183.010085 -149.389796) (xy 183.067978 -149.374283) (xy 183.1274 -149.36646)
			(xy 183.187336 -149.36646) (xy 183.246758 -149.374283) (xy 183.304651 -149.389796) (xy 183.360024 -149.412732)
			(xy 183.41193 -149.442699) (xy 183.45948 -149.479186) (xy 183.50186 -149.521566) (xy 183.538347 -149.569116)
			(xy 183.568314 -149.621022) (xy 183.59125 -149.676395) (xy 183.606763 -149.734288) (xy 183.614586 -149.79371)
			(xy 183.615076 -149.823678) (xy 183.615076 -150.67915) (xy 197.174612 -150.67915) (xy 197.174612 -149.81555)
			(xy 197.175102 -149.785582) (xy 197.182925 -149.72616) (xy 197.198438 -149.668267) (xy 197.221374 -149.612894)
			(xy 197.251341 -149.560988) (xy 197.287828 -149.513438) (xy 197.330208 -149.471058) (xy 197.377758 -149.434571)
			(xy 197.429664 -149.404604) (xy 197.485037 -149.381668) (xy 197.54293 -149.366155) (xy 197.602352 -149.358332)
			(xy 197.662288 -149.358332) (xy 197.72171 -149.366155) (xy 197.779603 -149.381668) (xy 197.834976 -149.404604)
			(xy 197.886882 -149.434571) (xy 197.934432 -149.471058) (xy 197.976812 -149.513438) (xy 198.013299 -149.560988)
			(xy 198.043266 -149.612894) (xy 198.066202 -149.668267) (xy 198.072386 -149.691344) (xy 236.708188 -149.691344)
			(xy 236.708188 -148.827744) (xy 236.708678 -148.79776) (xy 236.716506 -148.738304) (xy 236.732027 -148.680379)
			(xy 236.754976 -148.624975) (xy 236.78496 -148.573041) (xy 236.821466 -148.525465) (xy 236.863871 -148.48306)
			(xy 236.911447 -148.446554) (xy 236.963381 -148.41657) (xy 237.018785 -148.393621) (xy 237.07671 -148.3781)
			(xy 237.136166 -148.370272) (xy 237.196134 -148.370272) (xy 237.25559 -148.3781) (xy 237.313515 -148.393621)
			(xy 237.368919 -148.41657) (xy 237.420853 -148.446554) (xy 237.468429 -148.48306) (xy 237.510834 -148.525465)
			(xy 237.54734 -148.573041) (xy 237.577324 -148.624975) (xy 237.600273 -148.680379) (xy 237.615794 -148.738304)
			(xy 237.623622 -148.79776) (xy 237.624112 -148.827744) (xy 237.624112 -148.887434) (xy 296.945304 -148.887434)
			(xy 296.945304 -148.023834) (xy 296.945794 -147.993866) (xy 296.953617 -147.934444) (xy 296.96913 -147.876551)
			(xy 296.992066 -147.821178) (xy 297.022033 -147.769272) (xy 297.05852 -147.721722) (xy 297.1009 -147.679342)
			(xy 297.14845 -147.642855) (xy 297.200356 -147.612888) (xy 297.255729 -147.589952) (xy 297.313622 -147.574439)
			(xy 297.373044 -147.566616) (xy 297.43298 -147.566616) (xy 297.492402 -147.574439) (xy 297.550295 -147.589952)
			(xy 297.605668 -147.612888) (xy 297.657574 -147.642855) (xy 297.705124 -147.679342) (xy 297.747504 -147.721722)
			(xy 297.783991 -147.769272) (xy 297.813958 -147.821178) (xy 297.836894 -147.876551) (xy 297.852407 -147.934444)
			(xy 297.86023 -147.993866) (xy 297.86072 -148.023834) (xy 297.86072 -148.88591) (xy 315.916564 -148.88591)
			(xy 315.916564 -148.02231) (xy 315.917054 -147.992342) (xy 315.924877 -147.93292) (xy 315.94039 -147.875027)
			(xy 315.963326 -147.819654) (xy 315.993293 -147.767748) (xy 316.02978 -147.720198) (xy 316.07216 -147.677818)
			(xy 316.11971 -147.641331) (xy 316.171616 -147.611364) (xy 316.226989 -147.588428) (xy 316.284882 -147.572915)
			(xy 316.344304 -147.565092) (xy 316.40424 -147.565092) (xy 316.463662 -147.572915) (xy 316.521555 -147.588428)
			(xy 316.576928 -147.611364) (xy 316.628834 -147.641331) (xy 316.676384 -147.677818) (xy 316.718764 -147.720198)
			(xy 316.755251 -147.767748) (xy 316.785218 -147.819654) (xy 316.808154 -147.875027) (xy 316.823667 -147.93292)
			(xy 316.83149 -147.992342) (xy 316.83198 -148.02231) (xy 316.83198 -148.88591) (xy 316.831955 -148.887434)
			(xy 413.045148 -148.887434) (xy 413.045148 -148.023834) (xy 413.045638 -147.99385) (xy 413.053466 -147.934394)
			(xy 413.068987 -147.876469) (xy 413.091936 -147.821065) (xy 413.12192 -147.769131) (xy 413.158426 -147.721555)
			(xy 413.200831 -147.67915) (xy 413.248407 -147.642644) (xy 413.300341 -147.61266) (xy 413.355745 -147.589711)
			(xy 413.41367 -147.57419) (xy 413.473126 -147.566362) (xy 413.533094 -147.566362) (xy 413.59255 -147.57419)
			(xy 413.650475 -147.589711) (xy 413.705879 -147.61266) (xy 413.757813 -147.642644) (xy 413.805389 -147.67915)
			(xy 413.847794 -147.721555) (xy 413.8843 -147.769131) (xy 413.914284 -147.821065) (xy 413.937233 -147.876469)
			(xy 413.952754 -147.934394) (xy 413.960582 -147.99385) (xy 413.961072 -148.023834) (xy 413.961072 -148.88591)
			(xy 432.016408 -148.88591) (xy 432.016408 -148.02231) (xy 432.016898 -147.992326) (xy 432.024726 -147.93287)
			(xy 432.040247 -147.874945) (xy 432.063196 -147.819541) (xy 432.09318 -147.767607) (xy 432.129686 -147.720031)
			(xy 432.172091 -147.677626) (xy 432.219667 -147.64112) (xy 432.271601 -147.611136) (xy 432.327005 -147.588187)
			(xy 432.38493 -147.572666) (xy 432.444386 -147.564838) (xy 432.504354 -147.564838) (xy 432.56381 -147.572666)
			(xy 432.621735 -147.588187) (xy 432.677139 -147.611136) (xy 432.729073 -147.64112) (xy 432.776649 -147.677626)
			(xy 432.819054 -147.720031) (xy 432.85556 -147.767607) (xy 432.885544 -147.819541) (xy 432.908493 -147.874945)
			(xy 432.924014 -147.93287) (xy 432.931842 -147.992326) (xy 432.932332 -148.02231) (xy 432.932332 -148.88591)
			(xy 432.931842 -148.915894) (xy 432.924014 -148.97535) (xy 432.908493 -149.033275) (xy 432.885544 -149.088679)
			(xy 432.85556 -149.140613) (xy 432.819054 -149.188189) (xy 432.776649 -149.230594) (xy 432.729073 -149.2671)
			(xy 432.677139 -149.297084) (xy 432.621735 -149.320033) (xy 432.56381 -149.335554) (xy 432.504354 -149.343382)
			(xy 432.444386 -149.343382) (xy 432.38493 -149.335554) (xy 432.327005 -149.320033) (xy 432.271601 -149.297084)
			(xy 432.219667 -149.2671) (xy 432.172091 -149.230594) (xy 432.129686 -149.188189) (xy 432.09318 -149.140613)
			(xy 432.063196 -149.088679) (xy 432.040247 -149.033275) (xy 432.024726 -148.97535) (xy 432.016898 -148.915894)
			(xy 432.016408 -148.88591) (xy 413.961072 -148.88591) (xy 413.961072 -148.887434) (xy 413.960582 -148.917418)
			(xy 413.952754 -148.976874) (xy 413.937233 -149.034799) (xy 413.914284 -149.090203) (xy 413.8843 -149.142137)
			(xy 413.847794 -149.189713) (xy 413.805389 -149.232118) (xy 413.757813 -149.268624) (xy 413.705879 -149.298608)
			(xy 413.650475 -149.321557) (xy 413.59255 -149.337078) (xy 413.533094 -149.344906) (xy 413.473126 -149.344906)
			(xy 413.41367 -149.337078) (xy 413.355745 -149.321557) (xy 413.300341 -149.298608) (xy 413.248407 -149.268624)
			(xy 413.200831 -149.232118) (xy 413.158426 -149.189713) (xy 413.12192 -149.142137) (xy 413.091936 -149.090203)
			(xy 413.068987 -149.034799) (xy 413.053466 -148.976874) (xy 413.045638 -148.917418) (xy 413.045148 -148.887434)
			(xy 316.831955 -148.887434) (xy 316.83149 -148.915878) (xy 316.823667 -148.9753) (xy 316.808154 -149.033193)
			(xy 316.785218 -149.088566) (xy 316.755251 -149.140472) (xy 316.718764 -149.188022) (xy 316.676384 -149.230402)
			(xy 316.628834 -149.266889) (xy 316.576928 -149.296856) (xy 316.521555 -149.319792) (xy 316.463662 -149.335305)
			(xy 316.40424 -149.343128) (xy 316.344304 -149.343128) (xy 316.284882 -149.335305) (xy 316.226989 -149.319792)
			(xy 316.171616 -149.296856) (xy 316.11971 -149.266889) (xy 316.07216 -149.230402) (xy 316.02978 -149.188022)
			(xy 315.993293 -149.140472) (xy 315.963326 -149.088566) (xy 315.94039 -149.033193) (xy 315.924877 -148.9753)
			(xy 315.917054 -148.915878) (xy 315.916564 -148.88591) (xy 297.86072 -148.88591) (xy 297.86072 -148.887434)
			(xy 297.86023 -148.917402) (xy 297.852407 -148.976824) (xy 297.836894 -149.034717) (xy 297.813958 -149.09009)
			(xy 297.783991 -149.141996) (xy 297.747504 -149.189546) (xy 297.705124 -149.231926) (xy 297.657574 -149.268413)
			(xy 297.605668 -149.29838) (xy 297.550295 -149.321316) (xy 297.492402 -149.336829) (xy 297.43298 -149.344652)
			(xy 297.373044 -149.344652) (xy 297.313622 -149.336829) (xy 297.255729 -149.321316) (xy 297.200356 -149.29838)
			(xy 297.14845 -149.268413) (xy 297.1009 -149.231926) (xy 297.05852 -149.189546) (xy 297.022033 -149.141996)
			(xy 296.992066 -149.09009) (xy 296.96913 -149.034717) (xy 296.953617 -148.976824) (xy 296.945794 -148.917402)
			(xy 296.945304 -148.887434) (xy 237.624112 -148.887434) (xy 237.624112 -149.691344) (xy 237.623622 -149.721328)
			(xy 237.615794 -149.780784) (xy 237.600273 -149.838709) (xy 237.577324 -149.894113) (xy 237.54734 -149.946047)
			(xy 237.510834 -149.993623) (xy 237.468429 -150.036028) (xy 237.420853 -150.072534) (xy 237.368919 -150.102518)
			(xy 237.313515 -150.125467) (xy 237.25559 -150.140988) (xy 237.196134 -150.148816) (xy 237.136166 -150.148816)
			(xy 237.07671 -150.140988) (xy 237.018785 -150.125467) (xy 236.963381 -150.102518) (xy 236.911447 -150.072534)
			(xy 236.863871 -150.036028) (xy 236.821466 -149.993623) (xy 236.78496 -149.946047) (xy 236.754976 -149.894113)
			(xy 236.732027 -149.838709) (xy 236.716506 -149.780784) (xy 236.708678 -149.721328) (xy 236.708188 -149.691344)
			(xy 198.072386 -149.691344) (xy 198.081715 -149.72616) (xy 198.089538 -149.785582) (xy 198.090028 -149.81555)
			(xy 198.090028 -150.67915) (xy 198.089538 -150.709118) (xy 198.081715 -150.76854) (xy 198.066202 -150.826433)
			(xy 198.043266 -150.881806) (xy 198.013299 -150.933712) (xy 197.976812 -150.981262) (xy 197.934432 -151.023642)
			(xy 197.886882 -151.060129) (xy 197.834976 -151.090096) (xy 197.779603 -151.113032) (xy 197.72171 -151.128545)
			(xy 197.662288 -151.136368) (xy 197.602352 -151.136368) (xy 197.54293 -151.128545) (xy 197.485037 -151.113032)
			(xy 197.429664 -151.090096) (xy 197.377758 -151.060129) (xy 197.330208 -151.023642) (xy 197.287828 -150.981262)
			(xy 197.251341 -150.933712) (xy 197.221374 -150.881806) (xy 197.198438 -150.826433) (xy 197.182925 -150.76854)
			(xy 197.175102 -150.709118) (xy 197.174612 -150.67915) (xy 183.615076 -150.67915) (xy 183.615076 -150.687278)
			(xy 183.614586 -150.717246) (xy 183.606763 -150.776668) (xy 183.59125 -150.834561) (xy 183.568314 -150.889934)
			(xy 183.538347 -150.94184) (xy 183.50186 -150.98939) (xy 183.45948 -151.03177) (xy 183.41193 -151.068257)
			(xy 183.360024 -151.098224) (xy 183.304651 -151.12116) (xy 183.246758 -151.136673) (xy 183.187336 -151.144496)
			(xy 183.1274 -151.144496) (xy 183.067978 -151.136673) (xy 183.010085 -151.12116) (xy 182.954712 -151.098224)
			(xy 182.902806 -151.068257) (xy 182.855256 -151.03177) (xy 182.812876 -150.98939) (xy 182.776389 -150.94184)
			(xy 182.746422 -150.889934) (xy 182.723486 -150.834561) (xy 182.707973 -150.776668) (xy 182.70015 -150.717246)
			(xy 182.69966 -150.687278) (xy 81.990051 -150.687278) (xy 81.989694 -150.709134) (xy 81.981866 -150.76859)
			(xy 81.966345 -150.826515) (xy 81.943396 -150.881919) (xy 81.913412 -150.933853) (xy 81.876906 -150.981429)
			(xy 81.834501 -151.023834) (xy 81.786925 -151.06034) (xy 81.734991 -151.090324) (xy 81.679587 -151.113273)
			(xy 81.621662 -151.128794) (xy 81.562206 -151.136622) (xy 81.502238 -151.136622) (xy 81.442782 -151.128794)
			(xy 81.384857 -151.113273) (xy 81.329453 -151.090324) (xy 81.277519 -151.06034) (xy 81.229943 -151.023834)
			(xy 81.187538 -150.981429) (xy 81.151032 -150.933853) (xy 81.121048 -150.881919) (xy 81.098099 -150.826515)
			(xy 81.082578 -150.76859) (xy 81.07475 -150.709134) (xy 81.07426 -150.67915) (xy 67.515232 -150.67915)
			(xy 67.515232 -150.687278) (xy 67.514742 -150.717262) (xy 67.506914 -150.776718) (xy 67.491393 -150.834643)
			(xy 67.468444 -150.890047) (xy 67.43846 -150.941981) (xy 67.401954 -150.989557) (xy 67.359549 -151.031962)
			(xy 67.311973 -151.068468) (xy 67.260039 -151.098452) (xy 67.204635 -151.121401) (xy 67.14671 -151.136922)
			(xy 67.087254 -151.14475) (xy 67.027286 -151.14475) (xy 66.96783 -151.136922) (xy 66.909905 -151.121401)
			(xy 66.854501 -151.098452) (xy 66.802567 -151.068468) (xy 66.754991 -151.031962) (xy 66.712586 -150.989557)
			(xy 66.67608 -150.941981) (xy 66.646096 -150.890047) (xy 66.623147 -150.834643) (xy 66.607626 -150.776718)
			(xy 66.599798 -150.717262) (xy 66.599308 -150.687278) (xy 4.308094 -150.687278) (xy 4.308094 -152.487376)
			(xy 64.745108 -152.487376) (xy 64.745108 -151.623776) (xy 64.745598 -151.593792) (xy 64.753426 -151.534336)
			(xy 64.768947 -151.476411) (xy 64.791896 -151.421007) (xy 64.82188 -151.369073) (xy 64.858386 -151.321497)
			(xy 64.900791 -151.279092) (xy 64.948367 -151.242586) (xy 65.000301 -151.212602) (xy 65.055705 -151.189653)
			(xy 65.11363 -151.174132) (xy 65.173086 -151.166304) (xy 65.233054 -151.166304) (xy 65.29251 -151.174132)
			(xy 65.350435 -151.189653) (xy 65.405839 -151.212602) (xy 65.457773 -151.242586) (xy 65.505349 -151.279092)
			(xy 65.547754 -151.321497) (xy 65.58426 -151.369073) (xy 65.614244 -151.421007) (xy 65.637193 -151.476411)
			(xy 65.652714 -151.534336) (xy 65.660542 -151.593792) (xy 65.661032 -151.623776) (xy 65.661032 -152.485852)
			(xy 83.716368 -152.485852) (xy 83.716368 -151.622252) (xy 83.716858 -151.592268) (xy 83.724686 -151.532812)
			(xy 83.740207 -151.474887) (xy 83.763156 -151.419483) (xy 83.79314 -151.367549) (xy 83.829646 -151.319973)
			(xy 83.872051 -151.277568) (xy 83.919627 -151.241062) (xy 83.971561 -151.211078) (xy 84.026965 -151.188129)
			(xy 84.08489 -151.172608) (xy 84.144346 -151.16478) (xy 84.204314 -151.16478) (xy 84.26377 -151.172608)
			(xy 84.321695 -151.188129) (xy 84.377099 -151.211078) (xy 84.429033 -151.241062) (xy 84.476609 -151.277568)
			(xy 84.519014 -151.319973) (xy 84.55552 -151.367549) (xy 84.585504 -151.419483) (xy 84.608453 -151.474887)
			(xy 84.623974 -151.532812) (xy 84.631802 -151.592268) (xy 84.632292 -151.622252) (xy 84.632292 -152.485852)
			(xy 84.632267 -152.487376) (xy 180.84546 -152.487376) (xy 180.84546 -151.623776) (xy 180.84595 -151.593808)
			(xy 180.853773 -151.534386) (xy 180.869286 -151.476493) (xy 180.892222 -151.42112) (xy 180.922189 -151.369214)
			(xy 180.958676 -151.321664) (xy 181.001056 -151.279284) (xy 181.048606 -151.242797) (xy 181.100512 -151.21283)
			(xy 181.155885 -151.189894) (xy 181.213778 -151.174381) (xy 181.2732 -151.166558) (xy 181.333136 -151.166558)
			(xy 181.392558 -151.174381) (xy 181.450451 -151.189894) (xy 181.505824 -151.21283) (xy 181.55773 -151.242797)
			(xy 181.60528 -151.279284) (xy 181.64766 -151.321664) (xy 181.684147 -151.369214) (xy 181.714114 -151.42112)
			(xy 181.73705 -151.476493) (xy 181.752563 -151.534386) (xy 181.760386 -151.593808) (xy 181.760876 -151.623776)
			(xy 181.760876 -152.485852) (xy 199.81672 -152.485852) (xy 199.81672 -151.622252) (xy 199.81721 -151.592284)
			(xy 199.825033 -151.532862) (xy 199.840546 -151.474969) (xy 199.863482 -151.419596) (xy 199.893449 -151.36769)
			(xy 199.929936 -151.32014) (xy 199.972316 -151.27776) (xy 200.019866 -151.241273) (xy 200.071772 -151.211306)
			(xy 200.127145 -151.18837) (xy 200.185038 -151.172857) (xy 200.24446 -151.165034) (xy 200.304396 -151.165034)
			(xy 200.363818 -151.172857) (xy 200.421711 -151.18837) (xy 200.477084 -151.211306) (xy 200.52899 -151.241273)
			(xy 200.57654 -151.27776) (xy 200.61892 -151.32014) (xy 200.655407 -151.36769) (xy 200.685374 -151.419596)
			(xy 200.70831 -151.474969) (xy 200.723823 -151.532862) (xy 200.731646 -151.592284) (xy 200.732136 -151.622252)
			(xy 200.732136 -151.914098) (xy 236.712252 -151.914098) (xy 236.712252 -151.050498) (xy 236.712742 -151.020514)
			(xy 236.72057 -150.961058) (xy 236.736091 -150.903133) (xy 236.75904 -150.847729) (xy 236.789024 -150.795795)
			(xy 236.82553 -150.748219) (xy 236.867935 -150.705814) (xy 236.915511 -150.669308) (xy 236.967445 -150.639324)
			(xy 237.022849 -150.616375) (xy 237.080774 -150.600854) (xy 237.14023 -150.593026) (xy 237.200198 -150.593026)
			(xy 237.259654 -150.600854) (xy 237.317579 -150.616375) (xy 237.372983 -150.639324) (xy 237.424917 -150.669308)
			(xy 237.448336 -150.687278) (xy 298.799504 -150.687278) (xy 298.799504 -149.823678) (xy 298.799994 -149.79371)
			(xy 298.807817 -149.734288) (xy 298.82333 -149.676395) (xy 298.846266 -149.621022) (xy 298.876233 -149.569116)
			(xy 298.91272 -149.521566) (xy 298.9551 -149.479186) (xy 299.00265 -149.442699) (xy 299.054556 -149.412732)
			(xy 299.109929 -149.389796) (xy 299.167822 -149.374283) (xy 299.227244 -149.36646) (xy 299.28718 -149.36646)
			(xy 299.346602 -149.374283) (xy 299.404495 -149.389796) (xy 299.459868 -149.412732) (xy 299.511774 -149.442699)
			(xy 299.559324 -149.479186) (xy 299.601704 -149.521566) (xy 299.638191 -149.569116) (xy 299.668158 -149.621022)
			(xy 299.691094 -149.676395) (xy 299.706607 -149.734288) (xy 299.71443 -149.79371) (xy 299.71492 -149.823678)
			(xy 299.71492 -150.67915) (xy 313.274456 -150.67915) (xy 313.274456 -149.81555) (xy 313.274946 -149.785582)
			(xy 313.282769 -149.72616) (xy 313.298282 -149.668267) (xy 313.321218 -149.612894) (xy 313.351185 -149.560988)
			(xy 313.387672 -149.513438) (xy 313.430052 -149.471058) (xy 313.477602 -149.434571) (xy 313.529508 -149.404604)
			(xy 313.584881 -149.381668) (xy 313.642774 -149.366155) (xy 313.702196 -149.358332) (xy 313.762132 -149.358332)
			(xy 313.821554 -149.366155) (xy 313.879447 -149.381668) (xy 313.93482 -149.404604) (xy 313.986726 -149.434571)
			(xy 314.034276 -149.471058) (xy 314.076656 -149.513438) (xy 314.113143 -149.560988) (xy 314.14311 -149.612894)
			(xy 314.166046 -149.668267) (xy 314.181559 -149.72616) (xy 314.189382 -149.785582) (xy 314.189872 -149.81555)
			(xy 314.189872 -150.67915) (xy 314.189739 -150.687278) (xy 414.899348 -150.687278) (xy 414.899348 -149.823678)
			(xy 414.899838 -149.793694) (xy 414.907666 -149.734238) (xy 414.923187 -149.676313) (xy 414.946136 -149.620909)
			(xy 414.97612 -149.568975) (xy 415.012626 -149.521399) (xy 415.055031 -149.478994) (xy 415.102607 -149.442488)
			(xy 415.154541 -149.412504) (xy 415.209945 -149.389555) (xy 415.26787 -149.374034) (xy 415.327326 -149.366206)
			(xy 415.387294 -149.366206) (xy 415.44675 -149.374034) (xy 415.504675 -149.389555) (xy 415.560079 -149.412504)
			(xy 415.612013 -149.442488) (xy 415.659589 -149.478994) (xy 415.701994 -149.521399) (xy 415.7385 -149.568975)
			(xy 415.768484 -149.620909) (xy 415.791433 -149.676313) (xy 415.806954 -149.734238) (xy 415.814782 -149.793694)
			(xy 415.815272 -149.823678) (xy 415.815272 -150.67915) (xy 429.3743 -150.67915) (xy 429.3743 -149.81555)
			(xy 429.37479 -149.785566) (xy 429.382618 -149.72611) (xy 429.398139 -149.668185) (xy 429.421088 -149.612781)
			(xy 429.451072 -149.560847) (xy 429.487578 -149.513271) (xy 429.529983 -149.470866) (xy 429.577559 -149.43436)
			(xy 429.629493 -149.404376) (xy 429.684897 -149.381427) (xy 429.742822 -149.365906) (xy 429.802278 -149.358078)
			(xy 429.862246 -149.358078) (xy 429.921702 -149.365906) (xy 429.979627 -149.381427) (xy 430.035031 -149.404376)
			(xy 430.086965 -149.43436) (xy 430.134541 -149.470866) (xy 430.176946 -149.513271) (xy 430.213452 -149.560847)
			(xy 430.243436 -149.612781) (xy 430.266385 -149.668185) (xy 430.281906 -149.72611) (xy 430.289734 -149.785566)
			(xy 430.290224 -149.81555) (xy 430.290224 -150.67915) (xy 430.289734 -150.709134) (xy 430.281906 -150.76859)
			(xy 430.266385 -150.826515) (xy 430.243436 -150.881919) (xy 430.213452 -150.933853) (xy 430.176946 -150.981429)
			(xy 430.134541 -151.023834) (xy 430.086965 -151.06034) (xy 430.035031 -151.090324) (xy 429.979627 -151.113273)
			(xy 429.921702 -151.128794) (xy 429.862246 -151.136622) (xy 429.802278 -151.136622) (xy 429.742822 -151.128794)
			(xy 429.684897 -151.113273) (xy 429.629493 -151.090324) (xy 429.577559 -151.06034) (xy 429.529983 -151.023834)
			(xy 429.487578 -150.981429) (xy 429.451072 -150.933853) (xy 429.421088 -150.881919) (xy 429.398139 -150.826515)
			(xy 429.382618 -150.76859) (xy 429.37479 -150.709134) (xy 429.3743 -150.67915) (xy 415.815272 -150.67915)
			(xy 415.815272 -150.687278) (xy 415.814782 -150.717262) (xy 415.806954 -150.776718) (xy 415.791433 -150.834643)
			(xy 415.768484 -150.890047) (xy 415.7385 -150.941981) (xy 415.701994 -150.989557) (xy 415.659589 -151.031962)
			(xy 415.612013 -151.068468) (xy 415.560079 -151.098452) (xy 415.504675 -151.121401) (xy 415.44675 -151.136922)
			(xy 415.387294 -151.14475) (xy 415.327326 -151.14475) (xy 415.26787 -151.136922) (xy 415.209945 -151.121401)
			(xy 415.154541 -151.098452) (xy 415.102607 -151.068468) (xy 415.055031 -151.031962) (xy 415.012626 -150.989557)
			(xy 414.97612 -150.941981) (xy 414.946136 -150.890047) (xy 414.923187 -150.834643) (xy 414.907666 -150.776718)
			(xy 414.899838 -150.717262) (xy 414.899348 -150.687278) (xy 314.189739 -150.687278) (xy 314.189382 -150.709118)
			(xy 314.181559 -150.76854) (xy 314.166046 -150.826433) (xy 314.14311 -150.881806) (xy 314.113143 -150.933712)
			(xy 314.076656 -150.981262) (xy 314.034276 -151.023642) (xy 313.986726 -151.060129) (xy 313.93482 -151.090096)
			(xy 313.879447 -151.113032) (xy 313.821554 -151.128545) (xy 313.762132 -151.136368) (xy 313.702196 -151.136368)
			(xy 313.642774 -151.128545) (xy 313.584881 -151.113032) (xy 313.529508 -151.090096) (xy 313.477602 -151.060129)
			(xy 313.430052 -151.023642) (xy 313.387672 -150.981262) (xy 313.351185 -150.933712) (xy 313.321218 -150.881806)
			(xy 313.298282 -150.826433) (xy 313.282769 -150.76854) (xy 313.274946 -150.709118) (xy 313.274456 -150.67915)
			(xy 299.71492 -150.67915) (xy 299.71492 -150.687278) (xy 299.71443 -150.717246) (xy 299.706607 -150.776668)
			(xy 299.691094 -150.834561) (xy 299.668158 -150.889934) (xy 299.638191 -150.94184) (xy 299.601704 -150.98939)
			(xy 299.559324 -151.03177) (xy 299.511774 -151.068257) (xy 299.459868 -151.098224) (xy 299.404495 -151.12116)
			(xy 299.346602 -151.136673) (xy 299.28718 -151.144496) (xy 299.227244 -151.144496) (xy 299.167822 -151.136673)
			(xy 299.109929 -151.12116) (xy 299.054556 -151.098224) (xy 299.00265 -151.068257) (xy 298.9551 -151.03177)
			(xy 298.91272 -150.98939) (xy 298.876233 -150.94184) (xy 298.846266 -150.889934) (xy 298.82333 -150.834561)
			(xy 298.807817 -150.776668) (xy 298.799994 -150.717246) (xy 298.799504 -150.687278) (xy 237.448336 -150.687278)
			(xy 237.472493 -150.705814) (xy 237.514898 -150.748219) (xy 237.551404 -150.795795) (xy 237.581388 -150.847729)
			(xy 237.604337 -150.903133) (xy 237.619858 -150.961058) (xy 237.627686 -151.020514) (xy 237.628176 -151.050498)
			(xy 237.628176 -151.914098) (xy 237.627686 -151.944082) (xy 237.619858 -152.003538) (xy 237.604337 -152.061463)
			(xy 237.581388 -152.116867) (xy 237.551404 -152.168801) (xy 237.514898 -152.216377) (xy 237.472493 -152.258782)
			(xy 237.424917 -152.295288) (xy 237.372983 -152.325272) (xy 237.317579 -152.348221) (xy 237.259654 -152.363742)
			(xy 237.200198 -152.37157) (xy 237.14023 -152.37157) (xy 237.080774 -152.363742) (xy 237.022849 -152.348221)
			(xy 236.967445 -152.325272) (xy 236.915511 -152.295288) (xy 236.867935 -152.258782) (xy 236.82553 -152.216377)
			(xy 236.789024 -152.168801) (xy 236.75904 -152.116867) (xy 236.736091 -152.061463) (xy 236.72057 -152.003538)
			(xy 236.712742 -151.944082) (xy 236.712252 -151.914098) (xy 200.732136 -151.914098) (xy 200.732136 -152.485852)
			(xy 200.732111 -152.487376) (xy 296.945304 -152.487376) (xy 296.945304 -151.623776) (xy 296.945794 -151.593808)
			(xy 296.953617 -151.534386) (xy 296.96913 -151.476493) (xy 296.992066 -151.42112) (xy 297.022033 -151.369214)
			(xy 297.05852 -151.321664) (xy 297.1009 -151.279284) (xy 297.14845 -151.242797) (xy 297.200356 -151.21283)
			(xy 297.255729 -151.189894) (xy 297.313622 -151.174381) (xy 297.373044 -151.166558) (xy 297.43298 -151.166558)
			(xy 297.492402 -151.174381) (xy 297.550295 -151.189894) (xy 297.605668 -151.21283) (xy 297.657574 -151.242797)
			(xy 297.705124 -151.279284) (xy 297.747504 -151.321664) (xy 297.783991 -151.369214) (xy 297.813958 -151.42112)
			(xy 297.836894 -151.476493) (xy 297.852407 -151.534386) (xy 297.86023 -151.593808) (xy 297.86072 -151.623776)
			(xy 297.86072 -152.485852) (xy 315.916564 -152.485852) (xy 315.916564 -151.622252) (xy 315.917054 -151.592284)
			(xy 315.924877 -151.532862) (xy 315.94039 -151.474969) (xy 315.963326 -151.419596) (xy 315.993293 -151.36769)
			(xy 316.02978 -151.32014) (xy 316.07216 -151.27776) (xy 316.11971 -151.241273) (xy 316.171616 -151.211306)
			(xy 316.226989 -151.18837) (xy 316.284882 -151.172857) (xy 316.344304 -151.165034) (xy 316.40424 -151.165034)
			(xy 316.463662 -151.172857) (xy 316.521555 -151.18837) (xy 316.576928 -151.211306) (xy 316.628834 -151.241273)
			(xy 316.676384 -151.27776) (xy 316.718764 -151.32014) (xy 316.755251 -151.36769) (xy 316.785218 -151.419596)
			(xy 316.808154 -151.474969) (xy 316.823667 -151.532862) (xy 316.83149 -151.592284) (xy 316.83198 -151.622252)
			(xy 316.83198 -152.485852) (xy 316.831955 -152.487376) (xy 413.045148 -152.487376) (xy 413.045148 -151.623776)
			(xy 413.045638 -151.593792) (xy 413.053466 -151.534336) (xy 413.068987 -151.476411) (xy 413.091936 -151.421007)
			(xy 413.12192 -151.369073) (xy 413.158426 -151.321497) (xy 413.200831 -151.279092) (xy 413.248407 -151.242586)
			(xy 413.300341 -151.212602) (xy 413.355745 -151.189653) (xy 413.41367 -151.174132) (xy 413.473126 -151.166304)
			(xy 413.533094 -151.166304) (xy 413.59255 -151.174132) (xy 413.650475 -151.189653) (xy 413.705879 -151.212602)
			(xy 413.757813 -151.242586) (xy 413.805389 -151.279092) (xy 413.847794 -151.321497) (xy 413.8843 -151.369073)
			(xy 413.914284 -151.421007) (xy 413.937233 -151.476411) (xy 413.952754 -151.534336) (xy 413.960582 -151.593792)
			(xy 413.961072 -151.623776) (xy 413.961072 -152.485852) (xy 432.016408 -152.485852) (xy 432.016408 -151.622252)
			(xy 432.016898 -151.592268) (xy 432.024726 -151.532812) (xy 432.040247 -151.474887) (xy 432.063196 -151.419483)
			(xy 432.09318 -151.367549) (xy 432.129686 -151.319973) (xy 432.172091 -151.277568) (xy 432.219667 -151.241062)
			(xy 432.271601 -151.211078) (xy 432.327005 -151.188129) (xy 432.38493 -151.172608) (xy 432.444386 -151.16478)
			(xy 432.504354 -151.16478) (xy 432.56381 -151.172608) (xy 432.621735 -151.188129) (xy 432.677139 -151.211078)
			(xy 432.729073 -151.241062) (xy 432.776649 -151.277568) (xy 432.819054 -151.319973) (xy 432.85556 -151.367549)
			(xy 432.885544 -151.419483) (xy 432.908493 -151.474887) (xy 432.924014 -151.532812) (xy 432.931842 -151.592268)
			(xy 432.932332 -151.622252) (xy 432.932332 -152.485852) (xy 432.931842 -152.515836) (xy 432.924014 -152.575292)
			(xy 432.908493 -152.633217) (xy 432.885544 -152.688621) (xy 432.85556 -152.740555) (xy 432.819054 -152.788131)
			(xy 432.776649 -152.830536) (xy 432.729073 -152.867042) (xy 432.677139 -152.897026) (xy 432.621735 -152.919975)
			(xy 432.56381 -152.935496) (xy 432.504354 -152.943324) (xy 432.444386 -152.943324) (xy 432.38493 -152.935496)
			(xy 432.327005 -152.919975) (xy 432.271601 -152.897026) (xy 432.219667 -152.867042) (xy 432.172091 -152.830536)
			(xy 432.129686 -152.788131) (xy 432.09318 -152.740555) (xy 432.063196 -152.688621) (xy 432.040247 -152.633217)
			(xy 432.024726 -152.575292) (xy 432.016898 -152.515836) (xy 432.016408 -152.485852) (xy 413.961072 -152.485852)
			(xy 413.961072 -152.487376) (xy 413.960582 -152.51736) (xy 413.952754 -152.576816) (xy 413.937233 -152.634741)
			(xy 413.914284 -152.690145) (xy 413.8843 -152.742079) (xy 413.847794 -152.789655) (xy 413.805389 -152.83206)
			(xy 413.757813 -152.868566) (xy 413.705879 -152.89855) (xy 413.650475 -152.921499) (xy 413.59255 -152.93702)
			(xy 413.533094 -152.944848) (xy 413.473126 -152.944848) (xy 413.41367 -152.93702) (xy 413.355745 -152.921499)
			(xy 413.300341 -152.89855) (xy 413.248407 -152.868566) (xy 413.200831 -152.83206) (xy 413.158426 -152.789655)
			(xy 413.12192 -152.742079) (xy 413.091936 -152.690145) (xy 413.068987 -152.634741) (xy 413.053466 -152.576816)
			(xy 413.045638 -152.51736) (xy 413.045148 -152.487376) (xy 316.831955 -152.487376) (xy 316.83149 -152.51582)
			(xy 316.823667 -152.575242) (xy 316.808154 -152.633135) (xy 316.785218 -152.688508) (xy 316.755251 -152.740414)
			(xy 316.718764 -152.787964) (xy 316.676384 -152.830344) (xy 316.628834 -152.866831) (xy 316.576928 -152.896798)
			(xy 316.521555 -152.919734) (xy 316.463662 -152.935247) (xy 316.40424 -152.94307) (xy 316.344304 -152.94307)
			(xy 316.284882 -152.935247) (xy 316.226989 -152.919734) (xy 316.171616 -152.896798) (xy 316.11971 -152.866831)
			(xy 316.07216 -152.830344) (xy 316.02978 -152.787964) (xy 315.993293 -152.740414) (xy 315.963326 -152.688508)
			(xy 315.94039 -152.633135) (xy 315.924877 -152.575242) (xy 315.917054 -152.51582) (xy 315.916564 -152.485852)
			(xy 297.86072 -152.485852) (xy 297.86072 -152.487376) (xy 297.86023 -152.517344) (xy 297.852407 -152.576766)
			(xy 297.836894 -152.634659) (xy 297.813958 -152.690032) (xy 297.783991 -152.741938) (xy 297.747504 -152.789488)
			(xy 297.705124 -152.831868) (xy 297.657574 -152.868355) (xy 297.605668 -152.898322) (xy 297.550295 -152.921258)
			(xy 297.492402 -152.936771) (xy 297.43298 -152.944594) (xy 297.373044 -152.944594) (xy 297.313622 -152.936771)
			(xy 297.255729 -152.921258) (xy 297.200356 -152.898322) (xy 297.14845 -152.868355) (xy 297.1009 -152.831868)
			(xy 297.05852 -152.789488) (xy 297.022033 -152.741938) (xy 296.992066 -152.690032) (xy 296.96913 -152.634659)
			(xy 296.953617 -152.576766) (xy 296.945794 -152.517344) (xy 296.945304 -152.487376) (xy 200.732111 -152.487376)
			(xy 200.731646 -152.51582) (xy 200.723823 -152.575242) (xy 200.70831 -152.633135) (xy 200.685374 -152.688508)
			(xy 200.655407 -152.740414) (xy 200.61892 -152.787964) (xy 200.57654 -152.830344) (xy 200.52899 -152.866831)
			(xy 200.477084 -152.896798) (xy 200.421711 -152.919734) (xy 200.363818 -152.935247) (xy 200.304396 -152.94307)
			(xy 200.24446 -152.94307) (xy 200.185038 -152.935247) (xy 200.127145 -152.919734) (xy 200.071772 -152.896798)
			(xy 200.019866 -152.866831) (xy 199.972316 -152.830344) (xy 199.929936 -152.787964) (xy 199.893449 -152.740414)
			(xy 199.863482 -152.688508) (xy 199.840546 -152.633135) (xy 199.825033 -152.575242) (xy 199.81721 -152.51582)
			(xy 199.81672 -152.485852) (xy 181.760876 -152.485852) (xy 181.760876 -152.487376) (xy 181.760386 -152.517344)
			(xy 181.752563 -152.576766) (xy 181.73705 -152.634659) (xy 181.714114 -152.690032) (xy 181.684147 -152.741938)
			(xy 181.64766 -152.789488) (xy 181.60528 -152.831868) (xy 181.55773 -152.868355) (xy 181.505824 -152.898322)
			(xy 181.450451 -152.921258) (xy 181.392558 -152.936771) (xy 181.333136 -152.944594) (xy 181.2732 -152.944594)
			(xy 181.213778 -152.936771) (xy 181.155885 -152.921258) (xy 181.100512 -152.898322) (xy 181.048606 -152.868355)
			(xy 181.001056 -152.831868) (xy 180.958676 -152.789488) (xy 180.922189 -152.741938) (xy 180.892222 -152.690032)
			(xy 180.869286 -152.634659) (xy 180.853773 -152.576766) (xy 180.84595 -152.517344) (xy 180.84546 -152.487376)
			(xy 84.632267 -152.487376) (xy 84.631802 -152.515836) (xy 84.623974 -152.575292) (xy 84.608453 -152.633217)
			(xy 84.585504 -152.688621) (xy 84.55552 -152.740555) (xy 84.519014 -152.788131) (xy 84.476609 -152.830536)
			(xy 84.429033 -152.867042) (xy 84.377099 -152.897026) (xy 84.321695 -152.919975) (xy 84.26377 -152.935496)
			(xy 84.204314 -152.943324) (xy 84.144346 -152.943324) (xy 84.08489 -152.935496) (xy 84.026965 -152.919975)
			(xy 83.971561 -152.897026) (xy 83.919627 -152.867042) (xy 83.872051 -152.830536) (xy 83.829646 -152.788131)
			(xy 83.79314 -152.740555) (xy 83.763156 -152.688621) (xy 83.740207 -152.633217) (xy 83.724686 -152.575292)
			(xy 83.716858 -152.515836) (xy 83.716368 -152.485852) (xy 65.661032 -152.485852) (xy 65.661032 -152.487376)
			(xy 65.660542 -152.51736) (xy 65.652714 -152.576816) (xy 65.637193 -152.634741) (xy 65.614244 -152.690145)
			(xy 65.58426 -152.742079) (xy 65.547754 -152.789655) (xy 65.505349 -152.83206) (xy 65.457773 -152.868566)
			(xy 65.405839 -152.89855) (xy 65.350435 -152.921499) (xy 65.29251 -152.93702) (xy 65.233054 -152.944848)
			(xy 65.173086 -152.944848) (xy 65.11363 -152.93702) (xy 65.055705 -152.921499) (xy 65.000301 -152.89855)
			(xy 64.948367 -152.868566) (xy 64.900791 -152.83206) (xy 64.858386 -152.789655) (xy 64.82188 -152.742079)
			(xy 64.791896 -152.690145) (xy 64.768947 -152.634741) (xy 64.753426 -152.576816) (xy 64.745598 -152.51736)
			(xy 64.745108 -152.487376) (xy 4.308094 -152.487376) (xy 4.308094 -154.28722) (xy 66.599308 -154.28722)
			(xy 66.599308 -153.42362) (xy 66.599798 -153.393636) (xy 66.607626 -153.33418) (xy 66.623147 -153.276255)
			(xy 66.646096 -153.220851) (xy 66.67608 -153.168917) (xy 66.712586 -153.121341) (xy 66.754991 -153.078936)
			(xy 66.802567 -153.04243) (xy 66.854501 -153.012446) (xy 66.909905 -152.989497) (xy 66.96783 -152.973976)
			(xy 67.027286 -152.966148) (xy 67.087254 -152.966148) (xy 67.14671 -152.973976) (xy 67.204635 -152.989497)
			(xy 67.260039 -153.012446) (xy 67.311973 -153.04243) (xy 67.359549 -153.078936) (xy 67.401954 -153.121341)
			(xy 67.43846 -153.168917) (xy 67.468444 -153.220851) (xy 67.491393 -153.276255) (xy 67.506914 -153.33418)
			(xy 67.514742 -153.393636) (xy 67.515232 -153.42362) (xy 67.515232 -154.279346) (xy 81.07426 -154.279346)
			(xy 81.07426 -153.415746) (xy 81.07475 -153.385762) (xy 81.082578 -153.326306) (xy 81.098099 -153.268381)
			(xy 81.121048 -153.212977) (xy 81.151032 -153.161043) (xy 81.187538 -153.113467) (xy 81.229943 -153.071062)
			(xy 81.277519 -153.034556) (xy 81.329453 -153.004572) (xy 81.384857 -152.981623) (xy 81.442782 -152.966102)
			(xy 81.502238 -152.958274) (xy 81.562206 -152.958274) (xy 81.621662 -152.966102) (xy 81.679587 -152.981623)
			(xy 81.734991 -153.004572) (xy 81.786925 -153.034556) (xy 81.834501 -153.071062) (xy 81.876906 -153.113467)
			(xy 81.913412 -153.161043) (xy 81.943396 -153.212977) (xy 81.966345 -153.268381) (xy 81.981866 -153.326306)
			(xy 81.989694 -153.385762) (xy 81.990184 -153.415746) (xy 81.990184 -154.279346) (xy 81.990055 -154.28722)
			(xy 182.69966 -154.28722) (xy 182.69966 -153.42362) (xy 182.70015 -153.393652) (xy 182.707973 -153.33423)
			(xy 182.723486 -153.276337) (xy 182.746422 -153.220964) (xy 182.776389 -153.169058) (xy 182.812876 -153.121508)
			(xy 182.855256 -153.079128) (xy 182.902806 -153.042641) (xy 182.954712 -153.012674) (xy 183.010085 -152.989738)
			(xy 183.067978 -152.974225) (xy 183.1274 -152.966402) (xy 183.187336 -152.966402) (xy 183.246758 -152.974225)
			(xy 183.304651 -152.989738) (xy 183.360024 -153.012674) (xy 183.41193 -153.042641) (xy 183.45948 -153.079128)
			(xy 183.50186 -153.121508) (xy 183.538347 -153.169058) (xy 183.568314 -153.220964) (xy 183.59125 -153.276337)
			(xy 183.606763 -153.33423) (xy 183.614586 -153.393652) (xy 183.615076 -153.42362) (xy 183.615076 -154.279346)
			(xy 197.174612 -154.279346) (xy 197.174612 -153.415746) (xy 197.175102 -153.385778) (xy 197.182925 -153.326356)
			(xy 197.198438 -153.268463) (xy 197.221374 -153.21309) (xy 197.251341 -153.161184) (xy 197.287828 -153.113634)
			(xy 197.330208 -153.071254) (xy 197.377758 -153.034767) (xy 197.429664 -153.0048) (xy 197.485037 -152.981864)
			(xy 197.54293 -152.966351) (xy 197.602352 -152.958528) (xy 197.662288 -152.958528) (xy 197.72171 -152.966351)
			(xy 197.779603 -152.981864) (xy 197.834976 -153.0048) (xy 197.886882 -153.034767) (xy 197.934432 -153.071254)
			(xy 197.976812 -153.113634) (xy 198.013299 -153.161184) (xy 198.043266 -153.21309) (xy 198.066202 -153.268463)
			(xy 198.081715 -153.326356) (xy 198.089538 -153.385778) (xy 198.090028 -153.415746) (xy 198.090028 -154.279346)
			(xy 198.089899 -154.28722) (xy 298.799504 -154.28722) (xy 298.799504 -153.42362) (xy 298.799994 -153.393652)
			(xy 298.807817 -153.33423) (xy 298.82333 -153.276337) (xy 298.846266 -153.220964) (xy 298.876233 -153.169058)
			(xy 298.91272 -153.121508) (xy 298.9551 -153.079128) (xy 299.00265 -153.042641) (xy 299.054556 -153.012674)
			(xy 299.109929 -152.989738) (xy 299.167822 -152.974225) (xy 299.227244 -152.966402) (xy 299.28718 -152.966402)
			(xy 299.346602 -152.974225) (xy 299.404495 -152.989738) (xy 299.459868 -153.012674) (xy 299.511774 -153.042641)
			(xy 299.559324 -153.079128) (xy 299.601704 -153.121508) (xy 299.638191 -153.169058) (xy 299.668158 -153.220964)
			(xy 299.691094 -153.276337) (xy 299.706607 -153.33423) (xy 299.71443 -153.393652) (xy 299.71492 -153.42362)
			(xy 299.71492 -154.279346) (xy 313.274456 -154.279346) (xy 313.274456 -153.415746) (xy 313.274946 -153.385778)
			(xy 313.282769 -153.326356) (xy 313.298282 -153.268463) (xy 313.321218 -153.21309) (xy 313.351185 -153.161184)
			(xy 313.387672 -153.113634) (xy 313.430052 -153.071254) (xy 313.477602 -153.034767) (xy 313.529508 -153.0048)
			(xy 313.584881 -152.981864) (xy 313.642774 -152.966351) (xy 313.702196 -152.958528) (xy 313.762132 -152.958528)
			(xy 313.821554 -152.966351) (xy 313.879447 -152.981864) (xy 313.93482 -153.0048) (xy 313.986726 -153.034767)
			(xy 314.034276 -153.071254) (xy 314.076656 -153.113634) (xy 314.113143 -153.161184) (xy 314.14311 -153.21309)
			(xy 314.166046 -153.268463) (xy 314.181559 -153.326356) (xy 314.189382 -153.385778) (xy 314.189872 -153.415746)
			(xy 314.189872 -154.279346) (xy 314.189743 -154.28722) (xy 414.899348 -154.28722) (xy 414.899348 -153.42362)
			(xy 414.899838 -153.393636) (xy 414.907666 -153.33418) (xy 414.923187 -153.276255) (xy 414.946136 -153.220851)
			(xy 414.97612 -153.168917) (xy 415.012626 -153.121341) (xy 415.055031 -153.078936) (xy 415.102607 -153.04243)
			(xy 415.154541 -153.012446) (xy 415.209945 -152.989497) (xy 415.26787 -152.973976) (xy 415.327326 -152.966148)
			(xy 415.387294 -152.966148) (xy 415.44675 -152.973976) (xy 415.504675 -152.989497) (xy 415.560079 -153.012446)
			(xy 415.612013 -153.04243) (xy 415.659589 -153.078936) (xy 415.701994 -153.121341) (xy 415.7385 -153.168917)
			(xy 415.768484 -153.220851) (xy 415.791433 -153.276255) (xy 415.806954 -153.33418) (xy 415.814782 -153.393636)
			(xy 415.815272 -153.42362) (xy 415.815272 -154.279346) (xy 429.3743 -154.279346) (xy 429.3743 -153.415746)
			(xy 429.37479 -153.385762) (xy 429.382618 -153.326306) (xy 429.398139 -153.268381) (xy 429.421088 -153.212977)
			(xy 429.451072 -153.161043) (xy 429.487578 -153.113467) (xy 429.529983 -153.071062) (xy 429.577559 -153.034556)
			(xy 429.629493 -153.004572) (xy 429.684897 -152.981623) (xy 429.742822 -152.966102) (xy 429.802278 -152.958274)
			(xy 429.862246 -152.958274) (xy 429.921702 -152.966102) (xy 429.979627 -152.981623) (xy 430.035031 -153.004572)
			(xy 430.086965 -153.034556) (xy 430.134541 -153.071062) (xy 430.176946 -153.113467) (xy 430.213452 -153.161043)
			(xy 430.243436 -153.212977) (xy 430.266385 -153.268381) (xy 430.281906 -153.326306) (xy 430.289734 -153.385762)
			(xy 430.290224 -153.415746) (xy 430.290224 -154.279346) (xy 430.289734 -154.30933) (xy 430.281906 -154.368786)
			(xy 430.266385 -154.426711) (xy 430.243436 -154.482115) (xy 430.213452 -154.534049) (xy 430.176946 -154.581625)
			(xy 430.134541 -154.62403) (xy 430.086965 -154.660536) (xy 430.035031 -154.69052) (xy 429.979627 -154.713469)
			(xy 429.921702 -154.72899) (xy 429.862246 -154.736818) (xy 429.802278 -154.736818) (xy 429.742822 -154.72899)
			(xy 429.684897 -154.713469) (xy 429.629493 -154.69052) (xy 429.577559 -154.660536) (xy 429.529983 -154.62403)
			(xy 429.487578 -154.581625) (xy 429.451072 -154.534049) (xy 429.421088 -154.482115) (xy 429.398139 -154.426711)
			(xy 429.382618 -154.368786) (xy 429.37479 -154.30933) (xy 429.3743 -154.279346) (xy 415.815272 -154.279346)
			(xy 415.815272 -154.28722) (xy 415.814782 -154.317204) (xy 415.806954 -154.37666) (xy 415.791433 -154.434585)
			(xy 415.768484 -154.489989) (xy 415.7385 -154.541923) (xy 415.701994 -154.589499) (xy 415.659589 -154.631904)
			(xy 415.612013 -154.66841) (xy 415.560079 -154.698394) (xy 415.504675 -154.721343) (xy 415.44675 -154.736864)
			(xy 415.387294 -154.744692) (xy 415.327326 -154.744692) (xy 415.26787 -154.736864) (xy 415.209945 -154.721343)
			(xy 415.154541 -154.698394) (xy 415.102607 -154.66841) (xy 415.055031 -154.631904) (xy 415.012626 -154.589499)
			(xy 414.97612 -154.541923) (xy 414.946136 -154.489989) (xy 414.923187 -154.434585) (xy 414.907666 -154.37666)
			(xy 414.899838 -154.317204) (xy 414.899348 -154.28722) (xy 314.189743 -154.28722) (xy 314.189382 -154.309314)
			(xy 314.181559 -154.368736) (xy 314.166046 -154.426629) (xy 314.14311 -154.482002) (xy 314.113143 -154.533908)
			(xy 314.076656 -154.581458) (xy 314.034276 -154.623838) (xy 313.986726 -154.660325) (xy 313.93482 -154.690292)
			(xy 313.879447 -154.713228) (xy 313.821554 -154.728741) (xy 313.762132 -154.736564) (xy 313.702196 -154.736564)
			(xy 313.642774 -154.728741) (xy 313.584881 -154.713228) (xy 313.529508 -154.690292) (xy 313.477602 -154.660325)
			(xy 313.430052 -154.623838) (xy 313.387672 -154.581458) (xy 313.351185 -154.533908) (xy 313.321218 -154.482002)
			(xy 313.298282 -154.426629) (xy 313.282769 -154.368736) (xy 313.274946 -154.309314) (xy 313.274456 -154.279346)
			(xy 299.71492 -154.279346) (xy 299.71492 -154.28722) (xy 299.71443 -154.317188) (xy 299.706607 -154.37661)
			(xy 299.691094 -154.434503) (xy 299.668158 -154.489876) (xy 299.638191 -154.541782) (xy 299.601704 -154.589332)
			(xy 299.559324 -154.631712) (xy 299.511774 -154.668199) (xy 299.459868 -154.698166) (xy 299.404495 -154.721102)
			(xy 299.346602 -154.736615) (xy 299.28718 -154.744438) (xy 299.227244 -154.744438) (xy 299.167822 -154.736615)
			(xy 299.109929 -154.721102) (xy 299.054556 -154.698166) (xy 299.00265 -154.668199) (xy 298.9551 -154.631712)
			(xy 298.91272 -154.589332) (xy 298.876233 -154.541782) (xy 298.846266 -154.489876) (xy 298.82333 -154.434503)
			(xy 298.807817 -154.37661) (xy 298.799994 -154.317188) (xy 298.799504 -154.28722) (xy 198.089899 -154.28722)
			(xy 198.089538 -154.309314) (xy 198.081715 -154.368736) (xy 198.066202 -154.426629) (xy 198.043266 -154.482002)
			(xy 198.013299 -154.533908) (xy 197.976812 -154.581458) (xy 197.934432 -154.623838) (xy 197.886882 -154.660325)
			(xy 197.834976 -154.690292) (xy 197.779603 -154.713228) (xy 197.72171 -154.728741) (xy 197.662288 -154.736564)
			(xy 197.602352 -154.736564) (xy 197.54293 -154.728741) (xy 197.485037 -154.713228) (xy 197.429664 -154.690292)
			(xy 197.377758 -154.660325) (xy 197.330208 -154.623838) (xy 197.287828 -154.581458) (xy 197.251341 -154.533908)
			(xy 197.221374 -154.482002) (xy 197.198438 -154.426629) (xy 197.182925 -154.368736) (xy 197.175102 -154.309314)
			(xy 197.174612 -154.279346) (xy 183.615076 -154.279346) (xy 183.615076 -154.28722) (xy 183.614586 -154.317188)
			(xy 183.606763 -154.37661) (xy 183.59125 -154.434503) (xy 183.568314 -154.489876) (xy 183.538347 -154.541782)
			(xy 183.50186 -154.589332) (xy 183.45948 -154.631712) (xy 183.41193 -154.668199) (xy 183.360024 -154.698166)
			(xy 183.304651 -154.721102) (xy 183.246758 -154.736615) (xy 183.187336 -154.744438) (xy 183.1274 -154.744438)
			(xy 183.067978 -154.736615) (xy 183.010085 -154.721102) (xy 182.954712 -154.698166) (xy 182.902806 -154.668199)
			(xy 182.855256 -154.631712) (xy 182.812876 -154.589332) (xy 182.776389 -154.541782) (xy 182.746422 -154.489876)
			(xy 182.723486 -154.434503) (xy 182.707973 -154.37661) (xy 182.70015 -154.317188) (xy 182.69966 -154.28722)
			(xy 81.990055 -154.28722) (xy 81.989694 -154.30933) (xy 81.981866 -154.368786) (xy 81.966345 -154.426711)
			(xy 81.943396 -154.482115) (xy 81.913412 -154.534049) (xy 81.876906 -154.581625) (xy 81.834501 -154.62403)
			(xy 81.786925 -154.660536) (xy 81.734991 -154.69052) (xy 81.679587 -154.713469) (xy 81.621662 -154.72899)
			(xy 81.562206 -154.736818) (xy 81.502238 -154.736818) (xy 81.442782 -154.72899) (xy 81.384857 -154.713469)
			(xy 81.329453 -154.69052) (xy 81.277519 -154.660536) (xy 81.229943 -154.62403) (xy 81.187538 -154.581625)
			(xy 81.151032 -154.534049) (xy 81.121048 -154.482115) (xy 81.098099 -154.426711) (xy 81.082578 -154.368786)
			(xy 81.07475 -154.30933) (xy 81.07426 -154.279346) (xy 67.515232 -154.279346) (xy 67.515232 -154.28722)
			(xy 67.514742 -154.317204) (xy 67.506914 -154.37666) (xy 67.491393 -154.434585) (xy 67.468444 -154.489989)
			(xy 67.43846 -154.541923) (xy 67.401954 -154.589499) (xy 67.359549 -154.631904) (xy 67.311973 -154.66841)
			(xy 67.260039 -154.698394) (xy 67.204635 -154.721343) (xy 67.14671 -154.736864) (xy 67.087254 -154.744692)
			(xy 67.027286 -154.744692) (xy 66.96783 -154.736864) (xy 66.909905 -154.721343) (xy 66.854501 -154.698394)
			(xy 66.802567 -154.66841) (xy 66.754991 -154.631904) (xy 66.712586 -154.589499) (xy 66.67608 -154.541923)
			(xy 66.646096 -154.489989) (xy 66.623147 -154.434585) (xy 66.607626 -154.37666) (xy 66.599798 -154.317204)
			(xy 66.599308 -154.28722) (xy 4.308094 -154.28722) (xy 4.308094 -156.087318) (xy 64.745108 -156.087318)
			(xy 64.745108 -155.223718) (xy 64.745598 -155.193734) (xy 64.753426 -155.134278) (xy 64.768947 -155.076353)
			(xy 64.791896 -155.020949) (xy 64.82188 -154.969015) (xy 64.858386 -154.921439) (xy 64.900791 -154.879034)
			(xy 64.948367 -154.842528) (xy 65.000301 -154.812544) (xy 65.055705 -154.789595) (xy 65.11363 -154.774074)
			(xy 65.173086 -154.766246) (xy 65.233054 -154.766246) (xy 65.29251 -154.774074) (xy 65.350435 -154.789595)
			(xy 65.405839 -154.812544) (xy 65.457773 -154.842528) (xy 65.505349 -154.879034) (xy 65.547754 -154.921439)
			(xy 65.58426 -154.969015) (xy 65.614244 -155.020949) (xy 65.637193 -155.076353) (xy 65.652714 -155.134278)
			(xy 65.660542 -155.193734) (xy 65.661032 -155.223718) (xy 65.661032 -156.085794) (xy 83.716368 -156.085794)
			(xy 83.716368 -155.222194) (xy 83.716858 -155.19221) (xy 83.724686 -155.132754) (xy 83.740207 -155.074829)
			(xy 83.763156 -155.019425) (xy 83.79314 -154.967491) (xy 83.829646 -154.919915) (xy 83.872051 -154.87751)
			(xy 83.919627 -154.841004) (xy 83.971561 -154.81102) (xy 84.026965 -154.788071) (xy 84.08489 -154.77255)
			(xy 84.144346 -154.764722) (xy 84.204314 -154.764722) (xy 84.26377 -154.77255) (xy 84.321695 -154.788071)
			(xy 84.377099 -154.81102) (xy 84.429033 -154.841004) (xy 84.476609 -154.87751) (xy 84.519014 -154.919915)
			(xy 84.55552 -154.967491) (xy 84.585504 -155.019425) (xy 84.608453 -155.074829) (xy 84.623974 -155.132754)
			(xy 84.631802 -155.19221) (xy 84.632292 -155.222194) (xy 84.632292 -156.085794) (xy 84.632267 -156.087318)
			(xy 180.84546 -156.087318) (xy 180.84546 -155.223718) (xy 180.84595 -155.19375) (xy 180.853773 -155.134328)
			(xy 180.869286 -155.076435) (xy 180.892222 -155.021062) (xy 180.922189 -154.969156) (xy 180.958676 -154.921606)
			(xy 181.001056 -154.879226) (xy 181.048606 -154.842739) (xy 181.100512 -154.812772) (xy 181.155885 -154.789836)
			(xy 181.213778 -154.774323) (xy 181.2732 -154.7665) (xy 181.333136 -154.7665) (xy 181.392558 -154.774323)
			(xy 181.450451 -154.789836) (xy 181.505824 -154.812772) (xy 181.55773 -154.842739) (xy 181.60528 -154.879226)
			(xy 181.64766 -154.921606) (xy 181.684147 -154.969156) (xy 181.714114 -155.021062) (xy 181.73705 -155.076435)
			(xy 181.752563 -155.134328) (xy 181.760386 -155.19375) (xy 181.760876 -155.223718) (xy 181.760876 -156.085794)
			(xy 199.81672 -156.085794) (xy 199.81672 -155.222194) (xy 199.81721 -155.192226) (xy 199.825033 -155.132804)
			(xy 199.840546 -155.074911) (xy 199.863482 -155.019538) (xy 199.893449 -154.967632) (xy 199.929936 -154.920082)
			(xy 199.972316 -154.877702) (xy 200.019866 -154.841215) (xy 200.071772 -154.811248) (xy 200.127145 -154.788312)
			(xy 200.185038 -154.772799) (xy 200.24446 -154.764976) (xy 200.304396 -154.764976) (xy 200.363818 -154.772799)
			(xy 200.421711 -154.788312) (xy 200.477084 -154.811248) (xy 200.52899 -154.841215) (xy 200.57654 -154.877702)
			(xy 200.61892 -154.920082) (xy 200.655407 -154.967632) (xy 200.685374 -155.019538) (xy 200.70831 -155.074911)
			(xy 200.723823 -155.132804) (xy 200.731646 -155.192226) (xy 200.732136 -155.222194) (xy 200.732136 -156.085794)
			(xy 200.732111 -156.087318) (xy 296.945304 -156.087318) (xy 296.945304 -155.223718) (xy 296.945794 -155.19375)
			(xy 296.953617 -155.134328) (xy 296.96913 -155.076435) (xy 296.992066 -155.021062) (xy 297.022033 -154.969156)
			(xy 297.05852 -154.921606) (xy 297.1009 -154.879226) (xy 297.14845 -154.842739) (xy 297.200356 -154.812772)
			(xy 297.255729 -154.789836) (xy 297.313622 -154.774323) (xy 297.373044 -154.7665) (xy 297.43298 -154.7665)
			(xy 297.492402 -154.774323) (xy 297.550295 -154.789836) (xy 297.605668 -154.812772) (xy 297.657574 -154.842739)
			(xy 297.705124 -154.879226) (xy 297.747504 -154.921606) (xy 297.783991 -154.969156) (xy 297.813958 -155.021062)
			(xy 297.836894 -155.076435) (xy 297.852407 -155.134328) (xy 297.86023 -155.19375) (xy 297.86072 -155.223718)
			(xy 297.86072 -156.085794) (xy 315.916564 -156.085794) (xy 315.916564 -155.222194) (xy 315.917054 -155.192226)
			(xy 315.924877 -155.132804) (xy 315.94039 -155.074911) (xy 315.963326 -155.019538) (xy 315.993293 -154.967632)
			(xy 316.02978 -154.920082) (xy 316.07216 -154.877702) (xy 316.11971 -154.841215) (xy 316.171616 -154.811248)
			(xy 316.226989 -154.788312) (xy 316.284882 -154.772799) (xy 316.344304 -154.764976) (xy 316.40424 -154.764976)
			(xy 316.463662 -154.772799) (xy 316.521555 -154.788312) (xy 316.576928 -154.811248) (xy 316.628834 -154.841215)
			(xy 316.676384 -154.877702) (xy 316.718764 -154.920082) (xy 316.755251 -154.967632) (xy 316.785218 -155.019538)
			(xy 316.808154 -155.074911) (xy 316.823667 -155.132804) (xy 316.83149 -155.192226) (xy 316.83198 -155.222194)
			(xy 316.83198 -156.085794) (xy 316.831955 -156.087318) (xy 413.045148 -156.087318) (xy 413.045148 -155.223718)
			(xy 413.045638 -155.193734) (xy 413.053466 -155.134278) (xy 413.068987 -155.076353) (xy 413.091936 -155.020949)
			(xy 413.12192 -154.969015) (xy 413.158426 -154.921439) (xy 413.200831 -154.879034) (xy 413.248407 -154.842528)
			(xy 413.300341 -154.812544) (xy 413.355745 -154.789595) (xy 413.41367 -154.774074) (xy 413.473126 -154.766246)
			(xy 413.533094 -154.766246) (xy 413.59255 -154.774074) (xy 413.650475 -154.789595) (xy 413.705879 -154.812544)
			(xy 413.757813 -154.842528) (xy 413.805389 -154.879034) (xy 413.847794 -154.921439) (xy 413.8843 -154.969015)
			(xy 413.914284 -155.020949) (xy 413.937233 -155.076353) (xy 413.952754 -155.134278) (xy 413.960582 -155.193734)
			(xy 413.961072 -155.223718) (xy 413.961072 -156.085794) (xy 432.016408 -156.085794) (xy 432.016408 -155.222194)
			(xy 432.016898 -155.19221) (xy 432.024726 -155.132754) (xy 432.040247 -155.074829) (xy 432.063196 -155.019425)
			(xy 432.09318 -154.967491) (xy 432.129686 -154.919915) (xy 432.172091 -154.87751) (xy 432.219667 -154.841004)
			(xy 432.271601 -154.81102) (xy 432.327005 -154.788071) (xy 432.38493 -154.77255) (xy 432.444386 -154.764722)
			(xy 432.504354 -154.764722) (xy 432.56381 -154.77255) (xy 432.621735 -154.788071) (xy 432.677139 -154.81102)
			(xy 432.729073 -154.841004) (xy 432.776649 -154.87751) (xy 432.819054 -154.919915) (xy 432.85556 -154.967491)
			(xy 432.885544 -155.019425) (xy 432.908493 -155.074829) (xy 432.924014 -155.132754) (xy 432.931842 -155.19221)
			(xy 432.932332 -155.222194) (xy 432.932332 -156.085794) (xy 432.931842 -156.115778) (xy 432.924014 -156.175234)
			(xy 432.908493 -156.233159) (xy 432.885544 -156.288563) (xy 432.85556 -156.340497) (xy 432.819054 -156.388073)
			(xy 432.776649 -156.430478) (xy 432.729073 -156.466984) (xy 432.677139 -156.496968) (xy 432.621735 -156.519917)
			(xy 432.56381 -156.535438) (xy 432.504354 -156.543266) (xy 432.444386 -156.543266) (xy 432.38493 -156.535438)
			(xy 432.327005 -156.519917) (xy 432.271601 -156.496968) (xy 432.219667 -156.466984) (xy 432.172091 -156.430478)
			(xy 432.129686 -156.388073) (xy 432.09318 -156.340497) (xy 432.063196 -156.288563) (xy 432.040247 -156.233159)
			(xy 432.024726 -156.175234) (xy 432.016898 -156.115778) (xy 432.016408 -156.085794) (xy 413.961072 -156.085794)
			(xy 413.961072 -156.087318) (xy 413.960582 -156.117302) (xy 413.952754 -156.176758) (xy 413.937233 -156.234683)
			(xy 413.914284 -156.290087) (xy 413.8843 -156.342021) (xy 413.847794 -156.389597) (xy 413.805389 -156.432002)
			(xy 413.757813 -156.468508) (xy 413.705879 -156.498492) (xy 413.650475 -156.521441) (xy 413.59255 -156.536962)
			(xy 413.533094 -156.54479) (xy 413.473126 -156.54479) (xy 413.41367 -156.536962) (xy 413.355745 -156.521441)
			(xy 413.300341 -156.498492) (xy 413.248407 -156.468508) (xy 413.200831 -156.432002) (xy 413.158426 -156.389597)
			(xy 413.12192 -156.342021) (xy 413.091936 -156.290087) (xy 413.068987 -156.234683) (xy 413.053466 -156.176758)
			(xy 413.045638 -156.117302) (xy 413.045148 -156.087318) (xy 316.831955 -156.087318) (xy 316.83149 -156.115762)
			(xy 316.823667 -156.175184) (xy 316.808154 -156.233077) (xy 316.785218 -156.28845) (xy 316.755251 -156.340356)
			(xy 316.718764 -156.387906) (xy 316.676384 -156.430286) (xy 316.628834 -156.466773) (xy 316.576928 -156.49674)
			(xy 316.521555 -156.519676) (xy 316.463662 -156.535189) (xy 316.40424 -156.543012) (xy 316.344304 -156.543012)
			(xy 316.284882 -156.535189) (xy 316.226989 -156.519676) (xy 316.171616 -156.49674) (xy 316.11971 -156.466773)
			(xy 316.07216 -156.430286) (xy 316.02978 -156.387906) (xy 315.993293 -156.340356) (xy 315.963326 -156.28845)
			(xy 315.94039 -156.233077) (xy 315.924877 -156.175184) (xy 315.917054 -156.115762) (xy 315.916564 -156.085794)
			(xy 297.86072 -156.085794) (xy 297.86072 -156.087318) (xy 297.86023 -156.117286) (xy 297.852407 -156.176708)
			(xy 297.836894 -156.234601) (xy 297.813958 -156.289974) (xy 297.783991 -156.34188) (xy 297.747504 -156.38943)
			(xy 297.705124 -156.43181) (xy 297.657574 -156.468297) (xy 297.605668 -156.498264) (xy 297.550295 -156.5212)
			(xy 297.492402 -156.536713) (xy 297.43298 -156.544536) (xy 297.373044 -156.544536) (xy 297.313622 -156.536713)
			(xy 297.255729 -156.5212) (xy 297.200356 -156.498264) (xy 297.14845 -156.468297) (xy 297.1009 -156.43181)
			(xy 297.05852 -156.38943) (xy 297.022033 -156.34188) (xy 296.992066 -156.289974) (xy 296.96913 -156.234601)
			(xy 296.953617 -156.176708) (xy 296.945794 -156.117286) (xy 296.945304 -156.087318) (xy 200.732111 -156.087318)
			(xy 200.731646 -156.115762) (xy 200.723823 -156.175184) (xy 200.70831 -156.233077) (xy 200.685374 -156.28845)
			(xy 200.655407 -156.340356) (xy 200.61892 -156.387906) (xy 200.57654 -156.430286) (xy 200.52899 -156.466773)
			(xy 200.477084 -156.49674) (xy 200.421711 -156.519676) (xy 200.363818 -156.535189) (xy 200.304396 -156.543012)
			(xy 200.24446 -156.543012) (xy 200.185038 -156.535189) (xy 200.127145 -156.519676) (xy 200.071772 -156.49674)
			(xy 200.019866 -156.466773) (xy 199.972316 -156.430286) (xy 199.929936 -156.387906) (xy 199.893449 -156.340356)
			(xy 199.863482 -156.28845) (xy 199.840546 -156.233077) (xy 199.825033 -156.175184) (xy 199.81721 -156.115762)
			(xy 199.81672 -156.085794) (xy 181.760876 -156.085794) (xy 181.760876 -156.087318) (xy 181.760386 -156.117286)
			(xy 181.752563 -156.176708) (xy 181.73705 -156.234601) (xy 181.714114 -156.289974) (xy 181.684147 -156.34188)
			(xy 181.64766 -156.38943) (xy 181.60528 -156.43181) (xy 181.55773 -156.468297) (xy 181.505824 -156.498264)
			(xy 181.450451 -156.5212) (xy 181.392558 -156.536713) (xy 181.333136 -156.544536) (xy 181.2732 -156.544536)
			(xy 181.213778 -156.536713) (xy 181.155885 -156.5212) (xy 181.100512 -156.498264) (xy 181.048606 -156.468297)
			(xy 181.001056 -156.43181) (xy 180.958676 -156.38943) (xy 180.922189 -156.34188) (xy 180.892222 -156.289974)
			(xy 180.869286 -156.234601) (xy 180.853773 -156.176708) (xy 180.84595 -156.117286) (xy 180.84546 -156.087318)
			(xy 84.632267 -156.087318) (xy 84.631802 -156.115778) (xy 84.623974 -156.175234) (xy 84.608453 -156.233159)
			(xy 84.585504 -156.288563) (xy 84.55552 -156.340497) (xy 84.519014 -156.388073) (xy 84.476609 -156.430478)
			(xy 84.429033 -156.466984) (xy 84.377099 -156.496968) (xy 84.321695 -156.519917) (xy 84.26377 -156.535438)
			(xy 84.204314 -156.543266) (xy 84.144346 -156.543266) (xy 84.08489 -156.535438) (xy 84.026965 -156.519917)
			(xy 83.971561 -156.496968) (xy 83.919627 -156.466984) (xy 83.872051 -156.430478) (xy 83.829646 -156.388073)
			(xy 83.79314 -156.340497) (xy 83.763156 -156.288563) (xy 83.740207 -156.233159) (xy 83.724686 -156.175234)
			(xy 83.716858 -156.115778) (xy 83.716368 -156.085794) (xy 65.661032 -156.085794) (xy 65.661032 -156.087318)
			(xy 65.660542 -156.117302) (xy 65.652714 -156.176758) (xy 65.637193 -156.234683) (xy 65.614244 -156.290087)
			(xy 65.58426 -156.342021) (xy 65.547754 -156.389597) (xy 65.505349 -156.432002) (xy 65.457773 -156.468508)
			(xy 65.405839 -156.498492) (xy 65.350435 -156.521441) (xy 65.29251 -156.536962) (xy 65.233054 -156.54479)
			(xy 65.173086 -156.54479) (xy 65.11363 -156.536962) (xy 65.055705 -156.521441) (xy 65.000301 -156.498492)
			(xy 64.948367 -156.468508) (xy 64.900791 -156.432002) (xy 64.858386 -156.389597) (xy 64.82188 -156.342021)
			(xy 64.791896 -156.290087) (xy 64.768947 -156.234683) (xy 64.753426 -156.176758) (xy 64.745598 -156.117302)
			(xy 64.745108 -156.087318) (xy 4.308094 -156.087318) (xy 4.308094 -157.900066) (xy 228.314505 -157.900066)
			(xy 228.314505 -157.840134) (xy 228.322328 -157.780714) (xy 228.33784 -157.722823) (xy 228.360775 -157.667453)
			(xy 228.390741 -157.61555) (xy 228.427226 -157.568002) (xy 228.469605 -157.525624) (xy 228.517153 -157.489139)
			(xy 228.569056 -157.459173) (xy 228.624427 -157.436238) (xy 228.682318 -157.420727) (xy 228.741738 -157.412905)
			(xy 228.771704 -157.412436) (xy 229.635304 -157.412436) (xy 229.665274 -157.412838) (xy 229.724702 -157.420663)
			(xy 229.7826 -157.436177) (xy 229.837978 -157.459116) (xy 229.889888 -157.489086) (xy 229.937442 -157.525576)
			(xy 229.979827 -157.567961) (xy 230.016316 -157.615515) (xy 230.046286 -157.667425) (xy 230.069224 -157.722803)
			(xy 230.084738 -157.780702) (xy 230.092562 -157.84013) (xy 230.092562 -157.90007) (xy 230.089876 -157.920473)
			(xy 230.557725 -157.920473) (xy 230.557725 -157.860527) (xy 230.56555 -157.801095) (xy 230.581066 -157.743192)
			(xy 230.604007 -157.68781) (xy 230.633981 -157.635897) (xy 230.670475 -157.58834) (xy 230.712864 -157.545953)
			(xy 230.760423 -157.509463) (xy 230.812339 -157.479493) (xy 230.867722 -157.456555) (xy 230.925626 -157.441044)
			(xy 230.985059 -157.433223) (xy 231.015032 -157.432756) (xy 231.878632 -157.432756) (xy 231.908596 -157.43332)
			(xy 231.968011 -157.441146) (xy 232.025896 -157.45666) (xy 232.081261 -157.479596) (xy 232.133158 -157.509563)
			(xy 232.180701 -157.546046) (xy 232.223075 -157.588423) (xy 232.259555 -157.635968) (xy 232.289518 -157.687868)
			(xy 232.31245 -157.743235) (xy 232.32796 -157.801121) (xy 232.335782 -157.860536) (xy 232.335782 -157.920464)
			(xy 232.32796 -157.979879) (xy 232.31245 -158.037765) (xy 232.289518 -158.093132) (xy 232.259555 -158.145032)
			(xy 232.223075 -158.192577) (xy 232.180701 -158.234954) (xy 232.133158 -158.271437) (xy 232.081261 -158.301404)
			(xy 232.025896 -158.32434) (xy 231.968011 -158.339854) (xy 231.908596 -158.34768) (xy 231.878632 -158.348172)
			(xy 231.015032 -158.348172) (xy 230.985059 -158.347777) (xy 230.925626 -158.339956) (xy 230.867722 -158.324445)
			(xy 230.812339 -158.301507) (xy 230.760423 -158.271537) (xy 230.712864 -158.235047) (xy 230.670475 -158.19266)
			(xy 230.633981 -158.145103) (xy 230.604007 -158.09319) (xy 230.581066 -158.037808) (xy 230.56555 -157.979905)
			(xy 230.557725 -157.920473) (xy 230.089876 -157.920473) (xy 230.084738 -157.959498) (xy 230.069224 -158.017397)
			(xy 230.046286 -158.072775) (xy 230.016316 -158.124685) (xy 229.979827 -158.172239) (xy 229.937442 -158.214624)
			(xy 229.889888 -158.251114) (xy 229.837978 -158.281084) (xy 229.7826 -158.304023) (xy 229.724702 -158.319537)
			(xy 229.665274 -158.327362) (xy 229.635304 -158.327852) (xy 228.771704 -158.327852) (xy 228.741738 -158.327295)
			(xy 228.682318 -158.319473) (xy 228.624427 -158.303962) (xy 228.569056 -158.281027) (xy 228.517153 -158.251061)
			(xy 228.469605 -158.214576) (xy 228.427226 -158.172198) (xy 228.390741 -158.12465) (xy 228.360775 -158.072747)
			(xy 228.33784 -158.017377) (xy 228.322328 -157.959486) (xy 228.314505 -157.900066) (xy 4.308094 -157.900066)
			(xy 4.308094 -160.1851) (xy 45.524179 -160.1851) (xy 45.528134 -160.093263) (xy 45.539969 -160.002106)
			(xy 45.559596 -159.912303) (xy 45.58687 -159.824521) (xy 45.62159 -159.739407) (xy 45.663498 -159.657594)
			(xy 45.712284 -159.579686) (xy 45.767587 -159.506261) (xy 45.828997 -159.437861) (xy 45.896059 -159.374994)
			(xy 45.968278 -159.318124) (xy 46.045118 -159.267673) (xy 46.126011 -159.224014) (xy 46.210357 -159.187471)
			(xy 46.297533 -159.158314) (xy 46.386892 -159.13676) (xy 46.477773 -159.122966) (xy 46.569504 -159.117036)
			(xy 46.661405 -159.119014) (xy 46.752796 -159.128885) (xy 46.843 -159.146575) (xy 46.931349 -159.171955)
			(xy 47.017189 -159.204835) (xy 47.099885 -159.244973) (xy 47.178825 -159.292072) (xy 47.253423 -159.345782)
			(xy 47.323129 -159.405706) (xy 47.387424 -159.4714) (xy 47.445835 -159.542378) (xy 47.497927 -159.618115)
			(xy 47.543316 -159.69805) (xy 47.581666 -159.78159) (xy 47.612691 -159.868118) (xy 47.636164 -159.956993)
			(xy 47.65191 -160.047557) (xy 47.659812 -160.139139) (xy 47.660306 -160.1851) (xy 69.888875 -160.1851)
			(xy 69.892831 -160.093241) (xy 69.904668 -160.002062) (xy 69.9243 -159.912238) (xy 69.951581 -159.824435)
			(xy 69.986309 -159.739302) (xy 70.028227 -159.657469) (xy 70.077025 -159.579542) (xy 70.13234 -159.506099)
			(xy 70.193765 -159.437683) (xy 70.260844 -159.374801) (xy 70.333079 -159.317918) (xy 70.409938 -159.267455)
			(xy 70.49085 -159.223786) (xy 70.575216 -159.187234) (xy 70.662412 -159.15807) (xy 70.751793 -159.13651)
			(xy 70.842696 -159.122714) (xy 70.934449 -159.116782) (xy 71.026371 -159.118761) (xy 71.117784 -159.128634)
			(xy 71.208009 -159.146329) (xy 71.29638 -159.171714) (xy 71.38224 -159.204602) (xy 71.464956 -159.24475)
			(xy 71.543914 -159.291859) (xy 71.618531 -159.345582) (xy 71.688252 -159.40552) (xy 71.752563 -159.47123)
			(xy 71.810988 -159.542226) (xy 71.863093 -159.61798) (xy 71.908492 -159.697934) (xy 71.946851 -159.781494)
			(xy 71.977884 -159.868043) (xy 72.001362 -159.956939) (xy 72.017112 -160.047524) (xy 72.025016 -160.139128)
			(xy 72.02551 -160.1851) (xy 161.624277 -160.1851) (xy 161.628232 -160.093263) (xy 161.640067 -160.002106)
			(xy 161.659694 -159.912303) (xy 161.686968 -159.824521) (xy 161.721688 -159.739407) (xy 161.763596 -159.657594)
			(xy 161.812382 -159.579686) (xy 161.867685 -159.506261) (xy 161.929095 -159.437861) (xy 161.996157 -159.374994)
			(xy 162.068376 -159.318124) (xy 162.145216 -159.267673) (xy 162.226109 -159.224014) (xy 162.310455 -159.187471)
			(xy 162.397631 -159.158314) (xy 162.48699 -159.13676) (xy 162.577871 -159.122966) (xy 162.669602 -159.117036)
			(xy 162.761503 -159.119014) (xy 162.852894 -159.128885) (xy 162.943098 -159.146575) (xy 163.031447 -159.171955)
			(xy 163.117287 -159.204835) (xy 163.199983 -159.244973) (xy 163.278923 -159.292072) (xy 163.353521 -159.345782)
			(xy 163.423227 -159.405706) (xy 163.487522 -159.4714) (xy 163.545933 -159.542378) (xy 163.598025 -159.618115)
			(xy 163.643414 -159.69805) (xy 163.681764 -159.78159) (xy 163.712789 -159.868118) (xy 163.736262 -159.956993)
			(xy 163.752008 -160.047557) (xy 163.75991 -160.139139) (xy 163.760404 -160.1851) (xy 185.988973 -160.1851)
			(xy 185.992929 -160.093241) (xy 186.004766 -160.002062) (xy 186.024398 -159.912238) (xy 186.051679 -159.824435)
			(xy 186.086407 -159.739302) (xy 186.128325 -159.657469) (xy 186.177123 -159.579542) (xy 186.232438 -159.506099)
			(xy 186.293863 -159.437683) (xy 186.360942 -159.374801) (xy 186.433177 -159.317918) (xy 186.510036 -159.267455)
			(xy 186.590948 -159.223786) (xy 186.675314 -159.187234) (xy 186.76251 -159.15807) (xy 186.851891 -159.13651)
			(xy 186.942794 -159.122714) (xy 187.034547 -159.116782) (xy 187.126469 -159.118761) (xy 187.217882 -159.128634)
			(xy 187.308107 -159.146329) (xy 187.396478 -159.171714) (xy 187.482338 -159.204602) (xy 187.565054 -159.24475)
			(xy 187.644012 -159.291859) (xy 187.718629 -159.345582) (xy 187.78835 -159.40552) (xy 187.852661 -159.47123)
			(xy 187.911086 -159.542226) (xy 187.963191 -159.61798) (xy 188.00859 -159.697934) (xy 188.046949 -159.781494)
			(xy 188.077982 -159.868043) (xy 188.10146 -159.956939) (xy 188.11721 -160.047524) (xy 188.125114 -160.139128)
			(xy 188.125608 -160.1851) (xy 277.724121 -160.1851) (xy 277.728076 -160.093263) (xy 277.739911 -160.002106)
			(xy 277.759538 -159.912303) (xy 277.786812 -159.824521) (xy 277.821532 -159.739407) (xy 277.86344 -159.657594)
			(xy 277.912226 -159.579686) (xy 277.967529 -159.506261) (xy 278.028939 -159.437861) (xy 278.096001 -159.374994)
			(xy 278.16822 -159.318124) (xy 278.24506 -159.267673) (xy 278.325953 -159.224014) (xy 278.410299 -159.187471)
			(xy 278.497475 -159.158314) (xy 278.586834 -159.13676) (xy 278.677715 -159.122966) (xy 278.769446 -159.117036)
			(xy 278.861347 -159.119014) (xy 278.952738 -159.128885) (xy 279.042942 -159.146575) (xy 279.131291 -159.171955)
			(xy 279.217131 -159.204835) (xy 279.299827 -159.244973) (xy 279.378767 -159.292072) (xy 279.453365 -159.345782)
			(xy 279.523071 -159.405706) (xy 279.587366 -159.4714) (xy 279.645777 -159.542378) (xy 279.697869 -159.618115)
			(xy 279.743258 -159.69805) (xy 279.781608 -159.78159) (xy 279.812633 -159.868118) (xy 279.836106 -159.956993)
			(xy 279.851852 -160.047557) (xy 279.859754 -160.139139) (xy 279.860248 -160.1851) (xy 302.088817 -160.1851)
			(xy 302.092773 -160.093241) (xy 302.10461 -160.002062) (xy 302.124242 -159.912238) (xy 302.151523 -159.824435)
			(xy 302.186251 -159.739302) (xy 302.228169 -159.657469) (xy 302.276967 -159.579542) (xy 302.332282 -159.506099)
			(xy 302.393707 -159.437683) (xy 302.460786 -159.374801) (xy 302.533021 -159.317918) (xy 302.60988 -159.267455)
			(xy 302.690792 -159.223786) (xy 302.775158 -159.187234) (xy 302.862354 -159.15807) (xy 302.951735 -159.13651)
			(xy 303.042638 -159.122714) (xy 303.134391 -159.116782) (xy 303.226313 -159.118761) (xy 303.317726 -159.128634)
			(xy 303.407951 -159.146329) (xy 303.496322 -159.171714) (xy 303.582182 -159.204602) (xy 303.664898 -159.24475)
			(xy 303.743856 -159.291859) (xy 303.818473 -159.345582) (xy 303.888194 -159.40552) (xy 303.952505 -159.47123)
			(xy 304.01093 -159.542226) (xy 304.063035 -159.61798) (xy 304.108434 -159.697934) (xy 304.146793 -159.781494)
			(xy 304.177826 -159.868043) (xy 304.201304 -159.956939) (xy 304.217054 -160.047524) (xy 304.224958 -160.139128)
			(xy 304.225452 -160.1851) (xy 393.824219 -160.1851) (xy 393.828174 -160.093263) (xy 393.840009 -160.002106)
			(xy 393.859636 -159.912303) (xy 393.88691 -159.824521) (xy 393.92163 -159.739407) (xy 393.963538 -159.657594)
			(xy 394.012324 -159.579686) (xy 394.067627 -159.506261) (xy 394.129037 -159.437861) (xy 394.196099 -159.374994)
			(xy 394.268318 -159.318124) (xy 394.345158 -159.267673) (xy 394.426051 -159.224014) (xy 394.510397 -159.187471)
			(xy 394.597573 -159.158314) (xy 394.686932 -159.13676) (xy 394.777813 -159.122966) (xy 394.869544 -159.117036)
			(xy 394.961445 -159.119014) (xy 395.052836 -159.128885) (xy 395.14304 -159.146575) (xy 395.231389 -159.171955)
			(xy 395.317229 -159.204835) (xy 395.399925 -159.244973) (xy 395.478865 -159.292072) (xy 395.553463 -159.345782)
			(xy 395.623169 -159.405706) (xy 395.687464 -159.4714) (xy 395.745875 -159.542378) (xy 395.797967 -159.618115)
			(xy 395.843356 -159.69805) (xy 395.881706 -159.78159) (xy 395.912731 -159.868118) (xy 395.936204 -159.956993)
			(xy 395.95195 -160.047557) (xy 395.959852 -160.139139) (xy 395.960346 -160.1851) (xy 418.188915 -160.1851)
			(xy 418.192871 -160.093241) (xy 418.204708 -160.002062) (xy 418.22434 -159.912238) (xy 418.251621 -159.824435)
			(xy 418.286349 -159.739302) (xy 418.328267 -159.657469) (xy 418.377065 -159.579542) (xy 418.43238 -159.506099)
			(xy 418.493805 -159.437683) (xy 418.560884 -159.374801) (xy 418.633119 -159.317918) (xy 418.709978 -159.267455)
			(xy 418.79089 -159.223786) (xy 418.875256 -159.187234) (xy 418.962452 -159.15807) (xy 419.051833 -159.13651)
			(xy 419.142736 -159.122714) (xy 419.234489 -159.116782) (xy 419.326411 -159.118761) (xy 419.417824 -159.128634)
			(xy 419.508049 -159.146329) (xy 419.59642 -159.171714) (xy 419.68228 -159.204602) (xy 419.764996 -159.24475)
			(xy 419.843954 -159.291859) (xy 419.918571 -159.345582) (xy 419.988292 -159.40552) (xy 420.052603 -159.47123)
			(xy 420.111028 -159.542226) (xy 420.163133 -159.61798) (xy 420.208532 -159.697934) (xy 420.246891 -159.781494)
			(xy 420.277924 -159.868043) (xy 420.301402 -159.956939) (xy 420.317152 -160.047524) (xy 420.325056 -160.139128)
			(xy 420.32555 -160.1851) (xy 420.325056 -160.231072) (xy 420.317152 -160.322676) (xy 420.301402 -160.413261)
			(xy 420.277924 -160.502157) (xy 420.246891 -160.588706) (xy 420.208532 -160.672266) (xy 420.163133 -160.75222)
			(xy 420.111028 -160.827974) (xy 420.052603 -160.89897) (xy 419.988292 -160.96468) (xy 419.918571 -161.024618)
			(xy 419.843954 -161.078341) (xy 419.764996 -161.12545) (xy 419.68228 -161.165598) (xy 419.59642 -161.198486)
			(xy 419.508049 -161.223871) (xy 419.417824 -161.241566) (xy 419.326411 -161.251439) (xy 419.234489 -161.253418)
			(xy 419.142736 -161.247486) (xy 419.051833 -161.23369) (xy 418.962452 -161.21213) (xy 418.875256 -161.182966)
			(xy 418.79089 -161.146414) (xy 418.709978 -161.102745) (xy 418.633119 -161.052282) (xy 418.560884 -160.995399)
			(xy 418.493805 -160.932517) (xy 418.43238 -160.864101) (xy 418.377065 -160.790658) (xy 418.328267 -160.712731)
			(xy 418.286349 -160.630898) (xy 418.251621 -160.545765) (xy 418.22434 -160.457962) (xy 418.204708 -160.368138)
			(xy 418.192871 -160.276959) (xy 418.188915 -160.1851) (xy 395.960346 -160.1851) (xy 395.959852 -160.231061)
			(xy 395.95195 -160.322643) (xy 395.936204 -160.413207) (xy 395.912731 -160.502082) (xy 395.881706 -160.58861)
			(xy 395.843356 -160.67215) (xy 395.797967 -160.752085) (xy 395.745875 -160.827822) (xy 395.687464 -160.8988)
			(xy 395.623169 -160.964494) (xy 395.553463 -161.024418) (xy 395.478865 -161.078128) (xy 395.399925 -161.125227)
			(xy 395.317229 -161.165365) (xy 395.231389 -161.198245) (xy 395.14304 -161.223625) (xy 395.052836 -161.241315)
			(xy 394.961445 -161.251186) (xy 394.869544 -161.253164) (xy 394.777813 -161.247234) (xy 394.686932 -161.23344)
			(xy 394.597573 -161.211886) (xy 394.510397 -161.182729) (xy 394.426051 -161.146186) (xy 394.345158 -161.102527)
			(xy 394.268318 -161.052076) (xy 394.196099 -160.995206) (xy 394.129037 -160.932339) (xy 394.067627 -160.863939)
			(xy 394.012324 -160.790514) (xy 393.963538 -160.712606) (xy 393.92163 -160.630793) (xy 393.88691 -160.545679)
			(xy 393.859636 -160.457897) (xy 393.840009 -160.368094) (xy 393.828174 -160.276937) (xy 393.824219 -160.1851)
			(xy 304.225452 -160.1851) (xy 304.224958 -160.231072) (xy 304.217054 -160.322676) (xy 304.201304 -160.413261)
			(xy 304.177826 -160.502157) (xy 304.146793 -160.588706) (xy 304.108434 -160.672266) (xy 304.063035 -160.75222)
			(xy 304.01093 -160.827974) (xy 303.952505 -160.89897) (xy 303.888194 -160.96468) (xy 303.818473 -161.024618)
			(xy 303.743856 -161.078341) (xy 303.664898 -161.12545) (xy 303.582182 -161.165598) (xy 303.496322 -161.198486)
			(xy 303.407951 -161.223871) (xy 303.317726 -161.241566) (xy 303.226313 -161.251439) (xy 303.134391 -161.253418)
			(xy 303.042638 -161.247486) (xy 302.951735 -161.23369) (xy 302.862354 -161.21213) (xy 302.775158 -161.182966)
			(xy 302.690792 -161.146414) (xy 302.60988 -161.102745) (xy 302.533021 -161.052282) (xy 302.460786 -160.995399)
			(xy 302.393707 -160.932517) (xy 302.332282 -160.864101) (xy 302.276967 -160.790658) (xy 302.228169 -160.712731)
			(xy 302.186251 -160.630898) (xy 302.151523 -160.545765) (xy 302.124242 -160.457962) (xy 302.10461 -160.368138)
			(xy 302.092773 -160.276959) (xy 302.088817 -160.1851) (xy 279.860248 -160.1851) (xy 279.859754 -160.231061)
			(xy 279.851852 -160.322643) (xy 279.836106 -160.413207) (xy 279.812633 -160.502082) (xy 279.781608 -160.58861)
			(xy 279.743258 -160.67215) (xy 279.697869 -160.752085) (xy 279.645777 -160.827822) (xy 279.587366 -160.8988)
			(xy 279.523071 -160.964494) (xy 279.453365 -161.024418) (xy 279.378767 -161.078128) (xy 279.299827 -161.125227)
			(xy 279.217131 -161.165365) (xy 279.131291 -161.198245) (xy 279.042942 -161.223625) (xy 278.952738 -161.241315)
			(xy 278.861347 -161.251186) (xy 278.769446 -161.253164) (xy 278.677715 -161.247234) (xy 278.586834 -161.23344)
			(xy 278.497475 -161.211886) (xy 278.410299 -161.182729) (xy 278.325953 -161.146186) (xy 278.24506 -161.102527)
			(xy 278.16822 -161.052076) (xy 278.096001 -160.995206) (xy 278.028939 -160.932339) (xy 277.967529 -160.863939)
			(xy 277.912226 -160.790514) (xy 277.86344 -160.712606) (xy 277.821532 -160.630793) (xy 277.786812 -160.545679)
			(xy 277.759538 -160.457897) (xy 277.739911 -160.368094) (xy 277.728076 -160.276937) (xy 277.724121 -160.1851)
			(xy 188.125608 -160.1851) (xy 188.125114 -160.231072) (xy 188.11721 -160.322676) (xy 188.10146 -160.413261)
			(xy 188.077982 -160.502157) (xy 188.046949 -160.588706) (xy 188.00859 -160.672266) (xy 187.963191 -160.75222)
			(xy 187.911086 -160.827974) (xy 187.852661 -160.89897) (xy 187.78835 -160.96468) (xy 187.718629 -161.024618)
			(xy 187.644012 -161.078341) (xy 187.565054 -161.12545) (xy 187.482338 -161.165598) (xy 187.396478 -161.198486)
			(xy 187.308107 -161.223871) (xy 187.217882 -161.241566) (xy 187.126469 -161.251439) (xy 187.034547 -161.253418)
			(xy 186.942794 -161.247486) (xy 186.851891 -161.23369) (xy 186.76251 -161.21213) (xy 186.675314 -161.182966)
			(xy 186.590948 -161.146414) (xy 186.510036 -161.102745) (xy 186.433177 -161.052282) (xy 186.360942 -160.995399)
			(xy 186.293863 -160.932517) (xy 186.232438 -160.864101) (xy 186.177123 -160.790658) (xy 186.128325 -160.712731)
			(xy 186.086407 -160.630898) (xy 186.051679 -160.545765) (xy 186.024398 -160.457962) (xy 186.004766 -160.368138)
			(xy 185.992929 -160.276959) (xy 185.988973 -160.1851) (xy 163.760404 -160.1851) (xy 163.75991 -160.231061)
			(xy 163.752008 -160.322643) (xy 163.736262 -160.413207) (xy 163.712789 -160.502082) (xy 163.681764 -160.58861)
			(xy 163.643414 -160.67215) (xy 163.598025 -160.752085) (xy 163.545933 -160.827822) (xy 163.487522 -160.8988)
			(xy 163.423227 -160.964494) (xy 163.353521 -161.024418) (xy 163.278923 -161.078128) (xy 163.199983 -161.125227)
			(xy 163.117287 -161.165365) (xy 163.031447 -161.198245) (xy 162.943098 -161.223625) (xy 162.852894 -161.241315)
			(xy 162.761503 -161.251186) (xy 162.669602 -161.253164) (xy 162.577871 -161.247234) (xy 162.48699 -161.23344)
			(xy 162.397631 -161.211886) (xy 162.310455 -161.182729) (xy 162.226109 -161.146186) (xy 162.145216 -161.102527)
			(xy 162.068376 -161.052076) (xy 161.996157 -160.995206) (xy 161.929095 -160.932339) (xy 161.867685 -160.863939)
			(xy 161.812382 -160.790514) (xy 161.763596 -160.712606) (xy 161.721688 -160.630793) (xy 161.686968 -160.545679)
			(xy 161.659694 -160.457897) (xy 161.640067 -160.368094) (xy 161.628232 -160.276937) (xy 161.624277 -160.1851)
			(xy 72.02551 -160.1851) (xy 72.025016 -160.231072) (xy 72.017112 -160.322676) (xy 72.001362 -160.413261)
			(xy 71.977884 -160.502157) (xy 71.946851 -160.588706) (xy 71.908492 -160.672266) (xy 71.863093 -160.75222)
			(xy 71.810988 -160.827974) (xy 71.752563 -160.89897) (xy 71.688252 -160.96468) (xy 71.618531 -161.024618)
			(xy 71.543914 -161.078341) (xy 71.464956 -161.12545) (xy 71.38224 -161.165598) (xy 71.29638 -161.198486)
			(xy 71.208009 -161.223871) (xy 71.117784 -161.241566) (xy 71.026371 -161.251439) (xy 70.934449 -161.253418)
			(xy 70.842696 -161.247486) (xy 70.751793 -161.23369) (xy 70.662412 -161.21213) (xy 70.575216 -161.182966)
			(xy 70.49085 -161.146414) (xy 70.409938 -161.102745) (xy 70.333079 -161.052282) (xy 70.260844 -160.995399)
			(xy 70.193765 -160.932517) (xy 70.13234 -160.864101) (xy 70.077025 -160.790658) (xy 70.028227 -160.712731)
			(xy 69.986309 -160.630898) (xy 69.951581 -160.545765) (xy 69.9243 -160.457962) (xy 69.904668 -160.368138)
			(xy 69.892831 -160.276959) (xy 69.888875 -160.1851) (xy 47.660306 -160.1851) (xy 47.659812 -160.231061)
			(xy 47.65191 -160.322643) (xy 47.636164 -160.413207) (xy 47.612691 -160.502082) (xy 47.581666 -160.58861)
			(xy 47.543316 -160.67215) (xy 47.497927 -160.752085) (xy 47.445835 -160.827822) (xy 47.387424 -160.8988)
			(xy 47.323129 -160.964494) (xy 47.253423 -161.024418) (xy 47.178825 -161.078128) (xy 47.099885 -161.125227)
			(xy 47.017189 -161.165365) (xy 46.931349 -161.198245) (xy 46.843 -161.223625) (xy 46.752796 -161.241315)
			(xy 46.661405 -161.251186) (xy 46.569504 -161.253164) (xy 46.477773 -161.247234) (xy 46.386892 -161.23344)
			(xy 46.297533 -161.211886) (xy 46.210357 -161.182729) (xy 46.126011 -161.146186) (xy 46.045118 -161.102527)
			(xy 45.968278 -161.052076) (xy 45.896059 -160.995206) (xy 45.828997 -160.932339) (xy 45.767587 -160.863939)
			(xy 45.712284 -160.790514) (xy 45.663498 -160.712606) (xy 45.62159 -160.630793) (xy 45.58687 -160.545679)
			(xy 45.559596 -160.457897) (xy 45.539969 -160.368094) (xy 45.528134 -160.276937) (xy 45.524179 -160.1851)
			(xy 4.308094 -160.1851) (xy 4.308094 -168.065164) (xy 135.245906 -168.065164) (xy 135.245906 -168.005236)
			(xy 135.253728 -167.94582) (xy 135.269237 -167.887933) (xy 135.29217 -167.832566) (xy 135.322132 -167.780665)
			(xy 135.358612 -167.733119) (xy 135.400986 -167.690742) (xy 135.448529 -167.654257) (xy 135.500426 -167.624289)
			(xy 135.555791 -167.601351) (xy 135.613677 -167.585836) (xy 135.673092 -167.578009) (xy 135.703056 -167.577516)
			(xy 136.566656 -167.577516) (xy 136.596628 -167.577934) (xy 136.656061 -167.585754) (xy 136.713965 -167.601264)
			(xy 136.769348 -167.6242) (xy 136.821264 -167.654169) (xy 136.868823 -167.690658) (xy 136.911213 -167.733044)
			(xy 136.947707 -167.7806) (xy 136.977681 -167.832512) (xy 137.000622 -167.887894) (xy 137.016138 -167.945796)
			(xy 137.023963 -168.005228) (xy 137.023963 -168.065172) (xy 137.016138 -168.124604) (xy 137.000622 -168.182506)
			(xy 136.977681 -168.237888) (xy 136.947707 -168.2898) (xy 136.911213 -168.337356) (xy 136.868823 -168.379742)
			(xy 136.821264 -168.416231) (xy 136.769348 -168.4462) (xy 136.713965 -168.469136) (xy 136.656061 -168.484646)
			(xy 136.596628 -168.492466) (xy 136.566656 -168.492932) (xy 135.703056 -168.492932) (xy 135.673092 -168.492391)
			(xy 135.613677 -168.484564) (xy 135.555791 -168.469049) (xy 135.500426 -168.446111) (xy 135.448529 -168.416143)
			(xy 135.400986 -168.379658) (xy 135.358612 -168.337281) (xy 135.322132 -168.289735) (xy 135.29217 -168.237834)
			(xy 135.269237 -168.182467) (xy 135.253728 -168.12458) (xy 135.245906 -168.065164) (xy 4.308094 -168.065164)
			(xy 4.308094 -168.700164) (xy 133.213906 -168.700164) (xy 133.213906 -168.640236) (xy 133.221728 -168.58082)
			(xy 133.237237 -168.522933) (xy 133.26017 -168.467566) (xy 133.290132 -168.415665) (xy 133.326612 -168.368119)
			(xy 133.368986 -168.325742) (xy 133.416529 -168.289257) (xy 133.468426 -168.259289) (xy 133.523791 -168.236351)
			(xy 133.581677 -168.220836) (xy 133.641092 -168.213009) (xy 133.671056 -168.212516) (xy 134.534656 -168.212516)
			(xy 134.564628 -168.212934) (xy 134.624061 -168.220754) (xy 134.681965 -168.236264) (xy 134.737348 -168.2592)
			(xy 134.789264 -168.289169) (xy 134.836823 -168.325658) (xy 134.879213 -168.368044) (xy 134.915707 -168.4156)
			(xy 134.945681 -168.467512) (xy 134.968622 -168.522894) (xy 134.984138 -168.580796) (xy 134.991963 -168.640228)
			(xy 134.991963 -168.700172) (xy 134.984138 -168.759604) (xy 134.968622 -168.817506) (xy 134.945681 -168.872888)
			(xy 134.915707 -168.9248) (xy 134.879213 -168.972356) (xy 134.836823 -169.014742) (xy 134.789264 -169.051231)
			(xy 134.737348 -169.0812) (xy 134.681965 -169.104136) (xy 134.624061 -169.119646) (xy 134.564628 -169.127466)
			(xy 134.534656 -169.127932) (xy 133.671056 -169.127932) (xy 133.641092 -169.127391) (xy 133.581677 -169.119564)
			(xy 133.523791 -169.104049) (xy 133.468426 -169.081111) (xy 133.416529 -169.051143) (xy 133.368986 -169.014658)
			(xy 133.326612 -168.972281) (xy 133.290132 -168.924735) (xy 133.26017 -168.872834) (xy 133.237237 -168.817467)
			(xy 133.221728 -168.75958) (xy 133.213906 -168.700164) (xy 4.308094 -168.700164) (xy 4.308094 -169.61389)
			(xy 245.108869 -169.61389) (xy 245.108869 -169.55391) (xy 245.116699 -169.494444) (xy 245.132223 -169.436508)
			(xy 245.155178 -169.381095) (xy 245.185169 -169.329152) (xy 245.221684 -169.281569) (xy 245.264097 -169.239158)
			(xy 245.311684 -169.202648) (xy 245.363629 -169.172661) (xy 245.419045 -169.149711) (xy 245.476981 -169.134191)
			(xy 245.536448 -169.126367) (xy 245.566438 -169.1259) (xy 246.430038 -169.1259) (xy 246.460018 -169.126468)
			(xy 246.519465 -169.134299) (xy 246.577381 -169.149822) (xy 246.632776 -169.172772) (xy 246.684702 -169.202755)
			(xy 246.73227 -169.239259) (xy 246.774667 -169.281659) (xy 246.811166 -169.32923) (xy 246.841145 -169.381158)
			(xy 246.86409 -169.436555) (xy 246.879608 -169.494472) (xy 246.887434 -169.55392) (xy 246.887434 -169.61388)
			(xy 246.879608 -169.673328) (xy 246.86409 -169.731245) (xy 246.841145 -169.786642) (xy 246.811166 -169.83857)
			(xy 246.774667 -169.886141) (xy 246.73227 -169.928541) (xy 246.684702 -169.965045) (xy 246.632776 -169.995028)
			(xy 246.577381 -170.017978) (xy 246.519465 -170.033501) (xy 246.460018 -170.041332) (xy 246.430038 -170.041824)
			(xy 245.566438 -170.041824) (xy 245.536448 -170.041433) (xy 245.476981 -170.033609) (xy 245.419045 -170.018089)
			(xy 245.363629 -169.995139) (xy 245.311684 -169.965152) (xy 245.264097 -169.928642) (xy 245.221684 -169.886231)
			(xy 245.185169 -169.838648) (xy 245.155178 -169.786705) (xy 245.132223 -169.731292) (xy 245.116699 -169.673356)
			(xy 245.108869 -169.61389) (xy 4.308094 -169.61389) (xy 4.308094 -174.805086) (xy 141.546072 -174.805086)
			(xy 141.546072 -173.941486) (xy 141.546562 -173.911518) (xy 141.554385 -173.852096) (xy 141.569898 -173.794203)
			(xy 141.592834 -173.73883) (xy 141.622801 -173.686924) (xy 141.659288 -173.639374) (xy 141.701668 -173.596994)
			(xy 141.749218 -173.560507) (xy 141.801124 -173.53054) (xy 141.856497 -173.507604) (xy 141.91439 -173.492091)
			(xy 141.973812 -173.484268) (xy 142.033748 -173.484268) (xy 142.09317 -173.492091) (xy 142.106698 -173.495716)
			(xy 257.519424 -173.495716) (xy 257.519424 -172.632116) (xy 257.519914 -172.602132) (xy 257.527742 -172.542676)
			(xy 257.543263 -172.484751) (xy 257.566212 -172.429347) (xy 257.596196 -172.377413) (xy 257.632702 -172.329837)
			(xy 257.675107 -172.287432) (xy 257.722683 -172.250926) (xy 257.774617 -172.220942) (xy 257.830021 -172.197993)
			(xy 257.887946 -172.182472) (xy 257.947402 -172.174644) (xy 258.00737 -172.174644) (xy 258.066826 -172.182472)
			(xy 258.124751 -172.197993) (xy 258.180155 -172.220942) (xy 258.232089 -172.250926) (xy 258.279665 -172.287432)
			(xy 258.32207 -172.329837) (xy 258.358576 -172.377413) (xy 258.38856 -172.429347) (xy 258.411509 -172.484751)
			(xy 258.42703 -172.542676) (xy 258.434858 -172.602132) (xy 258.435348 -172.632116) (xy 258.435348 -173.495716)
			(xy 258.434858 -173.5257) (xy 258.42703 -173.585156) (xy 258.411509 -173.643081) (xy 258.38856 -173.698485)
			(xy 258.358576 -173.750419) (xy 258.32207 -173.797995) (xy 258.279665 -173.8404) (xy 258.232089 -173.876906)
			(xy 258.180155 -173.90689) (xy 258.124751 -173.929839) (xy 258.066826 -173.94536) (xy 258.00737 -173.953188)
			(xy 257.947402 -173.953188) (xy 257.887946 -173.94536) (xy 257.830021 -173.929839) (xy 257.774617 -173.90689)
			(xy 257.722683 -173.876906) (xy 257.675107 -173.8404) (xy 257.632702 -173.797995) (xy 257.596196 -173.750419)
			(xy 257.566212 -173.698485) (xy 257.543263 -173.643081) (xy 257.527742 -173.585156) (xy 257.519914 -173.5257)
			(xy 257.519424 -173.495716) (xy 142.106698 -173.495716) (xy 142.151063 -173.507604) (xy 142.206436 -173.53054)
			(xy 142.258342 -173.560507) (xy 142.305892 -173.596994) (xy 142.348272 -173.639374) (xy 142.384759 -173.686924)
			(xy 142.414726 -173.73883) (xy 142.437662 -173.794203) (xy 142.453175 -173.852096) (xy 142.460998 -173.911518)
			(xy 142.461488 -173.941486) (xy 142.461488 -174.805086) (xy 142.460998 -174.835054) (xy 142.453175 -174.894476)
			(xy 142.437662 -174.952369) (xy 142.414726 -175.007742) (xy 142.384759 -175.059648) (xy 142.348272 -175.107198)
			(xy 142.305892 -175.149578) (xy 142.258342 -175.186065) (xy 142.206436 -175.216032) (xy 142.151063 -175.238968)
			(xy 142.09317 -175.254481) (xy 142.033748 -175.262304) (xy 141.973812 -175.262304) (xy 141.91439 -175.254481)
			(xy 141.856497 -175.238968) (xy 141.801124 -175.216032) (xy 141.749218 -175.186065) (xy 141.701668 -175.149578)
			(xy 141.659288 -175.107198) (xy 141.622801 -175.059648) (xy 141.592834 -175.007742) (xy 141.569898 -174.952369)
			(xy 141.554385 -174.894476) (xy 141.546562 -174.835054) (xy 141.546072 -174.805086) (xy 4.308094 -174.805086)
			(xy 4.308094 -176.837086) (xy 142.181072 -176.837086) (xy 142.181072 -175.973486) (xy 142.181562 -175.943518)
			(xy 142.189385 -175.884096) (xy 142.204898 -175.826203) (xy 142.227834 -175.77083) (xy 142.257801 -175.718924)
			(xy 142.294288 -175.671374) (xy 142.336668 -175.628994) (xy 142.384218 -175.592507) (xy 142.436124 -175.56254)
			(xy 142.491497 -175.539604) (xy 142.54939 -175.524091) (xy 142.608812 -175.516268) (xy 142.668748 -175.516268)
			(xy 142.72817 -175.524091) (xy 142.786063 -175.539604) (xy 142.841436 -175.56254) (xy 142.893342 -175.592507)
			(xy 142.940892 -175.628994) (xy 142.983272 -175.671374) (xy 143.019759 -175.718924) (xy 143.049726 -175.77083)
			(xy 143.072662 -175.826203) (xy 143.088175 -175.884096) (xy 143.095998 -175.943518) (xy 143.096488 -175.973486)
			(xy 143.096488 -176.837086) (xy 143.095998 -176.867054) (xy 143.088175 -176.926476) (xy 143.072662 -176.984369)
			(xy 143.049726 -177.039742) (xy 143.019759 -177.091648) (xy 142.983272 -177.139198) (xy 142.940892 -177.181578)
			(xy 142.893342 -177.218065) (xy 142.841436 -177.248032) (xy 142.786063 -177.270968) (xy 142.72817 -177.286481)
			(xy 142.668748 -177.294304) (xy 142.608812 -177.294304) (xy 142.54939 -177.286481) (xy 142.491497 -177.270968)
			(xy 142.436124 -177.248032) (xy 142.384218 -177.218065) (xy 142.336668 -177.181578) (xy 142.294288 -177.139198)
			(xy 142.257801 -177.091648) (xy 142.227834 -177.039742) (xy 142.204898 -176.984369) (xy 142.189385 -176.926476)
			(xy 142.181562 -176.867054) (xy 142.181072 -176.837086) (xy 4.308094 -176.837086) (xy 4.308094 -178.995324)
			(xy 123.198636 -178.995324) (xy 123.198636 -178.131724) (xy 123.199126 -178.10174) (xy 123.206954 -178.042284)
			(xy 123.222475 -177.984359) (xy 123.245424 -177.928955) (xy 123.275408 -177.877021) (xy 123.311914 -177.829445)
			(xy 123.354319 -177.78704) (xy 123.401895 -177.750534) (xy 123.453829 -177.72055) (xy 123.509233 -177.697601)
			(xy 123.567158 -177.68208) (xy 123.626614 -177.674252) (xy 123.686582 -177.674252) (xy 123.746038 -177.68208)
			(xy 123.803963 -177.697601) (xy 123.859367 -177.72055) (xy 123.911301 -177.750534) (xy 123.958877 -177.78704)
			(xy 124.001282 -177.829445) (xy 124.037788 -177.877021) (xy 124.067772 -177.928955) (xy 124.090721 -177.984359)
			(xy 124.106242 -178.042284) (xy 124.11407 -178.10174) (xy 124.11456 -178.131724) (xy 124.11456 -178.869086)
			(xy 141.546072 -178.869086) (xy 141.546072 -178.005486) (xy 141.546562 -177.975518) (xy 141.554385 -177.916096)
			(xy 141.569898 -177.858203) (xy 141.592834 -177.80283) (xy 141.622801 -177.750924) (xy 141.659288 -177.703374)
			(xy 141.701668 -177.660994) (xy 141.749218 -177.624507) (xy 141.801124 -177.59454) (xy 141.856497 -177.571604)
			(xy 141.91439 -177.556091) (xy 141.973812 -177.548268) (xy 142.033748 -177.548268) (xy 142.09317 -177.556091)
			(xy 142.151063 -177.571604) (xy 142.206436 -177.59454) (xy 142.258342 -177.624507) (xy 142.305892 -177.660994)
			(xy 142.348272 -177.703374) (xy 142.384759 -177.750924) (xy 142.414726 -177.80283) (xy 142.437662 -177.858203)
			(xy 142.453175 -177.916096) (xy 142.460998 -177.975518) (xy 142.461488 -178.005486) (xy 142.461488 -178.869086)
			(xy 142.460998 -178.899054) (xy 142.453175 -178.958476) (xy 142.437662 -179.016369) (xy 142.414726 -179.071742)
			(xy 142.384759 -179.123648) (xy 142.348272 -179.171198) (xy 142.305892 -179.213578) (xy 142.258342 -179.250065)
			(xy 142.206436 -179.280032) (xy 142.151063 -179.302968) (xy 142.09317 -179.318481) (xy 142.033748 -179.326304)
			(xy 141.973812 -179.326304) (xy 141.91439 -179.318481) (xy 141.856497 -179.302968) (xy 141.801124 -179.280032)
			(xy 141.749218 -179.250065) (xy 141.701668 -179.213578) (xy 141.659288 -179.171198) (xy 141.622801 -179.123648)
			(xy 141.592834 -179.071742) (xy 141.569898 -179.016369) (xy 141.554385 -178.958476) (xy 141.546562 -178.899054)
			(xy 141.546072 -178.869086) (xy 124.11456 -178.869086) (xy 124.11456 -178.995324) (xy 124.11407 -179.025308)
			(xy 124.106242 -179.084764) (xy 124.090721 -179.142689) (xy 124.067772 -179.198093) (xy 124.037788 -179.250027)
			(xy 124.001282 -179.297603) (xy 123.958877 -179.340008) (xy 123.911301 -179.376514) (xy 123.859367 -179.406498)
			(xy 123.803963 -179.429447) (xy 123.746038 -179.444968) (xy 123.686582 -179.452796) (xy 123.626614 -179.452796)
			(xy 123.567158 -179.444968) (xy 123.509233 -179.429447) (xy 123.453829 -179.406498) (xy 123.401895 -179.376514)
			(xy 123.354319 -179.340008) (xy 123.311914 -179.297603) (xy 123.275408 -179.250027) (xy 123.245424 -179.198093)
			(xy 123.222475 -179.142689) (xy 123.206954 -179.084764) (xy 123.199126 -179.025308) (xy 123.198636 -178.995324)
			(xy 4.308094 -178.995324) (xy 4.308094 -180.901086) (xy 142.181072 -180.901086) (xy 142.181072 -180.037486)
			(xy 142.181562 -180.007518) (xy 142.189385 -179.948096) (xy 142.204898 -179.890203) (xy 142.227834 -179.83483)
			(xy 142.257801 -179.782924) (xy 142.294288 -179.735374) (xy 142.336668 -179.692994) (xy 142.384218 -179.656507)
			(xy 142.436124 -179.62654) (xy 142.491497 -179.603604) (xy 142.54939 -179.588091) (xy 142.608812 -179.580268)
			(xy 142.668748 -179.580268) (xy 142.72817 -179.588091) (xy 142.786063 -179.603604) (xy 142.841436 -179.62654)
			(xy 142.893342 -179.656507) (xy 142.940892 -179.692994) (xy 142.983272 -179.735374) (xy 143.019759 -179.782924)
			(xy 143.049726 -179.83483) (xy 143.072662 -179.890203) (xy 143.088175 -179.948096) (xy 143.095998 -180.007518)
			(xy 143.096488 -180.037486) (xy 143.096488 -180.901086) (xy 143.095998 -180.931054) (xy 143.088175 -180.990476)
			(xy 143.072662 -181.048369) (xy 143.049726 -181.103742) (xy 143.019759 -181.155648) (xy 142.983272 -181.203198)
			(xy 142.940892 -181.245578) (xy 142.893342 -181.282065) (xy 142.841436 -181.312032) (xy 142.786063 -181.334968)
			(xy 142.72817 -181.350481) (xy 142.668748 -181.358304) (xy 142.608812 -181.358304) (xy 142.54939 -181.350481)
			(xy 142.491497 -181.334968) (xy 142.436124 -181.312032) (xy 142.384218 -181.282065) (xy 142.336668 -181.245578)
			(xy 142.294288 -181.203198) (xy 142.257801 -181.155648) (xy 142.227834 -181.103742) (xy 142.204898 -181.048369)
			(xy 142.189385 -180.990476) (xy 142.181562 -180.931054) (xy 142.181072 -180.901086) (xy 4.308094 -180.901086)
			(xy 4.308094 -182.933086) (xy 141.546072 -182.933086) (xy 141.546072 -182.069486) (xy 141.546562 -182.039518)
			(xy 141.554385 -181.980096) (xy 141.569898 -181.922203) (xy 141.592834 -181.86683) (xy 141.622801 -181.814924)
			(xy 141.659288 -181.767374) (xy 141.701668 -181.724994) (xy 141.749218 -181.688507) (xy 141.801124 -181.65854)
			(xy 141.856497 -181.635604) (xy 141.91439 -181.620091) (xy 141.973812 -181.612268) (xy 142.033748 -181.612268)
			(xy 142.09317 -181.620091) (xy 142.151063 -181.635604) (xy 142.206436 -181.65854) (xy 142.258342 -181.688507)
			(xy 142.305892 -181.724994) (xy 142.348272 -181.767374) (xy 142.384759 -181.814924) (xy 142.414726 -181.86683)
			(xy 142.437662 -181.922203) (xy 142.453175 -181.980096) (xy 142.460998 -182.039518) (xy 142.461488 -182.069486)
			(xy 142.461488 -182.933086) (xy 142.460998 -182.963054) (xy 142.453175 -183.022476) (xy 142.437662 -183.080369)
			(xy 142.414726 -183.135742) (xy 142.384759 -183.187648) (xy 142.348272 -183.235198) (xy 142.305892 -183.277578)
			(xy 142.258342 -183.314065) (xy 142.206436 -183.344032) (xy 142.151063 -183.366968) (xy 142.09317 -183.382481)
			(xy 142.033748 -183.390304) (xy 141.973812 -183.390304) (xy 141.91439 -183.382481) (xy 141.856497 -183.366968)
			(xy 141.801124 -183.344032) (xy 141.749218 -183.314065) (xy 141.701668 -183.277578) (xy 141.659288 -183.235198)
			(xy 141.622801 -183.187648) (xy 141.592834 -183.135742) (xy 141.569898 -183.080369) (xy 141.554385 -183.022476)
			(xy 141.546562 -182.963054) (xy 141.546072 -182.933086) (xy 4.308094 -182.933086) (xy 4.308094 -187.124582)
			(xy 135.58115 -187.124582) (xy 135.58115 -187.064618) (xy 135.588977 -187.005166) (xy 135.604497 -186.947244)
			(xy 135.627444 -186.891844) (xy 135.657426 -186.839912) (xy 135.69393 -186.792339) (xy 135.736331 -186.749937)
			(xy 135.783904 -186.713432) (xy 135.835835 -186.683448) (xy 135.891235 -186.6605) (xy 135.949156 -186.644979)
			(xy 136.008608 -186.637151) (xy 136.03859 -186.63666) (xy 136.90219 -186.63666) (xy 136.932178 -186.637085)
			(xy 136.99164 -186.644912) (xy 137.049571 -186.660433) (xy 137.104981 -186.683384) (xy 137.156922 -186.713371)
			(xy 137.204504 -186.749881) (xy 137.246913 -186.792289) (xy 137.283424 -186.83987) (xy 137.313412 -186.89181)
			(xy 137.336363 -186.947219) (xy 137.351886 -187.005151) (xy 137.359715 -187.064612) (xy 137.359715 -187.124588)
			(xy 137.351886 -187.184049) (xy 137.336363 -187.241981) (xy 137.313412 -187.29739) (xy 137.283424 -187.34933)
			(xy 137.246913 -187.396911) (xy 137.204504 -187.439319) (xy 137.156922 -187.475829) (xy 137.104981 -187.505816)
			(xy 137.049571 -187.528767) (xy 136.99164 -187.544288) (xy 136.932178 -187.552115) (xy 136.90219 -187.552584)
			(xy 136.03859 -187.552584) (xy 136.008608 -187.552049) (xy 135.949156 -187.544221) (xy 135.891235 -187.5287)
			(xy 135.835835 -187.505752) (xy 135.783904 -187.475768) (xy 135.736331 -187.439263) (xy 135.69393 -187.396861)
			(xy 135.657426 -187.349288) (xy 135.627444 -187.297356) (xy 135.604497 -187.241956) (xy 135.588977 -187.184034)
			(xy 135.58115 -187.124582) (xy 4.308094 -187.124582) (xy 4.308094 -188.252885) (xy 128.656818 -188.252885)
			(xy 128.656818 -188.192915) (xy 128.664646 -188.133459) (xy 128.680167 -188.075533) (xy 128.703116 -188.020128)
			(xy 128.733101 -187.968193) (xy 128.769608 -187.920615) (xy 128.812012 -187.87821) (xy 128.859589 -187.841703)
			(xy 128.911524 -187.811718) (xy 128.966929 -187.788768) (xy 129.024855 -187.773246) (xy 129.084311 -187.765418)
			(xy 129.114296 -187.764928) (xy 129.977896 -187.764928) (xy 130.007881 -187.765417) (xy 130.067339 -187.773244)
			(xy 130.125266 -187.788765) (xy 130.180671 -187.811714) (xy 130.232607 -187.841699) (xy 130.280185 -187.878207)
			(xy 130.322591 -187.920612) (xy 130.359098 -187.96819) (xy 130.389084 -188.020125) (xy 130.412034 -188.075531)
			(xy 130.427555 -188.133458) (xy 130.435383 -188.192915) (xy 130.435383 -188.252885) (xy 130.434185 -188.261981)
			(xy 131.046262 -188.261981) (xy 131.046262 -188.202019) (xy 131.054088 -188.14257) (xy 131.069607 -188.084651)
			(xy 131.092553 -188.029253) (xy 131.122533 -187.977324) (xy 131.159034 -187.929752) (xy 131.201432 -187.887351)
			(xy 131.249002 -187.850847) (xy 131.30093 -187.820864) (xy 131.356326 -187.797915) (xy 131.414244 -187.782393)
			(xy 131.473693 -187.774564) (xy 131.503674 -187.774072) (xy 132.367274 -187.774072) (xy 132.397263 -187.774472)
			(xy 132.456728 -187.782297) (xy 132.514663 -187.797818) (xy 132.570077 -187.820768) (xy 132.62202 -187.850755)
			(xy 132.669605 -187.887266) (xy 132.712017 -187.929675) (xy 132.74853 -187.977258) (xy 132.77852 -188.0292)
			(xy 132.801474 -188.084612) (xy 132.816998 -188.142546) (xy 132.824827 -188.202011) (xy 132.824827 -188.261989)
			(xy 132.816998 -188.321454) (xy 132.801474 -188.379388) (xy 132.79518 -188.394582) (xy 133.54915 -188.394582)
			(xy 133.54915 -188.334618) (xy 133.556977 -188.275166) (xy 133.572497 -188.217244) (xy 133.595444 -188.161844)
			(xy 133.625426 -188.109912) (xy 133.66193 -188.062339) (xy 133.704331 -188.019937) (xy 133.751904 -187.983432)
			(xy 133.803835 -187.953448) (xy 133.859235 -187.9305) (xy 133.917156 -187.914979) (xy 133.976608 -187.907151)
			(xy 134.00659 -187.90666) (xy 134.87019 -187.90666) (xy 134.900178 -187.907085) (xy 134.95964 -187.914912)
			(xy 135.017571 -187.930433) (xy 135.072981 -187.953384) (xy 135.124922 -187.983371) (xy 135.172504 -188.019881)
			(xy 135.214913 -188.062289) (xy 135.251424 -188.10987) (xy 135.281412 -188.16181) (xy 135.304363 -188.217219)
			(xy 135.319886 -188.275151) (xy 135.327715 -188.334612) (xy 135.327715 -188.394588) (xy 135.319886 -188.454049)
			(xy 135.304363 -188.511981) (xy 135.281412 -188.56739) (xy 135.251424 -188.61933) (xy 135.214913 -188.666911)
			(xy 135.172504 -188.709319) (xy 135.124922 -188.745829) (xy 135.072981 -188.775816) (xy 135.017571 -188.798767)
			(xy 134.95964 -188.814288) (xy 134.900178 -188.822115) (xy 134.87019 -188.822584) (xy 134.00659 -188.822584)
			(xy 133.976608 -188.822049) (xy 133.917156 -188.814221) (xy 133.859235 -188.7987) (xy 133.803835 -188.775752)
			(xy 133.751904 -188.745768) (xy 133.704331 -188.709263) (xy 133.66193 -188.666861) (xy 133.625426 -188.619288)
			(xy 133.595444 -188.567356) (xy 133.572497 -188.511956) (xy 133.556977 -188.454034) (xy 133.54915 -188.394582)
			(xy 132.79518 -188.394582) (xy 132.77852 -188.4348) (xy 132.74853 -188.486742) (xy 132.712017 -188.534325)
			(xy 132.669605 -188.576734) (xy 132.62202 -188.613245) (xy 132.570077 -188.643232) (xy 132.514663 -188.666182)
			(xy 132.456728 -188.681703) (xy 132.397263 -188.689528) (xy 132.367274 -188.689996) (xy 131.503674 -188.689996)
			(xy 131.473693 -188.689436) (xy 131.414244 -188.681607) (xy 131.356326 -188.666085) (xy 131.30093 -188.643136)
			(xy 131.249002 -188.613153) (xy 131.201432 -188.576649) (xy 131.159034 -188.534248) (xy 131.122533 -188.486676)
			(xy 131.092553 -188.434747) (xy 131.069607 -188.379349) (xy 131.054088 -188.32143) (xy 131.046262 -188.261981)
			(xy 130.434185 -188.261981) (xy 130.427555 -188.312342) (xy 130.412034 -188.370269) (xy 130.389084 -188.425675)
			(xy 130.359098 -188.47761) (xy 130.322591 -188.525188) (xy 130.280185 -188.567593) (xy 130.232607 -188.604101)
			(xy 130.180671 -188.634086) (xy 130.125266 -188.657035) (xy 130.067339 -188.672556) (xy 130.007881 -188.680383)
			(xy 129.977896 -188.680852) (xy 129.114296 -188.680852) (xy 129.084311 -188.680382) (xy 129.024855 -188.672554)
			(xy 128.966929 -188.657032) (xy 128.911524 -188.634082) (xy 128.859589 -188.604097) (xy 128.812012 -188.56759)
			(xy 128.769608 -188.525185) (xy 128.733101 -188.477607) (xy 128.703116 -188.425672) (xy 128.680167 -188.370267)
			(xy 128.664646 -188.312341) (xy 128.656818 -188.252885) (xy 4.308094 -188.252885) (xy 4.308094 -195.726088)
			(xy 126.922185 -195.726088) (xy 126.922185 -195.666112) (xy 126.930014 -195.606648) (xy 126.945538 -195.548715)
			(xy 126.968491 -195.493304) (xy 126.99848 -195.441364) (xy 127.034993 -195.393782) (xy 127.077404 -195.351373)
			(xy 127.124989 -195.314864) (xy 127.176931 -195.284878) (xy 127.232344 -195.261928) (xy 127.290278 -195.246408)
			(xy 127.349742 -195.238583) (xy 127.37973 -195.238116) (xy 128.24333 -195.238116) (xy 128.273312 -195.238652)
			(xy 128.332761 -195.246482) (xy 128.39068 -195.262005) (xy 128.446078 -195.284955) (xy 128.498007 -195.314939)
			(xy 128.545577 -195.351444) (xy 128.587976 -195.393845) (xy 128.624478 -195.441418) (xy 128.654459 -195.493349)
			(xy 128.677405 -195.548748) (xy 128.692924 -195.606668) (xy 128.70075 -195.666118) (xy 128.70075 -195.726082)
			(xy 128.692924 -195.785532) (xy 128.677405 -195.843452) (xy 128.654459 -195.898851) (xy 128.624478 -195.950782)
			(xy 128.587976 -195.998355) (xy 128.545577 -196.040756) (xy 128.498007 -196.077261) (xy 128.446078 -196.107245)
			(xy 128.39068 -196.130195) (xy 128.332761 -196.145718) (xy 128.273312 -196.153548) (xy 128.24333 -196.15404)
			(xy 127.37973 -196.15404) (xy 127.349742 -196.153617) (xy 127.290278 -196.145792) (xy 127.232344 -196.130272)
			(xy 127.176931 -196.107322) (xy 127.124989 -196.077336) (xy 127.077404 -196.040827) (xy 127.034993 -195.998418)
			(xy 126.99848 -195.950836) (xy 126.968491 -195.898896) (xy 126.945538 -195.843485) (xy 126.930014 -195.785552)
			(xy 126.922185 -195.726088) (xy 4.308094 -195.726088) (xy 4.308094 -198.543743) (xy 138.243774 -198.543743)
			(xy 138.24519 -198.489257) (xy 138.254343 -198.435528) (xy 138.271047 -198.383647) (xy 138.294963 -198.33467)
			(xy 138.325603 -198.289594) (xy 138.362344 -198.249336) (xy 138.40444 -198.214715) (xy 138.451033 -198.186434)
			(xy 138.501175 -198.165071) (xy 138.553847 -198.151058) (xy 138.607977 -198.144682) (xy 138.635232 -198.144892)
			(xy 138.636502 -198.144892) (xy 139.488672 -198.144892) (xy 139.515926 -198.145353) (xy 139.56988 -198.153107)
			(xy 139.622181 -198.168461) (xy 139.671765 -198.191102) (xy 139.717622 -198.220569) (xy 139.758818 -198.256263)
			(xy 139.794514 -198.297456) (xy 139.823985 -198.34331) (xy 139.846629 -198.392892) (xy 139.861987 -198.445192)
			(xy 139.869745 -198.499146) (xy 139.869745 -198.553654) (xy 139.861987 -198.607608) (xy 139.846629 -198.659908)
			(xy 139.823985 -198.70949) (xy 139.794514 -198.755344) (xy 139.758818 -198.796537) (xy 139.717622 -198.832231)
			(xy 139.671765 -198.861698) (xy 139.622181 -198.884339) (xy 139.56988 -198.899693) (xy 139.515926 -198.907447)
			(xy 139.488672 -198.907908) (xy 139.477343 -198.907862) (xy 139.454723 -198.90659) (xy 139.44346 -198.905368)
			(xy 139.440412 -198.90486) (xy 138.672824 -198.90486) (xy 138.669776 -198.905368) (xy 138.642662 -198.908134)
			(xy 138.588177 -198.906693) (xy 138.534452 -198.897514) (xy 138.482579 -198.880785) (xy 138.433613 -198.856847)
			(xy 138.388552 -198.826185) (xy 138.348311 -198.789424) (xy 138.31371 -198.747312) (xy 138.285452 -198.700706)
			(xy 138.264112 -198.650554) (xy 138.250125 -198.597875) (xy 138.243774 -198.543743) (xy 4.308094 -198.543743)
			(xy 4.308094 -201.379368) (xy 98.428551 -201.379368) (xy 98.428551 -201.324832) (xy 98.436313 -201.270851)
			(xy 98.451678 -201.218525) (xy 98.474333 -201.168917) (xy 98.503818 -201.123039) (xy 98.539531 -201.081824)
			(xy 98.580747 -201.046112) (xy 98.626626 -201.016628) (xy 98.676234 -200.993974) (xy 98.728561 -200.978611)
			(xy 98.782542 -200.970851) (xy 98.80981 -200.970388) (xy 99.67341 -200.970388) (xy 99.700682 -200.970775)
			(xy 99.754672 -200.978539) (xy 99.807007 -200.993907) (xy 99.856623 -201.016567) (xy 99.902508 -201.046057)
			(xy 99.94373 -201.081777) (xy 99.979449 -201.123) (xy 100.008938 -201.168886) (xy 100.031596 -201.218502)
			(xy 100.046963 -201.270838) (xy 100.054725 -201.324828) (xy 100.054725 -201.379372) (xy 100.046963 -201.433362)
			(xy 100.031596 -201.485698) (xy 100.008938 -201.535314) (xy 99.979449 -201.5812) (xy 99.94373 -201.622423)
			(xy 99.902508 -201.658143) (xy 99.856623 -201.687633) (xy 99.807007 -201.710293) (xy 99.754672 -201.725661)
			(xy 99.700682 -201.733425) (xy 99.67341 -201.733912) (xy 98.80981 -201.733912) (xy 98.782542 -201.733349)
			(xy 98.728561 -201.725589) (xy 98.676234 -201.710226) (xy 98.626626 -201.687572) (xy 98.580747 -201.658088)
			(xy 98.539531 -201.622376) (xy 98.503818 -201.581161) (xy 98.474333 -201.535283) (xy 98.451678 -201.485675)
			(xy 98.436313 -201.433349) (xy 98.428551 -201.379368) (xy 4.308094 -201.379368) (xy 4.308094 -209.380836)
			(xy 445.288416 -209.380836) (xy 445.288416 -208.517236) (xy 445.288906 -208.487268) (xy 445.296729 -208.427846)
			(xy 445.312242 -208.369953) (xy 445.335178 -208.31458) (xy 445.365145 -208.262674) (xy 445.401632 -208.215124)
			(xy 445.444012 -208.172744) (xy 445.491562 -208.136257) (xy 445.543468 -208.10629) (xy 445.598841 -208.083354)
			(xy 445.656734 -208.067841) (xy 445.716156 -208.060018) (xy 445.776092 -208.060018) (xy 445.835514 -208.067841)
			(xy 445.893407 -208.083354) (xy 445.94878 -208.10629) (xy 446.000686 -208.136257) (xy 446.048236 -208.172744)
			(xy 446.090616 -208.215124) (xy 446.127103 -208.262674) (xy 446.15707 -208.31458) (xy 446.180006 -208.369953)
			(xy 446.195519 -208.427846) (xy 446.203342 -208.487268) (xy 446.203832 -208.517236) (xy 446.203832 -209.380836)
			(xy 446.203342 -209.410804) (xy 446.195519 -209.470226) (xy 446.180006 -209.528119) (xy 446.15707 -209.583492)
			(xy 446.127103 -209.635398) (xy 446.090616 -209.682948) (xy 446.048236 -209.725328) (xy 446.000686 -209.761815)
			(xy 445.94878 -209.791782) (xy 445.893407 -209.814718) (xy 445.835514 -209.830231) (xy 445.776092 -209.838054)
			(xy 445.716156 -209.838054) (xy 445.656734 -209.830231) (xy 445.598841 -209.814718) (xy 445.543468 -209.791782)
			(xy 445.491562 -209.761815) (xy 445.444012 -209.725328) (xy 445.401632 -209.682948) (xy 445.365145 -209.635398)
			(xy 445.335178 -209.583492) (xy 445.312242 -209.528119) (xy 445.296729 -209.470226) (xy 445.288906 -209.410804)
			(xy 445.288416 -209.380836) (xy 4.308094 -209.380836) (xy 4.308094 -225.261473) (xy 239.822113 -225.261473)
			(xy 239.822113 -225.201527) (xy 239.829938 -225.142093) (xy 239.845454 -225.084189) (xy 239.868395 -225.028806)
			(xy 239.89837 -224.976891) (xy 239.934864 -224.929333) (xy 239.977254 -224.886945) (xy 240.024814 -224.850454)
			(xy 240.076731 -224.820483) (xy 240.132115 -224.797545) (xy 240.19002 -224.782032) (xy 240.249455 -224.774211)
			(xy 240.279428 -224.773744) (xy 241.143028 -224.773744) (xy 241.172991 -224.774332) (xy 241.232405 -224.782157)
			(xy 241.290289 -224.79767) (xy 241.345653 -224.820606) (xy 241.39755 -224.850571) (xy 241.445091 -224.887054)
			(xy 241.487465 -224.92943) (xy 241.523944 -224.976974) (xy 241.553907 -225.028872) (xy 241.576839 -225.084238)
			(xy 241.592348 -225.142123) (xy 241.60017 -225.201537) (xy 241.60017 -225.261463) (xy 241.592348 -225.320877)
			(xy 241.576839 -225.378762) (xy 241.553907 -225.434128) (xy 241.523944 -225.486026) (xy 241.487465 -225.53357)
			(xy 241.445091 -225.575946) (xy 241.39755 -225.612429) (xy 241.345653 -225.642394) (xy 241.290289 -225.66533)
			(xy 241.232405 -225.680843) (xy 241.172991 -225.688668) (xy 241.143028 -225.68916) (xy 240.279428 -225.68916)
			(xy 240.249455 -225.688789) (xy 240.19002 -225.680968) (xy 240.132115 -225.665455) (xy 240.076731 -225.642517)
			(xy 240.024814 -225.612546) (xy 239.977254 -225.576055) (xy 239.934864 -225.533667) (xy 239.89837 -225.486109)
			(xy 239.868395 -225.434194) (xy 239.845454 -225.378811) (xy 239.829938 -225.320907) (xy 239.822113 -225.261473)
			(xy 4.308094 -225.261473) (xy 4.308094 -230.903589) (xy 383.216061 -230.903589) (xy 383.216061 -230.843611)
			(xy 383.22389 -230.784147) (xy 383.239413 -230.726213) (xy 383.262366 -230.670801) (xy 383.292355 -230.618858)
			(xy 383.328867 -230.571275) (xy 383.371278 -230.528865) (xy 383.418862 -230.492353) (xy 383.470804 -230.462364)
			(xy 383.526216 -230.439412) (xy 383.584151 -230.423889) (xy 383.643615 -230.416061) (xy 383.673604 -230.415592)
			(xy 384.537204 -230.415592) (xy 384.567185 -230.416174) (xy 384.626634 -230.424001) (xy 384.684553 -230.439521)
			(xy 384.739951 -230.462468) (xy 384.79188 -230.492449) (xy 384.839451 -230.528952) (xy 384.88185 -230.571352)
			(xy 384.918353 -230.618924) (xy 384.948334 -230.670853) (xy 384.97128 -230.726251) (xy 384.986799 -230.78417)
			(xy 384.994626 -230.843619) (xy 384.994626 -230.903581) (xy 384.986799 -230.96303) (xy 384.97128 -231.020949)
			(xy 384.948334 -231.076347) (xy 384.918353 -231.128276) (xy 384.88185 -231.175848) (xy 384.839451 -231.218248)
			(xy 384.79188 -231.254751) (xy 384.739951 -231.284732) (xy 384.684553 -231.307679) (xy 384.626634 -231.323199)
			(xy 384.567185 -231.331026) (xy 384.537204 -231.331516) (xy 383.673604 -231.331516) (xy 383.643615 -231.331139)
			(xy 383.584151 -231.323311) (xy 383.526216 -231.307788) (xy 383.470804 -231.284836) (xy 383.418862 -231.254847)
			(xy 383.371278 -231.218335) (xy 383.328867 -231.175925) (xy 383.292355 -231.128342) (xy 383.262366 -231.076399)
			(xy 383.239413 -231.020987) (xy 383.22389 -230.963053) (xy 383.216061 -230.903589) (xy 4.308094 -230.903589)
			(xy 4.308094 -234.655869) (xy 448.021157 -234.655869) (xy 448.021157 -234.595931) (xy 448.028981 -234.536505)
			(xy 448.044494 -234.478608) (xy 448.067432 -234.423232) (xy 448.097401 -234.371324) (xy 448.13389 -234.323771)
			(xy 448.176273 -234.281388) (xy 448.223825 -234.2449) (xy 448.275734 -234.214931) (xy 448.33111 -234.191993)
			(xy 448.389007 -234.17648) (xy 448.448433 -234.168657) (xy 448.478402 -234.168188) (xy 449.342002 -234.168188)
			(xy 449.371969 -234.168686) (xy 449.431391 -234.176509) (xy 449.489283 -234.192022) (xy 449.544656 -234.214958)
			(xy 449.596561 -234.244925) (xy 449.64411 -234.281411) (xy 449.68649 -234.323792) (xy 449.722976 -234.371341)
			(xy 449.752943 -234.423246) (xy 449.775879 -234.478618) (xy 449.791391 -234.536511) (xy 449.799214 -234.595933)
			(xy 449.799214 -234.655867) (xy 449.791391 -234.715289) (xy 449.775879 -234.773182) (xy 449.752943 -234.828554)
			(xy 449.722976 -234.880459) (xy 449.68649 -234.928008) (xy 449.64411 -234.970389) (xy 449.596561 -235.006875)
			(xy 449.544656 -235.036842) (xy 449.489283 -235.059778) (xy 449.431391 -235.075291) (xy 449.371969 -235.083114)
			(xy 449.342002 -235.083604) (xy 448.478402 -235.083604) (xy 448.448433 -235.083143) (xy 448.389007 -235.07532)
			(xy 448.33111 -235.059807) (xy 448.275734 -235.036869) (xy 448.223825 -235.0069) (xy 448.176273 -234.970412)
			(xy 448.13389 -234.928029) (xy 448.097401 -234.880476) (xy 448.067432 -234.828568) (xy 448.044494 -234.773192)
			(xy 448.028981 -234.715295) (xy 448.021157 -234.655869) (xy 4.308094 -234.655869) (xy 4.308094 -239.07907)
			(xy 153.398934 -239.07907) (xy 153.398934 -239.01913) (xy 153.406758 -238.959703) (xy 153.422271 -238.901805)
			(xy 153.445208 -238.846427) (xy 153.475178 -238.794517) (xy 153.511666 -238.746963) (xy 153.554049 -238.704578)
			(xy 153.601602 -238.668088) (xy 153.653511 -238.638116) (xy 153.708888 -238.615177) (xy 153.766785 -238.599661)
			(xy 153.826212 -238.591835) (xy 153.856182 -238.591344) (xy 154.719782 -238.591344) (xy 154.749749 -238.591908)
			(xy 154.809169 -238.599729) (xy 154.867061 -238.615239) (xy 154.922433 -238.638172) (xy 154.974337 -238.668138)
			(xy 155.021886 -238.704622) (xy 155.064267 -238.747) (xy 155.100752 -238.794548) (xy 155.13072 -238.846451)
			(xy 155.153656 -238.901822) (xy 155.169168 -238.959713) (xy 155.176991 -239.019133) (xy 155.176991 -239.079067)
			(xy 155.169168 -239.138487) (xy 155.153656 -239.196378) (xy 155.13072 -239.251749) (xy 155.100752 -239.303652)
			(xy 155.064267 -239.3512) (xy 155.021886 -239.393578) (xy 154.974337 -239.430062) (xy 154.922433 -239.460028)
			(xy 154.867061 -239.482961) (xy 154.809169 -239.498471) (xy 154.749749 -239.506292) (xy 154.719782 -239.50676)
			(xy 153.856182 -239.50676) (xy 153.826212 -239.506365) (xy 153.766785 -239.498539) (xy 153.708888 -239.483023)
			(xy 153.653511 -239.460084) (xy 153.601602 -239.430112) (xy 153.554049 -239.393622) (xy 153.511666 -239.351237)
			(xy 153.475178 -239.303683) (xy 153.445208 -239.251773) (xy 153.422271 -239.196395) (xy 153.406758 -239.138497)
			(xy 153.398934 -239.07907) (xy 4.308094 -239.07907) (xy 4.308094 -241.031522) (xy 4.307605 -241.10188)
			(xy 4.299704 -241.242374) (xy 4.283937 -241.382205) (xy 4.260354 -241.52093) (xy 4.229028 -241.658116)
			(xy 4.190059 -241.793328) (xy 4.143568 -241.926143) (xy 4.089703 -242.056141) (xy 4.028633 -242.182915)
			(xy 3.960549 -242.306064) (xy 3.885667 -242.425201) (xy 3.804222 -242.539952) (xy 3.71647 -242.649955)
			(xy 3.622687 -242.754863) (xy 3.573272 -242.80495) (xy 0.94488 -245.433342) (xy 0.907568 -245.471336)
			(xy 0.837834 -245.55183) (xy 0.774017 -245.637091) (xy 0.716442 -245.726686) (xy 0.665403 -245.820159)
			(xy 0.62116 -245.917033) (xy 0.583936 -246.016815) (xy 0.553923 -246.118998) (xy 0.531273 -246.223061)
			(xy 0.5161 -246.328474) (xy 0.508483 -246.4347) (xy 0.508 -246.48795) (xy 0.508 -270.89989) (xy 26.882353 -270.89989)
			(xy 26.886342 -270.75135) (xy 26.898299 -270.603237) (xy 26.918189 -270.45598) (xy 26.945954 -270.310004)
			(xy 26.981515 -270.165727) (xy 27.024769 -270.023568) (xy 27.075591 -269.883935) (xy 27.133835 -269.747232)
			(xy 27.199333 -269.613852) (xy 27.271896 -269.48418) (xy 27.351314 -269.35859) (xy 27.437359 -269.237443)
			(xy 27.529783 -269.12109) (xy 27.628319 -269.009866) (xy 27.732683 -268.904091) (xy 27.842575 -268.804071)
			(xy 27.957676 -268.710093) (xy 28.077656 -268.622429) (xy 28.202169 -268.541332) (xy 28.330855 -268.467035)
			(xy 28.463344 -268.399753) (xy 28.599253 -268.339679) (xy 28.738191 -268.286987) (xy 28.879757 -268.241828)
			(xy 29.023543 -268.204333) (xy 29.169134 -268.174611) (xy 29.31611 -268.152746) (xy 29.464049 -268.138802)
			(xy 29.612522 -268.132818) (xy 29.761103 -268.134813) (xy 29.909362 -268.144781) (xy 30.056873 -268.162692)
			(xy 30.203209 -268.188495) (xy 30.34795 -268.222115) (xy 30.490677 -268.263457) (xy 30.63098 -268.3124)
			(xy 30.768453 -268.368803) (xy 30.9027 -268.432504) (xy 31.033335 -268.50332) (xy 31.15998 -268.581045)
			(xy 31.28227 -268.665456) (xy 31.399853 -268.756309) (xy 31.51239 -268.853343) (xy 31.619557 -268.956278)
			(xy 31.721044 -269.064817) (xy 31.816558 -269.178646) (xy 31.905825 -269.297439) (xy 31.988586 -269.420851)
			(xy 32.064604 -269.548529) (xy 32.133659 -269.680102) (xy 32.195552 -269.815193) (xy 32.250105 -269.95341)
			(xy 32.29716 -270.094357) (xy 32.336582 -270.237627) (xy 32.368256 -270.382806) (xy 32.392092 -270.529475)
			(xy 32.408021 -270.677213) (xy 32.415997 -270.825593) (xy 32.416496 -270.89989) (xy 86.882487 -270.89989)
			(xy 86.886476 -270.75135) (xy 86.898433 -270.603237) (xy 86.918323 -270.45598) (xy 86.946088 -270.310004)
			(xy 86.981649 -270.165727) (xy 87.024903 -270.023568) (xy 87.075725 -269.883935) (xy 87.133969 -269.747232)
			(xy 87.199467 -269.613852) (xy 87.27203 -269.48418) (xy 87.351448 -269.35859) (xy 87.437493 -269.237443)
			(xy 87.529917 -269.12109) (xy 87.628453 -269.009866) (xy 87.732817 -268.904091) (xy 87.842709 -268.804071)
			(xy 87.95781 -268.710093) (xy 88.07779 -268.622429) (xy 88.202303 -268.541332) (xy 88.330989 -268.467035)
			(xy 88.463478 -268.399753) (xy 88.599387 -268.339679) (xy 88.738325 -268.286987) (xy 88.879891 -268.241828)
			(xy 89.023677 -268.204333) (xy 89.169268 -268.174611) (xy 89.316244 -268.152746) (xy 89.464183 -268.138802)
			(xy 89.612656 -268.132818) (xy 89.761237 -268.134813) (xy 89.909496 -268.144781) (xy 90.057007 -268.162692)
			(xy 90.203343 -268.188495) (xy 90.348084 -268.222115) (xy 90.490811 -268.263457) (xy 90.631114 -268.3124)
			(xy 90.768587 -268.368803) (xy 90.902834 -268.432504) (xy 91.033469 -268.50332) (xy 91.160114 -268.581045)
			(xy 91.282404 -268.665456) (xy 91.399987 -268.756309) (xy 91.512524 -268.853343) (xy 91.619691 -268.956278)
			(xy 91.721178 -269.064817) (xy 91.816692 -269.178646) (xy 91.905959 -269.297439) (xy 91.98872 -269.420851)
			(xy 92.064738 -269.548529) (xy 92.133793 -269.680102) (xy 92.195686 -269.815193) (xy 92.250239 -269.95341)
			(xy 92.297294 -270.094357) (xy 92.336716 -270.237627) (xy 92.36839 -270.382806) (xy 92.392226 -270.529475)
			(xy 92.408155 -270.677213) (xy 92.416131 -270.825593) (xy 92.41663 -270.89989) (xy 142.982451 -270.89989)
			(xy 142.98644 -270.75135) (xy 142.998397 -270.603237) (xy 143.018287 -270.45598) (xy 143.046052 -270.310004)
			(xy 143.081613 -270.165727) (xy 143.124867 -270.023568) (xy 143.175689 -269.883935) (xy 143.233933 -269.747232)
			(xy 143.299431 -269.613852) (xy 143.371994 -269.48418) (xy 143.451412 -269.35859) (xy 143.537457 -269.237443)
			(xy 143.629881 -269.12109) (xy 143.728417 -269.009866) (xy 143.832781 -268.904091) (xy 143.942673 -268.804071)
			(xy 144.057774 -268.710093) (xy 144.177754 -268.622429) (xy 144.302267 -268.541332) (xy 144.430953 -268.467035)
			(xy 144.563442 -268.399753) (xy 144.699351 -268.339679) (xy 144.838289 -268.286987) (xy 144.979855 -268.241828)
			(xy 145.123641 -268.204333) (xy 145.269232 -268.174611) (xy 145.416208 -268.152746) (xy 145.564147 -268.138802)
			(xy 145.71262 -268.132818) (xy 145.861201 -268.134813) (xy 146.00946 -268.144781) (xy 146.156971 -268.162692)
			(xy 146.303307 -268.188495) (xy 146.448048 -268.222115) (xy 146.590775 -268.263457) (xy 146.731078 -268.3124)
			(xy 146.868551 -268.368803) (xy 147.002798 -268.432504) (xy 147.133433 -268.50332) (xy 147.260078 -268.581045)
			(xy 147.382368 -268.665456) (xy 147.499951 -268.756309) (xy 147.612488 -268.853343) (xy 147.719655 -268.956278)
			(xy 147.821142 -269.064817) (xy 147.916656 -269.178646) (xy 148.005923 -269.297439) (xy 148.088684 -269.420851)
			(xy 148.164702 -269.548529) (xy 148.233757 -269.680102) (xy 148.29565 -269.815193) (xy 148.350203 -269.95341)
			(xy 148.397258 -270.094357) (xy 148.43668 -270.237627) (xy 148.468354 -270.382806) (xy 148.49219 -270.529475)
			(xy 148.508119 -270.677213) (xy 148.516095 -270.825593) (xy 148.516594 -270.89989) (xy 202.982331 -270.89989)
			(xy 202.98632 -270.75135) (xy 202.998277 -270.603237) (xy 203.018167 -270.45598) (xy 203.045932 -270.310004)
			(xy 203.081493 -270.165727) (xy 203.124747 -270.023568) (xy 203.175569 -269.883935) (xy 203.233813 -269.747232)
			(xy 203.299311 -269.613852) (xy 203.371874 -269.48418) (xy 203.451292 -269.35859) (xy 203.537337 -269.237443)
			(xy 203.629761 -269.12109) (xy 203.728297 -269.009866) (xy 203.832661 -268.904091) (xy 203.942553 -268.804071)
			(xy 204.057654 -268.710093) (xy 204.177634 -268.622429) (xy 204.302147 -268.541332) (xy 204.430833 -268.467035)
			(xy 204.563322 -268.399753) (xy 204.699231 -268.339679) (xy 204.838169 -268.286987) (xy 204.979735 -268.241828)
			(xy 205.123521 -268.204333) (xy 205.269112 -268.174611) (xy 205.416088 -268.152746) (xy 205.564027 -268.138802)
			(xy 205.7125 -268.132818) (xy 205.861081 -268.134813) (xy 206.00934 -268.144781) (xy 206.156851 -268.162692)
			(xy 206.303187 -268.188495) (xy 206.447928 -268.222115) (xy 206.590655 -268.263457) (xy 206.730958 -268.3124)
			(xy 206.868431 -268.368803) (xy 207.002678 -268.432504) (xy 207.133313 -268.50332) (xy 207.259958 -268.581045)
			(xy 207.382248 -268.665456) (xy 207.499831 -268.756309) (xy 207.612368 -268.853343) (xy 207.719535 -268.956278)
			(xy 207.821022 -269.064817) (xy 207.916536 -269.178646) (xy 208.005803 -269.297439) (xy 208.088564 -269.420851)
			(xy 208.164582 -269.548529) (xy 208.233637 -269.680102) (xy 208.29553 -269.815193) (xy 208.350083 -269.95341)
			(xy 208.397138 -270.094357) (xy 208.43656 -270.237627) (xy 208.468234 -270.382806) (xy 208.49207 -270.529475)
			(xy 208.507999 -270.677213) (xy 208.515975 -270.825593) (xy 208.516474 -270.89989) (xy 259.082549 -270.89989)
			(xy 259.086538 -270.75135) (xy 259.098495 -270.603237) (xy 259.118385 -270.45598) (xy 259.14615 -270.310004)
			(xy 259.181711 -270.165727) (xy 259.224965 -270.023568) (xy 259.275787 -269.883935) (xy 259.334031 -269.747232)
			(xy 259.399529 -269.613852) (xy 259.472092 -269.48418) (xy 259.55151 -269.35859) (xy 259.637555 -269.237443)
			(xy 259.729979 -269.12109) (xy 259.828515 -269.009866) (xy 259.932879 -268.904091) (xy 260.042771 -268.804071)
			(xy 260.157872 -268.710093) (xy 260.277852 -268.622429) (xy 260.402365 -268.541332) (xy 260.531051 -268.467035)
			(xy 260.66354 -268.399753) (xy 260.799449 -268.339679) (xy 260.938387 -268.286987) (xy 261.079953 -268.241828)
			(xy 261.223739 -268.204333) (xy 261.36933 -268.174611) (xy 261.516306 -268.152746) (xy 261.664245 -268.138802)
			(xy 261.812718 -268.132818) (xy 261.961299 -268.134813) (xy 262.109558 -268.144781) (xy 262.257069 -268.162692)
			(xy 262.403405 -268.188495) (xy 262.548146 -268.222115) (xy 262.690873 -268.263457) (xy 262.831176 -268.3124)
			(xy 262.968649 -268.368803) (xy 263.102896 -268.432504) (xy 263.233531 -268.50332) (xy 263.360176 -268.581045)
			(xy 263.482466 -268.665456) (xy 263.600049 -268.756309) (xy 263.712586 -268.853343) (xy 263.819753 -268.956278)
			(xy 263.92124 -269.064817) (xy 264.016754 -269.178646) (xy 264.106021 -269.297439) (xy 264.188782 -269.420851)
			(xy 264.2648 -269.548529) (xy 264.333855 -269.680102) (xy 264.395748 -269.815193) (xy 264.450301 -269.95341)
			(xy 264.497356 -270.094357) (xy 264.536778 -270.237627) (xy 264.568452 -270.382806) (xy 264.592288 -270.529475)
			(xy 264.608217 -270.677213) (xy 264.616193 -270.825593) (xy 264.616692 -270.89989) (xy 319.082429 -270.89989)
			(xy 319.086418 -270.75135) (xy 319.098375 -270.603237) (xy 319.118265 -270.45598) (xy 319.14603 -270.310004)
			(xy 319.181591 -270.165727) (xy 319.224845 -270.023568) (xy 319.275667 -269.883935) (xy 319.333911 -269.747232)
			(xy 319.399409 -269.613852) (xy 319.471972 -269.48418) (xy 319.55139 -269.35859) (xy 319.637435 -269.237443)
			(xy 319.729859 -269.12109) (xy 319.828395 -269.009866) (xy 319.932759 -268.904091) (xy 320.042651 -268.804071)
			(xy 320.157752 -268.710093) (xy 320.277732 -268.622429) (xy 320.402245 -268.541332) (xy 320.530931 -268.467035)
			(xy 320.66342 -268.399753) (xy 320.799329 -268.339679) (xy 320.938267 -268.286987) (xy 321.079833 -268.241828)
			(xy 321.223619 -268.204333) (xy 321.36921 -268.174611) (xy 321.516186 -268.152746) (xy 321.664125 -268.138802)
			(xy 321.812598 -268.132818) (xy 321.961179 -268.134813) (xy 322.109438 -268.144781) (xy 322.256949 -268.162692)
			(xy 322.403285 -268.188495) (xy 322.548026 -268.222115) (xy 322.690753 -268.263457) (xy 322.831056 -268.3124)
			(xy 322.968529 -268.368803) (xy 323.102776 -268.432504) (xy 323.233411 -268.50332) (xy 323.360056 -268.581045)
			(xy 323.482346 -268.665456) (xy 323.599929 -268.756309) (xy 323.712466 -268.853343) (xy 323.819633 -268.956278)
			(xy 323.92112 -269.064817) (xy 324.016634 -269.178646) (xy 324.105901 -269.297439) (xy 324.188662 -269.420851)
			(xy 324.26468 -269.548529) (xy 324.333735 -269.680102) (xy 324.395628 -269.815193) (xy 324.450181 -269.95341)
			(xy 324.497236 -270.094357) (xy 324.536658 -270.237627) (xy 324.568332 -270.382806) (xy 324.592168 -270.529475)
			(xy 324.608097 -270.677213) (xy 324.616073 -270.825593) (xy 324.616572 -270.89989) (xy 375.182393 -270.89989)
			(xy 375.186382 -270.75135) (xy 375.198339 -270.603237) (xy 375.218229 -270.45598) (xy 375.245994 -270.310004)
			(xy 375.281555 -270.165727) (xy 375.324809 -270.023568) (xy 375.375631 -269.883935) (xy 375.433875 -269.747232)
			(xy 375.499373 -269.613852) (xy 375.571936 -269.48418) (xy 375.651354 -269.35859) (xy 375.737399 -269.237443)
			(xy 375.829823 -269.12109) (xy 375.928359 -269.009866) (xy 376.032723 -268.904091) (xy 376.142615 -268.804071)
			(xy 376.257716 -268.710093) (xy 376.377696 -268.622429) (xy 376.502209 -268.541332) (xy 376.630895 -268.467035)
			(xy 376.763384 -268.399753) (xy 376.899293 -268.339679) (xy 377.038231 -268.286987) (xy 377.179797 -268.241828)
			(xy 377.323583 -268.204333) (xy 377.469174 -268.174611) (xy 377.61615 -268.152746) (xy 377.764089 -268.138802)
			(xy 377.912562 -268.132818) (xy 378.061143 -268.134813) (xy 378.209402 -268.144781) (xy 378.356913 -268.162692)
			(xy 378.503249 -268.188495) (xy 378.64799 -268.222115) (xy 378.790717 -268.263457) (xy 378.93102 -268.3124)
			(xy 379.068493 -268.368803) (xy 379.20274 -268.432504) (xy 379.333375 -268.50332) (xy 379.46002 -268.581045)
			(xy 379.58231 -268.665456) (xy 379.699893 -268.756309) (xy 379.81243 -268.853343) (xy 379.919597 -268.956278)
			(xy 380.021084 -269.064817) (xy 380.116598 -269.178646) (xy 380.205865 -269.297439) (xy 380.288626 -269.420851)
			(xy 380.364644 -269.548529) (xy 380.433699 -269.680102) (xy 380.495592 -269.815193) (xy 380.550145 -269.95341)
			(xy 380.5972 -270.094357) (xy 380.636622 -270.237627) (xy 380.668296 -270.382806) (xy 380.692132 -270.529475)
			(xy 380.708061 -270.677213) (xy 380.716037 -270.825593) (xy 380.716536 -270.89989) (xy 435.182527 -270.89989)
			(xy 435.186516 -270.75135) (xy 435.198473 -270.603237) (xy 435.218363 -270.45598) (xy 435.246128 -270.310004)
			(xy 435.281689 -270.165727) (xy 435.324943 -270.023568) (xy 435.375765 -269.883935) (xy 435.434009 -269.747232)
			(xy 435.499507 -269.613852) (xy 435.57207 -269.48418) (xy 435.651488 -269.35859) (xy 435.737533 -269.237443)
			(xy 435.829957 -269.12109) (xy 435.928493 -269.009866) (xy 436.032857 -268.904091) (xy 436.142749 -268.804071)
			(xy 436.25785 -268.710093) (xy 436.37783 -268.622429) (xy 436.502343 -268.541332) (xy 436.631029 -268.467035)
			(xy 436.763518 -268.399753) (xy 436.899427 -268.339679) (xy 437.038365 -268.286987) (xy 437.179931 -268.241828)
			(xy 437.323717 -268.204333) (xy 437.469308 -268.174611) (xy 437.616284 -268.152746) (xy 437.764223 -268.138802)
			(xy 437.912696 -268.132818) (xy 438.061277 -268.134813) (xy 438.209536 -268.144781) (xy 438.357047 -268.162692)
			(xy 438.503383 -268.188495) (xy 438.648124 -268.222115) (xy 438.790851 -268.263457) (xy 438.931154 -268.3124)
			(xy 439.068627 -268.368803) (xy 439.202874 -268.432504) (xy 439.333509 -268.50332) (xy 439.460154 -268.581045)
			(xy 439.582444 -268.665456) (xy 439.700027 -268.756309) (xy 439.812564 -268.853343) (xy 439.919731 -268.956278)
			(xy 440.021218 -269.064817) (xy 440.116732 -269.178646) (xy 440.205999 -269.297439) (xy 440.28876 -269.420851)
			(xy 440.364778 -269.548529) (xy 440.433833 -269.680102) (xy 440.495726 -269.815193) (xy 440.550279 -269.95341)
			(xy 440.597334 -270.094357) (xy 440.636756 -270.237627) (xy 440.66843 -270.382806) (xy 440.692266 -270.529475)
			(xy 440.708195 -270.677213) (xy 440.716171 -270.825593) (xy 440.71667 -270.89989) (xy 440.716171 -270.974187)
			(xy 440.708195 -271.122567) (xy 440.692266 -271.270305) (xy 440.66843 -271.416974) (xy 440.636756 -271.562153)
			(xy 440.597334 -271.705423) (xy 440.550279 -271.84637) (xy 440.495726 -271.984587) (xy 440.433833 -272.119678)
			(xy 440.364778 -272.251251) (xy 440.28876 -272.378929) (xy 440.205999 -272.502341) (xy 440.116732 -272.621134)
			(xy 440.021218 -272.734963) (xy 439.919731 -272.843502) (xy 439.812564 -272.946437) (xy 439.700027 -273.043471)
			(xy 439.582444 -273.134324) (xy 439.460154 -273.218735) (xy 439.333509 -273.29646) (xy 439.202874 -273.367276)
			(xy 439.068627 -273.430977) (xy 438.931154 -273.48738) (xy 438.790851 -273.536323) (xy 438.648124 -273.577665)
			(xy 438.503383 -273.611285) (xy 438.357047 -273.637088) (xy 438.209536 -273.654999) (xy 438.061277 -273.664967)
			(xy 437.912696 -273.666962) (xy 437.764223 -273.660978) (xy 437.616284 -273.647034) (xy 437.469308 -273.625169)
			(xy 437.323717 -273.595447) (xy 437.179931 -273.557952) (xy 437.038365 -273.512793) (xy 436.899427 -273.460101)
			(xy 436.763518 -273.400027) (xy 436.631029 -273.332745) (xy 436.502343 -273.258448) (xy 436.37783 -273.177351)
			(xy 436.25785 -273.089687) (xy 436.142749 -272.995709) (xy 436.032857 -272.895689) (xy 435.928493 -272.789914)
			(xy 435.829957 -272.67869) (xy 435.737533 -272.562337) (xy 435.651488 -272.44119) (xy 435.57207 -272.3156)
			(xy 435.499507 -272.185928) (xy 435.434009 -272.052548) (xy 435.375765 -271.915845) (xy 435.324943 -271.776212)
			(xy 435.281689 -271.634053) (xy 435.246128 -271.489776) (xy 435.218363 -271.3438) (xy 435.198473 -271.196543)
			(xy 435.186516 -271.04843) (xy 435.182527 -270.89989) (xy 380.716536 -270.89989) (xy 380.716037 -270.974187)
			(xy 380.708061 -271.122567) (xy 380.692132 -271.270305) (xy 380.668296 -271.416974) (xy 380.636622 -271.562153)
			(xy 380.5972 -271.705423) (xy 380.550145 -271.84637) (xy 380.495592 -271.984587) (xy 380.433699 -272.119678)
			(xy 380.364644 -272.251251) (xy 380.288626 -272.378929) (xy 380.205865 -272.502341) (xy 380.116598 -272.621134)
			(xy 380.021084 -272.734963) (xy 379.919597 -272.843502) (xy 379.81243 -272.946437) (xy 379.699893 -273.043471)
			(xy 379.627012 -273.099784) (xy 392.443982 -273.099784) (xy 392.447942 -273.05073) (xy 392.459719 -273.002946)
			(xy 392.47901 -272.95767) (xy 392.505313 -272.916074) (xy 392.537948 -272.879237) (xy 392.576069 -272.848112)
			(xy 392.61869 -272.823505) (xy 392.664706 -272.806053) (xy 392.712925 -272.796209) (xy 392.7621 -272.794228)
			(xy 392.810955 -272.80016) (xy 392.858226 -272.813852) (xy 392.902688 -272.83495) (xy 392.943191 -272.862906)
			(xy 392.978684 -272.896998) (xy 393.008249 -272.936342) (xy 393.03112 -272.979919) (xy 393.046704 -273.0266)
			(xy 393.054599 -273.075177) (xy 393.055094 -273.099784) (xy 394.344156 -273.099784) (xy 394.348116 -273.05073)
			(xy 394.359893 -273.002946) (xy 394.379184 -272.95767) (xy 394.405487 -272.916074) (xy 394.438122 -272.879237)
			(xy 394.476243 -272.848112) (xy 394.518864 -272.823505) (xy 394.56488 -272.806053) (xy 394.613099 -272.796209)
			(xy 394.662274 -272.794228) (xy 394.711129 -272.80016) (xy 394.7584 -272.813852) (xy 394.802862 -272.83495)
			(xy 394.843365 -272.862906) (xy 394.878858 -272.896998) (xy 394.908423 -272.936342) (xy 394.931294 -272.979919)
			(xy 394.946878 -273.0266) (xy 394.954773 -273.075177) (xy 394.955268 -273.099784) (xy 396.244076 -273.099784)
			(xy 396.248036 -273.05073) (xy 396.259813 -273.002946) (xy 396.279104 -272.95767) (xy 396.305407 -272.916074)
			(xy 396.338042 -272.879237) (xy 396.376163 -272.848112) (xy 396.418784 -272.823505) (xy 396.4648 -272.806053)
			(xy 396.513019 -272.796209) (xy 396.562194 -272.794228) (xy 396.611049 -272.80016) (xy 396.65832 -272.813852)
			(xy 396.702782 -272.83495) (xy 396.743285 -272.862906) (xy 396.778778 -272.896998) (xy 396.808343 -272.936342)
			(xy 396.831214 -272.979919) (xy 396.846798 -273.0266) (xy 396.854693 -273.075177) (xy 396.855188 -273.099784)
			(xy 398.143996 -273.099784) (xy 398.147956 -273.05073) (xy 398.159733 -273.002946) (xy 398.179024 -272.95767)
			(xy 398.205327 -272.916074) (xy 398.237962 -272.879237) (xy 398.276083 -272.848112) (xy 398.318704 -272.823505)
			(xy 398.36472 -272.806053) (xy 398.412939 -272.796209) (xy 398.462114 -272.794228) (xy 398.510969 -272.80016)
			(xy 398.55824 -272.813852) (xy 398.602702 -272.83495) (xy 398.643205 -272.862906) (xy 398.678698 -272.896998)
			(xy 398.708263 -272.936342) (xy 398.731134 -272.979919) (xy 398.746718 -273.0266) (xy 398.754613 -273.075177)
			(xy 398.755108 -273.099784) (xy 400.04417 -273.099784) (xy 400.04813 -273.05073) (xy 400.059907 -273.002946)
			(xy 400.079198 -272.95767) (xy 400.105501 -272.916074) (xy 400.138136 -272.879237) (xy 400.176257 -272.848112)
			(xy 400.218878 -272.823505) (xy 400.264894 -272.806053) (xy 400.313113 -272.796209) (xy 400.362288 -272.794228)
			(xy 400.411143 -272.80016) (xy 400.458414 -272.813852) (xy 400.502876 -272.83495) (xy 400.543379 -272.862906)
			(xy 400.578872 -272.896998) (xy 400.608437 -272.936342) (xy 400.631308 -272.979919) (xy 400.646892 -273.0266)
			(xy 400.654787 -273.075177) (xy 400.655282 -273.099784) (xy 401.94409 -273.099784) (xy 401.94805 -273.05073)
			(xy 401.959827 -273.002946) (xy 401.979118 -272.95767) (xy 402.005421 -272.916074) (xy 402.038056 -272.879237)
			(xy 402.076177 -272.848112) (xy 402.118798 -272.823505) (xy 402.164814 -272.806053) (xy 402.213033 -272.796209)
			(xy 402.262208 -272.794228) (xy 402.311063 -272.80016) (xy 402.358334 -272.813852) (xy 402.402796 -272.83495)
			(xy 402.443299 -272.862906) (xy 402.478792 -272.896998) (xy 402.508357 -272.936342) (xy 402.531228 -272.979919)
			(xy 402.546812 -273.0266) (xy 402.554707 -273.075177) (xy 402.555202 -273.099784) (xy 403.84401 -273.099784)
			(xy 403.84797 -273.05073) (xy 403.859747 -273.002946) (xy 403.879038 -272.95767) (xy 403.905341 -272.916074)
			(xy 403.937976 -272.879237) (xy 403.976097 -272.848112) (xy 404.018718 -272.823505) (xy 404.064734 -272.806053)
			(xy 404.112953 -272.796209) (xy 404.162128 -272.794228) (xy 404.210983 -272.80016) (xy 404.258254 -272.813852)
			(xy 404.302716 -272.83495) (xy 404.343219 -272.862906) (xy 404.378712 -272.896998) (xy 404.408277 -272.936342)
			(xy 404.431148 -272.979919) (xy 404.446732 -273.0266) (xy 404.454627 -273.075177) (xy 404.455122 -273.099784)
			(xy 405.744184 -273.099784) (xy 405.748144 -273.05073) (xy 405.759921 -273.002946) (xy 405.779212 -272.95767)
			(xy 405.805515 -272.916074) (xy 405.83815 -272.879237) (xy 405.876271 -272.848112) (xy 405.918892 -272.823505)
			(xy 405.964908 -272.806053) (xy 406.013127 -272.796209) (xy 406.062302 -272.794228) (xy 406.111157 -272.80016)
			(xy 406.158428 -272.813852) (xy 406.20289 -272.83495) (xy 406.243393 -272.862906) (xy 406.278886 -272.896998)
			(xy 406.308451 -272.936342) (xy 406.331322 -272.979919) (xy 406.346906 -273.0266) (xy 406.354801 -273.075177)
			(xy 406.355291 -273.09953) (xy 407.64385 -273.09953) (xy 407.64781 -273.050476) (xy 407.659587 -273.002692)
			(xy 407.678878 -272.957416) (xy 407.705181 -272.91582) (xy 407.737816 -272.878983) (xy 407.775937 -272.847858)
			(xy 407.818558 -272.823251) (xy 407.864574 -272.805799) (xy 407.912793 -272.795955) (xy 407.961968 -272.793974)
			(xy 408.010823 -272.799906) (xy 408.058094 -272.813598) (xy 408.102556 -272.834696) (xy 408.143059 -272.862652)
			(xy 408.178552 -272.896744) (xy 408.208117 -272.936088) (xy 408.230988 -272.979665) (xy 408.246572 -273.026346)
			(xy 408.254467 -273.074923) (xy 408.254962 -273.09953) (xy 408.254957 -273.099784) (xy 409.54377 -273.099784)
			(xy 409.54773 -273.05073) (xy 409.559507 -273.002946) (xy 409.578798 -272.95767) (xy 409.605101 -272.916074)
			(xy 409.637736 -272.879237) (xy 409.675857 -272.848112) (xy 409.718478 -272.823505) (xy 409.764494 -272.806053)
			(xy 409.812713 -272.796209) (xy 409.861888 -272.794228) (xy 409.910743 -272.80016) (xy 409.958014 -272.813852)
			(xy 410.002476 -272.83495) (xy 410.042979 -272.862906) (xy 410.078472 -272.896998) (xy 410.108037 -272.936342)
			(xy 410.130908 -272.979919) (xy 410.146492 -273.0266) (xy 410.154387 -273.075177) (xy 410.154882 -273.099784)
			(xy 411.443944 -273.099784) (xy 411.447904 -273.05073) (xy 411.459681 -273.002946) (xy 411.478972 -272.95767)
			(xy 411.505275 -272.916074) (xy 411.53791 -272.879237) (xy 411.576031 -272.848112) (xy 411.618652 -272.823505)
			(xy 411.664668 -272.806053) (xy 411.712887 -272.796209) (xy 411.762062 -272.794228) (xy 411.810917 -272.80016)
			(xy 411.858188 -272.813852) (xy 411.90265 -272.83495) (xy 411.943153 -272.862906) (xy 411.978646 -272.896998)
			(xy 412.008211 -272.936342) (xy 412.031082 -272.979919) (xy 412.046666 -273.0266) (xy 412.054561 -273.075177)
			(xy 412.055056 -273.099784) (xy 413.343864 -273.099784) (xy 413.347824 -273.05073) (xy 413.359601 -273.002946)
			(xy 413.378892 -272.95767) (xy 413.405195 -272.916074) (xy 413.43783 -272.879237) (xy 413.475951 -272.848112)
			(xy 413.518572 -272.823505) (xy 413.564588 -272.806053) (xy 413.612807 -272.796209) (xy 413.661982 -272.794228)
			(xy 413.710837 -272.80016) (xy 413.758108 -272.813852) (xy 413.80257 -272.83495) (xy 413.843073 -272.862906)
			(xy 413.878566 -272.896998) (xy 413.908131 -272.936342) (xy 413.931002 -272.979919) (xy 413.946586 -273.0266)
			(xy 413.954481 -273.075177) (xy 413.954976 -273.099784) (xy 415.243784 -273.099784) (xy 415.247744 -273.05073)
			(xy 415.259521 -273.002946) (xy 415.278812 -272.95767) (xy 415.305115 -272.916074) (xy 415.33775 -272.879237)
			(xy 415.375871 -272.848112) (xy 415.418492 -272.823505) (xy 415.464508 -272.806053) (xy 415.512727 -272.796209)
			(xy 415.561902 -272.794228) (xy 415.610757 -272.80016) (xy 415.658028 -272.813852) (xy 415.70249 -272.83495)
			(xy 415.742993 -272.862906) (xy 415.778486 -272.896998) (xy 415.808051 -272.936342) (xy 415.830922 -272.979919)
			(xy 415.846506 -273.0266) (xy 415.854401 -273.075177) (xy 415.854896 -273.099784) (xy 417.143958 -273.099784)
			(xy 417.147918 -273.05073) (xy 417.159695 -273.002946) (xy 417.178986 -272.95767) (xy 417.205289 -272.916074)
			(xy 417.237924 -272.879237) (xy 417.276045 -272.848112) (xy 417.318666 -272.823505) (xy 417.364682 -272.806053)
			(xy 417.412901 -272.796209) (xy 417.462076 -272.794228) (xy 417.510931 -272.80016) (xy 417.558202 -272.813852)
			(xy 417.602664 -272.83495) (xy 417.643167 -272.862906) (xy 417.67866 -272.896998) (xy 417.708225 -272.936342)
			(xy 417.731096 -272.979919) (xy 417.74668 -273.0266) (xy 417.754575 -273.075177) (xy 417.75507 -273.099784)
			(xy 419.043878 -273.099784) (xy 419.047838 -273.05073) (xy 419.059615 -273.002946) (xy 419.078906 -272.95767)
			(xy 419.105209 -272.916074) (xy 419.137844 -272.879237) (xy 419.175965 -272.848112) (xy 419.218586 -272.823505)
			(xy 419.264602 -272.806053) (xy 419.312821 -272.796209) (xy 419.361996 -272.794228) (xy 419.410851 -272.80016)
			(xy 419.458122 -272.813852) (xy 419.502584 -272.83495) (xy 419.543087 -272.862906) (xy 419.57858 -272.896998)
			(xy 419.608145 -272.936342) (xy 419.631016 -272.979919) (xy 419.6466 -273.0266) (xy 419.654495 -273.075177)
			(xy 419.65499 -273.099784) (xy 420.943798 -273.099784) (xy 420.947758 -273.05073) (xy 420.959535 -273.002946)
			(xy 420.978826 -272.95767) (xy 421.005129 -272.916074) (xy 421.037764 -272.879237) (xy 421.075885 -272.848112)
			(xy 421.118506 -272.823505) (xy 421.164522 -272.806053) (xy 421.212741 -272.796209) (xy 421.261916 -272.794228)
			(xy 421.310771 -272.80016) (xy 421.358042 -272.813852) (xy 421.402504 -272.83495) (xy 421.443007 -272.862906)
			(xy 421.4785 -272.896998) (xy 421.508065 -272.936342) (xy 421.530936 -272.979919) (xy 421.54652 -273.0266)
			(xy 421.554415 -273.075177) (xy 421.55491 -273.099784) (xy 422.843972 -273.099784) (xy 422.847932 -273.05073)
			(xy 422.859709 -273.002946) (xy 422.879 -272.95767) (xy 422.905303 -272.916074) (xy 422.937938 -272.879237)
			(xy 422.976059 -272.848112) (xy 423.01868 -272.823505) (xy 423.064696 -272.806053) (xy 423.112915 -272.796209)
			(xy 423.16209 -272.794228) (xy 423.210945 -272.80016) (xy 423.258216 -272.813852) (xy 423.302678 -272.83495)
			(xy 423.343181 -272.862906) (xy 423.378674 -272.896998) (xy 423.408239 -272.936342) (xy 423.43111 -272.979919)
			(xy 423.446694 -273.0266) (xy 423.454589 -273.075177) (xy 423.455084 -273.099784) (xy 424.743892 -273.099784)
			(xy 424.747852 -273.05073) (xy 424.759629 -273.002946) (xy 424.77892 -272.95767) (xy 424.805223 -272.916074)
			(xy 424.837858 -272.879237) (xy 424.875979 -272.848112) (xy 424.9186 -272.823505) (xy 424.964616 -272.806053)
			(xy 425.012835 -272.796209) (xy 425.06201 -272.794228) (xy 425.110865 -272.80016) (xy 425.158136 -272.813852)
			(xy 425.202598 -272.83495) (xy 425.243101 -272.862906) (xy 425.278594 -272.896998) (xy 425.308159 -272.936342)
			(xy 425.33103 -272.979919) (xy 425.346614 -273.0266) (xy 425.354509 -273.075177) (xy 425.355004 -273.099784)
			(xy 426.643812 -273.099784) (xy 426.647772 -273.05073) (xy 426.659549 -273.002946) (xy 426.67884 -272.95767)
			(xy 426.705143 -272.916074) (xy 426.737778 -272.879237) (xy 426.775899 -272.848112) (xy 426.81852 -272.823505)
			(xy 426.864536 -272.806053) (xy 426.912755 -272.796209) (xy 426.96193 -272.794228) (xy 427.010785 -272.80016)
			(xy 427.058056 -272.813852) (xy 427.102518 -272.83495) (xy 427.143021 -272.862906) (xy 427.178514 -272.896998)
			(xy 427.208079 -272.936342) (xy 427.23095 -272.979919) (xy 427.246534 -273.0266) (xy 427.254429 -273.075177)
			(xy 427.254924 -273.099784) (xy 428.543732 -273.099784) (xy 428.547692 -273.05073) (xy 428.559469 -273.002946)
			(xy 428.57876 -272.95767) (xy 428.605063 -272.916074) (xy 428.637698 -272.879237) (xy 428.675819 -272.848112)
			(xy 428.71844 -272.823505) (xy 428.764456 -272.806053) (xy 428.812675 -272.796209) (xy 428.86185 -272.794228)
			(xy 428.910705 -272.80016) (xy 428.957976 -272.813852) (xy 429.002438 -272.83495) (xy 429.042941 -272.862906)
			(xy 429.078434 -272.896998) (xy 429.107999 -272.936342) (xy 429.13087 -272.979919) (xy 429.146454 -273.0266)
			(xy 429.154349 -273.075177) (xy 429.154844 -273.099784) (xy 429.154349 -273.124391) (xy 429.146454 -273.172968)
			(xy 429.13087 -273.219649) (xy 429.107999 -273.263226) (xy 429.078434 -273.30257) (xy 429.042941 -273.336662)
			(xy 429.002438 -273.364618) (xy 428.957976 -273.385716) (xy 428.910705 -273.399408) (xy 428.86185 -273.40534)
			(xy 428.812675 -273.403359) (xy 428.764456 -273.393515) (xy 428.71844 -273.376063) (xy 428.675819 -273.351456)
			(xy 428.637698 -273.320331) (xy 428.605063 -273.283494) (xy 428.57876 -273.241898) (xy 428.559469 -273.196622)
			(xy 428.547692 -273.148838) (xy 428.543732 -273.099784) (xy 427.254924 -273.099784) (xy 427.254429 -273.124391)
			(xy 427.246534 -273.172968) (xy 427.23095 -273.219649) (xy 427.208079 -273.263226) (xy 427.178514 -273.30257)
			(xy 427.143021 -273.336662) (xy 427.102518 -273.364618) (xy 427.058056 -273.385716) (xy 427.010785 -273.399408)
			(xy 426.96193 -273.40534) (xy 426.912755 -273.403359) (xy 426.864536 -273.393515) (xy 426.81852 -273.376063)
			(xy 426.775899 -273.351456) (xy 426.737778 -273.320331) (xy 426.705143 -273.283494) (xy 426.67884 -273.241898)
			(xy 426.659549 -273.196622) (xy 426.647772 -273.148838) (xy 426.643812 -273.099784) (xy 425.355004 -273.099784)
			(xy 425.354509 -273.124391) (xy 425.346614 -273.172968) (xy 425.33103 -273.219649) (xy 425.308159 -273.263226)
			(xy 425.278594 -273.30257) (xy 425.243101 -273.336662) (xy 425.202598 -273.364618) (xy 425.158136 -273.385716)
			(xy 425.110865 -273.399408) (xy 425.06201 -273.40534) (xy 425.012835 -273.403359) (xy 424.964616 -273.393515)
			(xy 424.9186 -273.376063) (xy 424.875979 -273.351456) (xy 424.837858 -273.320331) (xy 424.805223 -273.283494)
			(xy 424.77892 -273.241898) (xy 424.759629 -273.196622) (xy 424.747852 -273.148838) (xy 424.743892 -273.099784)
			(xy 423.455084 -273.099784) (xy 423.454589 -273.124391) (xy 423.446694 -273.172968) (xy 423.43111 -273.219649)
			(xy 423.408239 -273.263226) (xy 423.378674 -273.30257) (xy 423.343181 -273.336662) (xy 423.302678 -273.364618)
			(xy 423.258216 -273.385716) (xy 423.210945 -273.399408) (xy 423.16209 -273.40534) (xy 423.112915 -273.403359)
			(xy 423.064696 -273.393515) (xy 423.01868 -273.376063) (xy 422.976059 -273.351456) (xy 422.937938 -273.320331)
			(xy 422.905303 -273.283494) (xy 422.879 -273.241898) (xy 422.859709 -273.196622) (xy 422.847932 -273.148838)
			(xy 422.843972 -273.099784) (xy 421.55491 -273.099784) (xy 421.554415 -273.124391) (xy 421.54652 -273.172968)
			(xy 421.530936 -273.219649) (xy 421.508065 -273.263226) (xy 421.4785 -273.30257) (xy 421.443007 -273.336662)
			(xy 421.402504 -273.364618) (xy 421.358042 -273.385716) (xy 421.310771 -273.399408) (xy 421.261916 -273.40534)
			(xy 421.212741 -273.403359) (xy 421.164522 -273.393515) (xy 421.118506 -273.376063) (xy 421.075885 -273.351456)
			(xy 421.037764 -273.320331) (xy 421.005129 -273.283494) (xy 420.978826 -273.241898) (xy 420.959535 -273.196622)
			(xy 420.947758 -273.148838) (xy 420.943798 -273.099784) (xy 419.65499 -273.099784) (xy 419.654495 -273.124391)
			(xy 419.6466 -273.172968) (xy 419.631016 -273.219649) (xy 419.608145 -273.263226) (xy 419.57858 -273.30257)
			(xy 419.543087 -273.336662) (xy 419.502584 -273.364618) (xy 419.458122 -273.385716) (xy 419.410851 -273.399408)
			(xy 419.361996 -273.40534) (xy 419.312821 -273.403359) (xy 419.264602 -273.393515) (xy 419.218586 -273.376063)
			(xy 419.175965 -273.351456) (xy 419.137844 -273.320331) (xy 419.105209 -273.283494) (xy 419.078906 -273.241898)
			(xy 419.059615 -273.196622) (xy 419.047838 -273.148838) (xy 419.043878 -273.099784) (xy 417.75507 -273.099784)
			(xy 417.754575 -273.124391) (xy 417.74668 -273.172968) (xy 417.731096 -273.219649) (xy 417.708225 -273.263226)
			(xy 417.67866 -273.30257) (xy 417.643167 -273.336662) (xy 417.602664 -273.364618) (xy 417.558202 -273.385716)
			(xy 417.510931 -273.399408) (xy 417.462076 -273.40534) (xy 417.412901 -273.403359) (xy 417.364682 -273.393515)
			(xy 417.318666 -273.376063) (xy 417.276045 -273.351456) (xy 417.237924 -273.320331) (xy 417.205289 -273.283494)
			(xy 417.178986 -273.241898) (xy 417.159695 -273.196622) (xy 417.147918 -273.148838) (xy 417.143958 -273.099784)
			(xy 415.854896 -273.099784) (xy 415.854401 -273.124391) (xy 415.846506 -273.172968) (xy 415.830922 -273.219649)
			(xy 415.808051 -273.263226) (xy 415.778486 -273.30257) (xy 415.742993 -273.336662) (xy 415.70249 -273.364618)
			(xy 415.658028 -273.385716) (xy 415.610757 -273.399408) (xy 415.561902 -273.40534) (xy 415.512727 -273.403359)
			(xy 415.464508 -273.393515) (xy 415.418492 -273.376063) (xy 415.375871 -273.351456) (xy 415.33775 -273.320331)
			(xy 415.305115 -273.283494) (xy 415.278812 -273.241898) (xy 415.259521 -273.196622) (xy 415.247744 -273.148838)
			(xy 415.243784 -273.099784) (xy 413.954976 -273.099784) (xy 413.954481 -273.124391) (xy 413.946586 -273.172968)
			(xy 413.931002 -273.219649) (xy 413.908131 -273.263226) (xy 413.878566 -273.30257) (xy 413.843073 -273.336662)
			(xy 413.80257 -273.364618) (xy 413.758108 -273.385716) (xy 413.710837 -273.399408) (xy 413.661982 -273.40534)
			(xy 413.612807 -273.403359) (xy 413.564588 -273.393515) (xy 413.518572 -273.376063) (xy 413.475951 -273.351456)
			(xy 413.43783 -273.320331) (xy 413.405195 -273.283494) (xy 413.378892 -273.241898) (xy 413.359601 -273.196622)
			(xy 413.347824 -273.148838) (xy 413.343864 -273.099784) (xy 412.055056 -273.099784) (xy 412.054561 -273.124391)
			(xy 412.046666 -273.172968) (xy 412.031082 -273.219649) (xy 412.008211 -273.263226) (xy 411.978646 -273.30257)
			(xy 411.943153 -273.336662) (xy 411.90265 -273.364618) (xy 411.858188 -273.385716) (xy 411.810917 -273.399408)
			(xy 411.762062 -273.40534) (xy 411.712887 -273.403359) (xy 411.664668 -273.393515) (xy 411.618652 -273.376063)
			(xy 411.576031 -273.351456) (xy 411.53791 -273.320331) (xy 411.505275 -273.283494) (xy 411.478972 -273.241898)
			(xy 411.459681 -273.196622) (xy 411.447904 -273.148838) (xy 411.443944 -273.099784) (xy 410.154882 -273.099784)
			(xy 410.154387 -273.124391) (xy 410.146492 -273.172968) (xy 410.130908 -273.219649) (xy 410.108037 -273.263226)
			(xy 410.078472 -273.30257) (xy 410.042979 -273.336662) (xy 410.002476 -273.364618) (xy 409.958014 -273.385716)
			(xy 409.910743 -273.399408) (xy 409.861888 -273.40534) (xy 409.812713 -273.403359) (xy 409.764494 -273.393515)
			(xy 409.718478 -273.376063) (xy 409.675857 -273.351456) (xy 409.637736 -273.320331) (xy 409.605101 -273.283494)
			(xy 409.578798 -273.241898) (xy 409.559507 -273.196622) (xy 409.54773 -273.148838) (xy 409.54377 -273.099784)
			(xy 408.254957 -273.099784) (xy 408.254467 -273.124137) (xy 408.246572 -273.172714) (xy 408.230988 -273.219395)
			(xy 408.208117 -273.262972) (xy 408.178552 -273.302316) (xy 408.143059 -273.336408) (xy 408.102556 -273.364364)
			(xy 408.058094 -273.385462) (xy 408.010823 -273.399154) (xy 407.961968 -273.405086) (xy 407.912793 -273.403105)
			(xy 407.864574 -273.393261) (xy 407.818558 -273.375809) (xy 407.775937 -273.351202) (xy 407.737816 -273.320077)
			(xy 407.705181 -273.28324) (xy 407.678878 -273.241644) (xy 407.659587 -273.196368) (xy 407.64781 -273.148584)
			(xy 407.64385 -273.09953) (xy 406.355291 -273.09953) (xy 406.355296 -273.099784) (xy 406.354801 -273.124391)
			(xy 406.346906 -273.172968) (xy 406.331322 -273.219649) (xy 406.308451 -273.263226) (xy 406.278886 -273.30257)
			(xy 406.243393 -273.336662) (xy 406.20289 -273.364618) (xy 406.158428 -273.385716) (xy 406.111157 -273.399408)
			(xy 406.062302 -273.40534) (xy 406.013127 -273.403359) (xy 405.964908 -273.393515) (xy 405.918892 -273.376063)
			(xy 405.876271 -273.351456) (xy 405.83815 -273.320331) (xy 405.805515 -273.283494) (xy 405.779212 -273.241898)
			(xy 405.759921 -273.196622) (xy 405.748144 -273.148838) (xy 405.744184 -273.099784) (xy 404.455122 -273.099784)
			(xy 404.454627 -273.124391) (xy 404.446732 -273.172968) (xy 404.431148 -273.219649) (xy 404.408277 -273.263226)
			(xy 404.378712 -273.30257) (xy 404.343219 -273.336662) (xy 404.302716 -273.364618) (xy 404.258254 -273.385716)
			(xy 404.210983 -273.399408) (xy 404.162128 -273.40534) (xy 404.112953 -273.403359) (xy 404.064734 -273.393515)
			(xy 404.018718 -273.376063) (xy 403.976097 -273.351456) (xy 403.937976 -273.320331) (xy 403.905341 -273.283494)
			(xy 403.879038 -273.241898) (xy 403.859747 -273.196622) (xy 403.84797 -273.148838) (xy 403.84401 -273.099784)
			(xy 402.555202 -273.099784) (xy 402.554707 -273.124391) (xy 402.546812 -273.172968) (xy 402.531228 -273.219649)
			(xy 402.508357 -273.263226) (xy 402.478792 -273.30257) (xy 402.443299 -273.336662) (xy 402.402796 -273.364618)
			(xy 402.358334 -273.385716) (xy 402.311063 -273.399408) (xy 402.262208 -273.40534) (xy 402.213033 -273.403359)
			(xy 402.164814 -273.393515) (xy 402.118798 -273.376063) (xy 402.076177 -273.351456) (xy 402.038056 -273.320331)
			(xy 402.005421 -273.283494) (xy 401.979118 -273.241898) (xy 401.959827 -273.196622) (xy 401.94805 -273.148838)
			(xy 401.94409 -273.099784) (xy 400.655282 -273.099784) (xy 400.654787 -273.124391) (xy 400.646892 -273.172968)
			(xy 400.631308 -273.219649) (xy 400.608437 -273.263226) (xy 400.578872 -273.30257) (xy 400.543379 -273.336662)
			(xy 400.502876 -273.364618) (xy 400.458414 -273.385716) (xy 400.411143 -273.399408) (xy 400.362288 -273.40534)
			(xy 400.313113 -273.403359) (xy 400.264894 -273.393515) (xy 400.218878 -273.376063) (xy 400.176257 -273.351456)
			(xy 400.138136 -273.320331) (xy 400.105501 -273.283494) (xy 400.079198 -273.241898) (xy 400.059907 -273.196622)
			(xy 400.04813 -273.148838) (xy 400.04417 -273.099784) (xy 398.755108 -273.099784) (xy 398.754613 -273.124391)
			(xy 398.746718 -273.172968) (xy 398.731134 -273.219649) (xy 398.708263 -273.263226) (xy 398.678698 -273.30257)
			(xy 398.643205 -273.336662) (xy 398.602702 -273.364618) (xy 398.55824 -273.385716) (xy 398.510969 -273.399408)
			(xy 398.462114 -273.40534) (xy 398.412939 -273.403359) (xy 398.36472 -273.393515) (xy 398.318704 -273.376063)
			(xy 398.276083 -273.351456) (xy 398.237962 -273.320331) (xy 398.205327 -273.283494) (xy 398.179024 -273.241898)
			(xy 398.159733 -273.196622) (xy 398.147956 -273.148838) (xy 398.143996 -273.099784) (xy 396.855188 -273.099784)
			(xy 396.854693 -273.124391) (xy 396.846798 -273.172968) (xy 396.831214 -273.219649) (xy 396.808343 -273.263226)
			(xy 396.778778 -273.30257) (xy 396.743285 -273.336662) (xy 396.702782 -273.364618) (xy 396.65832 -273.385716)
			(xy 396.611049 -273.399408) (xy 396.562194 -273.40534) (xy 396.513019 -273.403359) (xy 396.4648 -273.393515)
			(xy 396.418784 -273.376063) (xy 396.376163 -273.351456) (xy 396.338042 -273.320331) (xy 396.305407 -273.283494)
			(xy 396.279104 -273.241898) (xy 396.259813 -273.196622) (xy 396.248036 -273.148838) (xy 396.244076 -273.099784)
			(xy 394.955268 -273.099784) (xy 394.954773 -273.124391) (xy 394.946878 -273.172968) (xy 394.931294 -273.219649)
			(xy 394.908423 -273.263226) (xy 394.878858 -273.30257) (xy 394.843365 -273.336662) (xy 394.802862 -273.364618)
			(xy 394.7584 -273.385716) (xy 394.711129 -273.399408) (xy 394.662274 -273.40534) (xy 394.613099 -273.403359)
			(xy 394.56488 -273.393515) (xy 394.518864 -273.376063) (xy 394.476243 -273.351456) (xy 394.438122 -273.320331)
			(xy 394.405487 -273.283494) (xy 394.379184 -273.241898) (xy 394.359893 -273.196622) (xy 394.348116 -273.148838)
			(xy 394.344156 -273.099784) (xy 393.055094 -273.099784) (xy 393.054599 -273.124391) (xy 393.046704 -273.172968)
			(xy 393.03112 -273.219649) (xy 393.008249 -273.263226) (xy 392.978684 -273.30257) (xy 392.943191 -273.336662)
			(xy 392.902688 -273.364618) (xy 392.858226 -273.385716) (xy 392.810955 -273.399408) (xy 392.7621 -273.40534)
			(xy 392.712925 -273.403359) (xy 392.664706 -273.393515) (xy 392.61869 -273.376063) (xy 392.576069 -273.351456)
			(xy 392.537948 -273.320331) (xy 392.505313 -273.283494) (xy 392.47901 -273.241898) (xy 392.459719 -273.196622)
			(xy 392.447942 -273.148838) (xy 392.443982 -273.099784) (xy 379.627012 -273.099784) (xy 379.58231 -273.134324)
			(xy 379.46002 -273.218735) (xy 379.333375 -273.29646) (xy 379.20274 -273.367276) (xy 379.068493 -273.430977)
			(xy 378.93102 -273.48738) (xy 378.790717 -273.536323) (xy 378.64799 -273.577665) (xy 378.503249 -273.611285)
			(xy 378.356913 -273.637088) (xy 378.209402 -273.654999) (xy 378.061143 -273.664967) (xy 377.912562 -273.666962)
			(xy 377.764089 -273.660978) (xy 377.61615 -273.647034) (xy 377.469174 -273.625169) (xy 377.323583 -273.595447)
			(xy 377.179797 -273.557952) (xy 377.038231 -273.512793) (xy 376.899293 -273.460101) (xy 376.763384 -273.400027)
			(xy 376.630895 -273.332745) (xy 376.502209 -273.258448) (xy 376.377696 -273.177351) (xy 376.257716 -273.089687)
			(xy 376.142615 -272.995709) (xy 376.032723 -272.895689) (xy 375.928359 -272.789914) (xy 375.829823 -272.67869)
			(xy 375.737399 -272.562337) (xy 375.651354 -272.44119) (xy 375.571936 -272.3156) (xy 375.499373 -272.185928)
			(xy 375.433875 -272.052548) (xy 375.375631 -271.915845) (xy 375.324809 -271.776212) (xy 375.281555 -271.634053)
			(xy 375.245994 -271.489776) (xy 375.218229 -271.3438) (xy 375.198339 -271.196543) (xy 375.186382 -271.04843)
			(xy 375.182393 -270.89989) (xy 324.616572 -270.89989) (xy 324.616073 -270.974187) (xy 324.608097 -271.122567)
			(xy 324.592168 -271.270305) (xy 324.568332 -271.416974) (xy 324.536658 -271.562153) (xy 324.497236 -271.705423)
			(xy 324.450181 -271.84637) (xy 324.395628 -271.984587) (xy 324.333735 -272.119678) (xy 324.26468 -272.251251)
			(xy 324.188662 -272.378929) (xy 324.105901 -272.502341) (xy 324.016634 -272.621134) (xy 323.92112 -272.734963)
			(xy 323.819633 -272.843502) (xy 323.712466 -272.946437) (xy 323.599929 -273.043471) (xy 323.482346 -273.134324)
			(xy 323.360056 -273.218735) (xy 323.233411 -273.29646) (xy 323.102776 -273.367276) (xy 322.968529 -273.430977)
			(xy 322.831056 -273.48738) (xy 322.690753 -273.536323) (xy 322.548026 -273.577665) (xy 322.403285 -273.611285)
			(xy 322.256949 -273.637088) (xy 322.109438 -273.654999) (xy 321.961179 -273.664967) (xy 321.812598 -273.666962)
			(xy 321.664125 -273.660978) (xy 321.516186 -273.647034) (xy 321.36921 -273.625169) (xy 321.223619 -273.595447)
			(xy 321.079833 -273.557952) (xy 320.938267 -273.512793) (xy 320.799329 -273.460101) (xy 320.66342 -273.400027)
			(xy 320.530931 -273.332745) (xy 320.402245 -273.258448) (xy 320.277732 -273.177351) (xy 320.157752 -273.089687)
			(xy 320.042651 -272.995709) (xy 319.932759 -272.895689) (xy 319.828395 -272.789914) (xy 319.729859 -272.67869)
			(xy 319.637435 -272.562337) (xy 319.55139 -272.44119) (xy 319.471972 -272.3156) (xy 319.399409 -272.185928)
			(xy 319.333911 -272.052548) (xy 319.275667 -271.915845) (xy 319.224845 -271.776212) (xy 319.181591 -271.634053)
			(xy 319.14603 -271.489776) (xy 319.118265 -271.3438) (xy 319.098375 -271.196543) (xy 319.086418 -271.04843)
			(xy 319.082429 -270.89989) (xy 264.616692 -270.89989) (xy 264.616193 -270.974187) (xy 264.608217 -271.122567)
			(xy 264.592288 -271.270305) (xy 264.568452 -271.416974) (xy 264.536778 -271.562153) (xy 264.497356 -271.705423)
			(xy 264.450301 -271.84637) (xy 264.395748 -271.984587) (xy 264.333855 -272.119678) (xy 264.2648 -272.251251)
			(xy 264.188782 -272.378929) (xy 264.106021 -272.502341) (xy 264.016754 -272.621134) (xy 263.92124 -272.734963)
			(xy 263.819753 -272.843502) (xy 263.712586 -272.946437) (xy 263.600049 -273.043471) (xy 263.527168 -273.099784)
			(xy 276.343884 -273.099784) (xy 276.347844 -273.05073) (xy 276.359621 -273.002946) (xy 276.378912 -272.95767)
			(xy 276.405215 -272.916074) (xy 276.43785 -272.879237) (xy 276.475971 -272.848112) (xy 276.518592 -272.823505)
			(xy 276.564608 -272.806053) (xy 276.612827 -272.796209) (xy 276.662002 -272.794228) (xy 276.710857 -272.80016)
			(xy 276.758128 -272.813852) (xy 276.80259 -272.83495) (xy 276.843093 -272.862906) (xy 276.878586 -272.896998)
			(xy 276.908151 -272.936342) (xy 276.931022 -272.979919) (xy 276.946606 -273.0266) (xy 276.954501 -273.075177)
			(xy 276.954996 -273.099784) (xy 278.244058 -273.099784) (xy 278.248018 -273.05073) (xy 278.259795 -273.002946)
			(xy 278.279086 -272.95767) (xy 278.305389 -272.916074) (xy 278.338024 -272.879237) (xy 278.376145 -272.848112)
			(xy 278.418766 -272.823505) (xy 278.464782 -272.806053) (xy 278.513001 -272.796209) (xy 278.562176 -272.794228)
			(xy 278.611031 -272.80016) (xy 278.658302 -272.813852) (xy 278.702764 -272.83495) (xy 278.743267 -272.862906)
			(xy 278.77876 -272.896998) (xy 278.808325 -272.936342) (xy 278.831196 -272.979919) (xy 278.84678 -273.0266)
			(xy 278.854675 -273.075177) (xy 278.85517 -273.099784) (xy 280.143978 -273.099784) (xy 280.147938 -273.05073)
			(xy 280.159715 -273.002946) (xy 280.179006 -272.95767) (xy 280.205309 -272.916074) (xy 280.237944 -272.879237)
			(xy 280.276065 -272.848112) (xy 280.318686 -272.823505) (xy 280.364702 -272.806053) (xy 280.412921 -272.796209)
			(xy 280.462096 -272.794228) (xy 280.510951 -272.80016) (xy 280.558222 -272.813852) (xy 280.602684 -272.83495)
			(xy 280.643187 -272.862906) (xy 280.67868 -272.896998) (xy 280.708245 -272.936342) (xy 280.731116 -272.979919)
			(xy 280.7467 -273.0266) (xy 280.754595 -273.075177) (xy 280.75509 -273.099784) (xy 282.043898 -273.099784)
			(xy 282.047858 -273.05073) (xy 282.059635 -273.002946) (xy 282.078926 -272.95767) (xy 282.105229 -272.916074)
			(xy 282.137864 -272.879237) (xy 282.175985 -272.848112) (xy 282.218606 -272.823505) (xy 282.264622 -272.806053)
			(xy 282.312841 -272.796209) (xy 282.362016 -272.794228) (xy 282.410871 -272.80016) (xy 282.458142 -272.813852)
			(xy 282.502604 -272.83495) (xy 282.543107 -272.862906) (xy 282.5786 -272.896998) (xy 282.608165 -272.936342)
			(xy 282.631036 -272.979919) (xy 282.64662 -273.0266) (xy 282.654515 -273.075177) (xy 282.65501 -273.099784)
			(xy 283.944072 -273.099784) (xy 283.948032 -273.05073) (xy 283.959809 -273.002946) (xy 283.9791 -272.95767)
			(xy 284.005403 -272.916074) (xy 284.038038 -272.879237) (xy 284.076159 -272.848112) (xy 284.11878 -272.823505)
			(xy 284.164796 -272.806053) (xy 284.213015 -272.796209) (xy 284.26219 -272.794228) (xy 284.311045 -272.80016)
			(xy 284.358316 -272.813852) (xy 284.402778 -272.83495) (xy 284.443281 -272.862906) (xy 284.478774 -272.896998)
			(xy 284.508339 -272.936342) (xy 284.53121 -272.979919) (xy 284.546794 -273.0266) (xy 284.554689 -273.075177)
			(xy 284.555184 -273.099784) (xy 285.843992 -273.099784) (xy 285.847952 -273.05073) (xy 285.859729 -273.002946)
			(xy 285.87902 -272.95767) (xy 285.905323 -272.916074) (xy 285.937958 -272.879237) (xy 285.976079 -272.848112)
			(xy 286.0187 -272.823505) (xy 286.064716 -272.806053) (xy 286.112935 -272.796209) (xy 286.16211 -272.794228)
			(xy 286.210965 -272.80016) (xy 286.258236 -272.813852) (xy 286.302698 -272.83495) (xy 286.343201 -272.862906)
			(xy 286.378694 -272.896998) (xy 286.408259 -272.936342) (xy 286.43113 -272.979919) (xy 286.446714 -273.0266)
			(xy 286.454609 -273.075177) (xy 286.455104 -273.099784) (xy 287.743912 -273.099784) (xy 287.747872 -273.05073)
			(xy 287.759649 -273.002946) (xy 287.77894 -272.95767) (xy 287.805243 -272.916074) (xy 287.837878 -272.879237)
			(xy 287.875999 -272.848112) (xy 287.91862 -272.823505) (xy 287.964636 -272.806053) (xy 288.012855 -272.796209)
			(xy 288.06203 -272.794228) (xy 288.110885 -272.80016) (xy 288.158156 -272.813852) (xy 288.202618 -272.83495)
			(xy 288.243121 -272.862906) (xy 288.278614 -272.896998) (xy 288.308179 -272.936342) (xy 288.33105 -272.979919)
			(xy 288.346634 -273.0266) (xy 288.354529 -273.075177) (xy 288.355024 -273.099784) (xy 289.644086 -273.099784)
			(xy 289.648046 -273.05073) (xy 289.659823 -273.002946) (xy 289.679114 -272.95767) (xy 289.705417 -272.916074)
			(xy 289.738052 -272.879237) (xy 289.776173 -272.848112) (xy 289.818794 -272.823505) (xy 289.86481 -272.806053)
			(xy 289.913029 -272.796209) (xy 289.962204 -272.794228) (xy 290.011059 -272.80016) (xy 290.05833 -272.813852)
			(xy 290.102792 -272.83495) (xy 290.143295 -272.862906) (xy 290.178788 -272.896998) (xy 290.208353 -272.936342)
			(xy 290.231224 -272.979919) (xy 290.246808 -273.0266) (xy 290.254703 -273.075177) (xy 290.255193 -273.09953)
			(xy 291.543752 -273.09953) (xy 291.547712 -273.050476) (xy 291.559489 -273.002692) (xy 291.57878 -272.957416)
			(xy 291.605083 -272.91582) (xy 291.637718 -272.878983) (xy 291.675839 -272.847858) (xy 291.71846 -272.823251)
			(xy 291.764476 -272.805799) (xy 291.812695 -272.795955) (xy 291.86187 -272.793974) (xy 291.910725 -272.799906)
			(xy 291.957996 -272.813598) (xy 292.002458 -272.834696) (xy 292.042961 -272.862652) (xy 292.078454 -272.896744)
			(xy 292.108019 -272.936088) (xy 292.13089 -272.979665) (xy 292.146474 -273.026346) (xy 292.154369 -273.074923)
			(xy 292.154864 -273.09953) (xy 292.154859 -273.099784) (xy 293.443672 -273.099784) (xy 293.447632 -273.05073)
			(xy 293.459409 -273.002946) (xy 293.4787 -272.95767) (xy 293.505003 -272.916074) (xy 293.537638 -272.879237)
			(xy 293.575759 -272.848112) (xy 293.61838 -272.823505) (xy 293.664396 -272.806053) (xy 293.712615 -272.796209)
			(xy 293.76179 -272.794228) (xy 293.810645 -272.80016) (xy 293.857916 -272.813852) (xy 293.902378 -272.83495)
			(xy 293.942881 -272.862906) (xy 293.978374 -272.896998) (xy 294.007939 -272.936342) (xy 294.03081 -272.979919)
			(xy 294.046394 -273.0266) (xy 294.054289 -273.075177) (xy 294.054784 -273.099784) (xy 295.343846 -273.099784)
			(xy 295.347806 -273.05073) (xy 295.359583 -273.002946) (xy 295.378874 -272.95767) (xy 295.405177 -272.916074)
			(xy 295.437812 -272.879237) (xy 295.475933 -272.848112) (xy 295.518554 -272.823505) (xy 295.56457 -272.806053)
			(xy 295.612789 -272.796209) (xy 295.661964 -272.794228) (xy 295.710819 -272.80016) (xy 295.75809 -272.813852)
			(xy 295.802552 -272.83495) (xy 295.843055 -272.862906) (xy 295.878548 -272.896998) (xy 295.908113 -272.936342)
			(xy 295.930984 -272.979919) (xy 295.946568 -273.0266) (xy 295.954463 -273.075177) (xy 295.954958 -273.099784)
			(xy 297.243766 -273.099784) (xy 297.247726 -273.05073) (xy 297.259503 -273.002946) (xy 297.278794 -272.95767)
			(xy 297.305097 -272.916074) (xy 297.337732 -272.879237) (xy 297.375853 -272.848112) (xy 297.418474 -272.823505)
			(xy 297.46449 -272.806053) (xy 297.512709 -272.796209) (xy 297.561884 -272.794228) (xy 297.610739 -272.80016)
			(xy 297.65801 -272.813852) (xy 297.702472 -272.83495) (xy 297.742975 -272.862906) (xy 297.778468 -272.896998)
			(xy 297.808033 -272.936342) (xy 297.830904 -272.979919) (xy 297.846488 -273.0266) (xy 297.854383 -273.075177)
			(xy 297.854878 -273.099784) (xy 299.143686 -273.099784) (xy 299.147646 -273.05073) (xy 299.159423 -273.002946)
			(xy 299.178714 -272.95767) (xy 299.205017 -272.916074) (xy 299.237652 -272.879237) (xy 299.275773 -272.848112)
			(xy 299.318394 -272.823505) (xy 299.36441 -272.806053) (xy 299.412629 -272.796209) (xy 299.461804 -272.794228)
			(xy 299.510659 -272.80016) (xy 299.55793 -272.813852) (xy 299.602392 -272.83495) (xy 299.642895 -272.862906)
			(xy 299.678388 -272.896998) (xy 299.707953 -272.936342) (xy 299.730824 -272.979919) (xy 299.746408 -273.0266)
			(xy 299.754303 -273.075177) (xy 299.754798 -273.099784) (xy 301.04386 -273.099784) (xy 301.04782 -273.05073)
			(xy 301.059597 -273.002946) (xy 301.078888 -272.95767) (xy 301.105191 -272.916074) (xy 301.137826 -272.879237)
			(xy 301.175947 -272.848112) (xy 301.218568 -272.823505) (xy 301.264584 -272.806053) (xy 301.312803 -272.796209)
			(xy 301.361978 -272.794228) (xy 301.410833 -272.80016) (xy 301.458104 -272.813852) (xy 301.502566 -272.83495)
			(xy 301.543069 -272.862906) (xy 301.578562 -272.896998) (xy 301.608127 -272.936342) (xy 301.630998 -272.979919)
			(xy 301.646582 -273.0266) (xy 301.654477 -273.075177) (xy 301.654972 -273.099784) (xy 302.94378 -273.099784)
			(xy 302.94774 -273.05073) (xy 302.959517 -273.002946) (xy 302.978808 -272.95767) (xy 303.005111 -272.916074)
			(xy 303.037746 -272.879237) (xy 303.075867 -272.848112) (xy 303.118488 -272.823505) (xy 303.164504 -272.806053)
			(xy 303.212723 -272.796209) (xy 303.261898 -272.794228) (xy 303.310753 -272.80016) (xy 303.358024 -272.813852)
			(xy 303.402486 -272.83495) (xy 303.442989 -272.862906) (xy 303.478482 -272.896998) (xy 303.508047 -272.936342)
			(xy 303.530918 -272.979919) (xy 303.546502 -273.0266) (xy 303.554397 -273.075177) (xy 303.554892 -273.099784)
			(xy 304.8437 -273.099784) (xy 304.84766 -273.05073) (xy 304.859437 -273.002946) (xy 304.878728 -272.95767)
			(xy 304.905031 -272.916074) (xy 304.937666 -272.879237) (xy 304.975787 -272.848112) (xy 305.018408 -272.823505)
			(xy 305.064424 -272.806053) (xy 305.112643 -272.796209) (xy 305.161818 -272.794228) (xy 305.210673 -272.80016)
			(xy 305.257944 -272.813852) (xy 305.302406 -272.83495) (xy 305.342909 -272.862906) (xy 305.378402 -272.896998)
			(xy 305.407967 -272.936342) (xy 305.430838 -272.979919) (xy 305.446422 -273.0266) (xy 305.454317 -273.075177)
			(xy 305.454812 -273.099784) (xy 306.743874 -273.099784) (xy 306.747834 -273.05073) (xy 306.759611 -273.002946)
			(xy 306.778902 -272.95767) (xy 306.805205 -272.916074) (xy 306.83784 -272.879237) (xy 306.875961 -272.848112)
			(xy 306.918582 -272.823505) (xy 306.964598 -272.806053) (xy 307.012817 -272.796209) (xy 307.061992 -272.794228)
			(xy 307.110847 -272.80016) (xy 307.158118 -272.813852) (xy 307.20258 -272.83495) (xy 307.243083 -272.862906)
			(xy 307.278576 -272.896998) (xy 307.308141 -272.936342) (xy 307.331012 -272.979919) (xy 307.346596 -273.0266)
			(xy 307.354491 -273.075177) (xy 307.354986 -273.099784) (xy 308.643794 -273.099784) (xy 308.647754 -273.05073)
			(xy 308.659531 -273.002946) (xy 308.678822 -272.95767) (xy 308.705125 -272.916074) (xy 308.73776 -272.879237)
			(xy 308.775881 -272.848112) (xy 308.818502 -272.823505) (xy 308.864518 -272.806053) (xy 308.912737 -272.796209)
			(xy 308.961912 -272.794228) (xy 309.010767 -272.80016) (xy 309.058038 -272.813852) (xy 309.1025 -272.83495)
			(xy 309.143003 -272.862906) (xy 309.178496 -272.896998) (xy 309.208061 -272.936342) (xy 309.230932 -272.979919)
			(xy 309.246516 -273.0266) (xy 309.254411 -273.075177) (xy 309.254906 -273.099784) (xy 310.543714 -273.099784)
			(xy 310.547674 -273.05073) (xy 310.559451 -273.002946) (xy 310.578742 -272.95767) (xy 310.605045 -272.916074)
			(xy 310.63768 -272.879237) (xy 310.675801 -272.848112) (xy 310.718422 -272.823505) (xy 310.764438 -272.806053)
			(xy 310.812657 -272.796209) (xy 310.861832 -272.794228) (xy 310.910687 -272.80016) (xy 310.957958 -272.813852)
			(xy 311.00242 -272.83495) (xy 311.042923 -272.862906) (xy 311.078416 -272.896998) (xy 311.107981 -272.936342)
			(xy 311.130852 -272.979919) (xy 311.146436 -273.0266) (xy 311.154331 -273.075177) (xy 311.154826 -273.099784)
			(xy 312.443634 -273.099784) (xy 312.447594 -273.05073) (xy 312.459371 -273.002946) (xy 312.478662 -272.95767)
			(xy 312.504965 -272.916074) (xy 312.5376 -272.879237) (xy 312.575721 -272.848112) (xy 312.618342 -272.823505)
			(xy 312.664358 -272.806053) (xy 312.712577 -272.796209) (xy 312.761752 -272.794228) (xy 312.810607 -272.80016)
			(xy 312.857878 -272.813852) (xy 312.90234 -272.83495) (xy 312.942843 -272.862906) (xy 312.978336 -272.896998)
			(xy 313.007901 -272.936342) (xy 313.030772 -272.979919) (xy 313.046356 -273.0266) (xy 313.054251 -273.075177)
			(xy 313.054746 -273.099784) (xy 313.054251 -273.124391) (xy 313.046356 -273.172968) (xy 313.030772 -273.219649)
			(xy 313.007901 -273.263226) (xy 312.978336 -273.30257) (xy 312.942843 -273.336662) (xy 312.90234 -273.364618)
			(xy 312.857878 -273.385716) (xy 312.810607 -273.399408) (xy 312.761752 -273.40534) (xy 312.712577 -273.403359)
			(xy 312.664358 -273.393515) (xy 312.618342 -273.376063) (xy 312.575721 -273.351456) (xy 312.5376 -273.320331)
			(xy 312.504965 -273.283494) (xy 312.478662 -273.241898) (xy 312.459371 -273.196622) (xy 312.447594 -273.148838)
			(xy 312.443634 -273.099784) (xy 311.154826 -273.099784) (xy 311.154331 -273.124391) (xy 311.146436 -273.172968)
			(xy 311.130852 -273.219649) (xy 311.107981 -273.263226) (xy 311.078416 -273.30257) (xy 311.042923 -273.336662)
			(xy 311.00242 -273.364618) (xy 310.957958 -273.385716) (xy 310.910687 -273.399408) (xy 310.861832 -273.40534)
			(xy 310.812657 -273.403359) (xy 310.764438 -273.393515) (xy 310.718422 -273.376063) (xy 310.675801 -273.351456)
			(xy 310.63768 -273.320331) (xy 310.605045 -273.283494) (xy 310.578742 -273.241898) (xy 310.559451 -273.196622)
			(xy 310.547674 -273.148838) (xy 310.543714 -273.099784) (xy 309.254906 -273.099784) (xy 309.254411 -273.124391)
			(xy 309.246516 -273.172968) (xy 309.230932 -273.219649) (xy 309.208061 -273.263226) (xy 309.178496 -273.30257)
			(xy 309.143003 -273.336662) (xy 309.1025 -273.364618) (xy 309.058038 -273.385716) (xy 309.010767 -273.399408)
			(xy 308.961912 -273.40534) (xy 308.912737 -273.403359) (xy 308.864518 -273.393515) (xy 308.818502 -273.376063)
			(xy 308.775881 -273.351456) (xy 308.73776 -273.320331) (xy 308.705125 -273.283494) (xy 308.678822 -273.241898)
			(xy 308.659531 -273.196622) (xy 308.647754 -273.148838) (xy 308.643794 -273.099784) (xy 307.354986 -273.099784)
			(xy 307.354491 -273.124391) (xy 307.346596 -273.172968) (xy 307.331012 -273.219649) (xy 307.308141 -273.263226)
			(xy 307.278576 -273.30257) (xy 307.243083 -273.336662) (xy 307.20258 -273.364618) (xy 307.158118 -273.385716)
			(xy 307.110847 -273.399408) (xy 307.061992 -273.40534) (xy 307.012817 -273.403359) (xy 306.964598 -273.393515)
			(xy 306.918582 -273.376063) (xy 306.875961 -273.351456) (xy 306.83784 -273.320331) (xy 306.805205 -273.283494)
			(xy 306.778902 -273.241898) (xy 306.759611 -273.196622) (xy 306.747834 -273.148838) (xy 306.743874 -273.099784)
			(xy 305.454812 -273.099784) (xy 305.454317 -273.124391) (xy 305.446422 -273.172968) (xy 305.430838 -273.219649)
			(xy 305.407967 -273.263226) (xy 305.378402 -273.30257) (xy 305.342909 -273.336662) (xy 305.302406 -273.364618)
			(xy 305.257944 -273.385716) (xy 305.210673 -273.399408) (xy 305.161818 -273.40534) (xy 305.112643 -273.403359)
			(xy 305.064424 -273.393515) (xy 305.018408 -273.376063) (xy 304.975787 -273.351456) (xy 304.937666 -273.320331)
			(xy 304.905031 -273.283494) (xy 304.878728 -273.241898) (xy 304.859437 -273.196622) (xy 304.84766 -273.148838)
			(xy 304.8437 -273.099784) (xy 303.554892 -273.099784) (xy 303.554397 -273.124391) (xy 303.546502 -273.172968)
			(xy 303.530918 -273.219649) (xy 303.508047 -273.263226) (xy 303.478482 -273.30257) (xy 303.442989 -273.336662)
			(xy 303.402486 -273.364618) (xy 303.358024 -273.385716) (xy 303.310753 -273.399408) (xy 303.261898 -273.40534)
			(xy 303.212723 -273.403359) (xy 303.164504 -273.393515) (xy 303.118488 -273.376063) (xy 303.075867 -273.351456)
			(xy 303.037746 -273.320331) (xy 303.005111 -273.283494) (xy 302.978808 -273.241898) (xy 302.959517 -273.196622)
			(xy 302.94774 -273.148838) (xy 302.94378 -273.099784) (xy 301.654972 -273.099784) (xy 301.654477 -273.124391)
			(xy 301.646582 -273.172968) (xy 301.630998 -273.219649) (xy 301.608127 -273.263226) (xy 301.578562 -273.30257)
			(xy 301.543069 -273.336662) (xy 301.502566 -273.364618) (xy 301.458104 -273.385716) (xy 301.410833 -273.399408)
			(xy 301.361978 -273.40534) (xy 301.312803 -273.403359) (xy 301.264584 -273.393515) (xy 301.218568 -273.376063)
			(xy 301.175947 -273.351456) (xy 301.137826 -273.320331) (xy 301.105191 -273.283494) (xy 301.078888 -273.241898)
			(xy 301.059597 -273.196622) (xy 301.04782 -273.148838) (xy 301.04386 -273.099784) (xy 299.754798 -273.099784)
			(xy 299.754303 -273.124391) (xy 299.746408 -273.172968) (xy 299.730824 -273.219649) (xy 299.707953 -273.263226)
			(xy 299.678388 -273.30257) (xy 299.642895 -273.336662) (xy 299.602392 -273.364618) (xy 299.55793 -273.385716)
			(xy 299.510659 -273.399408) (xy 299.461804 -273.40534) (xy 299.412629 -273.403359) (xy 299.36441 -273.393515)
			(xy 299.318394 -273.376063) (xy 299.275773 -273.351456) (xy 299.237652 -273.320331) (xy 299.205017 -273.283494)
			(xy 299.178714 -273.241898) (xy 299.159423 -273.196622) (xy 299.147646 -273.148838) (xy 299.143686 -273.099784)
			(xy 297.854878 -273.099784) (xy 297.854383 -273.124391) (xy 297.846488 -273.172968) (xy 297.830904 -273.219649)
			(xy 297.808033 -273.263226) (xy 297.778468 -273.30257) (xy 297.742975 -273.336662) (xy 297.702472 -273.364618)
			(xy 297.65801 -273.385716) (xy 297.610739 -273.399408) (xy 297.561884 -273.40534) (xy 297.512709 -273.403359)
			(xy 297.46449 -273.393515) (xy 297.418474 -273.376063) (xy 297.375853 -273.351456) (xy 297.337732 -273.320331)
			(xy 297.305097 -273.283494) (xy 297.278794 -273.241898) (xy 297.259503 -273.196622) (xy 297.247726 -273.148838)
			(xy 297.243766 -273.099784) (xy 295.954958 -273.099784) (xy 295.954463 -273.124391) (xy 295.946568 -273.172968)
			(xy 295.930984 -273.219649) (xy 295.908113 -273.263226) (xy 295.878548 -273.30257) (xy 295.843055 -273.336662)
			(xy 295.802552 -273.364618) (xy 295.75809 -273.385716) (xy 295.710819 -273.399408) (xy 295.661964 -273.40534)
			(xy 295.612789 -273.403359) (xy 295.56457 -273.393515) (xy 295.518554 -273.376063) (xy 295.475933 -273.351456)
			(xy 295.437812 -273.320331) (xy 295.405177 -273.283494) (xy 295.378874 -273.241898) (xy 295.359583 -273.196622)
			(xy 295.347806 -273.148838) (xy 295.343846 -273.099784) (xy 294.054784 -273.099784) (xy 294.054289 -273.124391)
			(xy 294.046394 -273.172968) (xy 294.03081 -273.219649) (xy 294.007939 -273.263226) (xy 293.978374 -273.30257)
			(xy 293.942881 -273.336662) (xy 293.902378 -273.364618) (xy 293.857916 -273.385716) (xy 293.810645 -273.399408)
			(xy 293.76179 -273.40534) (xy 293.712615 -273.403359) (xy 293.664396 -273.393515) (xy 293.61838 -273.376063)
			(xy 293.575759 -273.351456) (xy 293.537638 -273.320331) (xy 293.505003 -273.283494) (xy 293.4787 -273.241898)
			(xy 293.459409 -273.196622) (xy 293.447632 -273.148838) (xy 293.443672 -273.099784) (xy 292.154859 -273.099784)
			(xy 292.154369 -273.124137) (xy 292.146474 -273.172714) (xy 292.13089 -273.219395) (xy 292.108019 -273.262972)
			(xy 292.078454 -273.302316) (xy 292.042961 -273.336408) (xy 292.002458 -273.364364) (xy 291.957996 -273.385462)
			(xy 291.910725 -273.399154) (xy 291.86187 -273.405086) (xy 291.812695 -273.403105) (xy 291.764476 -273.393261)
			(xy 291.71846 -273.375809) (xy 291.675839 -273.351202) (xy 291.637718 -273.320077) (xy 291.605083 -273.28324)
			(xy 291.57878 -273.241644) (xy 291.559489 -273.196368) (xy 291.547712 -273.148584) (xy 291.543752 -273.09953)
			(xy 290.255193 -273.09953) (xy 290.255198 -273.099784) (xy 290.254703 -273.124391) (xy 290.246808 -273.172968)
			(xy 290.231224 -273.219649) (xy 290.208353 -273.263226) (xy 290.178788 -273.30257) (xy 290.143295 -273.336662)
			(xy 290.102792 -273.364618) (xy 290.05833 -273.385716) (xy 290.011059 -273.399408) (xy 289.962204 -273.40534)
			(xy 289.913029 -273.403359) (xy 289.86481 -273.393515) (xy 289.818794 -273.376063) (xy 289.776173 -273.351456)
			(xy 289.738052 -273.320331) (xy 289.705417 -273.283494) (xy 289.679114 -273.241898) (xy 289.659823 -273.196622)
			(xy 289.648046 -273.148838) (xy 289.644086 -273.099784) (xy 288.355024 -273.099784) (xy 288.354529 -273.124391)
			(xy 288.346634 -273.172968) (xy 288.33105 -273.219649) (xy 288.308179 -273.263226) (xy 288.278614 -273.30257)
			(xy 288.243121 -273.336662) (xy 288.202618 -273.364618) (xy 288.158156 -273.385716) (xy 288.110885 -273.399408)
			(xy 288.06203 -273.40534) (xy 288.012855 -273.403359) (xy 287.964636 -273.393515) (xy 287.91862 -273.376063)
			(xy 287.875999 -273.351456) (xy 287.837878 -273.320331) (xy 287.805243 -273.283494) (xy 287.77894 -273.241898)
			(xy 287.759649 -273.196622) (xy 287.747872 -273.148838) (xy 287.743912 -273.099784) (xy 286.455104 -273.099784)
			(xy 286.454609 -273.124391) (xy 286.446714 -273.172968) (xy 286.43113 -273.219649) (xy 286.408259 -273.263226)
			(xy 286.378694 -273.30257) (xy 286.343201 -273.336662) (xy 286.302698 -273.364618) (xy 286.258236 -273.385716)
			(xy 286.210965 -273.399408) (xy 286.16211 -273.40534) (xy 286.112935 -273.403359) (xy 286.064716 -273.393515)
			(xy 286.0187 -273.376063) (xy 285.976079 -273.351456) (xy 285.937958 -273.320331) (xy 285.905323 -273.283494)
			(xy 285.87902 -273.241898) (xy 285.859729 -273.196622) (xy 285.847952 -273.148838) (xy 285.843992 -273.099784)
			(xy 284.555184 -273.099784) (xy 284.554689 -273.124391) (xy 284.546794 -273.172968) (xy 284.53121 -273.219649)
			(xy 284.508339 -273.263226) (xy 284.478774 -273.30257) (xy 284.443281 -273.336662) (xy 284.402778 -273.364618)
			(xy 284.358316 -273.385716) (xy 284.311045 -273.399408) (xy 284.26219 -273.40534) (xy 284.213015 -273.403359)
			(xy 284.164796 -273.393515) (xy 284.11878 -273.376063) (xy 284.076159 -273.351456) (xy 284.038038 -273.320331)
			(xy 284.005403 -273.283494) (xy 283.9791 -273.241898) (xy 283.959809 -273.196622) (xy 283.948032 -273.148838)
			(xy 283.944072 -273.099784) (xy 282.65501 -273.099784) (xy 282.654515 -273.124391) (xy 282.64662 -273.172968)
			(xy 282.631036 -273.219649) (xy 282.608165 -273.263226) (xy 282.5786 -273.30257) (xy 282.543107 -273.336662)
			(xy 282.502604 -273.364618) (xy 282.458142 -273.385716) (xy 282.410871 -273.399408) (xy 282.362016 -273.40534)
			(xy 282.312841 -273.403359) (xy 282.264622 -273.393515) (xy 282.218606 -273.376063) (xy 282.175985 -273.351456)
			(xy 282.137864 -273.320331) (xy 282.105229 -273.283494) (xy 282.078926 -273.241898) (xy 282.059635 -273.196622)
			(xy 282.047858 -273.148838) (xy 282.043898 -273.099784) (xy 280.75509 -273.099784) (xy 280.754595 -273.124391)
			(xy 280.7467 -273.172968) (xy 280.731116 -273.219649) (xy 280.708245 -273.263226) (xy 280.67868 -273.30257)
			(xy 280.643187 -273.336662) (xy 280.602684 -273.364618) (xy 280.558222 -273.385716) (xy 280.510951 -273.399408)
			(xy 280.462096 -273.40534) (xy 280.412921 -273.403359) (xy 280.364702 -273.393515) (xy 280.318686 -273.376063)
			(xy 280.276065 -273.351456) (xy 280.237944 -273.320331) (xy 280.205309 -273.283494) (xy 280.179006 -273.241898)
			(xy 280.159715 -273.196622) (xy 280.147938 -273.148838) (xy 280.143978 -273.099784) (xy 278.85517 -273.099784)
			(xy 278.854675 -273.124391) (xy 278.84678 -273.172968) (xy 278.831196 -273.219649) (xy 278.808325 -273.263226)
			(xy 278.77876 -273.30257) (xy 278.743267 -273.336662) (xy 278.702764 -273.364618) (xy 278.658302 -273.385716)
			(xy 278.611031 -273.399408) (xy 278.562176 -273.40534) (xy 278.513001 -273.403359) (xy 278.464782 -273.393515)
			(xy 278.418766 -273.376063) (xy 278.376145 -273.351456) (xy 278.338024 -273.320331) (xy 278.305389 -273.283494)
			(xy 278.279086 -273.241898) (xy 278.259795 -273.196622) (xy 278.248018 -273.148838) (xy 278.244058 -273.099784)
			(xy 276.954996 -273.099784) (xy 276.954501 -273.124391) (xy 276.946606 -273.172968) (xy 276.931022 -273.219649)
			(xy 276.908151 -273.263226) (xy 276.878586 -273.30257) (xy 276.843093 -273.336662) (xy 276.80259 -273.364618)
			(xy 276.758128 -273.385716) (xy 276.710857 -273.399408) (xy 276.662002 -273.40534) (xy 276.612827 -273.403359)
			(xy 276.564608 -273.393515) (xy 276.518592 -273.376063) (xy 276.475971 -273.351456) (xy 276.43785 -273.320331)
			(xy 276.405215 -273.283494) (xy 276.378912 -273.241898) (xy 276.359621 -273.196622) (xy 276.347844 -273.148838)
			(xy 276.343884 -273.099784) (xy 263.527168 -273.099784) (xy 263.482466 -273.134324) (xy 263.360176 -273.218735)
			(xy 263.233531 -273.29646) (xy 263.102896 -273.367276) (xy 262.968649 -273.430977) (xy 262.831176 -273.48738)
			(xy 262.690873 -273.536323) (xy 262.548146 -273.577665) (xy 262.403405 -273.611285) (xy 262.257069 -273.637088)
			(xy 262.109558 -273.654999) (xy 261.961299 -273.664967) (xy 261.812718 -273.666962) (xy 261.664245 -273.660978)
			(xy 261.516306 -273.647034) (xy 261.36933 -273.625169) (xy 261.223739 -273.595447) (xy 261.079953 -273.557952)
			(xy 260.938387 -273.512793) (xy 260.799449 -273.460101) (xy 260.66354 -273.400027) (xy 260.531051 -273.332745)
			(xy 260.402365 -273.258448) (xy 260.277852 -273.177351) (xy 260.157872 -273.089687) (xy 260.042771 -272.995709)
			(xy 259.932879 -272.895689) (xy 259.828515 -272.789914) (xy 259.729979 -272.67869) (xy 259.637555 -272.562337)
			(xy 259.55151 -272.44119) (xy 259.472092 -272.3156) (xy 259.399529 -272.185928) (xy 259.334031 -272.052548)
			(xy 259.275787 -271.915845) (xy 259.224965 -271.776212) (xy 259.181711 -271.634053) (xy 259.14615 -271.489776)
			(xy 259.118385 -271.3438) (xy 259.098495 -271.196543) (xy 259.086538 -271.04843) (xy 259.082549 -270.89989)
			(xy 208.516474 -270.89989) (xy 208.515975 -270.974187) (xy 208.507999 -271.122567) (xy 208.49207 -271.270305)
			(xy 208.468234 -271.416974) (xy 208.43656 -271.562153) (xy 208.397138 -271.705423) (xy 208.350083 -271.84637)
			(xy 208.29553 -271.984587) (xy 208.233637 -272.119678) (xy 208.164582 -272.251251) (xy 208.088564 -272.378929)
			(xy 208.005803 -272.502341) (xy 207.916536 -272.621134) (xy 207.821022 -272.734963) (xy 207.719535 -272.843502)
			(xy 207.612368 -272.946437) (xy 207.499831 -273.043471) (xy 207.382248 -273.134324) (xy 207.259958 -273.218735)
			(xy 207.133313 -273.29646) (xy 207.002678 -273.367276) (xy 206.868431 -273.430977) (xy 206.730958 -273.48738)
			(xy 206.590655 -273.536323) (xy 206.447928 -273.577665) (xy 206.303187 -273.611285) (xy 206.156851 -273.637088)
			(xy 206.00934 -273.654999) (xy 205.861081 -273.664967) (xy 205.7125 -273.666962) (xy 205.564027 -273.660978)
			(xy 205.416088 -273.647034) (xy 205.269112 -273.625169) (xy 205.123521 -273.595447) (xy 204.979735 -273.557952)
			(xy 204.838169 -273.512793) (xy 204.699231 -273.460101) (xy 204.563322 -273.400027) (xy 204.430833 -273.332745)
			(xy 204.302147 -273.258448) (xy 204.177634 -273.177351) (xy 204.057654 -273.089687) (xy 203.942553 -272.995709)
			(xy 203.832661 -272.895689) (xy 203.728297 -272.789914) (xy 203.629761 -272.67869) (xy 203.537337 -272.562337)
			(xy 203.451292 -272.44119) (xy 203.371874 -272.3156) (xy 203.299311 -272.185928) (xy 203.233813 -272.052548)
			(xy 203.175569 -271.915845) (xy 203.124747 -271.776212) (xy 203.081493 -271.634053) (xy 203.045932 -271.489776)
			(xy 203.018167 -271.3438) (xy 202.998277 -271.196543) (xy 202.98632 -271.04843) (xy 202.982331 -270.89989)
			(xy 148.516594 -270.89989) (xy 148.516095 -270.974187) (xy 148.508119 -271.122567) (xy 148.49219 -271.270305)
			(xy 148.468354 -271.416974) (xy 148.43668 -271.562153) (xy 148.397258 -271.705423) (xy 148.350203 -271.84637)
			(xy 148.29565 -271.984587) (xy 148.233757 -272.119678) (xy 148.164702 -272.251251) (xy 148.088684 -272.378929)
			(xy 148.005923 -272.502341) (xy 147.916656 -272.621134) (xy 147.821142 -272.734963) (xy 147.719655 -272.843502)
			(xy 147.612488 -272.946437) (xy 147.499951 -273.043471) (xy 147.42707 -273.099784) (xy 160.24404 -273.099784)
			(xy 160.248 -273.05073) (xy 160.259777 -273.002946) (xy 160.279068 -272.95767) (xy 160.305371 -272.916074)
			(xy 160.338006 -272.879237) (xy 160.376127 -272.848112) (xy 160.418748 -272.823505) (xy 160.464764 -272.806053)
			(xy 160.512983 -272.796209) (xy 160.562158 -272.794228) (xy 160.611013 -272.80016) (xy 160.658284 -272.813852)
			(xy 160.702746 -272.83495) (xy 160.743249 -272.862906) (xy 160.778742 -272.896998) (xy 160.808307 -272.936342)
			(xy 160.831178 -272.979919) (xy 160.846762 -273.0266) (xy 160.854657 -273.075177) (xy 160.855152 -273.099784)
			(xy 162.144214 -273.099784) (xy 162.148174 -273.05073) (xy 162.159951 -273.002946) (xy 162.179242 -272.95767)
			(xy 162.205545 -272.916074) (xy 162.23818 -272.879237) (xy 162.276301 -272.848112) (xy 162.318922 -272.823505)
			(xy 162.364938 -272.806053) (xy 162.413157 -272.796209) (xy 162.462332 -272.794228) (xy 162.511187 -272.80016)
			(xy 162.558458 -272.813852) (xy 162.60292 -272.83495) (xy 162.643423 -272.862906) (xy 162.678916 -272.896998)
			(xy 162.708481 -272.936342) (xy 162.731352 -272.979919) (xy 162.746936 -273.0266) (xy 162.754831 -273.075177)
			(xy 162.755326 -273.099784) (xy 164.044134 -273.099784) (xy 164.048094 -273.05073) (xy 164.059871 -273.002946)
			(xy 164.079162 -272.95767) (xy 164.105465 -272.916074) (xy 164.1381 -272.879237) (xy 164.176221 -272.848112)
			(xy 164.218842 -272.823505) (xy 164.264858 -272.806053) (xy 164.313077 -272.796209) (xy 164.362252 -272.794228)
			(xy 164.411107 -272.80016) (xy 164.458378 -272.813852) (xy 164.50284 -272.83495) (xy 164.543343 -272.862906)
			(xy 164.578836 -272.896998) (xy 164.608401 -272.936342) (xy 164.631272 -272.979919) (xy 164.646856 -273.0266)
			(xy 164.654751 -273.075177) (xy 164.655246 -273.099784) (xy 165.944054 -273.099784) (xy 165.948014 -273.05073)
			(xy 165.959791 -273.002946) (xy 165.979082 -272.95767) (xy 166.005385 -272.916074) (xy 166.03802 -272.879237)
			(xy 166.076141 -272.848112) (xy 166.118762 -272.823505) (xy 166.164778 -272.806053) (xy 166.212997 -272.796209)
			(xy 166.262172 -272.794228) (xy 166.311027 -272.80016) (xy 166.358298 -272.813852) (xy 166.40276 -272.83495)
			(xy 166.443263 -272.862906) (xy 166.478756 -272.896998) (xy 166.508321 -272.936342) (xy 166.531192 -272.979919)
			(xy 166.546776 -273.0266) (xy 166.554671 -273.075177) (xy 166.555166 -273.099784) (xy 167.844228 -273.099784)
			(xy 167.848188 -273.05073) (xy 167.859965 -273.002946) (xy 167.879256 -272.95767) (xy 167.905559 -272.916074)
			(xy 167.938194 -272.879237) (xy 167.976315 -272.848112) (xy 168.018936 -272.823505) (xy 168.064952 -272.806053)
			(xy 168.113171 -272.796209) (xy 168.162346 -272.794228) (xy 168.211201 -272.80016) (xy 168.258472 -272.813852)
			(xy 168.302934 -272.83495) (xy 168.343437 -272.862906) (xy 168.37893 -272.896998) (xy 168.408495 -272.936342)
			(xy 168.431366 -272.979919) (xy 168.44695 -273.0266) (xy 168.454845 -273.075177) (xy 168.45534 -273.099784)
			(xy 169.744148 -273.099784) (xy 169.748108 -273.05073) (xy 169.759885 -273.002946) (xy 169.779176 -272.95767)
			(xy 169.805479 -272.916074) (xy 169.838114 -272.879237) (xy 169.876235 -272.848112) (xy 169.918856 -272.823505)
			(xy 169.964872 -272.806053) (xy 170.013091 -272.796209) (xy 170.062266 -272.794228) (xy 170.111121 -272.80016)
			(xy 170.158392 -272.813852) (xy 170.202854 -272.83495) (xy 170.243357 -272.862906) (xy 170.27885 -272.896998)
			(xy 170.308415 -272.936342) (xy 170.331286 -272.979919) (xy 170.34687 -273.0266) (xy 170.354765 -273.075177)
			(xy 170.35526 -273.099784) (xy 171.644068 -273.099784) (xy 171.648028 -273.05073) (xy 171.659805 -273.002946)
			(xy 171.679096 -272.95767) (xy 171.705399 -272.916074) (xy 171.738034 -272.879237) (xy 171.776155 -272.848112)
			(xy 171.818776 -272.823505) (xy 171.864792 -272.806053) (xy 171.913011 -272.796209) (xy 171.962186 -272.794228)
			(xy 172.011041 -272.80016) (xy 172.058312 -272.813852) (xy 172.102774 -272.83495) (xy 172.143277 -272.862906)
			(xy 172.17877 -272.896998) (xy 172.208335 -272.936342) (xy 172.231206 -272.979919) (xy 172.24679 -273.0266)
			(xy 172.254685 -273.075177) (xy 172.25518 -273.099784) (xy 173.544242 -273.099784) (xy 173.548202 -273.05073)
			(xy 173.559979 -273.002946) (xy 173.57927 -272.95767) (xy 173.605573 -272.916074) (xy 173.638208 -272.879237)
			(xy 173.676329 -272.848112) (xy 173.71895 -272.823505) (xy 173.764966 -272.806053) (xy 173.813185 -272.796209)
			(xy 173.86236 -272.794228) (xy 173.911215 -272.80016) (xy 173.958486 -272.813852) (xy 174.002948 -272.83495)
			(xy 174.043451 -272.862906) (xy 174.078944 -272.896998) (xy 174.108509 -272.936342) (xy 174.13138 -272.979919)
			(xy 174.146964 -273.0266) (xy 174.154859 -273.075177) (xy 174.155349 -273.09953) (xy 175.443908 -273.09953)
			(xy 175.447868 -273.050476) (xy 175.459645 -273.002692) (xy 175.478936 -272.957416) (xy 175.505239 -272.91582)
			(xy 175.537874 -272.878983) (xy 175.575995 -272.847858) (xy 175.618616 -272.823251) (xy 175.664632 -272.805799)
			(xy 175.712851 -272.795955) (xy 175.762026 -272.793974) (xy 175.810881 -272.799906) (xy 175.858152 -272.813598)
			(xy 175.902614 -272.834696) (xy 175.943117 -272.862652) (xy 175.97861 -272.896744) (xy 176.008175 -272.936088)
			(xy 176.031046 -272.979665) (xy 176.04663 -273.026346) (xy 176.054525 -273.074923) (xy 176.05502 -273.09953)
			(xy 176.055015 -273.099784) (xy 177.343828 -273.099784) (xy 177.347788 -273.05073) (xy 177.359565 -273.002946)
			(xy 177.378856 -272.95767) (xy 177.405159 -272.916074) (xy 177.437794 -272.879237) (xy 177.475915 -272.848112)
			(xy 177.518536 -272.823505) (xy 177.564552 -272.806053) (xy 177.612771 -272.796209) (xy 177.661946 -272.794228)
			(xy 177.710801 -272.80016) (xy 177.758072 -272.813852) (xy 177.802534 -272.83495) (xy 177.843037 -272.862906)
			(xy 177.87853 -272.896998) (xy 177.908095 -272.936342) (xy 177.930966 -272.979919) (xy 177.94655 -273.0266)
			(xy 177.954445 -273.075177) (xy 177.95494 -273.099784) (xy 179.244002 -273.099784) (xy 179.247962 -273.05073)
			(xy 179.259739 -273.002946) (xy 179.27903 -272.95767) (xy 179.305333 -272.916074) (xy 179.337968 -272.879237)
			(xy 179.376089 -272.848112) (xy 179.41871 -272.823505) (xy 179.464726 -272.806053) (xy 179.512945 -272.796209)
			(xy 179.56212 -272.794228) (xy 179.610975 -272.80016) (xy 179.658246 -272.813852) (xy 179.702708 -272.83495)
			(xy 179.743211 -272.862906) (xy 179.778704 -272.896998) (xy 179.808269 -272.936342) (xy 179.83114 -272.979919)
			(xy 179.846724 -273.0266) (xy 179.854619 -273.075177) (xy 179.855114 -273.099784) (xy 181.143922 -273.099784)
			(xy 181.147882 -273.05073) (xy 181.159659 -273.002946) (xy 181.17895 -272.95767) (xy 181.205253 -272.916074)
			(xy 181.237888 -272.879237) (xy 181.276009 -272.848112) (xy 181.31863 -272.823505) (xy 181.364646 -272.806053)
			(xy 181.412865 -272.796209) (xy 181.46204 -272.794228) (xy 181.510895 -272.80016) (xy 181.558166 -272.813852)
			(xy 181.602628 -272.83495) (xy 181.643131 -272.862906) (xy 181.678624 -272.896998) (xy 181.708189 -272.936342)
			(xy 181.73106 -272.979919) (xy 181.746644 -273.0266) (xy 181.754539 -273.075177) (xy 181.755034 -273.099784)
			(xy 183.043842 -273.099784) (xy 183.047802 -273.05073) (xy 183.059579 -273.002946) (xy 183.07887 -272.95767)
			(xy 183.105173 -272.916074) (xy 183.137808 -272.879237) (xy 183.175929 -272.848112) (xy 183.21855 -272.823505)
			(xy 183.264566 -272.806053) (xy 183.312785 -272.796209) (xy 183.36196 -272.794228) (xy 183.410815 -272.80016)
			(xy 183.458086 -272.813852) (xy 183.502548 -272.83495) (xy 183.543051 -272.862906) (xy 183.578544 -272.896998)
			(xy 183.608109 -272.936342) (xy 183.63098 -272.979919) (xy 183.646564 -273.0266) (xy 183.654459 -273.075177)
			(xy 183.654954 -273.099784) (xy 184.944016 -273.099784) (xy 184.947976 -273.05073) (xy 184.959753 -273.002946)
			(xy 184.979044 -272.95767) (xy 185.005347 -272.916074) (xy 185.037982 -272.879237) (xy 185.076103 -272.848112)
			(xy 185.118724 -272.823505) (xy 185.16474 -272.806053) (xy 185.212959 -272.796209) (xy 185.262134 -272.794228)
			(xy 185.310989 -272.80016) (xy 185.35826 -272.813852) (xy 185.402722 -272.83495) (xy 185.443225 -272.862906)
			(xy 185.478718 -272.896998) (xy 185.508283 -272.936342) (xy 185.531154 -272.979919) (xy 185.546738 -273.0266)
			(xy 185.554633 -273.075177) (xy 185.555128 -273.099784) (xy 186.843936 -273.099784) (xy 186.847896 -273.05073)
			(xy 186.859673 -273.002946) (xy 186.878964 -272.95767) (xy 186.905267 -272.916074) (xy 186.937902 -272.879237)
			(xy 186.976023 -272.848112) (xy 187.018644 -272.823505) (xy 187.06466 -272.806053) (xy 187.112879 -272.796209)
			(xy 187.162054 -272.794228) (xy 187.210909 -272.80016) (xy 187.25818 -272.813852) (xy 187.302642 -272.83495)
			(xy 187.343145 -272.862906) (xy 187.378638 -272.896998) (xy 187.408203 -272.936342) (xy 187.431074 -272.979919)
			(xy 187.446658 -273.0266) (xy 187.454553 -273.075177) (xy 187.455048 -273.099784) (xy 188.743856 -273.099784)
			(xy 188.747816 -273.05073) (xy 188.759593 -273.002946) (xy 188.778884 -272.95767) (xy 188.805187 -272.916074)
			(xy 188.837822 -272.879237) (xy 188.875943 -272.848112) (xy 188.918564 -272.823505) (xy 188.96458 -272.806053)
			(xy 189.012799 -272.796209) (xy 189.061974 -272.794228) (xy 189.110829 -272.80016) (xy 189.1581 -272.813852)
			(xy 189.202562 -272.83495) (xy 189.243065 -272.862906) (xy 189.278558 -272.896998) (xy 189.308123 -272.936342)
			(xy 189.330994 -272.979919) (xy 189.346578 -273.0266) (xy 189.354473 -273.075177) (xy 189.354968 -273.099784)
			(xy 190.64403 -273.099784) (xy 190.64799 -273.05073) (xy 190.659767 -273.002946) (xy 190.679058 -272.95767)
			(xy 190.705361 -272.916074) (xy 190.737996 -272.879237) (xy 190.776117 -272.848112) (xy 190.818738 -272.823505)
			(xy 190.864754 -272.806053) (xy 190.912973 -272.796209) (xy 190.962148 -272.794228) (xy 191.011003 -272.80016)
			(xy 191.058274 -272.813852) (xy 191.102736 -272.83495) (xy 191.143239 -272.862906) (xy 191.178732 -272.896998)
			(xy 191.208297 -272.936342) (xy 191.231168 -272.979919) (xy 191.246752 -273.0266) (xy 191.254647 -273.075177)
			(xy 191.255142 -273.099784) (xy 192.54395 -273.099784) (xy 192.54791 -273.05073) (xy 192.559687 -273.002946)
			(xy 192.578978 -272.95767) (xy 192.605281 -272.916074) (xy 192.637916 -272.879237) (xy 192.676037 -272.848112)
			(xy 192.718658 -272.823505) (xy 192.764674 -272.806053) (xy 192.812893 -272.796209) (xy 192.862068 -272.794228)
			(xy 192.910923 -272.80016) (xy 192.958194 -272.813852) (xy 193.002656 -272.83495) (xy 193.043159 -272.862906)
			(xy 193.078652 -272.896998) (xy 193.108217 -272.936342) (xy 193.131088 -272.979919) (xy 193.146672 -273.0266)
			(xy 193.154567 -273.075177) (xy 193.155062 -273.099784) (xy 194.44387 -273.099784) (xy 194.44783 -273.05073)
			(xy 194.459607 -273.002946) (xy 194.478898 -272.95767) (xy 194.505201 -272.916074) (xy 194.537836 -272.879237)
			(xy 194.575957 -272.848112) (xy 194.618578 -272.823505) (xy 194.664594 -272.806053) (xy 194.712813 -272.796209)
			(xy 194.761988 -272.794228) (xy 194.810843 -272.80016) (xy 194.858114 -272.813852) (xy 194.902576 -272.83495)
			(xy 194.943079 -272.862906) (xy 194.978572 -272.896998) (xy 195.008137 -272.936342) (xy 195.031008 -272.979919)
			(xy 195.046592 -273.0266) (xy 195.054487 -273.075177) (xy 195.054982 -273.099784) (xy 196.34379 -273.099784)
			(xy 196.34775 -273.05073) (xy 196.359527 -273.002946) (xy 196.378818 -272.95767) (xy 196.405121 -272.916074)
			(xy 196.437756 -272.879237) (xy 196.475877 -272.848112) (xy 196.518498 -272.823505) (xy 196.564514 -272.806053)
			(xy 196.612733 -272.796209) (xy 196.661908 -272.794228) (xy 196.710763 -272.80016) (xy 196.758034 -272.813852)
			(xy 196.802496 -272.83495) (xy 196.842999 -272.862906) (xy 196.878492 -272.896998) (xy 196.908057 -272.936342)
			(xy 196.930928 -272.979919) (xy 196.946512 -273.0266) (xy 196.954407 -273.075177) (xy 196.954902 -273.099784)
			(xy 196.954407 -273.124391) (xy 196.946512 -273.172968) (xy 196.930928 -273.219649) (xy 196.908057 -273.263226)
			(xy 196.878492 -273.30257) (xy 196.842999 -273.336662) (xy 196.802496 -273.364618) (xy 196.758034 -273.385716)
			(xy 196.710763 -273.399408) (xy 196.661908 -273.40534) (xy 196.612733 -273.403359) (xy 196.564514 -273.393515)
			(xy 196.518498 -273.376063) (xy 196.475877 -273.351456) (xy 196.437756 -273.320331) (xy 196.405121 -273.283494)
			(xy 196.378818 -273.241898) (xy 196.359527 -273.196622) (xy 196.34775 -273.148838) (xy 196.34379 -273.099784)
			(xy 195.054982 -273.099784) (xy 195.054487 -273.124391) (xy 195.046592 -273.172968) (xy 195.031008 -273.219649)
			(xy 195.008137 -273.263226) (xy 194.978572 -273.30257) (xy 194.943079 -273.336662) (xy 194.902576 -273.364618)
			(xy 194.858114 -273.385716) (xy 194.810843 -273.399408) (xy 194.761988 -273.40534) (xy 194.712813 -273.403359)
			(xy 194.664594 -273.393515) (xy 194.618578 -273.376063) (xy 194.575957 -273.351456) (xy 194.537836 -273.320331)
			(xy 194.505201 -273.283494) (xy 194.478898 -273.241898) (xy 194.459607 -273.196622) (xy 194.44783 -273.148838)
			(xy 194.44387 -273.099784) (xy 193.155062 -273.099784) (xy 193.154567 -273.124391) (xy 193.146672 -273.172968)
			(xy 193.131088 -273.219649) (xy 193.108217 -273.263226) (xy 193.078652 -273.30257) (xy 193.043159 -273.336662)
			(xy 193.002656 -273.364618) (xy 192.958194 -273.385716) (xy 192.910923 -273.399408) (xy 192.862068 -273.40534)
			(xy 192.812893 -273.403359) (xy 192.764674 -273.393515) (xy 192.718658 -273.376063) (xy 192.676037 -273.351456)
			(xy 192.637916 -273.320331) (xy 192.605281 -273.283494) (xy 192.578978 -273.241898) (xy 192.559687 -273.196622)
			(xy 192.54791 -273.148838) (xy 192.54395 -273.099784) (xy 191.255142 -273.099784) (xy 191.254647 -273.124391)
			(xy 191.246752 -273.172968) (xy 191.231168 -273.219649) (xy 191.208297 -273.263226) (xy 191.178732 -273.30257)
			(xy 191.143239 -273.336662) (xy 191.102736 -273.364618) (xy 191.058274 -273.385716) (xy 191.011003 -273.399408)
			(xy 190.962148 -273.40534) (xy 190.912973 -273.403359) (xy 190.864754 -273.393515) (xy 190.818738 -273.376063)
			(xy 190.776117 -273.351456) (xy 190.737996 -273.320331) (xy 190.705361 -273.283494) (xy 190.679058 -273.241898)
			(xy 190.659767 -273.196622) (xy 190.64799 -273.148838) (xy 190.64403 -273.099784) (xy 189.354968 -273.099784)
			(xy 189.354473 -273.124391) (xy 189.346578 -273.172968) (xy 189.330994 -273.219649) (xy 189.308123 -273.263226)
			(xy 189.278558 -273.30257) (xy 189.243065 -273.336662) (xy 189.202562 -273.364618) (xy 189.1581 -273.385716)
			(xy 189.110829 -273.399408) (xy 189.061974 -273.40534) (xy 189.012799 -273.403359) (xy 188.96458 -273.393515)
			(xy 188.918564 -273.376063) (xy 188.875943 -273.351456) (xy 188.837822 -273.320331) (xy 188.805187 -273.283494)
			(xy 188.778884 -273.241898) (xy 188.759593 -273.196622) (xy 188.747816 -273.148838) (xy 188.743856 -273.099784)
			(xy 187.455048 -273.099784) (xy 187.454553 -273.124391) (xy 187.446658 -273.172968) (xy 187.431074 -273.219649)
			(xy 187.408203 -273.263226) (xy 187.378638 -273.30257) (xy 187.343145 -273.336662) (xy 187.302642 -273.364618)
			(xy 187.25818 -273.385716) (xy 187.210909 -273.399408) (xy 187.162054 -273.40534) (xy 187.112879 -273.403359)
			(xy 187.06466 -273.393515) (xy 187.018644 -273.376063) (xy 186.976023 -273.351456) (xy 186.937902 -273.320331)
			(xy 186.905267 -273.283494) (xy 186.878964 -273.241898) (xy 186.859673 -273.196622) (xy 186.847896 -273.148838)
			(xy 186.843936 -273.099784) (xy 185.555128 -273.099784) (xy 185.554633 -273.124391) (xy 185.546738 -273.172968)
			(xy 185.531154 -273.219649) (xy 185.508283 -273.263226) (xy 185.478718 -273.30257) (xy 185.443225 -273.336662)
			(xy 185.402722 -273.364618) (xy 185.35826 -273.385716) (xy 185.310989 -273.399408) (xy 185.262134 -273.40534)
			(xy 185.212959 -273.403359) (xy 185.16474 -273.393515) (xy 185.118724 -273.376063) (xy 185.076103 -273.351456)
			(xy 185.037982 -273.320331) (xy 185.005347 -273.283494) (xy 184.979044 -273.241898) (xy 184.959753 -273.196622)
			(xy 184.947976 -273.148838) (xy 184.944016 -273.099784) (xy 183.654954 -273.099784) (xy 183.654459 -273.124391)
			(xy 183.646564 -273.172968) (xy 183.63098 -273.219649) (xy 183.608109 -273.263226) (xy 183.578544 -273.30257)
			(xy 183.543051 -273.336662) (xy 183.502548 -273.364618) (xy 183.458086 -273.385716) (xy 183.410815 -273.399408)
			(xy 183.36196 -273.40534) (xy 183.312785 -273.403359) (xy 183.264566 -273.393515) (xy 183.21855 -273.376063)
			(xy 183.175929 -273.351456) (xy 183.137808 -273.320331) (xy 183.105173 -273.283494) (xy 183.07887 -273.241898)
			(xy 183.059579 -273.196622) (xy 183.047802 -273.148838) (xy 183.043842 -273.099784) (xy 181.755034 -273.099784)
			(xy 181.754539 -273.124391) (xy 181.746644 -273.172968) (xy 181.73106 -273.219649) (xy 181.708189 -273.263226)
			(xy 181.678624 -273.30257) (xy 181.643131 -273.336662) (xy 181.602628 -273.364618) (xy 181.558166 -273.385716)
			(xy 181.510895 -273.399408) (xy 181.46204 -273.40534) (xy 181.412865 -273.403359) (xy 181.364646 -273.393515)
			(xy 181.31863 -273.376063) (xy 181.276009 -273.351456) (xy 181.237888 -273.320331) (xy 181.205253 -273.283494)
			(xy 181.17895 -273.241898) (xy 181.159659 -273.196622) (xy 181.147882 -273.148838) (xy 181.143922 -273.099784)
			(xy 179.855114 -273.099784) (xy 179.854619 -273.124391) (xy 179.846724 -273.172968) (xy 179.83114 -273.219649)
			(xy 179.808269 -273.263226) (xy 179.778704 -273.30257) (xy 179.743211 -273.336662) (xy 179.702708 -273.364618)
			(xy 179.658246 -273.385716) (xy 179.610975 -273.399408) (xy 179.56212 -273.40534) (xy 179.512945 -273.403359)
			(xy 179.464726 -273.393515) (xy 179.41871 -273.376063) (xy 179.376089 -273.351456) (xy 179.337968 -273.320331)
			(xy 179.305333 -273.283494) (xy 179.27903 -273.241898) (xy 179.259739 -273.196622) (xy 179.247962 -273.148838)
			(xy 179.244002 -273.099784) (xy 177.95494 -273.099784) (xy 177.954445 -273.124391) (xy 177.94655 -273.172968)
			(xy 177.930966 -273.219649) (xy 177.908095 -273.263226) (xy 177.87853 -273.30257) (xy 177.843037 -273.336662)
			(xy 177.802534 -273.364618) (xy 177.758072 -273.385716) (xy 177.710801 -273.399408) (xy 177.661946 -273.40534)
			(xy 177.612771 -273.403359) (xy 177.564552 -273.393515) (xy 177.518536 -273.376063) (xy 177.475915 -273.351456)
			(xy 177.437794 -273.320331) (xy 177.405159 -273.283494) (xy 177.378856 -273.241898) (xy 177.359565 -273.196622)
			(xy 177.347788 -273.148838) (xy 177.343828 -273.099784) (xy 176.055015 -273.099784) (xy 176.054525 -273.124137)
			(xy 176.04663 -273.172714) (xy 176.031046 -273.219395) (xy 176.008175 -273.262972) (xy 175.97861 -273.302316)
			(xy 175.943117 -273.336408) (xy 175.902614 -273.364364) (xy 175.858152 -273.385462) (xy 175.810881 -273.399154)
			(xy 175.762026 -273.405086) (xy 175.712851 -273.403105) (xy 175.664632 -273.393261) (xy 175.618616 -273.375809)
			(xy 175.575995 -273.351202) (xy 175.537874 -273.320077) (xy 175.505239 -273.28324) (xy 175.478936 -273.241644)
			(xy 175.459645 -273.196368) (xy 175.447868 -273.148584) (xy 175.443908 -273.09953) (xy 174.155349 -273.09953)
			(xy 174.155354 -273.099784) (xy 174.154859 -273.124391) (xy 174.146964 -273.172968) (xy 174.13138 -273.219649)
			(xy 174.108509 -273.263226) (xy 174.078944 -273.30257) (xy 174.043451 -273.336662) (xy 174.002948 -273.364618)
			(xy 173.958486 -273.385716) (xy 173.911215 -273.399408) (xy 173.86236 -273.40534) (xy 173.813185 -273.403359)
			(xy 173.764966 -273.393515) (xy 173.71895 -273.376063) (xy 173.676329 -273.351456) (xy 173.638208 -273.320331)
			(xy 173.605573 -273.283494) (xy 173.57927 -273.241898) (xy 173.559979 -273.196622) (xy 173.548202 -273.148838)
			(xy 173.544242 -273.099784) (xy 172.25518 -273.099784) (xy 172.254685 -273.124391) (xy 172.24679 -273.172968)
			(xy 172.231206 -273.219649) (xy 172.208335 -273.263226) (xy 172.17877 -273.30257) (xy 172.143277 -273.336662)
			(xy 172.102774 -273.364618) (xy 172.058312 -273.385716) (xy 172.011041 -273.399408) (xy 171.962186 -273.40534)
			(xy 171.913011 -273.403359) (xy 171.864792 -273.393515) (xy 171.818776 -273.376063) (xy 171.776155 -273.351456)
			(xy 171.738034 -273.320331) (xy 171.705399 -273.283494) (xy 171.679096 -273.241898) (xy 171.659805 -273.196622)
			(xy 171.648028 -273.148838) (xy 171.644068 -273.099784) (xy 170.35526 -273.099784) (xy 170.354765 -273.124391)
			(xy 170.34687 -273.172968) (xy 170.331286 -273.219649) (xy 170.308415 -273.263226) (xy 170.27885 -273.30257)
			(xy 170.243357 -273.336662) (xy 170.202854 -273.364618) (xy 170.158392 -273.385716) (xy 170.111121 -273.399408)
			(xy 170.062266 -273.40534) (xy 170.013091 -273.403359) (xy 169.964872 -273.393515) (xy 169.918856 -273.376063)
			(xy 169.876235 -273.351456) (xy 169.838114 -273.320331) (xy 169.805479 -273.283494) (xy 169.779176 -273.241898)
			(xy 169.759885 -273.196622) (xy 169.748108 -273.148838) (xy 169.744148 -273.099784) (xy 168.45534 -273.099784)
			(xy 168.454845 -273.124391) (xy 168.44695 -273.172968) (xy 168.431366 -273.219649) (xy 168.408495 -273.263226)
			(xy 168.37893 -273.30257) (xy 168.343437 -273.336662) (xy 168.302934 -273.364618) (xy 168.258472 -273.385716)
			(xy 168.211201 -273.399408) (xy 168.162346 -273.40534) (xy 168.113171 -273.403359) (xy 168.064952 -273.393515)
			(xy 168.018936 -273.376063) (xy 167.976315 -273.351456) (xy 167.938194 -273.320331) (xy 167.905559 -273.283494)
			(xy 167.879256 -273.241898) (xy 167.859965 -273.196622) (xy 167.848188 -273.148838) (xy 167.844228 -273.099784)
			(xy 166.555166 -273.099784) (xy 166.554671 -273.124391) (xy 166.546776 -273.172968) (xy 166.531192 -273.219649)
			(xy 166.508321 -273.263226) (xy 166.478756 -273.30257) (xy 166.443263 -273.336662) (xy 166.40276 -273.364618)
			(xy 166.358298 -273.385716) (xy 166.311027 -273.399408) (xy 166.262172 -273.40534) (xy 166.212997 -273.403359)
			(xy 166.164778 -273.393515) (xy 166.118762 -273.376063) (xy 166.076141 -273.351456) (xy 166.03802 -273.320331)
			(xy 166.005385 -273.283494) (xy 165.979082 -273.241898) (xy 165.959791 -273.196622) (xy 165.948014 -273.148838)
			(xy 165.944054 -273.099784) (xy 164.655246 -273.099784) (xy 164.654751 -273.124391) (xy 164.646856 -273.172968)
			(xy 164.631272 -273.219649) (xy 164.608401 -273.263226) (xy 164.578836 -273.30257) (xy 164.543343 -273.336662)
			(xy 164.50284 -273.364618) (xy 164.458378 -273.385716) (xy 164.411107 -273.399408) (xy 164.362252 -273.40534)
			(xy 164.313077 -273.403359) (xy 164.264858 -273.393515) (xy 164.218842 -273.376063) (xy 164.176221 -273.351456)
			(xy 164.1381 -273.320331) (xy 164.105465 -273.283494) (xy 164.079162 -273.241898) (xy 164.059871 -273.196622)
			(xy 164.048094 -273.148838) (xy 164.044134 -273.099784) (xy 162.755326 -273.099784) (xy 162.754831 -273.124391)
			(xy 162.746936 -273.172968) (xy 162.731352 -273.219649) (xy 162.708481 -273.263226) (xy 162.678916 -273.30257)
			(xy 162.643423 -273.336662) (xy 162.60292 -273.364618) (xy 162.558458 -273.385716) (xy 162.511187 -273.399408)
			(xy 162.462332 -273.40534) (xy 162.413157 -273.403359) (xy 162.364938 -273.393515) (xy 162.318922 -273.376063)
			(xy 162.276301 -273.351456) (xy 162.23818 -273.320331) (xy 162.205545 -273.283494) (xy 162.179242 -273.241898)
			(xy 162.159951 -273.196622) (xy 162.148174 -273.148838) (xy 162.144214 -273.099784) (xy 160.855152 -273.099784)
			(xy 160.854657 -273.124391) (xy 160.846762 -273.172968) (xy 160.831178 -273.219649) (xy 160.808307 -273.263226)
			(xy 160.778742 -273.30257) (xy 160.743249 -273.336662) (xy 160.702746 -273.364618) (xy 160.658284 -273.385716)
			(xy 160.611013 -273.399408) (xy 160.562158 -273.40534) (xy 160.512983 -273.403359) (xy 160.464764 -273.393515)
			(xy 160.418748 -273.376063) (xy 160.376127 -273.351456) (xy 160.338006 -273.320331) (xy 160.305371 -273.283494)
			(xy 160.279068 -273.241898) (xy 160.259777 -273.196622) (xy 160.248 -273.148838) (xy 160.24404 -273.099784)
			(xy 147.42707 -273.099784) (xy 147.382368 -273.134324) (xy 147.260078 -273.218735) (xy 147.133433 -273.29646)
			(xy 147.002798 -273.367276) (xy 146.868551 -273.430977) (xy 146.731078 -273.48738) (xy 146.590775 -273.536323)
			(xy 146.448048 -273.577665) (xy 146.303307 -273.611285) (xy 146.156971 -273.637088) (xy 146.00946 -273.654999)
			(xy 145.861201 -273.664967) (xy 145.71262 -273.666962) (xy 145.564147 -273.660978) (xy 145.416208 -273.647034)
			(xy 145.269232 -273.625169) (xy 145.123641 -273.595447) (xy 144.979855 -273.557952) (xy 144.838289 -273.512793)
			(xy 144.699351 -273.460101) (xy 144.563442 -273.400027) (xy 144.430953 -273.332745) (xy 144.302267 -273.258448)
			(xy 144.177754 -273.177351) (xy 144.057774 -273.089687) (xy 143.942673 -272.995709) (xy 143.832781 -272.895689)
			(xy 143.728417 -272.789914) (xy 143.629881 -272.67869) (xy 143.537457 -272.562337) (xy 143.451412 -272.44119)
			(xy 143.371994 -272.3156) (xy 143.299431 -272.185928) (xy 143.233933 -272.052548) (xy 143.175689 -271.915845)
			(xy 143.124867 -271.776212) (xy 143.081613 -271.634053) (xy 143.046052 -271.489776) (xy 143.018287 -271.3438)
			(xy 142.998397 -271.196543) (xy 142.98644 -271.04843) (xy 142.982451 -270.89989) (xy 92.41663 -270.89989)
			(xy 92.416131 -270.974187) (xy 92.408155 -271.122567) (xy 92.392226 -271.270305) (xy 92.36839 -271.416974)
			(xy 92.336716 -271.562153) (xy 92.297294 -271.705423) (xy 92.250239 -271.84637) (xy 92.195686 -271.984587)
			(xy 92.133793 -272.119678) (xy 92.064738 -272.251251) (xy 91.98872 -272.378929) (xy 91.905959 -272.502341)
			(xy 91.816692 -272.621134) (xy 91.721178 -272.734963) (xy 91.619691 -272.843502) (xy 91.512524 -272.946437)
			(xy 91.399987 -273.043471) (xy 91.282404 -273.134324) (xy 91.160114 -273.218735) (xy 91.033469 -273.29646)
			(xy 90.902834 -273.367276) (xy 90.768587 -273.430977) (xy 90.631114 -273.48738) (xy 90.490811 -273.536323)
			(xy 90.348084 -273.577665) (xy 90.203343 -273.611285) (xy 90.057007 -273.637088) (xy 89.909496 -273.654999)
			(xy 89.761237 -273.664967) (xy 89.612656 -273.666962) (xy 89.464183 -273.660978) (xy 89.316244 -273.647034)
			(xy 89.169268 -273.625169) (xy 89.023677 -273.595447) (xy 88.879891 -273.557952) (xy 88.738325 -273.512793)
			(xy 88.599387 -273.460101) (xy 88.463478 -273.400027) (xy 88.330989 -273.332745) (xy 88.202303 -273.258448)
			(xy 88.07779 -273.177351) (xy 87.95781 -273.089687) (xy 87.842709 -272.995709) (xy 87.732817 -272.895689)
			(xy 87.628453 -272.789914) (xy 87.529917 -272.67869) (xy 87.437493 -272.562337) (xy 87.351448 -272.44119)
			(xy 87.27203 -272.3156) (xy 87.199467 -272.185928) (xy 87.133969 -272.052548) (xy 87.075725 -271.915845)
			(xy 87.024903 -271.776212) (xy 86.981649 -271.634053) (xy 86.946088 -271.489776) (xy 86.918323 -271.3438)
			(xy 86.898433 -271.196543) (xy 86.886476 -271.04843) (xy 86.882487 -270.89989) (xy 32.416496 -270.89989)
			(xy 32.415997 -270.974187) (xy 32.408021 -271.122567) (xy 32.392092 -271.270305) (xy 32.368256 -271.416974)
			(xy 32.336582 -271.562153) (xy 32.29716 -271.705423) (xy 32.250105 -271.84637) (xy 32.195552 -271.984587)
			(xy 32.133659 -272.119678) (xy 32.064604 -272.251251) (xy 31.988586 -272.378929) (xy 31.905825 -272.502341)
			(xy 31.816558 -272.621134) (xy 31.721044 -272.734963) (xy 31.619557 -272.843502) (xy 31.51239 -272.946437)
			(xy 31.399853 -273.043471) (xy 31.326972 -273.099784) (xy 44.143942 -273.099784) (xy 44.147902 -273.05073)
			(xy 44.159679 -273.002946) (xy 44.17897 -272.95767) (xy 44.205273 -272.916074) (xy 44.237908 -272.879237)
			(xy 44.276029 -272.848112) (xy 44.31865 -272.823505) (xy 44.364666 -272.806053) (xy 44.412885 -272.796209)
			(xy 44.46206 -272.794228) (xy 44.510915 -272.80016) (xy 44.558186 -272.813852) (xy 44.602648 -272.83495)
			(xy 44.643151 -272.862906) (xy 44.678644 -272.896998) (xy 44.708209 -272.936342) (xy 44.73108 -272.979919)
			(xy 44.746664 -273.0266) (xy 44.754559 -273.075177) (xy 44.755054 -273.099784) (xy 46.044116 -273.099784)
			(xy 46.048076 -273.05073) (xy 46.059853 -273.002946) (xy 46.079144 -272.95767) (xy 46.105447 -272.916074)
			(xy 46.138082 -272.879237) (xy 46.176203 -272.848112) (xy 46.218824 -272.823505) (xy 46.26484 -272.806053)
			(xy 46.313059 -272.796209) (xy 46.362234 -272.794228) (xy 46.411089 -272.80016) (xy 46.45836 -272.813852)
			(xy 46.502822 -272.83495) (xy 46.543325 -272.862906) (xy 46.578818 -272.896998) (xy 46.608383 -272.936342)
			(xy 46.631254 -272.979919) (xy 46.646838 -273.0266) (xy 46.654733 -273.075177) (xy 46.655228 -273.099784)
			(xy 47.944036 -273.099784) (xy 47.947996 -273.05073) (xy 47.959773 -273.002946) (xy 47.979064 -272.95767)
			(xy 48.005367 -272.916074) (xy 48.038002 -272.879237) (xy 48.076123 -272.848112) (xy 48.118744 -272.823505)
			(xy 48.16476 -272.806053) (xy 48.212979 -272.796209) (xy 48.262154 -272.794228) (xy 48.311009 -272.80016)
			(xy 48.35828 -272.813852) (xy 48.402742 -272.83495) (xy 48.443245 -272.862906) (xy 48.478738 -272.896998)
			(xy 48.508303 -272.936342) (xy 48.531174 -272.979919) (xy 48.546758 -273.0266) (xy 48.554653 -273.075177)
			(xy 48.555148 -273.099784) (xy 49.843956 -273.099784) (xy 49.847916 -273.05073) (xy 49.859693 -273.002946)
			(xy 49.878984 -272.95767) (xy 49.905287 -272.916074) (xy 49.937922 -272.879237) (xy 49.976043 -272.848112)
			(xy 50.018664 -272.823505) (xy 50.06468 -272.806053) (xy 50.112899 -272.796209) (xy 50.162074 -272.794228)
			(xy 50.210929 -272.80016) (xy 50.2582 -272.813852) (xy 50.302662 -272.83495) (xy 50.343165 -272.862906)
			(xy 50.378658 -272.896998) (xy 50.408223 -272.936342) (xy 50.431094 -272.979919) (xy 50.446678 -273.0266)
			(xy 50.454573 -273.075177) (xy 50.455068 -273.099784) (xy 51.74413 -273.099784) (xy 51.74809 -273.05073)
			(xy 51.759867 -273.002946) (xy 51.779158 -272.95767) (xy 51.805461 -272.916074) (xy 51.838096 -272.879237)
			(xy 51.876217 -272.848112) (xy 51.918838 -272.823505) (xy 51.964854 -272.806053) (xy 52.013073 -272.796209)
			(xy 52.062248 -272.794228) (xy 52.111103 -272.80016) (xy 52.158374 -272.813852) (xy 52.202836 -272.83495)
			(xy 52.243339 -272.862906) (xy 52.278832 -272.896998) (xy 52.308397 -272.936342) (xy 52.331268 -272.979919)
			(xy 52.346852 -273.0266) (xy 52.354747 -273.075177) (xy 52.355242 -273.099784) (xy 53.64405 -273.099784)
			(xy 53.64801 -273.05073) (xy 53.659787 -273.002946) (xy 53.679078 -272.95767) (xy 53.705381 -272.916074)
			(xy 53.738016 -272.879237) (xy 53.776137 -272.848112) (xy 53.818758 -272.823505) (xy 53.864774 -272.806053)
			(xy 53.912993 -272.796209) (xy 53.962168 -272.794228) (xy 54.011023 -272.80016) (xy 54.058294 -272.813852)
			(xy 54.102756 -272.83495) (xy 54.143259 -272.862906) (xy 54.178752 -272.896998) (xy 54.208317 -272.936342)
			(xy 54.231188 -272.979919) (xy 54.246772 -273.0266) (xy 54.254667 -273.075177) (xy 54.255162 -273.099784)
			(xy 55.54397 -273.099784) (xy 55.54793 -273.05073) (xy 55.559707 -273.002946) (xy 55.578998 -272.95767)
			(xy 55.605301 -272.916074) (xy 55.637936 -272.879237) (xy 55.676057 -272.848112) (xy 55.718678 -272.823505)
			(xy 55.764694 -272.806053) (xy 55.812913 -272.796209) (xy 55.862088 -272.794228) (xy 55.910943 -272.80016)
			(xy 55.958214 -272.813852) (xy 56.002676 -272.83495) (xy 56.043179 -272.862906) (xy 56.078672 -272.896998)
			(xy 56.108237 -272.936342) (xy 56.131108 -272.979919) (xy 56.146692 -273.0266) (xy 56.154587 -273.075177)
			(xy 56.155082 -273.099784) (xy 57.444144 -273.099784) (xy 57.448104 -273.05073) (xy 57.459881 -273.002946)
			(xy 57.479172 -272.95767) (xy 57.505475 -272.916074) (xy 57.53811 -272.879237) (xy 57.576231 -272.848112)
			(xy 57.618852 -272.823505) (xy 57.664868 -272.806053) (xy 57.713087 -272.796209) (xy 57.762262 -272.794228)
			(xy 57.811117 -272.80016) (xy 57.858388 -272.813852) (xy 57.90285 -272.83495) (xy 57.943353 -272.862906)
			(xy 57.978846 -272.896998) (xy 58.008411 -272.936342) (xy 58.031282 -272.979919) (xy 58.046866 -273.0266)
			(xy 58.054761 -273.075177) (xy 58.055251 -273.09953) (xy 59.34381 -273.09953) (xy 59.34777 -273.050476)
			(xy 59.359547 -273.002692) (xy 59.378838 -272.957416) (xy 59.405141 -272.91582) (xy 59.437776 -272.878983)
			(xy 59.475897 -272.847858) (xy 59.518518 -272.823251) (xy 59.564534 -272.805799) (xy 59.612753 -272.795955)
			(xy 59.661928 -272.793974) (xy 59.710783 -272.799906) (xy 59.758054 -272.813598) (xy 59.802516 -272.834696)
			(xy 59.843019 -272.862652) (xy 59.878512 -272.896744) (xy 59.908077 -272.936088) (xy 59.930948 -272.979665)
			(xy 59.946532 -273.026346) (xy 59.954427 -273.074923) (xy 59.954922 -273.09953) (xy 59.954917 -273.099784)
			(xy 61.24373 -273.099784) (xy 61.24769 -273.05073) (xy 61.259467 -273.002946) (xy 61.278758 -272.95767)
			(xy 61.305061 -272.916074) (xy 61.337696 -272.879237) (xy 61.375817 -272.848112) (xy 61.418438 -272.823505)
			(xy 61.464454 -272.806053) (xy 61.512673 -272.796209) (xy 61.561848 -272.794228) (xy 61.610703 -272.80016)
			(xy 61.657974 -272.813852) (xy 61.702436 -272.83495) (xy 61.742939 -272.862906) (xy 61.778432 -272.896998)
			(xy 61.807997 -272.936342) (xy 61.830868 -272.979919) (xy 61.846452 -273.0266) (xy 61.854347 -273.075177)
			(xy 61.854842 -273.099784) (xy 63.143904 -273.099784) (xy 63.147864 -273.05073) (xy 63.159641 -273.002946)
			(xy 63.178932 -272.95767) (xy 63.205235 -272.916074) (xy 63.23787 -272.879237) (xy 63.275991 -272.848112)
			(xy 63.318612 -272.823505) (xy 63.364628 -272.806053) (xy 63.412847 -272.796209) (xy 63.462022 -272.794228)
			(xy 63.510877 -272.80016) (xy 63.558148 -272.813852) (xy 63.60261 -272.83495) (xy 63.643113 -272.862906)
			(xy 63.678606 -272.896998) (xy 63.708171 -272.936342) (xy 63.731042 -272.979919) (xy 63.746626 -273.0266)
			(xy 63.754521 -273.075177) (xy 63.755016 -273.099784) (xy 65.043824 -273.099784) (xy 65.047784 -273.05073)
			(xy 65.059561 -273.002946) (xy 65.078852 -272.95767) (xy 65.105155 -272.916074) (xy 65.13779 -272.879237)
			(xy 65.175911 -272.848112) (xy 65.218532 -272.823505) (xy 65.264548 -272.806053) (xy 65.312767 -272.796209)
			(xy 65.361942 -272.794228) (xy 65.410797 -272.80016) (xy 65.458068 -272.813852) (xy 65.50253 -272.83495)
			(xy 65.543033 -272.862906) (xy 65.578526 -272.896998) (xy 65.608091 -272.936342) (xy 65.630962 -272.979919)
			(xy 65.646546 -273.0266) (xy 65.654441 -273.075177) (xy 65.654936 -273.099784) (xy 66.943744 -273.099784)
			(xy 66.947704 -273.05073) (xy 66.959481 -273.002946) (xy 66.978772 -272.95767) (xy 67.005075 -272.916074)
			(xy 67.03771 -272.879237) (xy 67.075831 -272.848112) (xy 67.118452 -272.823505) (xy 67.164468 -272.806053)
			(xy 67.212687 -272.796209) (xy 67.261862 -272.794228) (xy 67.310717 -272.80016) (xy 67.357988 -272.813852)
			(xy 67.40245 -272.83495) (xy 67.442953 -272.862906) (xy 67.478446 -272.896998) (xy 67.508011 -272.936342)
			(xy 67.530882 -272.979919) (xy 67.546466 -273.0266) (xy 67.554361 -273.075177) (xy 67.554856 -273.099784)
			(xy 68.843918 -273.099784) (xy 68.847878 -273.05073) (xy 68.859655 -273.002946) (xy 68.878946 -272.95767)
			(xy 68.905249 -272.916074) (xy 68.937884 -272.879237) (xy 68.976005 -272.848112) (xy 69.018626 -272.823505)
			(xy 69.064642 -272.806053) (xy 69.112861 -272.796209) (xy 69.162036 -272.794228) (xy 69.210891 -272.80016)
			(xy 69.258162 -272.813852) (xy 69.302624 -272.83495) (xy 69.343127 -272.862906) (xy 69.37862 -272.896998)
			(xy 69.408185 -272.936342) (xy 69.431056 -272.979919) (xy 69.44664 -273.0266) (xy 69.454535 -273.075177)
			(xy 69.45503 -273.099784) (xy 70.743838 -273.099784) (xy 70.747798 -273.05073) (xy 70.759575 -273.002946)
			(xy 70.778866 -272.95767) (xy 70.805169 -272.916074) (xy 70.837804 -272.879237) (xy 70.875925 -272.848112)
			(xy 70.918546 -272.823505) (xy 70.964562 -272.806053) (xy 71.012781 -272.796209) (xy 71.061956 -272.794228)
			(xy 71.110811 -272.80016) (xy 71.158082 -272.813852) (xy 71.202544 -272.83495) (xy 71.243047 -272.862906)
			(xy 71.27854 -272.896998) (xy 71.308105 -272.936342) (xy 71.330976 -272.979919) (xy 71.34656 -273.0266)
			(xy 71.354455 -273.075177) (xy 71.35495 -273.099784) (xy 72.643758 -273.099784) (xy 72.647718 -273.05073)
			(xy 72.659495 -273.002946) (xy 72.678786 -272.95767) (xy 72.705089 -272.916074) (xy 72.737724 -272.879237)
			(xy 72.775845 -272.848112) (xy 72.818466 -272.823505) (xy 72.864482 -272.806053) (xy 72.912701 -272.796209)
			(xy 72.961876 -272.794228) (xy 73.010731 -272.80016) (xy 73.058002 -272.813852) (xy 73.102464 -272.83495)
			(xy 73.142967 -272.862906) (xy 73.17846 -272.896998) (xy 73.208025 -272.936342) (xy 73.230896 -272.979919)
			(xy 73.24648 -273.0266) (xy 73.254375 -273.075177) (xy 73.25487 -273.099784) (xy 74.543932 -273.099784)
			(xy 74.547892 -273.05073) (xy 74.559669 -273.002946) (xy 74.57896 -272.95767) (xy 74.605263 -272.916074)
			(xy 74.637898 -272.879237) (xy 74.676019 -272.848112) (xy 74.71864 -272.823505) (xy 74.764656 -272.806053)
			(xy 74.812875 -272.796209) (xy 74.86205 -272.794228) (xy 74.910905 -272.80016) (xy 74.958176 -272.813852)
			(xy 75.002638 -272.83495) (xy 75.043141 -272.862906) (xy 75.078634 -272.896998) (xy 75.108199 -272.936342)
			(xy 75.13107 -272.979919) (xy 75.146654 -273.0266) (xy 75.154549 -273.075177) (xy 75.155044 -273.099784)
			(xy 76.443852 -273.099784) (xy 76.447812 -273.05073) (xy 76.459589 -273.002946) (xy 76.47888 -272.95767)
			(xy 76.505183 -272.916074) (xy 76.537818 -272.879237) (xy 76.575939 -272.848112) (xy 76.61856 -272.823505)
			(xy 76.664576 -272.806053) (xy 76.712795 -272.796209) (xy 76.76197 -272.794228) (xy 76.810825 -272.80016)
			(xy 76.858096 -272.813852) (xy 76.902558 -272.83495) (xy 76.943061 -272.862906) (xy 76.978554 -272.896998)
			(xy 77.008119 -272.936342) (xy 77.03099 -272.979919) (xy 77.046574 -273.0266) (xy 77.054469 -273.075177)
			(xy 77.054964 -273.099784) (xy 78.343772 -273.099784) (xy 78.347732 -273.05073) (xy 78.359509 -273.002946)
			(xy 78.3788 -272.95767) (xy 78.405103 -272.916074) (xy 78.437738 -272.879237) (xy 78.475859 -272.848112)
			(xy 78.51848 -272.823505) (xy 78.564496 -272.806053) (xy 78.612715 -272.796209) (xy 78.66189 -272.794228)
			(xy 78.710745 -272.80016) (xy 78.758016 -272.813852) (xy 78.802478 -272.83495) (xy 78.842981 -272.862906)
			(xy 78.878474 -272.896998) (xy 78.908039 -272.936342) (xy 78.93091 -272.979919) (xy 78.946494 -273.0266)
			(xy 78.954389 -273.075177) (xy 78.954884 -273.099784) (xy 80.243692 -273.099784) (xy 80.247652 -273.05073)
			(xy 80.259429 -273.002946) (xy 80.27872 -272.95767) (xy 80.305023 -272.916074) (xy 80.337658 -272.879237)
			(xy 80.375779 -272.848112) (xy 80.4184 -272.823505) (xy 80.464416 -272.806053) (xy 80.512635 -272.796209)
			(xy 80.56181 -272.794228) (xy 80.610665 -272.80016) (xy 80.657936 -272.813852) (xy 80.702398 -272.83495)
			(xy 80.742901 -272.862906) (xy 80.778394 -272.896998) (xy 80.807959 -272.936342) (xy 80.83083 -272.979919)
			(xy 80.846414 -273.0266) (xy 80.854309 -273.075177) (xy 80.854804 -273.099784) (xy 80.854309 -273.124391)
			(xy 80.846414 -273.172968) (xy 80.83083 -273.219649) (xy 80.807959 -273.263226) (xy 80.778394 -273.30257)
			(xy 80.742901 -273.336662) (xy 80.702398 -273.364618) (xy 80.657936 -273.385716) (xy 80.610665 -273.399408)
			(xy 80.56181 -273.40534) (xy 80.512635 -273.403359) (xy 80.464416 -273.393515) (xy 80.4184 -273.376063)
			(xy 80.375779 -273.351456) (xy 80.337658 -273.320331) (xy 80.305023 -273.283494) (xy 80.27872 -273.241898)
			(xy 80.259429 -273.196622) (xy 80.247652 -273.148838) (xy 80.243692 -273.099784) (xy 78.954884 -273.099784)
			(xy 78.954389 -273.124391) (xy 78.946494 -273.172968) (xy 78.93091 -273.219649) (xy 78.908039 -273.263226)
			(xy 78.878474 -273.30257) (xy 78.842981 -273.336662) (xy 78.802478 -273.364618) (xy 78.758016 -273.385716)
			(xy 78.710745 -273.399408) (xy 78.66189 -273.40534) (xy 78.612715 -273.403359) (xy 78.564496 -273.393515)
			(xy 78.51848 -273.376063) (xy 78.475859 -273.351456) (xy 78.437738 -273.320331) (xy 78.405103 -273.283494)
			(xy 78.3788 -273.241898) (xy 78.359509 -273.196622) (xy 78.347732 -273.148838) (xy 78.343772 -273.099784)
			(xy 77.054964 -273.099784) (xy 77.054469 -273.124391) (xy 77.046574 -273.172968) (xy 77.03099 -273.219649)
			(xy 77.008119 -273.263226) (xy 76.978554 -273.30257) (xy 76.943061 -273.336662) (xy 76.902558 -273.364618)
			(xy 76.858096 -273.385716) (xy 76.810825 -273.399408) (xy 76.76197 -273.40534) (xy 76.712795 -273.403359)
			(xy 76.664576 -273.393515) (xy 76.61856 -273.376063) (xy 76.575939 -273.351456) (xy 76.537818 -273.320331)
			(xy 76.505183 -273.283494) (xy 76.47888 -273.241898) (xy 76.459589 -273.196622) (xy 76.447812 -273.148838)
			(xy 76.443852 -273.099784) (xy 75.155044 -273.099784) (xy 75.154549 -273.124391) (xy 75.146654 -273.172968)
			(xy 75.13107 -273.219649) (xy 75.108199 -273.263226) (xy 75.078634 -273.30257) (xy 75.043141 -273.336662)
			(xy 75.002638 -273.364618) (xy 74.958176 -273.385716) (xy 74.910905 -273.399408) (xy 74.86205 -273.40534)
			(xy 74.812875 -273.403359) (xy 74.764656 -273.393515) (xy 74.71864 -273.376063) (xy 74.676019 -273.351456)
			(xy 74.637898 -273.320331) (xy 74.605263 -273.283494) (xy 74.57896 -273.241898) (xy 74.559669 -273.196622)
			(xy 74.547892 -273.148838) (xy 74.543932 -273.099784) (xy 73.25487 -273.099784) (xy 73.254375 -273.124391)
			(xy 73.24648 -273.172968) (xy 73.230896 -273.219649) (xy 73.208025 -273.263226) (xy 73.17846 -273.30257)
			(xy 73.142967 -273.336662) (xy 73.102464 -273.364618) (xy 73.058002 -273.385716) (xy 73.010731 -273.399408)
			(xy 72.961876 -273.40534) (xy 72.912701 -273.403359) (xy 72.864482 -273.393515) (xy 72.818466 -273.376063)
			(xy 72.775845 -273.351456) (xy 72.737724 -273.320331) (xy 72.705089 -273.283494) (xy 72.678786 -273.241898)
			(xy 72.659495 -273.196622) (xy 72.647718 -273.148838) (xy 72.643758 -273.099784) (xy 71.35495 -273.099784)
			(xy 71.354455 -273.124391) (xy 71.34656 -273.172968) (xy 71.330976 -273.219649) (xy 71.308105 -273.263226)
			(xy 71.27854 -273.30257) (xy 71.243047 -273.336662) (xy 71.202544 -273.364618) (xy 71.158082 -273.385716)
			(xy 71.110811 -273.399408) (xy 71.061956 -273.40534) (xy 71.012781 -273.403359) (xy 70.964562 -273.393515)
			(xy 70.918546 -273.376063) (xy 70.875925 -273.351456) (xy 70.837804 -273.320331) (xy 70.805169 -273.283494)
			(xy 70.778866 -273.241898) (xy 70.759575 -273.196622) (xy 70.747798 -273.148838) (xy 70.743838 -273.099784)
			(xy 69.45503 -273.099784) (xy 69.454535 -273.124391) (xy 69.44664 -273.172968) (xy 69.431056 -273.219649)
			(xy 69.408185 -273.263226) (xy 69.37862 -273.30257) (xy 69.343127 -273.336662) (xy 69.302624 -273.364618)
			(xy 69.258162 -273.385716) (xy 69.210891 -273.399408) (xy 69.162036 -273.40534) (xy 69.112861 -273.403359)
			(xy 69.064642 -273.393515) (xy 69.018626 -273.376063) (xy 68.976005 -273.351456) (xy 68.937884 -273.320331)
			(xy 68.905249 -273.283494) (xy 68.878946 -273.241898) (xy 68.859655 -273.196622) (xy 68.847878 -273.148838)
			(xy 68.843918 -273.099784) (xy 67.554856 -273.099784) (xy 67.554361 -273.124391) (xy 67.546466 -273.172968)
			(xy 67.530882 -273.219649) (xy 67.508011 -273.263226) (xy 67.478446 -273.30257) (xy 67.442953 -273.336662)
			(xy 67.40245 -273.364618) (xy 67.357988 -273.385716) (xy 67.310717 -273.399408) (xy 67.261862 -273.40534)
			(xy 67.212687 -273.403359) (xy 67.164468 -273.393515) (xy 67.118452 -273.376063) (xy 67.075831 -273.351456)
			(xy 67.03771 -273.320331) (xy 67.005075 -273.283494) (xy 66.978772 -273.241898) (xy 66.959481 -273.196622)
			(xy 66.947704 -273.148838) (xy 66.943744 -273.099784) (xy 65.654936 -273.099784) (xy 65.654441 -273.124391)
			(xy 65.646546 -273.172968) (xy 65.630962 -273.219649) (xy 65.608091 -273.263226) (xy 65.578526 -273.30257)
			(xy 65.543033 -273.336662) (xy 65.50253 -273.364618) (xy 65.458068 -273.385716) (xy 65.410797 -273.399408)
			(xy 65.361942 -273.40534) (xy 65.312767 -273.403359) (xy 65.264548 -273.393515) (xy 65.218532 -273.376063)
			(xy 65.175911 -273.351456) (xy 65.13779 -273.320331) (xy 65.105155 -273.283494) (xy 65.078852 -273.241898)
			(xy 65.059561 -273.196622) (xy 65.047784 -273.148838) (xy 65.043824 -273.099784) (xy 63.755016 -273.099784)
			(xy 63.754521 -273.124391) (xy 63.746626 -273.172968) (xy 63.731042 -273.219649) (xy 63.708171 -273.263226)
			(xy 63.678606 -273.30257) (xy 63.643113 -273.336662) (xy 63.60261 -273.364618) (xy 63.558148 -273.385716)
			(xy 63.510877 -273.399408) (xy 63.462022 -273.40534) (xy 63.412847 -273.403359) (xy 63.364628 -273.393515)
			(xy 63.318612 -273.376063) (xy 63.275991 -273.351456) (xy 63.23787 -273.320331) (xy 63.205235 -273.283494)
			(xy 63.178932 -273.241898) (xy 63.159641 -273.196622) (xy 63.147864 -273.148838) (xy 63.143904 -273.099784)
			(xy 61.854842 -273.099784) (xy 61.854347 -273.124391) (xy 61.846452 -273.172968) (xy 61.830868 -273.219649)
			(xy 61.807997 -273.263226) (xy 61.778432 -273.30257) (xy 61.742939 -273.336662) (xy 61.702436 -273.364618)
			(xy 61.657974 -273.385716) (xy 61.610703 -273.399408) (xy 61.561848 -273.40534) (xy 61.512673 -273.403359)
			(xy 61.464454 -273.393515) (xy 61.418438 -273.376063) (xy 61.375817 -273.351456) (xy 61.337696 -273.320331)
			(xy 61.305061 -273.283494) (xy 61.278758 -273.241898) (xy 61.259467 -273.196622) (xy 61.24769 -273.148838)
			(xy 61.24373 -273.099784) (xy 59.954917 -273.099784) (xy 59.954427 -273.124137) (xy 59.946532 -273.172714)
			(xy 59.930948 -273.219395) (xy 59.908077 -273.262972) (xy 59.878512 -273.302316) (xy 59.843019 -273.336408)
			(xy 59.802516 -273.364364) (xy 59.758054 -273.385462) (xy 59.710783 -273.399154) (xy 59.661928 -273.405086)
			(xy 59.612753 -273.403105) (xy 59.564534 -273.393261) (xy 59.518518 -273.375809) (xy 59.475897 -273.351202)
			(xy 59.437776 -273.320077) (xy 59.405141 -273.28324) (xy 59.378838 -273.241644) (xy 59.359547 -273.196368)
			(xy 59.34777 -273.148584) (xy 59.34381 -273.09953) (xy 58.055251 -273.09953) (xy 58.055256 -273.099784)
			(xy 58.054761 -273.124391) (xy 58.046866 -273.172968) (xy 58.031282 -273.219649) (xy 58.008411 -273.263226)
			(xy 57.978846 -273.30257) (xy 57.943353 -273.336662) (xy 57.90285 -273.364618) (xy 57.858388 -273.385716)
			(xy 57.811117 -273.399408) (xy 57.762262 -273.40534) (xy 57.713087 -273.403359) (xy 57.664868 -273.393515)
			(xy 57.618852 -273.376063) (xy 57.576231 -273.351456) (xy 57.53811 -273.320331) (xy 57.505475 -273.283494)
			(xy 57.479172 -273.241898) (xy 57.459881 -273.196622) (xy 57.448104 -273.148838) (xy 57.444144 -273.099784)
			(xy 56.155082 -273.099784) (xy 56.154587 -273.124391) (xy 56.146692 -273.172968) (xy 56.131108 -273.219649)
			(xy 56.108237 -273.263226) (xy 56.078672 -273.30257) (xy 56.043179 -273.336662) (xy 56.002676 -273.364618)
			(xy 55.958214 -273.385716) (xy 55.910943 -273.399408) (xy 55.862088 -273.40534) (xy 55.812913 -273.403359)
			(xy 55.764694 -273.393515) (xy 55.718678 -273.376063) (xy 55.676057 -273.351456) (xy 55.637936 -273.320331)
			(xy 55.605301 -273.283494) (xy 55.578998 -273.241898) (xy 55.559707 -273.196622) (xy 55.54793 -273.148838)
			(xy 55.54397 -273.099784) (xy 54.255162 -273.099784) (xy 54.254667 -273.124391) (xy 54.246772 -273.172968)
			(xy 54.231188 -273.219649) (xy 54.208317 -273.263226) (xy 54.178752 -273.30257) (xy 54.143259 -273.336662)
			(xy 54.102756 -273.364618) (xy 54.058294 -273.385716) (xy 54.011023 -273.399408) (xy 53.962168 -273.40534)
			(xy 53.912993 -273.403359) (xy 53.864774 -273.393515) (xy 53.818758 -273.376063) (xy 53.776137 -273.351456)
			(xy 53.738016 -273.320331) (xy 53.705381 -273.283494) (xy 53.679078 -273.241898) (xy 53.659787 -273.196622)
			(xy 53.64801 -273.148838) (xy 53.64405 -273.099784) (xy 52.355242 -273.099784) (xy 52.354747 -273.124391)
			(xy 52.346852 -273.172968) (xy 52.331268 -273.219649) (xy 52.308397 -273.263226) (xy 52.278832 -273.30257)
			(xy 52.243339 -273.336662) (xy 52.202836 -273.364618) (xy 52.158374 -273.385716) (xy 52.111103 -273.399408)
			(xy 52.062248 -273.40534) (xy 52.013073 -273.403359) (xy 51.964854 -273.393515) (xy 51.918838 -273.376063)
			(xy 51.876217 -273.351456) (xy 51.838096 -273.320331) (xy 51.805461 -273.283494) (xy 51.779158 -273.241898)
			(xy 51.759867 -273.196622) (xy 51.74809 -273.148838) (xy 51.74413 -273.099784) (xy 50.455068 -273.099784)
			(xy 50.454573 -273.124391) (xy 50.446678 -273.172968) (xy 50.431094 -273.219649) (xy 50.408223 -273.263226)
			(xy 50.378658 -273.30257) (xy 50.343165 -273.336662) (xy 50.302662 -273.364618) (xy 50.2582 -273.385716)
			(xy 50.210929 -273.399408) (xy 50.162074 -273.40534) (xy 50.112899 -273.403359) (xy 50.06468 -273.393515)
			(xy 50.018664 -273.376063) (xy 49.976043 -273.351456) (xy 49.937922 -273.320331) (xy 49.905287 -273.283494)
			(xy 49.878984 -273.241898) (xy 49.859693 -273.196622) (xy 49.847916 -273.148838) (xy 49.843956 -273.099784)
			(xy 48.555148 -273.099784) (xy 48.554653 -273.124391) (xy 48.546758 -273.172968) (xy 48.531174 -273.219649)
			(xy 48.508303 -273.263226) (xy 48.478738 -273.30257) (xy 48.443245 -273.336662) (xy 48.402742 -273.364618)
			(xy 48.35828 -273.385716) (xy 48.311009 -273.399408) (xy 48.262154 -273.40534) (xy 48.212979 -273.403359)
			(xy 48.16476 -273.393515) (xy 48.118744 -273.376063) (xy 48.076123 -273.351456) (xy 48.038002 -273.320331)
			(xy 48.005367 -273.283494) (xy 47.979064 -273.241898) (xy 47.959773 -273.196622) (xy 47.947996 -273.148838)
			(xy 47.944036 -273.099784) (xy 46.655228 -273.099784) (xy 46.654733 -273.124391) (xy 46.646838 -273.172968)
			(xy 46.631254 -273.219649) (xy 46.608383 -273.263226) (xy 46.578818 -273.30257) (xy 46.543325 -273.336662)
			(xy 46.502822 -273.364618) (xy 46.45836 -273.385716) (xy 46.411089 -273.399408) (xy 46.362234 -273.40534)
			(xy 46.313059 -273.403359) (xy 46.26484 -273.393515) (xy 46.218824 -273.376063) (xy 46.176203 -273.351456)
			(xy 46.138082 -273.320331) (xy 46.105447 -273.283494) (xy 46.079144 -273.241898) (xy 46.059853 -273.196622)
			(xy 46.048076 -273.148838) (xy 46.044116 -273.099784) (xy 44.755054 -273.099784) (xy 44.754559 -273.124391)
			(xy 44.746664 -273.172968) (xy 44.73108 -273.219649) (xy 44.708209 -273.263226) (xy 44.678644 -273.30257)
			(xy 44.643151 -273.336662) (xy 44.602648 -273.364618) (xy 44.558186 -273.385716) (xy 44.510915 -273.399408)
			(xy 44.46206 -273.40534) (xy 44.412885 -273.403359) (xy 44.364666 -273.393515) (xy 44.31865 -273.376063)
			(xy 44.276029 -273.351456) (xy 44.237908 -273.320331) (xy 44.205273 -273.283494) (xy 44.17897 -273.241898)
			(xy 44.159679 -273.196622) (xy 44.147902 -273.148838) (xy 44.143942 -273.099784) (xy 31.326972 -273.099784)
			(xy 31.28227 -273.134324) (xy 31.15998 -273.218735) (xy 31.033335 -273.29646) (xy 30.9027 -273.367276)
			(xy 30.768453 -273.430977) (xy 30.63098 -273.48738) (xy 30.490677 -273.536323) (xy 30.34795 -273.577665)
			(xy 30.203209 -273.611285) (xy 30.056873 -273.637088) (xy 29.909362 -273.654999) (xy 29.761103 -273.664967)
			(xy 29.612522 -273.666962) (xy 29.464049 -273.660978) (xy 29.31611 -273.647034) (xy 29.169134 -273.625169)
			(xy 29.023543 -273.595447) (xy 28.879757 -273.557952) (xy 28.738191 -273.512793) (xy 28.599253 -273.460101)
			(xy 28.463344 -273.400027) (xy 28.330855 -273.332745) (xy 28.202169 -273.258448) (xy 28.077656 -273.177351)
			(xy 27.957676 -273.089687) (xy 27.842575 -272.995709) (xy 27.732683 -272.895689) (xy 27.628319 -272.789914)
			(xy 27.529783 -272.67869) (xy 27.437359 -272.562337) (xy 27.351314 -272.44119) (xy 27.271896 -272.3156)
			(xy 27.199333 -272.185928) (xy 27.133835 -272.052548) (xy 27.075591 -271.915845) (xy 27.024769 -271.776212)
			(xy 26.981515 -271.634053) (xy 26.945954 -271.489776) (xy 26.918189 -271.3438) (xy 26.898299 -271.196543)
			(xy 26.886342 -271.04843) (xy 26.882353 -270.89989) (xy 0.508 -270.89989) (xy 0.508 -274.049744)
			(xy 44.143942 -274.049744) (xy 44.147902 -274.00069) (xy 44.159679 -273.952906) (xy 44.17897 -273.90763)
			(xy 44.205273 -273.866034) (xy 44.237908 -273.829197) (xy 44.276029 -273.798072) (xy 44.31865 -273.773465)
			(xy 44.364666 -273.756013) (xy 44.412885 -273.746169) (xy 44.46206 -273.744188) (xy 44.510915 -273.75012)
			(xy 44.558186 -273.763812) (xy 44.602648 -273.78491) (xy 44.643151 -273.812866) (xy 44.678644 -273.846958)
			(xy 44.708209 -273.886302) (xy 44.73108 -273.929879) (xy 44.746664 -273.97656) (xy 44.754559 -274.025137)
			(xy 44.755054 -274.049744) (xy 46.044116 -274.049744) (xy 46.048076 -274.00069) (xy 46.059853 -273.952906)
			(xy 46.079144 -273.90763) (xy 46.105447 -273.866034) (xy 46.138082 -273.829197) (xy 46.176203 -273.798072)
			(xy 46.218824 -273.773465) (xy 46.26484 -273.756013) (xy 46.313059 -273.746169) (xy 46.362234 -273.744188)
			(xy 46.411089 -273.75012) (xy 46.45836 -273.763812) (xy 46.502822 -273.78491) (xy 46.543325 -273.812866)
			(xy 46.578818 -273.846958) (xy 46.608383 -273.886302) (xy 46.631254 -273.929879) (xy 46.646838 -273.97656)
			(xy 46.654733 -274.025137) (xy 46.655228 -274.049744) (xy 47.944036 -274.049744) (xy 47.947996 -274.00069)
			(xy 47.959773 -273.952906) (xy 47.979064 -273.90763) (xy 48.005367 -273.866034) (xy 48.038002 -273.829197)
			(xy 48.076123 -273.798072) (xy 48.118744 -273.773465) (xy 48.16476 -273.756013) (xy 48.212979 -273.746169)
			(xy 48.262154 -273.744188) (xy 48.311009 -273.75012) (xy 48.35828 -273.763812) (xy 48.402742 -273.78491)
			(xy 48.443245 -273.812866) (xy 48.478738 -273.846958) (xy 48.508303 -273.886302) (xy 48.531174 -273.929879)
			(xy 48.546758 -273.97656) (xy 48.554653 -274.025137) (xy 48.555148 -274.049744) (xy 49.843956 -274.049744)
			(xy 49.847916 -274.00069) (xy 49.859693 -273.952906) (xy 49.878984 -273.90763) (xy 49.905287 -273.866034)
			(xy 49.937922 -273.829197) (xy 49.976043 -273.798072) (xy 50.018664 -273.773465) (xy 50.06468 -273.756013)
			(xy 50.112899 -273.746169) (xy 50.162074 -273.744188) (xy 50.210929 -273.75012) (xy 50.2582 -273.763812)
			(xy 50.302662 -273.78491) (xy 50.343165 -273.812866) (xy 50.378658 -273.846958) (xy 50.408223 -273.886302)
			(xy 50.431094 -273.929879) (xy 50.446678 -273.97656) (xy 50.454573 -274.025137) (xy 50.455068 -274.049744)
			(xy 51.74413 -274.049744) (xy 51.74809 -274.00069) (xy 51.759867 -273.952906) (xy 51.779158 -273.90763)
			(xy 51.805461 -273.866034) (xy 51.838096 -273.829197) (xy 51.876217 -273.798072) (xy 51.918838 -273.773465)
			(xy 51.964854 -273.756013) (xy 52.013073 -273.746169) (xy 52.062248 -273.744188) (xy 52.111103 -273.75012)
			(xy 52.158374 -273.763812) (xy 52.202836 -273.78491) (xy 52.243339 -273.812866) (xy 52.278832 -273.846958)
			(xy 52.308397 -273.886302) (xy 52.331268 -273.929879) (xy 52.346852 -273.97656) (xy 52.354747 -274.025137)
			(xy 52.355242 -274.049744) (xy 53.64405 -274.049744) (xy 53.64801 -274.00069) (xy 53.659787 -273.952906)
			(xy 53.679078 -273.90763) (xy 53.705381 -273.866034) (xy 53.738016 -273.829197) (xy 53.776137 -273.798072)
			(xy 53.818758 -273.773465) (xy 53.864774 -273.756013) (xy 53.912993 -273.746169) (xy 53.962168 -273.744188)
			(xy 54.011023 -273.75012) (xy 54.058294 -273.763812) (xy 54.102756 -273.78491) (xy 54.143259 -273.812866)
			(xy 54.178752 -273.846958) (xy 54.208317 -273.886302) (xy 54.231188 -273.929879) (xy 54.246772 -273.97656)
			(xy 54.254667 -274.025137) (xy 54.255162 -274.049744) (xy 55.54397 -274.049744) (xy 55.54793 -274.00069)
			(xy 55.559707 -273.952906) (xy 55.578998 -273.90763) (xy 55.605301 -273.866034) (xy 55.637936 -273.829197)
			(xy 55.676057 -273.798072) (xy 55.718678 -273.773465) (xy 55.764694 -273.756013) (xy 55.812913 -273.746169)
			(xy 55.862088 -273.744188) (xy 55.910943 -273.75012) (xy 55.958214 -273.763812) (xy 56.002676 -273.78491)
			(xy 56.043179 -273.812866) (xy 56.078672 -273.846958) (xy 56.108237 -273.886302) (xy 56.131108 -273.929879)
			(xy 56.146692 -273.97656) (xy 56.154587 -274.025137) (xy 56.155082 -274.049744) (xy 57.444144 -274.049744)
			(xy 57.448104 -274.00069) (xy 57.459881 -273.952906) (xy 57.479172 -273.90763) (xy 57.505475 -273.866034)
			(xy 57.53811 -273.829197) (xy 57.576231 -273.798072) (xy 57.618852 -273.773465) (xy 57.664868 -273.756013)
			(xy 57.713087 -273.746169) (xy 57.762262 -273.744188) (xy 57.811117 -273.75012) (xy 57.858388 -273.763812)
			(xy 57.90285 -273.78491) (xy 57.943353 -273.812866) (xy 57.978846 -273.846958) (xy 58.008411 -273.886302)
			(xy 58.031282 -273.929879) (xy 58.046866 -273.97656) (xy 58.054761 -274.025137) (xy 58.055251 -274.04949)
			(xy 59.34381 -274.04949) (xy 59.34777 -274.000436) (xy 59.359547 -273.952652) (xy 59.378838 -273.907376)
			(xy 59.405141 -273.86578) (xy 59.437776 -273.828943) (xy 59.475897 -273.797818) (xy 59.518518 -273.773211)
			(xy 59.564534 -273.755759) (xy 59.612753 -273.745915) (xy 59.661928 -273.743934) (xy 59.710783 -273.749866)
			(xy 59.758054 -273.763558) (xy 59.802516 -273.784656) (xy 59.843019 -273.812612) (xy 59.878512 -273.846704)
			(xy 59.908077 -273.886048) (xy 59.930948 -273.929625) (xy 59.946532 -273.976306) (xy 59.954427 -274.024883)
			(xy 59.954922 -274.04949) (xy 59.954917 -274.049744) (xy 61.24373 -274.049744) (xy 61.24769 -274.00069)
			(xy 61.259467 -273.952906) (xy 61.278758 -273.90763) (xy 61.305061 -273.866034) (xy 61.337696 -273.829197)
			(xy 61.375817 -273.798072) (xy 61.418438 -273.773465) (xy 61.464454 -273.756013) (xy 61.512673 -273.746169)
			(xy 61.561848 -273.744188) (xy 61.610703 -273.75012) (xy 61.657974 -273.763812) (xy 61.702436 -273.78491)
			(xy 61.742939 -273.812866) (xy 61.778432 -273.846958) (xy 61.807997 -273.886302) (xy 61.830868 -273.929879)
			(xy 61.846452 -273.97656) (xy 61.854347 -274.025137) (xy 61.854842 -274.049744) (xy 63.143904 -274.049744)
			(xy 63.147864 -274.00069) (xy 63.159641 -273.952906) (xy 63.178932 -273.90763) (xy 63.205235 -273.866034)
			(xy 63.23787 -273.829197) (xy 63.275991 -273.798072) (xy 63.318612 -273.773465) (xy 63.364628 -273.756013)
			(xy 63.412847 -273.746169) (xy 63.462022 -273.744188) (xy 63.510877 -273.75012) (xy 63.558148 -273.763812)
			(xy 63.60261 -273.78491) (xy 63.643113 -273.812866) (xy 63.678606 -273.846958) (xy 63.708171 -273.886302)
			(xy 63.731042 -273.929879) (xy 63.746626 -273.97656) (xy 63.754521 -274.025137) (xy 63.755016 -274.049744)
			(xy 65.043824 -274.049744) (xy 65.047784 -274.00069) (xy 65.059561 -273.952906) (xy 65.078852 -273.90763)
			(xy 65.105155 -273.866034) (xy 65.13779 -273.829197) (xy 65.175911 -273.798072) (xy 65.218532 -273.773465)
			(xy 65.264548 -273.756013) (xy 65.312767 -273.746169) (xy 65.361942 -273.744188) (xy 65.410797 -273.75012)
			(xy 65.458068 -273.763812) (xy 65.50253 -273.78491) (xy 65.543033 -273.812866) (xy 65.578526 -273.846958)
			(xy 65.608091 -273.886302) (xy 65.630962 -273.929879) (xy 65.646546 -273.97656) (xy 65.654441 -274.025137)
			(xy 65.654936 -274.049744) (xy 66.943744 -274.049744) (xy 66.947704 -274.00069) (xy 66.959481 -273.952906)
			(xy 66.978772 -273.90763) (xy 67.005075 -273.866034) (xy 67.03771 -273.829197) (xy 67.075831 -273.798072)
			(xy 67.118452 -273.773465) (xy 67.164468 -273.756013) (xy 67.212687 -273.746169) (xy 67.261862 -273.744188)
			(xy 67.310717 -273.75012) (xy 67.357988 -273.763812) (xy 67.40245 -273.78491) (xy 67.442953 -273.812866)
			(xy 67.478446 -273.846958) (xy 67.508011 -273.886302) (xy 67.530882 -273.929879) (xy 67.546466 -273.97656)
			(xy 67.554361 -274.025137) (xy 67.554856 -274.049744) (xy 68.843918 -274.049744) (xy 68.847878 -274.00069)
			(xy 68.859655 -273.952906) (xy 68.878946 -273.90763) (xy 68.905249 -273.866034) (xy 68.937884 -273.829197)
			(xy 68.976005 -273.798072) (xy 69.018626 -273.773465) (xy 69.064642 -273.756013) (xy 69.112861 -273.746169)
			(xy 69.162036 -273.744188) (xy 69.210891 -273.75012) (xy 69.258162 -273.763812) (xy 69.302624 -273.78491)
			(xy 69.343127 -273.812866) (xy 69.37862 -273.846958) (xy 69.408185 -273.886302) (xy 69.431056 -273.929879)
			(xy 69.44664 -273.97656) (xy 69.454535 -274.025137) (xy 69.45503 -274.049744) (xy 70.743838 -274.049744)
			(xy 70.747798 -274.00069) (xy 70.759575 -273.952906) (xy 70.778866 -273.90763) (xy 70.805169 -273.866034)
			(xy 70.837804 -273.829197) (xy 70.875925 -273.798072) (xy 70.918546 -273.773465) (xy 70.964562 -273.756013)
			(xy 71.012781 -273.746169) (xy 71.061956 -273.744188) (xy 71.110811 -273.75012) (xy 71.158082 -273.763812)
			(xy 71.202544 -273.78491) (xy 71.243047 -273.812866) (xy 71.27854 -273.846958) (xy 71.308105 -273.886302)
			(xy 71.330976 -273.929879) (xy 71.34656 -273.97656) (xy 71.354455 -274.025137) (xy 71.35495 -274.049744)
			(xy 72.643758 -274.049744) (xy 72.647718 -274.00069) (xy 72.659495 -273.952906) (xy 72.678786 -273.90763)
			(xy 72.705089 -273.866034) (xy 72.737724 -273.829197) (xy 72.775845 -273.798072) (xy 72.818466 -273.773465)
			(xy 72.864482 -273.756013) (xy 72.912701 -273.746169) (xy 72.961876 -273.744188) (xy 73.010731 -273.75012)
			(xy 73.058002 -273.763812) (xy 73.102464 -273.78491) (xy 73.142967 -273.812866) (xy 73.17846 -273.846958)
			(xy 73.208025 -273.886302) (xy 73.230896 -273.929879) (xy 73.24648 -273.97656) (xy 73.254375 -274.025137)
			(xy 73.25487 -274.049744) (xy 74.543932 -274.049744) (xy 74.547892 -274.00069) (xy 74.559669 -273.952906)
			(xy 74.57896 -273.90763) (xy 74.605263 -273.866034) (xy 74.637898 -273.829197) (xy 74.676019 -273.798072)
			(xy 74.71864 -273.773465) (xy 74.764656 -273.756013) (xy 74.812875 -273.746169) (xy 74.86205 -273.744188)
			(xy 74.910905 -273.75012) (xy 74.958176 -273.763812) (xy 75.002638 -273.78491) (xy 75.043141 -273.812866)
			(xy 75.078634 -273.846958) (xy 75.108199 -273.886302) (xy 75.13107 -273.929879) (xy 75.146654 -273.97656)
			(xy 75.154549 -274.025137) (xy 75.155044 -274.049744) (xy 76.443852 -274.049744) (xy 76.447812 -274.00069)
			(xy 76.459589 -273.952906) (xy 76.47888 -273.90763) (xy 76.505183 -273.866034) (xy 76.537818 -273.829197)
			(xy 76.575939 -273.798072) (xy 76.61856 -273.773465) (xy 76.664576 -273.756013) (xy 76.712795 -273.746169)
			(xy 76.76197 -273.744188) (xy 76.810825 -273.75012) (xy 76.858096 -273.763812) (xy 76.902558 -273.78491)
			(xy 76.943061 -273.812866) (xy 76.978554 -273.846958) (xy 77.008119 -273.886302) (xy 77.03099 -273.929879)
			(xy 77.046574 -273.97656) (xy 77.054469 -274.025137) (xy 77.054964 -274.049744) (xy 78.343772 -274.049744)
			(xy 78.347732 -274.00069) (xy 78.359509 -273.952906) (xy 78.3788 -273.90763) (xy 78.405103 -273.866034)
			(xy 78.437738 -273.829197) (xy 78.475859 -273.798072) (xy 78.51848 -273.773465) (xy 78.564496 -273.756013)
			(xy 78.612715 -273.746169) (xy 78.66189 -273.744188) (xy 78.710745 -273.75012) (xy 78.758016 -273.763812)
			(xy 78.802478 -273.78491) (xy 78.842981 -273.812866) (xy 78.878474 -273.846958) (xy 78.908039 -273.886302)
			(xy 78.93091 -273.929879) (xy 78.946494 -273.97656) (xy 78.954389 -274.025137) (xy 78.954884 -274.049744)
			(xy 80.243692 -274.049744) (xy 80.247652 -274.00069) (xy 80.259429 -273.952906) (xy 80.27872 -273.90763)
			(xy 80.305023 -273.866034) (xy 80.337658 -273.829197) (xy 80.375779 -273.798072) (xy 80.4184 -273.773465)
			(xy 80.464416 -273.756013) (xy 80.512635 -273.746169) (xy 80.56181 -273.744188) (xy 80.610665 -273.75012)
			(xy 80.657936 -273.763812) (xy 80.702398 -273.78491) (xy 80.742901 -273.812866) (xy 80.778394 -273.846958)
			(xy 80.807959 -273.886302) (xy 80.83083 -273.929879) (xy 80.846414 -273.97656) (xy 80.854309 -274.025137)
			(xy 80.854804 -274.049744) (xy 160.24404 -274.049744) (xy 160.248 -274.00069) (xy 160.259777 -273.952906)
			(xy 160.279068 -273.90763) (xy 160.305371 -273.866034) (xy 160.338006 -273.829197) (xy 160.376127 -273.798072)
			(xy 160.418748 -273.773465) (xy 160.464764 -273.756013) (xy 160.512983 -273.746169) (xy 160.562158 -273.744188)
			(xy 160.611013 -273.75012) (xy 160.658284 -273.763812) (xy 160.702746 -273.78491) (xy 160.743249 -273.812866)
			(xy 160.778742 -273.846958) (xy 160.808307 -273.886302) (xy 160.831178 -273.929879) (xy 160.846762 -273.97656)
			(xy 160.854657 -274.025137) (xy 160.855152 -274.049744) (xy 162.144214 -274.049744) (xy 162.148174 -274.00069)
			(xy 162.159951 -273.952906) (xy 162.179242 -273.90763) (xy 162.205545 -273.866034) (xy 162.23818 -273.829197)
			(xy 162.276301 -273.798072) (xy 162.318922 -273.773465) (xy 162.364938 -273.756013) (xy 162.413157 -273.746169)
			(xy 162.462332 -273.744188) (xy 162.511187 -273.75012) (xy 162.558458 -273.763812) (xy 162.60292 -273.78491)
			(xy 162.643423 -273.812866) (xy 162.678916 -273.846958) (xy 162.708481 -273.886302) (xy 162.731352 -273.929879)
			(xy 162.746936 -273.97656) (xy 162.754831 -274.025137) (xy 162.755326 -274.049744) (xy 164.044134 -274.049744)
			(xy 164.048094 -274.00069) (xy 164.059871 -273.952906) (xy 164.079162 -273.90763) (xy 164.105465 -273.866034)
			(xy 164.1381 -273.829197) (xy 164.176221 -273.798072) (xy 164.218842 -273.773465) (xy 164.264858 -273.756013)
			(xy 164.313077 -273.746169) (xy 164.362252 -273.744188) (xy 164.411107 -273.75012) (xy 164.458378 -273.763812)
			(xy 164.50284 -273.78491) (xy 164.543343 -273.812866) (xy 164.578836 -273.846958) (xy 164.608401 -273.886302)
			(xy 164.631272 -273.929879) (xy 164.646856 -273.97656) (xy 164.654751 -274.025137) (xy 164.655246 -274.049744)
			(xy 165.944054 -274.049744) (xy 165.948014 -274.00069) (xy 165.959791 -273.952906) (xy 165.979082 -273.90763)
			(xy 166.005385 -273.866034) (xy 166.03802 -273.829197) (xy 166.076141 -273.798072) (xy 166.118762 -273.773465)
			(xy 166.164778 -273.756013) (xy 166.212997 -273.746169) (xy 166.262172 -273.744188) (xy 166.311027 -273.75012)
			(xy 166.358298 -273.763812) (xy 166.40276 -273.78491) (xy 166.443263 -273.812866) (xy 166.478756 -273.846958)
			(xy 166.508321 -273.886302) (xy 166.531192 -273.929879) (xy 166.546776 -273.97656) (xy 166.554671 -274.025137)
			(xy 166.555166 -274.049744) (xy 167.844228 -274.049744) (xy 167.848188 -274.00069) (xy 167.859965 -273.952906)
			(xy 167.879256 -273.90763) (xy 167.905559 -273.866034) (xy 167.938194 -273.829197) (xy 167.976315 -273.798072)
			(xy 168.018936 -273.773465) (xy 168.064952 -273.756013) (xy 168.113171 -273.746169) (xy 168.162346 -273.744188)
			(xy 168.211201 -273.75012) (xy 168.258472 -273.763812) (xy 168.302934 -273.78491) (xy 168.343437 -273.812866)
			(xy 168.37893 -273.846958) (xy 168.408495 -273.886302) (xy 168.431366 -273.929879) (xy 168.44695 -273.97656)
			(xy 168.454845 -274.025137) (xy 168.45534 -274.049744) (xy 169.744148 -274.049744) (xy 169.748108 -274.00069)
			(xy 169.759885 -273.952906) (xy 169.779176 -273.90763) (xy 169.805479 -273.866034) (xy 169.838114 -273.829197)
			(xy 169.876235 -273.798072) (xy 169.918856 -273.773465) (xy 169.964872 -273.756013) (xy 170.013091 -273.746169)
			(xy 170.062266 -273.744188) (xy 170.111121 -273.75012) (xy 170.158392 -273.763812) (xy 170.202854 -273.78491)
			(xy 170.243357 -273.812866) (xy 170.27885 -273.846958) (xy 170.308415 -273.886302) (xy 170.331286 -273.929879)
			(xy 170.34687 -273.97656) (xy 170.354765 -274.025137) (xy 170.35526 -274.049744) (xy 171.644068 -274.049744)
			(xy 171.648028 -274.00069) (xy 171.659805 -273.952906) (xy 171.679096 -273.90763) (xy 171.705399 -273.866034)
			(xy 171.738034 -273.829197) (xy 171.776155 -273.798072) (xy 171.818776 -273.773465) (xy 171.864792 -273.756013)
			(xy 171.913011 -273.746169) (xy 171.962186 -273.744188) (xy 172.011041 -273.75012) (xy 172.058312 -273.763812)
			(xy 172.102774 -273.78491) (xy 172.143277 -273.812866) (xy 172.17877 -273.846958) (xy 172.208335 -273.886302)
			(xy 172.231206 -273.929879) (xy 172.24679 -273.97656) (xy 172.254685 -274.025137) (xy 172.25518 -274.049744)
			(xy 173.544242 -274.049744) (xy 173.548202 -274.00069) (xy 173.559979 -273.952906) (xy 173.57927 -273.90763)
			(xy 173.605573 -273.866034) (xy 173.638208 -273.829197) (xy 173.676329 -273.798072) (xy 173.71895 -273.773465)
			(xy 173.764966 -273.756013) (xy 173.813185 -273.746169) (xy 173.86236 -273.744188) (xy 173.911215 -273.75012)
			(xy 173.958486 -273.763812) (xy 174.002948 -273.78491) (xy 174.043451 -273.812866) (xy 174.078944 -273.846958)
			(xy 174.108509 -273.886302) (xy 174.13138 -273.929879) (xy 174.146964 -273.97656) (xy 174.154859 -274.025137)
			(xy 174.155349 -274.04949) (xy 175.443908 -274.04949) (xy 175.447868 -274.000436) (xy 175.459645 -273.952652)
			(xy 175.478936 -273.907376) (xy 175.505239 -273.86578) (xy 175.537874 -273.828943) (xy 175.575995 -273.797818)
			(xy 175.618616 -273.773211) (xy 175.664632 -273.755759) (xy 175.712851 -273.745915) (xy 175.762026 -273.743934)
			(xy 175.810881 -273.749866) (xy 175.858152 -273.763558) (xy 175.902614 -273.784656) (xy 175.943117 -273.812612)
			(xy 175.97861 -273.846704) (xy 176.008175 -273.886048) (xy 176.031046 -273.929625) (xy 176.04663 -273.976306)
			(xy 176.054525 -274.024883) (xy 176.05502 -274.04949) (xy 176.055015 -274.049744) (xy 177.343828 -274.049744)
			(xy 177.347788 -274.00069) (xy 177.359565 -273.952906) (xy 177.378856 -273.90763) (xy 177.405159 -273.866034)
			(xy 177.437794 -273.829197) (xy 177.475915 -273.798072) (xy 177.518536 -273.773465) (xy 177.564552 -273.756013)
			(xy 177.612771 -273.746169) (xy 177.661946 -273.744188) (xy 177.710801 -273.75012) (xy 177.758072 -273.763812)
			(xy 177.802534 -273.78491) (xy 177.843037 -273.812866) (xy 177.87853 -273.846958) (xy 177.908095 -273.886302)
			(xy 177.930966 -273.929879) (xy 177.94655 -273.97656) (xy 177.954445 -274.025137) (xy 177.95494 -274.049744)
			(xy 179.244002 -274.049744) (xy 179.247962 -274.00069) (xy 179.259739 -273.952906) (xy 179.27903 -273.90763)
			(xy 179.305333 -273.866034) (xy 179.337968 -273.829197) (xy 179.376089 -273.798072) (xy 179.41871 -273.773465)
			(xy 179.464726 -273.756013) (xy 179.512945 -273.746169) (xy 179.56212 -273.744188) (xy 179.610975 -273.75012)
			(xy 179.658246 -273.763812) (xy 179.702708 -273.78491) (xy 179.743211 -273.812866) (xy 179.778704 -273.846958)
			(xy 179.808269 -273.886302) (xy 179.83114 -273.929879) (xy 179.846724 -273.97656) (xy 179.854619 -274.025137)
			(xy 179.855114 -274.049744) (xy 181.143922 -274.049744) (xy 181.147882 -274.00069) (xy 181.159659 -273.952906)
			(xy 181.17895 -273.90763) (xy 181.205253 -273.866034) (xy 181.237888 -273.829197) (xy 181.276009 -273.798072)
			(xy 181.31863 -273.773465) (xy 181.364646 -273.756013) (xy 181.412865 -273.746169) (xy 181.46204 -273.744188)
			(xy 181.510895 -273.75012) (xy 181.558166 -273.763812) (xy 181.602628 -273.78491) (xy 181.643131 -273.812866)
			(xy 181.678624 -273.846958) (xy 181.708189 -273.886302) (xy 181.73106 -273.929879) (xy 181.746644 -273.97656)
			(xy 181.754539 -274.025137) (xy 181.755034 -274.049744) (xy 183.043842 -274.049744) (xy 183.047802 -274.00069)
			(xy 183.059579 -273.952906) (xy 183.07887 -273.90763) (xy 183.105173 -273.866034) (xy 183.137808 -273.829197)
			(xy 183.175929 -273.798072) (xy 183.21855 -273.773465) (xy 183.264566 -273.756013) (xy 183.312785 -273.746169)
			(xy 183.36196 -273.744188) (xy 183.410815 -273.75012) (xy 183.458086 -273.763812) (xy 183.502548 -273.78491)
			(xy 183.543051 -273.812866) (xy 183.578544 -273.846958) (xy 183.608109 -273.886302) (xy 183.63098 -273.929879)
			(xy 183.646564 -273.97656) (xy 183.654459 -274.025137) (xy 183.654954 -274.049744) (xy 184.944016 -274.049744)
			(xy 184.947976 -274.00069) (xy 184.959753 -273.952906) (xy 184.979044 -273.90763) (xy 185.005347 -273.866034)
			(xy 185.037982 -273.829197) (xy 185.076103 -273.798072) (xy 185.118724 -273.773465) (xy 185.16474 -273.756013)
			(xy 185.212959 -273.746169) (xy 185.262134 -273.744188) (xy 185.310989 -273.75012) (xy 185.35826 -273.763812)
			(xy 185.402722 -273.78491) (xy 185.443225 -273.812866) (xy 185.478718 -273.846958) (xy 185.508283 -273.886302)
			(xy 185.531154 -273.929879) (xy 185.546738 -273.97656) (xy 185.554633 -274.025137) (xy 185.555128 -274.049744)
			(xy 186.843936 -274.049744) (xy 186.847896 -274.00069) (xy 186.859673 -273.952906) (xy 186.878964 -273.90763)
			(xy 186.905267 -273.866034) (xy 186.937902 -273.829197) (xy 186.976023 -273.798072) (xy 187.018644 -273.773465)
			(xy 187.06466 -273.756013) (xy 187.112879 -273.746169) (xy 187.162054 -273.744188) (xy 187.210909 -273.75012)
			(xy 187.25818 -273.763812) (xy 187.302642 -273.78491) (xy 187.343145 -273.812866) (xy 187.378638 -273.846958)
			(xy 187.408203 -273.886302) (xy 187.431074 -273.929879) (xy 187.446658 -273.97656) (xy 187.454553 -274.025137)
			(xy 187.455048 -274.049744) (xy 188.743856 -274.049744) (xy 188.747816 -274.00069) (xy 188.759593 -273.952906)
			(xy 188.778884 -273.90763) (xy 188.805187 -273.866034) (xy 188.837822 -273.829197) (xy 188.875943 -273.798072)
			(xy 188.918564 -273.773465) (xy 188.96458 -273.756013) (xy 189.012799 -273.746169) (xy 189.061974 -273.744188)
			(xy 189.110829 -273.75012) (xy 189.1581 -273.763812) (xy 189.202562 -273.78491) (xy 189.243065 -273.812866)
			(xy 189.278558 -273.846958) (xy 189.308123 -273.886302) (xy 189.330994 -273.929879) (xy 189.346578 -273.97656)
			(xy 189.354473 -274.025137) (xy 189.354968 -274.049744) (xy 190.64403 -274.049744) (xy 190.64799 -274.00069)
			(xy 190.659767 -273.952906) (xy 190.679058 -273.90763) (xy 190.705361 -273.866034) (xy 190.737996 -273.829197)
			(xy 190.776117 -273.798072) (xy 190.818738 -273.773465) (xy 190.864754 -273.756013) (xy 190.912973 -273.746169)
			(xy 190.962148 -273.744188) (xy 191.011003 -273.75012) (xy 191.058274 -273.763812) (xy 191.102736 -273.78491)
			(xy 191.143239 -273.812866) (xy 191.178732 -273.846958) (xy 191.208297 -273.886302) (xy 191.231168 -273.929879)
			(xy 191.246752 -273.97656) (xy 191.254647 -274.025137) (xy 191.255142 -274.049744) (xy 192.54395 -274.049744)
			(xy 192.54791 -274.00069) (xy 192.559687 -273.952906) (xy 192.578978 -273.90763) (xy 192.605281 -273.866034)
			(xy 192.637916 -273.829197) (xy 192.676037 -273.798072) (xy 192.718658 -273.773465) (xy 192.764674 -273.756013)
			(xy 192.812893 -273.746169) (xy 192.862068 -273.744188) (xy 192.910923 -273.75012) (xy 192.958194 -273.763812)
			(xy 193.002656 -273.78491) (xy 193.043159 -273.812866) (xy 193.078652 -273.846958) (xy 193.108217 -273.886302)
			(xy 193.131088 -273.929879) (xy 193.146672 -273.97656) (xy 193.154567 -274.025137) (xy 193.155062 -274.049744)
			(xy 194.44387 -274.049744) (xy 194.44783 -274.00069) (xy 194.459607 -273.952906) (xy 194.478898 -273.90763)
			(xy 194.505201 -273.866034) (xy 194.537836 -273.829197) (xy 194.575957 -273.798072) (xy 194.618578 -273.773465)
			(xy 194.664594 -273.756013) (xy 194.712813 -273.746169) (xy 194.761988 -273.744188) (xy 194.810843 -273.75012)
			(xy 194.858114 -273.763812) (xy 194.902576 -273.78491) (xy 194.943079 -273.812866) (xy 194.978572 -273.846958)
			(xy 195.008137 -273.886302) (xy 195.031008 -273.929879) (xy 195.046592 -273.97656) (xy 195.054487 -274.025137)
			(xy 195.054982 -274.049744) (xy 196.34379 -274.049744) (xy 196.34775 -274.00069) (xy 196.359527 -273.952906)
			(xy 196.378818 -273.90763) (xy 196.405121 -273.866034) (xy 196.437756 -273.829197) (xy 196.475877 -273.798072)
			(xy 196.518498 -273.773465) (xy 196.564514 -273.756013) (xy 196.612733 -273.746169) (xy 196.661908 -273.744188)
			(xy 196.710763 -273.75012) (xy 196.758034 -273.763812) (xy 196.802496 -273.78491) (xy 196.842999 -273.812866)
			(xy 196.878492 -273.846958) (xy 196.908057 -273.886302) (xy 196.930928 -273.929879) (xy 196.946512 -273.97656)
			(xy 196.954407 -274.025137) (xy 196.954902 -274.049744) (xy 276.343884 -274.049744) (xy 276.347844 -274.00069)
			(xy 276.359621 -273.952906) (xy 276.378912 -273.90763) (xy 276.405215 -273.866034) (xy 276.43785 -273.829197)
			(xy 276.475971 -273.798072) (xy 276.518592 -273.773465) (xy 276.564608 -273.756013) (xy 276.612827 -273.746169)
			(xy 276.662002 -273.744188) (xy 276.710857 -273.75012) (xy 276.758128 -273.763812) (xy 276.80259 -273.78491)
			(xy 276.843093 -273.812866) (xy 276.878586 -273.846958) (xy 276.908151 -273.886302) (xy 276.931022 -273.929879)
			(xy 276.946606 -273.97656) (xy 276.954501 -274.025137) (xy 276.954996 -274.049744) (xy 278.244058 -274.049744)
			(xy 278.248018 -274.00069) (xy 278.259795 -273.952906) (xy 278.279086 -273.90763) (xy 278.305389 -273.866034)
			(xy 278.338024 -273.829197) (xy 278.376145 -273.798072) (xy 278.418766 -273.773465) (xy 278.464782 -273.756013)
			(xy 278.513001 -273.746169) (xy 278.562176 -273.744188) (xy 278.611031 -273.75012) (xy 278.658302 -273.763812)
			(xy 278.702764 -273.78491) (xy 278.743267 -273.812866) (xy 278.77876 -273.846958) (xy 278.808325 -273.886302)
			(xy 278.831196 -273.929879) (xy 278.84678 -273.97656) (xy 278.854675 -274.025137) (xy 278.85517 -274.049744)
			(xy 280.143978 -274.049744) (xy 280.147938 -274.00069) (xy 280.159715 -273.952906) (xy 280.179006 -273.90763)
			(xy 280.205309 -273.866034) (xy 280.237944 -273.829197) (xy 280.276065 -273.798072) (xy 280.318686 -273.773465)
			(xy 280.364702 -273.756013) (xy 280.412921 -273.746169) (xy 280.462096 -273.744188) (xy 280.510951 -273.75012)
			(xy 280.558222 -273.763812) (xy 280.602684 -273.78491) (xy 280.643187 -273.812866) (xy 280.67868 -273.846958)
			(xy 280.708245 -273.886302) (xy 280.731116 -273.929879) (xy 280.7467 -273.97656) (xy 280.754595 -274.025137)
			(xy 280.75509 -274.049744) (xy 282.043898 -274.049744) (xy 282.047858 -274.00069) (xy 282.059635 -273.952906)
			(xy 282.078926 -273.90763) (xy 282.105229 -273.866034) (xy 282.137864 -273.829197) (xy 282.175985 -273.798072)
			(xy 282.218606 -273.773465) (xy 282.264622 -273.756013) (xy 282.312841 -273.746169) (xy 282.362016 -273.744188)
			(xy 282.410871 -273.75012) (xy 282.458142 -273.763812) (xy 282.502604 -273.78491) (xy 282.543107 -273.812866)
			(xy 282.5786 -273.846958) (xy 282.608165 -273.886302) (xy 282.631036 -273.929879) (xy 282.64662 -273.97656)
			(xy 282.654515 -274.025137) (xy 282.65501 -274.049744) (xy 283.944072 -274.049744) (xy 283.948032 -274.00069)
			(xy 283.959809 -273.952906) (xy 283.9791 -273.90763) (xy 284.005403 -273.866034) (xy 284.038038 -273.829197)
			(xy 284.076159 -273.798072) (xy 284.11878 -273.773465) (xy 284.164796 -273.756013) (xy 284.213015 -273.746169)
			(xy 284.26219 -273.744188) (xy 284.311045 -273.75012) (xy 284.358316 -273.763812) (xy 284.402778 -273.78491)
			(xy 284.443281 -273.812866) (xy 284.478774 -273.846958) (xy 284.508339 -273.886302) (xy 284.53121 -273.929879)
			(xy 284.546794 -273.97656) (xy 284.554689 -274.025137) (xy 284.555184 -274.049744) (xy 285.843992 -274.049744)
			(xy 285.847952 -274.00069) (xy 285.859729 -273.952906) (xy 285.87902 -273.90763) (xy 285.905323 -273.866034)
			(xy 285.937958 -273.829197) (xy 285.976079 -273.798072) (xy 286.0187 -273.773465) (xy 286.064716 -273.756013)
			(xy 286.112935 -273.746169) (xy 286.16211 -273.744188) (xy 286.210965 -273.75012) (xy 286.258236 -273.763812)
			(xy 286.302698 -273.78491) (xy 286.343201 -273.812866) (xy 286.378694 -273.846958) (xy 286.408259 -273.886302)
			(xy 286.43113 -273.929879) (xy 286.446714 -273.97656) (xy 286.454609 -274.025137) (xy 286.455104 -274.049744)
			(xy 287.743912 -274.049744) (xy 287.747872 -274.00069) (xy 287.759649 -273.952906) (xy 287.77894 -273.90763)
			(xy 287.805243 -273.866034) (xy 287.837878 -273.829197) (xy 287.875999 -273.798072) (xy 287.91862 -273.773465)
			(xy 287.964636 -273.756013) (xy 288.012855 -273.746169) (xy 288.06203 -273.744188) (xy 288.110885 -273.75012)
			(xy 288.158156 -273.763812) (xy 288.202618 -273.78491) (xy 288.243121 -273.812866) (xy 288.278614 -273.846958)
			(xy 288.308179 -273.886302) (xy 288.33105 -273.929879) (xy 288.346634 -273.97656) (xy 288.354529 -274.025137)
			(xy 288.355024 -274.049744) (xy 289.644086 -274.049744) (xy 289.648046 -274.00069) (xy 289.659823 -273.952906)
			(xy 289.679114 -273.90763) (xy 289.705417 -273.866034) (xy 289.738052 -273.829197) (xy 289.776173 -273.798072)
			(xy 289.818794 -273.773465) (xy 289.86481 -273.756013) (xy 289.913029 -273.746169) (xy 289.962204 -273.744188)
			(xy 290.011059 -273.75012) (xy 290.05833 -273.763812) (xy 290.102792 -273.78491) (xy 290.143295 -273.812866)
			(xy 290.178788 -273.846958) (xy 290.208353 -273.886302) (xy 290.231224 -273.929879) (xy 290.246808 -273.97656)
			(xy 290.254703 -274.025137) (xy 290.255193 -274.04949) (xy 291.543752 -274.04949) (xy 291.547712 -274.000436)
			(xy 291.559489 -273.952652) (xy 291.57878 -273.907376) (xy 291.605083 -273.86578) (xy 291.637718 -273.828943)
			(xy 291.675839 -273.797818) (xy 291.71846 -273.773211) (xy 291.764476 -273.755759) (xy 291.812695 -273.745915)
			(xy 291.86187 -273.743934) (xy 291.910725 -273.749866) (xy 291.957996 -273.763558) (xy 292.002458 -273.784656)
			(xy 292.042961 -273.812612) (xy 292.078454 -273.846704) (xy 292.108019 -273.886048) (xy 292.13089 -273.929625)
			(xy 292.146474 -273.976306) (xy 292.154369 -274.024883) (xy 292.154864 -274.04949) (xy 292.154859 -274.049744)
			(xy 293.443672 -274.049744) (xy 293.447632 -274.00069) (xy 293.459409 -273.952906) (xy 293.4787 -273.90763)
			(xy 293.505003 -273.866034) (xy 293.537638 -273.829197) (xy 293.575759 -273.798072) (xy 293.61838 -273.773465)
			(xy 293.664396 -273.756013) (xy 293.712615 -273.746169) (xy 293.76179 -273.744188) (xy 293.810645 -273.75012)
			(xy 293.857916 -273.763812) (xy 293.902378 -273.78491) (xy 293.942881 -273.812866) (xy 293.978374 -273.846958)
			(xy 294.007939 -273.886302) (xy 294.03081 -273.929879) (xy 294.046394 -273.97656) (xy 294.054289 -274.025137)
			(xy 294.054784 -274.049744) (xy 295.343846 -274.049744) (xy 295.347806 -274.00069) (xy 295.359583 -273.952906)
			(xy 295.378874 -273.90763) (xy 295.405177 -273.866034) (xy 295.437812 -273.829197) (xy 295.475933 -273.798072)
			(xy 295.518554 -273.773465) (xy 295.56457 -273.756013) (xy 295.612789 -273.746169) (xy 295.661964 -273.744188)
			(xy 295.710819 -273.75012) (xy 295.75809 -273.763812) (xy 295.802552 -273.78491) (xy 295.843055 -273.812866)
			(xy 295.878548 -273.846958) (xy 295.908113 -273.886302) (xy 295.930984 -273.929879) (xy 295.946568 -273.97656)
			(xy 295.954463 -274.025137) (xy 295.954958 -274.049744) (xy 297.243766 -274.049744) (xy 297.247726 -274.00069)
			(xy 297.259503 -273.952906) (xy 297.278794 -273.90763) (xy 297.305097 -273.866034) (xy 297.337732 -273.829197)
			(xy 297.375853 -273.798072) (xy 297.418474 -273.773465) (xy 297.46449 -273.756013) (xy 297.512709 -273.746169)
			(xy 297.561884 -273.744188) (xy 297.610739 -273.75012) (xy 297.65801 -273.763812) (xy 297.702472 -273.78491)
			(xy 297.742975 -273.812866) (xy 297.778468 -273.846958) (xy 297.808033 -273.886302) (xy 297.830904 -273.929879)
			(xy 297.846488 -273.97656) (xy 297.854383 -274.025137) (xy 297.854878 -274.049744) (xy 299.143686 -274.049744)
			(xy 299.147646 -274.00069) (xy 299.159423 -273.952906) (xy 299.178714 -273.90763) (xy 299.205017 -273.866034)
			(xy 299.237652 -273.829197) (xy 299.275773 -273.798072) (xy 299.318394 -273.773465) (xy 299.36441 -273.756013)
			(xy 299.412629 -273.746169) (xy 299.461804 -273.744188) (xy 299.510659 -273.75012) (xy 299.55793 -273.763812)
			(xy 299.602392 -273.78491) (xy 299.642895 -273.812866) (xy 299.678388 -273.846958) (xy 299.707953 -273.886302)
			(xy 299.730824 -273.929879) (xy 299.746408 -273.97656) (xy 299.754303 -274.025137) (xy 299.754798 -274.049744)
			(xy 301.04386 -274.049744) (xy 301.04782 -274.00069) (xy 301.059597 -273.952906) (xy 301.078888 -273.90763)
			(xy 301.105191 -273.866034) (xy 301.137826 -273.829197) (xy 301.175947 -273.798072) (xy 301.218568 -273.773465)
			(xy 301.264584 -273.756013) (xy 301.312803 -273.746169) (xy 301.361978 -273.744188) (xy 301.410833 -273.75012)
			(xy 301.458104 -273.763812) (xy 301.502566 -273.78491) (xy 301.543069 -273.812866) (xy 301.578562 -273.846958)
			(xy 301.608127 -273.886302) (xy 301.630998 -273.929879) (xy 301.646582 -273.97656) (xy 301.654477 -274.025137)
			(xy 301.654972 -274.049744) (xy 302.94378 -274.049744) (xy 302.94774 -274.00069) (xy 302.959517 -273.952906)
			(xy 302.978808 -273.90763) (xy 303.005111 -273.866034) (xy 303.037746 -273.829197) (xy 303.075867 -273.798072)
			(xy 303.118488 -273.773465) (xy 303.164504 -273.756013) (xy 303.212723 -273.746169) (xy 303.261898 -273.744188)
			(xy 303.310753 -273.75012) (xy 303.358024 -273.763812) (xy 303.402486 -273.78491) (xy 303.442989 -273.812866)
			(xy 303.478482 -273.846958) (xy 303.508047 -273.886302) (xy 303.530918 -273.929879) (xy 303.546502 -273.97656)
			(xy 303.554397 -274.025137) (xy 303.554892 -274.049744) (xy 304.8437 -274.049744) (xy 304.84766 -274.00069)
			(xy 304.859437 -273.952906) (xy 304.878728 -273.90763) (xy 304.905031 -273.866034) (xy 304.937666 -273.829197)
			(xy 304.975787 -273.798072) (xy 305.018408 -273.773465) (xy 305.064424 -273.756013) (xy 305.112643 -273.746169)
			(xy 305.161818 -273.744188) (xy 305.210673 -273.75012) (xy 305.257944 -273.763812) (xy 305.302406 -273.78491)
			(xy 305.342909 -273.812866) (xy 305.378402 -273.846958) (xy 305.407967 -273.886302) (xy 305.430838 -273.929879)
			(xy 305.446422 -273.97656) (xy 305.454317 -274.025137) (xy 305.454812 -274.049744) (xy 306.743874 -274.049744)
			(xy 306.747834 -274.00069) (xy 306.759611 -273.952906) (xy 306.778902 -273.90763) (xy 306.805205 -273.866034)
			(xy 306.83784 -273.829197) (xy 306.875961 -273.798072) (xy 306.918582 -273.773465) (xy 306.964598 -273.756013)
			(xy 307.012817 -273.746169) (xy 307.061992 -273.744188) (xy 307.110847 -273.75012) (xy 307.158118 -273.763812)
			(xy 307.20258 -273.78491) (xy 307.243083 -273.812866) (xy 307.278576 -273.846958) (xy 307.308141 -273.886302)
			(xy 307.331012 -273.929879) (xy 307.346596 -273.97656) (xy 307.354491 -274.025137) (xy 307.354986 -274.049744)
			(xy 308.643794 -274.049744) (xy 308.647754 -274.00069) (xy 308.659531 -273.952906) (xy 308.678822 -273.90763)
			(xy 308.705125 -273.866034) (xy 308.73776 -273.829197) (xy 308.775881 -273.798072) (xy 308.818502 -273.773465)
			(xy 308.864518 -273.756013) (xy 308.912737 -273.746169) (xy 308.961912 -273.744188) (xy 309.010767 -273.75012)
			(xy 309.058038 -273.763812) (xy 309.1025 -273.78491) (xy 309.143003 -273.812866) (xy 309.178496 -273.846958)
			(xy 309.208061 -273.886302) (xy 309.230932 -273.929879) (xy 309.246516 -273.97656) (xy 309.254411 -274.025137)
			(xy 309.254906 -274.049744) (xy 310.543714 -274.049744) (xy 310.547674 -274.00069) (xy 310.559451 -273.952906)
			(xy 310.578742 -273.90763) (xy 310.605045 -273.866034) (xy 310.63768 -273.829197) (xy 310.675801 -273.798072)
			(xy 310.718422 -273.773465) (xy 310.764438 -273.756013) (xy 310.812657 -273.746169) (xy 310.861832 -273.744188)
			(xy 310.910687 -273.75012) (xy 310.957958 -273.763812) (xy 311.00242 -273.78491) (xy 311.042923 -273.812866)
			(xy 311.078416 -273.846958) (xy 311.107981 -273.886302) (xy 311.130852 -273.929879) (xy 311.146436 -273.97656)
			(xy 311.154331 -274.025137) (xy 311.154826 -274.049744) (xy 312.443634 -274.049744) (xy 312.447594 -274.00069)
			(xy 312.459371 -273.952906) (xy 312.478662 -273.90763) (xy 312.504965 -273.866034) (xy 312.5376 -273.829197)
			(xy 312.575721 -273.798072) (xy 312.618342 -273.773465) (xy 312.664358 -273.756013) (xy 312.712577 -273.746169)
			(xy 312.761752 -273.744188) (xy 312.810607 -273.75012) (xy 312.857878 -273.763812) (xy 312.90234 -273.78491)
			(xy 312.942843 -273.812866) (xy 312.978336 -273.846958) (xy 313.007901 -273.886302) (xy 313.030772 -273.929879)
			(xy 313.046356 -273.97656) (xy 313.054251 -274.025137) (xy 313.054746 -274.049744) (xy 392.443982 -274.049744)
			(xy 392.447942 -274.00069) (xy 392.459719 -273.952906) (xy 392.47901 -273.90763) (xy 392.505313 -273.866034)
			(xy 392.537948 -273.829197) (xy 392.576069 -273.798072) (xy 392.61869 -273.773465) (xy 392.664706 -273.756013)
			(xy 392.712925 -273.746169) (xy 392.7621 -273.744188) (xy 392.810955 -273.75012) (xy 392.858226 -273.763812)
			(xy 392.902688 -273.78491) (xy 392.943191 -273.812866) (xy 392.978684 -273.846958) (xy 393.008249 -273.886302)
			(xy 393.03112 -273.929879) (xy 393.046704 -273.97656) (xy 393.054599 -274.025137) (xy 393.055094 -274.049744)
			(xy 394.344156 -274.049744) (xy 394.348116 -274.00069) (xy 394.359893 -273.952906) (xy 394.379184 -273.90763)
			(xy 394.405487 -273.866034) (xy 394.438122 -273.829197) (xy 394.476243 -273.798072) (xy 394.518864 -273.773465)
			(xy 394.56488 -273.756013) (xy 394.613099 -273.746169) (xy 394.662274 -273.744188) (xy 394.711129 -273.75012)
			(xy 394.7584 -273.763812) (xy 394.802862 -273.78491) (xy 394.843365 -273.812866) (xy 394.878858 -273.846958)
			(xy 394.908423 -273.886302) (xy 394.931294 -273.929879) (xy 394.946878 -273.97656) (xy 394.954773 -274.025137)
			(xy 394.955268 -274.049744) (xy 396.244076 -274.049744) (xy 396.248036 -274.00069) (xy 396.259813 -273.952906)
			(xy 396.279104 -273.90763) (xy 396.305407 -273.866034) (xy 396.338042 -273.829197) (xy 396.376163 -273.798072)
			(xy 396.418784 -273.773465) (xy 396.4648 -273.756013) (xy 396.513019 -273.746169) (xy 396.562194 -273.744188)
			(xy 396.611049 -273.75012) (xy 396.65832 -273.763812) (xy 396.702782 -273.78491) (xy 396.743285 -273.812866)
			(xy 396.778778 -273.846958) (xy 396.808343 -273.886302) (xy 396.831214 -273.929879) (xy 396.846798 -273.97656)
			(xy 396.854693 -274.025137) (xy 396.855188 -274.049744) (xy 398.143996 -274.049744) (xy 398.147956 -274.00069)
			(xy 398.159733 -273.952906) (xy 398.179024 -273.90763) (xy 398.205327 -273.866034) (xy 398.237962 -273.829197)
			(xy 398.276083 -273.798072) (xy 398.318704 -273.773465) (xy 398.36472 -273.756013) (xy 398.412939 -273.746169)
			(xy 398.462114 -273.744188) (xy 398.510969 -273.75012) (xy 398.55824 -273.763812) (xy 398.602702 -273.78491)
			(xy 398.643205 -273.812866) (xy 398.678698 -273.846958) (xy 398.708263 -273.886302) (xy 398.731134 -273.929879)
			(xy 398.746718 -273.97656) (xy 398.754613 -274.025137) (xy 398.755108 -274.049744) (xy 400.04417 -274.049744)
			(xy 400.04813 -274.00069) (xy 400.059907 -273.952906) (xy 400.079198 -273.90763) (xy 400.105501 -273.866034)
			(xy 400.138136 -273.829197) (xy 400.176257 -273.798072) (xy 400.218878 -273.773465) (xy 400.264894 -273.756013)
			(xy 400.313113 -273.746169) (xy 400.362288 -273.744188) (xy 400.411143 -273.75012) (xy 400.458414 -273.763812)
			(xy 400.502876 -273.78491) (xy 400.543379 -273.812866) (xy 400.578872 -273.846958) (xy 400.608437 -273.886302)
			(xy 400.631308 -273.929879) (xy 400.646892 -273.97656) (xy 400.654787 -274.025137) (xy 400.655282 -274.049744)
			(xy 401.94409 -274.049744) (xy 401.94805 -274.00069) (xy 401.959827 -273.952906) (xy 401.979118 -273.90763)
			(xy 402.005421 -273.866034) (xy 402.038056 -273.829197) (xy 402.076177 -273.798072) (xy 402.118798 -273.773465)
			(xy 402.164814 -273.756013) (xy 402.213033 -273.746169) (xy 402.262208 -273.744188) (xy 402.311063 -273.75012)
			(xy 402.358334 -273.763812) (xy 402.402796 -273.78491) (xy 402.443299 -273.812866) (xy 402.478792 -273.846958)
			(xy 402.508357 -273.886302) (xy 402.531228 -273.929879) (xy 402.546812 -273.97656) (xy 402.554707 -274.025137)
			(xy 402.555202 -274.049744) (xy 403.84401 -274.049744) (xy 403.84797 -274.00069) (xy 403.859747 -273.952906)
			(xy 403.879038 -273.90763) (xy 403.905341 -273.866034) (xy 403.937976 -273.829197) (xy 403.976097 -273.798072)
			(xy 404.018718 -273.773465) (xy 404.064734 -273.756013) (xy 404.112953 -273.746169) (xy 404.162128 -273.744188)
			(xy 404.210983 -273.75012) (xy 404.258254 -273.763812) (xy 404.302716 -273.78491) (xy 404.343219 -273.812866)
			(xy 404.378712 -273.846958) (xy 404.408277 -273.886302) (xy 404.431148 -273.929879) (xy 404.446732 -273.97656)
			(xy 404.454627 -274.025137) (xy 404.455122 -274.049744) (xy 405.744184 -274.049744) (xy 405.748144 -274.00069)
			(xy 405.759921 -273.952906) (xy 405.779212 -273.90763) (xy 405.805515 -273.866034) (xy 405.83815 -273.829197)
			(xy 405.876271 -273.798072) (xy 405.918892 -273.773465) (xy 405.964908 -273.756013) (xy 406.013127 -273.746169)
			(xy 406.062302 -273.744188) (xy 406.111157 -273.75012) (xy 406.158428 -273.763812) (xy 406.20289 -273.78491)
			(xy 406.243393 -273.812866) (xy 406.278886 -273.846958) (xy 406.308451 -273.886302) (xy 406.331322 -273.929879)
			(xy 406.346906 -273.97656) (xy 406.354801 -274.025137) (xy 406.355291 -274.04949) (xy 407.64385 -274.04949)
			(xy 407.64781 -274.000436) (xy 407.659587 -273.952652) (xy 407.678878 -273.907376) (xy 407.705181 -273.86578)
			(xy 407.737816 -273.828943) (xy 407.775937 -273.797818) (xy 407.818558 -273.773211) (xy 407.864574 -273.755759)
			(xy 407.912793 -273.745915) (xy 407.961968 -273.743934) (xy 408.010823 -273.749866) (xy 408.058094 -273.763558)
			(xy 408.102556 -273.784656) (xy 408.143059 -273.812612) (xy 408.178552 -273.846704) (xy 408.208117 -273.886048)
			(xy 408.230988 -273.929625) (xy 408.246572 -273.976306) (xy 408.254467 -274.024883) (xy 408.254962 -274.04949)
			(xy 408.254957 -274.049744) (xy 409.54377 -274.049744) (xy 409.54773 -274.00069) (xy 409.559507 -273.952906)
			(xy 409.578798 -273.90763) (xy 409.605101 -273.866034) (xy 409.637736 -273.829197) (xy 409.675857 -273.798072)
			(xy 409.718478 -273.773465) (xy 409.764494 -273.756013) (xy 409.812713 -273.746169) (xy 409.861888 -273.744188)
			(xy 409.910743 -273.75012) (xy 409.958014 -273.763812) (xy 410.002476 -273.78491) (xy 410.042979 -273.812866)
			(xy 410.078472 -273.846958) (xy 410.108037 -273.886302) (xy 410.130908 -273.929879) (xy 410.146492 -273.97656)
			(xy 410.154387 -274.025137) (xy 410.154882 -274.049744) (xy 411.443944 -274.049744) (xy 411.447904 -274.00069)
			(xy 411.459681 -273.952906) (xy 411.478972 -273.90763) (xy 411.505275 -273.866034) (xy 411.53791 -273.829197)
			(xy 411.576031 -273.798072) (xy 411.618652 -273.773465) (xy 411.664668 -273.756013) (xy 411.712887 -273.746169)
			(xy 411.762062 -273.744188) (xy 411.810917 -273.75012) (xy 411.858188 -273.763812) (xy 411.90265 -273.78491)
			(xy 411.943153 -273.812866) (xy 411.978646 -273.846958) (xy 412.008211 -273.886302) (xy 412.031082 -273.929879)
			(xy 412.046666 -273.97656) (xy 412.054561 -274.025137) (xy 412.055056 -274.049744) (xy 413.343864 -274.049744)
			(xy 413.347824 -274.00069) (xy 413.359601 -273.952906) (xy 413.378892 -273.90763) (xy 413.405195 -273.866034)
			(xy 413.43783 -273.829197) (xy 413.475951 -273.798072) (xy 413.518572 -273.773465) (xy 413.564588 -273.756013)
			(xy 413.612807 -273.746169) (xy 413.661982 -273.744188) (xy 413.710837 -273.75012) (xy 413.758108 -273.763812)
			(xy 413.80257 -273.78491) (xy 413.843073 -273.812866) (xy 413.878566 -273.846958) (xy 413.908131 -273.886302)
			(xy 413.931002 -273.929879) (xy 413.946586 -273.97656) (xy 413.954481 -274.025137) (xy 413.954976 -274.049744)
			(xy 415.243784 -274.049744) (xy 415.247744 -274.00069) (xy 415.259521 -273.952906) (xy 415.278812 -273.90763)
			(xy 415.305115 -273.866034) (xy 415.33775 -273.829197) (xy 415.375871 -273.798072) (xy 415.418492 -273.773465)
			(xy 415.464508 -273.756013) (xy 415.512727 -273.746169) (xy 415.561902 -273.744188) (xy 415.610757 -273.75012)
			(xy 415.658028 -273.763812) (xy 415.70249 -273.78491) (xy 415.742993 -273.812866) (xy 415.778486 -273.846958)
			(xy 415.808051 -273.886302) (xy 415.830922 -273.929879) (xy 415.846506 -273.97656) (xy 415.854401 -274.025137)
			(xy 415.854896 -274.049744) (xy 417.143958 -274.049744) (xy 417.147918 -274.00069) (xy 417.159695 -273.952906)
			(xy 417.178986 -273.90763) (xy 417.205289 -273.866034) (xy 417.237924 -273.829197) (xy 417.276045 -273.798072)
			(xy 417.318666 -273.773465) (xy 417.364682 -273.756013) (xy 417.412901 -273.746169) (xy 417.462076 -273.744188)
			(xy 417.510931 -273.75012) (xy 417.558202 -273.763812) (xy 417.602664 -273.78491) (xy 417.643167 -273.812866)
			(xy 417.67866 -273.846958) (xy 417.708225 -273.886302) (xy 417.731096 -273.929879) (xy 417.74668 -273.97656)
			(xy 417.754575 -274.025137) (xy 417.75507 -274.049744) (xy 419.043878 -274.049744) (xy 419.047838 -274.00069)
			(xy 419.059615 -273.952906) (xy 419.078906 -273.90763) (xy 419.105209 -273.866034) (xy 419.137844 -273.829197)
			(xy 419.175965 -273.798072) (xy 419.218586 -273.773465) (xy 419.264602 -273.756013) (xy 419.312821 -273.746169)
			(xy 419.361996 -273.744188) (xy 419.410851 -273.75012) (xy 419.458122 -273.763812) (xy 419.502584 -273.78491)
			(xy 419.543087 -273.812866) (xy 419.57858 -273.846958) (xy 419.608145 -273.886302) (xy 419.631016 -273.929879)
			(xy 419.6466 -273.97656) (xy 419.654495 -274.025137) (xy 419.65499 -274.049744) (xy 420.943798 -274.049744)
			(xy 420.947758 -274.00069) (xy 420.959535 -273.952906) (xy 420.978826 -273.90763) (xy 421.005129 -273.866034)
			(xy 421.037764 -273.829197) (xy 421.075885 -273.798072) (xy 421.118506 -273.773465) (xy 421.164522 -273.756013)
			(xy 421.212741 -273.746169) (xy 421.261916 -273.744188) (xy 421.310771 -273.75012) (xy 421.358042 -273.763812)
			(xy 421.402504 -273.78491) (xy 421.443007 -273.812866) (xy 421.4785 -273.846958) (xy 421.508065 -273.886302)
			(xy 421.530936 -273.929879) (xy 421.54652 -273.97656) (xy 421.554415 -274.025137) (xy 421.55491 -274.049744)
			(xy 422.843972 -274.049744) (xy 422.847932 -274.00069) (xy 422.859709 -273.952906) (xy 422.879 -273.90763)
			(xy 422.905303 -273.866034) (xy 422.937938 -273.829197) (xy 422.976059 -273.798072) (xy 423.01868 -273.773465)
			(xy 423.064696 -273.756013) (xy 423.112915 -273.746169) (xy 423.16209 -273.744188) (xy 423.210945 -273.75012)
			(xy 423.258216 -273.763812) (xy 423.302678 -273.78491) (xy 423.343181 -273.812866) (xy 423.378674 -273.846958)
			(xy 423.408239 -273.886302) (xy 423.43111 -273.929879) (xy 423.446694 -273.97656) (xy 423.454589 -274.025137)
			(xy 423.455084 -274.049744) (xy 424.743892 -274.049744) (xy 424.747852 -274.00069) (xy 424.759629 -273.952906)
			(xy 424.77892 -273.90763) (xy 424.805223 -273.866034) (xy 424.837858 -273.829197) (xy 424.875979 -273.798072)
			(xy 424.9186 -273.773465) (xy 424.964616 -273.756013) (xy 425.012835 -273.746169) (xy 425.06201 -273.744188)
			(xy 425.110865 -273.75012) (xy 425.158136 -273.763812) (xy 425.202598 -273.78491) (xy 425.243101 -273.812866)
			(xy 425.278594 -273.846958) (xy 425.308159 -273.886302) (xy 425.33103 -273.929879) (xy 425.346614 -273.97656)
			(xy 425.354509 -274.025137) (xy 425.355004 -274.049744) (xy 426.643812 -274.049744) (xy 426.647772 -274.00069)
			(xy 426.659549 -273.952906) (xy 426.67884 -273.90763) (xy 426.705143 -273.866034) (xy 426.737778 -273.829197)
			(xy 426.775899 -273.798072) (xy 426.81852 -273.773465) (xy 426.864536 -273.756013) (xy 426.912755 -273.746169)
			(xy 426.96193 -273.744188) (xy 427.010785 -273.75012) (xy 427.058056 -273.763812) (xy 427.102518 -273.78491)
			(xy 427.143021 -273.812866) (xy 427.178514 -273.846958) (xy 427.208079 -273.886302) (xy 427.23095 -273.929879)
			(xy 427.246534 -273.97656) (xy 427.254429 -274.025137) (xy 427.254924 -274.049744) (xy 428.543732 -274.049744)
			(xy 428.547692 -274.00069) (xy 428.559469 -273.952906) (xy 428.57876 -273.90763) (xy 428.605063 -273.866034)
			(xy 428.637698 -273.829197) (xy 428.675819 -273.798072) (xy 428.71844 -273.773465) (xy 428.764456 -273.756013)
			(xy 428.812675 -273.746169) (xy 428.86185 -273.744188) (xy 428.910705 -273.75012) (xy 428.957976 -273.763812)
			(xy 429.002438 -273.78491) (xy 429.042941 -273.812866) (xy 429.078434 -273.846958) (xy 429.107999 -273.886302)
			(xy 429.13087 -273.929879) (xy 429.146454 -273.97656) (xy 429.154349 -274.025137) (xy 429.154844 -274.049744)
			(xy 429.154349 -274.074351) (xy 429.146454 -274.122928) (xy 429.13087 -274.169609) (xy 429.107999 -274.213186)
			(xy 429.078434 -274.25253) (xy 429.042941 -274.286622) (xy 429.002438 -274.314578) (xy 428.957976 -274.335676)
			(xy 428.910705 -274.349368) (xy 428.86185 -274.3553) (xy 428.812675 -274.353319) (xy 428.764456 -274.343475)
			(xy 428.71844 -274.326023) (xy 428.675819 -274.301416) (xy 428.637698 -274.270291) (xy 428.605063 -274.233454)
			(xy 428.57876 -274.191858) (xy 428.559469 -274.146582) (xy 428.547692 -274.098798) (xy 428.543732 -274.049744)
			(xy 427.254924 -274.049744) (xy 427.254429 -274.074351) (xy 427.246534 -274.122928) (xy 427.23095 -274.169609)
			(xy 427.208079 -274.213186) (xy 427.178514 -274.25253) (xy 427.143021 -274.286622) (xy 427.102518 -274.314578)
			(xy 427.058056 -274.335676) (xy 427.010785 -274.349368) (xy 426.96193 -274.3553) (xy 426.912755 -274.353319)
			(xy 426.864536 -274.343475) (xy 426.81852 -274.326023) (xy 426.775899 -274.301416) (xy 426.737778 -274.270291)
			(xy 426.705143 -274.233454) (xy 426.67884 -274.191858) (xy 426.659549 -274.146582) (xy 426.647772 -274.098798)
			(xy 426.643812 -274.049744) (xy 425.355004 -274.049744) (xy 425.354509 -274.074351) (xy 425.346614 -274.122928)
			(xy 425.33103 -274.169609) (xy 425.308159 -274.213186) (xy 425.278594 -274.25253) (xy 425.243101 -274.286622)
			(xy 425.202598 -274.314578) (xy 425.158136 -274.335676) (xy 425.110865 -274.349368) (xy 425.06201 -274.3553)
			(xy 425.012835 -274.353319) (xy 424.964616 -274.343475) (xy 424.9186 -274.326023) (xy 424.875979 -274.301416)
			(xy 424.837858 -274.270291) (xy 424.805223 -274.233454) (xy 424.77892 -274.191858) (xy 424.759629 -274.146582)
			(xy 424.747852 -274.098798) (xy 424.743892 -274.049744) (xy 423.455084 -274.049744) (xy 423.454589 -274.074351)
			(xy 423.446694 -274.122928) (xy 423.43111 -274.169609) (xy 423.408239 -274.213186) (xy 423.378674 -274.25253)
			(xy 423.343181 -274.286622) (xy 423.302678 -274.314578) (xy 423.258216 -274.335676) (xy 423.210945 -274.349368)
			(xy 423.16209 -274.3553) (xy 423.112915 -274.353319) (xy 423.064696 -274.343475) (xy 423.01868 -274.326023)
			(xy 422.976059 -274.301416) (xy 422.937938 -274.270291) (xy 422.905303 -274.233454) (xy 422.879 -274.191858)
			(xy 422.859709 -274.146582) (xy 422.847932 -274.098798) (xy 422.843972 -274.049744) (xy 421.55491 -274.049744)
			(xy 421.554415 -274.074351) (xy 421.54652 -274.122928) (xy 421.530936 -274.169609) (xy 421.508065 -274.213186)
			(xy 421.4785 -274.25253) (xy 421.443007 -274.286622) (xy 421.402504 -274.314578) (xy 421.358042 -274.335676)
			(xy 421.310771 -274.349368) (xy 421.261916 -274.3553) (xy 421.212741 -274.353319) (xy 421.164522 -274.343475)
			(xy 421.118506 -274.326023) (xy 421.075885 -274.301416) (xy 421.037764 -274.270291) (xy 421.005129 -274.233454)
			(xy 420.978826 -274.191858) (xy 420.959535 -274.146582) (xy 420.947758 -274.098798) (xy 420.943798 -274.049744)
			(xy 419.65499 -274.049744) (xy 419.654495 -274.074351) (xy 419.6466 -274.122928) (xy 419.631016 -274.169609)
			(xy 419.608145 -274.213186) (xy 419.57858 -274.25253) (xy 419.543087 -274.286622) (xy 419.502584 -274.314578)
			(xy 419.458122 -274.335676) (xy 419.410851 -274.349368) (xy 419.361996 -274.3553) (xy 419.312821 -274.353319)
			(xy 419.264602 -274.343475) (xy 419.218586 -274.326023) (xy 419.175965 -274.301416) (xy 419.137844 -274.270291)
			(xy 419.105209 -274.233454) (xy 419.078906 -274.191858) (xy 419.059615 -274.146582) (xy 419.047838 -274.098798)
			(xy 419.043878 -274.049744) (xy 417.75507 -274.049744) (xy 417.754575 -274.074351) (xy 417.74668 -274.122928)
			(xy 417.731096 -274.169609) (xy 417.708225 -274.213186) (xy 417.67866 -274.25253) (xy 417.643167 -274.286622)
			(xy 417.602664 -274.314578) (xy 417.558202 -274.335676) (xy 417.510931 -274.349368) (xy 417.462076 -274.3553)
			(xy 417.412901 -274.353319) (xy 417.364682 -274.343475) (xy 417.318666 -274.326023) (xy 417.276045 -274.301416)
			(xy 417.237924 -274.270291) (xy 417.205289 -274.233454) (xy 417.178986 -274.191858) (xy 417.159695 -274.146582)
			(xy 417.147918 -274.098798) (xy 417.143958 -274.049744) (xy 415.854896 -274.049744) (xy 415.854401 -274.074351)
			(xy 415.846506 -274.122928) (xy 415.830922 -274.169609) (xy 415.808051 -274.213186) (xy 415.778486 -274.25253)
			(xy 415.742993 -274.286622) (xy 415.70249 -274.314578) (xy 415.658028 -274.335676) (xy 415.610757 -274.349368)
			(xy 415.561902 -274.3553) (xy 415.512727 -274.353319) (xy 415.464508 -274.343475) (xy 415.418492 -274.326023)
			(xy 415.375871 -274.301416) (xy 415.33775 -274.270291) (xy 415.305115 -274.233454) (xy 415.278812 -274.191858)
			(xy 415.259521 -274.146582) (xy 415.247744 -274.098798) (xy 415.243784 -274.049744) (xy 413.954976 -274.049744)
			(xy 413.954481 -274.074351) (xy 413.946586 -274.122928) (xy 413.931002 -274.169609) (xy 413.908131 -274.213186)
			(xy 413.878566 -274.25253) (xy 413.843073 -274.286622) (xy 413.80257 -274.314578) (xy 413.758108 -274.335676)
			(xy 413.710837 -274.349368) (xy 413.661982 -274.3553) (xy 413.612807 -274.353319) (xy 413.564588 -274.343475)
			(xy 413.518572 -274.326023) (xy 413.475951 -274.301416) (xy 413.43783 -274.270291) (xy 413.405195 -274.233454)
			(xy 413.378892 -274.191858) (xy 413.359601 -274.146582) (xy 413.347824 -274.098798) (xy 413.343864 -274.049744)
			(xy 412.055056 -274.049744) (xy 412.054561 -274.074351) (xy 412.046666 -274.122928) (xy 412.031082 -274.169609)
			(xy 412.008211 -274.213186) (xy 411.978646 -274.25253) (xy 411.943153 -274.286622) (xy 411.90265 -274.314578)
			(xy 411.858188 -274.335676) (xy 411.810917 -274.349368) (xy 411.762062 -274.3553) (xy 411.712887 -274.353319)
			(xy 411.664668 -274.343475) (xy 411.618652 -274.326023) (xy 411.576031 -274.301416) (xy 411.53791 -274.270291)
			(xy 411.505275 -274.233454) (xy 411.478972 -274.191858) (xy 411.459681 -274.146582) (xy 411.447904 -274.098798)
			(xy 411.443944 -274.049744) (xy 410.154882 -274.049744) (xy 410.154387 -274.074351) (xy 410.146492 -274.122928)
			(xy 410.130908 -274.169609) (xy 410.108037 -274.213186) (xy 410.078472 -274.25253) (xy 410.042979 -274.286622)
			(xy 410.002476 -274.314578) (xy 409.958014 -274.335676) (xy 409.910743 -274.349368) (xy 409.861888 -274.3553)
			(xy 409.812713 -274.353319) (xy 409.764494 -274.343475) (xy 409.718478 -274.326023) (xy 409.675857 -274.301416)
			(xy 409.637736 -274.270291) (xy 409.605101 -274.233454) (xy 409.578798 -274.191858) (xy 409.559507 -274.146582)
			(xy 409.54773 -274.098798) (xy 409.54377 -274.049744) (xy 408.254957 -274.049744) (xy 408.254467 -274.074097)
			(xy 408.246572 -274.122674) (xy 408.230988 -274.169355) (xy 408.208117 -274.212932) (xy 408.178552 -274.252276)
			(xy 408.143059 -274.286368) (xy 408.102556 -274.314324) (xy 408.058094 -274.335422) (xy 408.010823 -274.349114)
			(xy 407.961968 -274.355046) (xy 407.912793 -274.353065) (xy 407.864574 -274.343221) (xy 407.818558 -274.325769)
			(xy 407.775937 -274.301162) (xy 407.737816 -274.270037) (xy 407.705181 -274.2332) (xy 407.678878 -274.191604)
			(xy 407.659587 -274.146328) (xy 407.64781 -274.098544) (xy 407.64385 -274.04949) (xy 406.355291 -274.04949)
			(xy 406.355296 -274.049744) (xy 406.354801 -274.074351) (xy 406.346906 -274.122928) (xy 406.331322 -274.169609)
			(xy 406.308451 -274.213186) (xy 406.278886 -274.25253) (xy 406.243393 -274.286622) (xy 406.20289 -274.314578)
			(xy 406.158428 -274.335676) (xy 406.111157 -274.349368) (xy 406.062302 -274.3553) (xy 406.013127 -274.353319)
			(xy 405.964908 -274.343475) (xy 405.918892 -274.326023) (xy 405.876271 -274.301416) (xy 405.83815 -274.270291)
			(xy 405.805515 -274.233454) (xy 405.779212 -274.191858) (xy 405.759921 -274.146582) (xy 405.748144 -274.098798)
			(xy 405.744184 -274.049744) (xy 404.455122 -274.049744) (xy 404.454627 -274.074351) (xy 404.446732 -274.122928)
			(xy 404.431148 -274.169609) (xy 404.408277 -274.213186) (xy 404.378712 -274.25253) (xy 404.343219 -274.286622)
			(xy 404.302716 -274.314578) (xy 404.258254 -274.335676) (xy 404.210983 -274.349368) (xy 404.162128 -274.3553)
			(xy 404.112953 -274.353319) (xy 404.064734 -274.343475) (xy 404.018718 -274.326023) (xy 403.976097 -274.301416)
			(xy 403.937976 -274.270291) (xy 403.905341 -274.233454) (xy 403.879038 -274.191858) (xy 403.859747 -274.146582)
			(xy 403.84797 -274.098798) (xy 403.84401 -274.049744) (xy 402.555202 -274.049744) (xy 402.554707 -274.074351)
			(xy 402.546812 -274.122928) (xy 402.531228 -274.169609) (xy 402.508357 -274.213186) (xy 402.478792 -274.25253)
			(xy 402.443299 -274.286622) (xy 402.402796 -274.314578) (xy 402.358334 -274.335676) (xy 402.311063 -274.349368)
			(xy 402.262208 -274.3553) (xy 402.213033 -274.353319) (xy 402.164814 -274.343475) (xy 402.118798 -274.326023)
			(xy 402.076177 -274.301416) (xy 402.038056 -274.270291) (xy 402.005421 -274.233454) (xy 401.979118 -274.191858)
			(xy 401.959827 -274.146582) (xy 401.94805 -274.098798) (xy 401.94409 -274.049744) (xy 400.655282 -274.049744)
			(xy 400.654787 -274.074351) (xy 400.646892 -274.122928) (xy 400.631308 -274.169609) (xy 400.608437 -274.213186)
			(xy 400.578872 -274.25253) (xy 400.543379 -274.286622) (xy 400.502876 -274.314578) (xy 400.458414 -274.335676)
			(xy 400.411143 -274.349368) (xy 400.362288 -274.3553) (xy 400.313113 -274.353319) (xy 400.264894 -274.343475)
			(xy 400.218878 -274.326023) (xy 400.176257 -274.301416) (xy 400.138136 -274.270291) (xy 400.105501 -274.233454)
			(xy 400.079198 -274.191858) (xy 400.059907 -274.146582) (xy 400.04813 -274.098798) (xy 400.04417 -274.049744)
			(xy 398.755108 -274.049744) (xy 398.754613 -274.074351) (xy 398.746718 -274.122928) (xy 398.731134 -274.169609)
			(xy 398.708263 -274.213186) (xy 398.678698 -274.25253) (xy 398.643205 -274.286622) (xy 398.602702 -274.314578)
			(xy 398.55824 -274.335676) (xy 398.510969 -274.349368) (xy 398.462114 -274.3553) (xy 398.412939 -274.353319)
			(xy 398.36472 -274.343475) (xy 398.318704 -274.326023) (xy 398.276083 -274.301416) (xy 398.237962 -274.270291)
			(xy 398.205327 -274.233454) (xy 398.179024 -274.191858) (xy 398.159733 -274.146582) (xy 398.147956 -274.098798)
			(xy 398.143996 -274.049744) (xy 396.855188 -274.049744) (xy 396.854693 -274.074351) (xy 396.846798 -274.122928)
			(xy 396.831214 -274.169609) (xy 396.808343 -274.213186) (xy 396.778778 -274.25253) (xy 396.743285 -274.286622)
			(xy 396.702782 -274.314578) (xy 396.65832 -274.335676) (xy 396.611049 -274.349368) (xy 396.562194 -274.3553)
			(xy 396.513019 -274.353319) (xy 396.4648 -274.343475) (xy 396.418784 -274.326023) (xy 396.376163 -274.301416)
			(xy 396.338042 -274.270291) (xy 396.305407 -274.233454) (xy 396.279104 -274.191858) (xy 396.259813 -274.146582)
			(xy 396.248036 -274.098798) (xy 396.244076 -274.049744) (xy 394.955268 -274.049744) (xy 394.954773 -274.074351)
			(xy 394.946878 -274.122928) (xy 394.931294 -274.169609) (xy 394.908423 -274.213186) (xy 394.878858 -274.25253)
			(xy 394.843365 -274.286622) (xy 394.802862 -274.314578) (xy 394.7584 -274.335676) (xy 394.711129 -274.349368)
			(xy 394.662274 -274.3553) (xy 394.613099 -274.353319) (xy 394.56488 -274.343475) (xy 394.518864 -274.326023)
			(xy 394.476243 -274.301416) (xy 394.438122 -274.270291) (xy 394.405487 -274.233454) (xy 394.379184 -274.191858)
			(xy 394.359893 -274.146582) (xy 394.348116 -274.098798) (xy 394.344156 -274.049744) (xy 393.055094 -274.049744)
			(xy 393.054599 -274.074351) (xy 393.046704 -274.122928) (xy 393.03112 -274.169609) (xy 393.008249 -274.213186)
			(xy 392.978684 -274.25253) (xy 392.943191 -274.286622) (xy 392.902688 -274.314578) (xy 392.858226 -274.335676)
			(xy 392.810955 -274.349368) (xy 392.7621 -274.3553) (xy 392.712925 -274.353319) (xy 392.664706 -274.343475)
			(xy 392.61869 -274.326023) (xy 392.576069 -274.301416) (xy 392.537948 -274.270291) (xy 392.505313 -274.233454)
			(xy 392.47901 -274.191858) (xy 392.459719 -274.146582) (xy 392.447942 -274.098798) (xy 392.443982 -274.049744)
			(xy 313.054746 -274.049744) (xy 313.054251 -274.074351) (xy 313.046356 -274.122928) (xy 313.030772 -274.169609)
			(xy 313.007901 -274.213186) (xy 312.978336 -274.25253) (xy 312.942843 -274.286622) (xy 312.90234 -274.314578)
			(xy 312.857878 -274.335676) (xy 312.810607 -274.349368) (xy 312.761752 -274.3553) (xy 312.712577 -274.353319)
			(xy 312.664358 -274.343475) (xy 312.618342 -274.326023) (xy 312.575721 -274.301416) (xy 312.5376 -274.270291)
			(xy 312.504965 -274.233454) (xy 312.478662 -274.191858) (xy 312.459371 -274.146582) (xy 312.447594 -274.098798)
			(xy 312.443634 -274.049744) (xy 311.154826 -274.049744) (xy 311.154331 -274.074351) (xy 311.146436 -274.122928)
			(xy 311.130852 -274.169609) (xy 311.107981 -274.213186) (xy 311.078416 -274.25253) (xy 311.042923 -274.286622)
			(xy 311.00242 -274.314578) (xy 310.957958 -274.335676) (xy 310.910687 -274.349368) (xy 310.861832 -274.3553)
			(xy 310.812657 -274.353319) (xy 310.764438 -274.343475) (xy 310.718422 -274.326023) (xy 310.675801 -274.301416)
			(xy 310.63768 -274.270291) (xy 310.605045 -274.233454) (xy 310.578742 -274.191858) (xy 310.559451 -274.146582)
			(xy 310.547674 -274.098798) (xy 310.543714 -274.049744) (xy 309.254906 -274.049744) (xy 309.254411 -274.074351)
			(xy 309.246516 -274.122928) (xy 309.230932 -274.169609) (xy 309.208061 -274.213186) (xy 309.178496 -274.25253)
			(xy 309.143003 -274.286622) (xy 309.1025 -274.314578) (xy 309.058038 -274.335676) (xy 309.010767 -274.349368)
			(xy 308.961912 -274.3553) (xy 308.912737 -274.353319) (xy 308.864518 -274.343475) (xy 308.818502 -274.326023)
			(xy 308.775881 -274.301416) (xy 308.73776 -274.270291) (xy 308.705125 -274.233454) (xy 308.678822 -274.191858)
			(xy 308.659531 -274.146582) (xy 308.647754 -274.098798) (xy 308.643794 -274.049744) (xy 307.354986 -274.049744)
			(xy 307.354491 -274.074351) (xy 307.346596 -274.122928) (xy 307.331012 -274.169609) (xy 307.308141 -274.213186)
			(xy 307.278576 -274.25253) (xy 307.243083 -274.286622) (xy 307.20258 -274.314578) (xy 307.158118 -274.335676)
			(xy 307.110847 -274.349368) (xy 307.061992 -274.3553) (xy 307.012817 -274.353319) (xy 306.964598 -274.343475)
			(xy 306.918582 -274.326023) (xy 306.875961 -274.301416) (xy 306.83784 -274.270291) (xy 306.805205 -274.233454)
			(xy 306.778902 -274.191858) (xy 306.759611 -274.146582) (xy 306.747834 -274.098798) (xy 306.743874 -274.049744)
			(xy 305.454812 -274.049744) (xy 305.454317 -274.074351) (xy 305.446422 -274.122928) (xy 305.430838 -274.169609)
			(xy 305.407967 -274.213186) (xy 305.378402 -274.25253) (xy 305.342909 -274.286622) (xy 305.302406 -274.314578)
			(xy 305.257944 -274.335676) (xy 305.210673 -274.349368) (xy 305.161818 -274.3553) (xy 305.112643 -274.353319)
			(xy 305.064424 -274.343475) (xy 305.018408 -274.326023) (xy 304.975787 -274.301416) (xy 304.937666 -274.270291)
			(xy 304.905031 -274.233454) (xy 304.878728 -274.191858) (xy 304.859437 -274.146582) (xy 304.84766 -274.098798)
			(xy 304.8437 -274.049744) (xy 303.554892 -274.049744) (xy 303.554397 -274.074351) (xy 303.546502 -274.122928)
			(xy 303.530918 -274.169609) (xy 303.508047 -274.213186) (xy 303.478482 -274.25253) (xy 303.442989 -274.286622)
			(xy 303.402486 -274.314578) (xy 303.358024 -274.335676) (xy 303.310753 -274.349368) (xy 303.261898 -274.3553)
			(xy 303.212723 -274.353319) (xy 303.164504 -274.343475) (xy 303.118488 -274.326023) (xy 303.075867 -274.301416)
			(xy 303.037746 -274.270291) (xy 303.005111 -274.233454) (xy 302.978808 -274.191858) (xy 302.959517 -274.146582)
			(xy 302.94774 -274.098798) (xy 302.94378 -274.049744) (xy 301.654972 -274.049744) (xy 301.654477 -274.074351)
			(xy 301.646582 -274.122928) (xy 301.630998 -274.169609) (xy 301.608127 -274.213186) (xy 301.578562 -274.25253)
			(xy 301.543069 -274.286622) (xy 301.502566 -274.314578) (xy 301.458104 -274.335676) (xy 301.410833 -274.349368)
			(xy 301.361978 -274.3553) (xy 301.312803 -274.353319) (xy 301.264584 -274.343475) (xy 301.218568 -274.326023)
			(xy 301.175947 -274.301416) (xy 301.137826 -274.270291) (xy 301.105191 -274.233454) (xy 301.078888 -274.191858)
			(xy 301.059597 -274.146582) (xy 301.04782 -274.098798) (xy 301.04386 -274.049744) (xy 299.754798 -274.049744)
			(xy 299.754303 -274.074351) (xy 299.746408 -274.122928) (xy 299.730824 -274.169609) (xy 299.707953 -274.213186)
			(xy 299.678388 -274.25253) (xy 299.642895 -274.286622) (xy 299.602392 -274.314578) (xy 299.55793 -274.335676)
			(xy 299.510659 -274.349368) (xy 299.461804 -274.3553) (xy 299.412629 -274.353319) (xy 299.36441 -274.343475)
			(xy 299.318394 -274.326023) (xy 299.275773 -274.301416) (xy 299.237652 -274.270291) (xy 299.205017 -274.233454)
			(xy 299.178714 -274.191858) (xy 299.159423 -274.146582) (xy 299.147646 -274.098798) (xy 299.143686 -274.049744)
			(xy 297.854878 -274.049744) (xy 297.854383 -274.074351) (xy 297.846488 -274.122928) (xy 297.830904 -274.169609)
			(xy 297.808033 -274.213186) (xy 297.778468 -274.25253) (xy 297.742975 -274.286622) (xy 297.702472 -274.314578)
			(xy 297.65801 -274.335676) (xy 297.610739 -274.349368) (xy 297.561884 -274.3553) (xy 297.512709 -274.353319)
			(xy 297.46449 -274.343475) (xy 297.418474 -274.326023) (xy 297.375853 -274.301416) (xy 297.337732 -274.270291)
			(xy 297.305097 -274.233454) (xy 297.278794 -274.191858) (xy 297.259503 -274.146582) (xy 297.247726 -274.098798)
			(xy 297.243766 -274.049744) (xy 295.954958 -274.049744) (xy 295.954463 -274.074351) (xy 295.946568 -274.122928)
			(xy 295.930984 -274.169609) (xy 295.908113 -274.213186) (xy 295.878548 -274.25253) (xy 295.843055 -274.286622)
			(xy 295.802552 -274.314578) (xy 295.75809 -274.335676) (xy 295.710819 -274.349368) (xy 295.661964 -274.3553)
			(xy 295.612789 -274.353319) (xy 295.56457 -274.343475) (xy 295.518554 -274.326023) (xy 295.475933 -274.301416)
			(xy 295.437812 -274.270291) (xy 295.405177 -274.233454) (xy 295.378874 -274.191858) (xy 295.359583 -274.146582)
			(xy 295.347806 -274.098798) (xy 295.343846 -274.049744) (xy 294.054784 -274.049744) (xy 294.054289 -274.074351)
			(xy 294.046394 -274.122928) (xy 294.03081 -274.169609) (xy 294.007939 -274.213186) (xy 293.978374 -274.25253)
			(xy 293.942881 -274.286622) (xy 293.902378 -274.314578) (xy 293.857916 -274.335676) (xy 293.810645 -274.349368)
			(xy 293.76179 -274.3553) (xy 293.712615 -274.353319) (xy 293.664396 -274.343475) (xy 293.61838 -274.326023)
			(xy 293.575759 -274.301416) (xy 293.537638 -274.270291) (xy 293.505003 -274.233454) (xy 293.4787 -274.191858)
			(xy 293.459409 -274.146582) (xy 293.447632 -274.098798) (xy 293.443672 -274.049744) (xy 292.154859 -274.049744)
			(xy 292.154369 -274.074097) (xy 292.146474 -274.122674) (xy 292.13089 -274.169355) (xy 292.108019 -274.212932)
			(xy 292.078454 -274.252276) (xy 292.042961 -274.286368) (xy 292.002458 -274.314324) (xy 291.957996 -274.335422)
			(xy 291.910725 -274.349114) (xy 291.86187 -274.355046) (xy 291.812695 -274.353065) (xy 291.764476 -274.343221)
			(xy 291.71846 -274.325769) (xy 291.675839 -274.301162) (xy 291.637718 -274.270037) (xy 291.605083 -274.2332)
			(xy 291.57878 -274.191604) (xy 291.559489 -274.146328) (xy 291.547712 -274.098544) (xy 291.543752 -274.04949)
			(xy 290.255193 -274.04949) (xy 290.255198 -274.049744) (xy 290.254703 -274.074351) (xy 290.246808 -274.122928)
			(xy 290.231224 -274.169609) (xy 290.208353 -274.213186) (xy 290.178788 -274.25253) (xy 290.143295 -274.286622)
			(xy 290.102792 -274.314578) (xy 290.05833 -274.335676) (xy 290.011059 -274.349368) (xy 289.962204 -274.3553)
			(xy 289.913029 -274.353319) (xy 289.86481 -274.343475) (xy 289.818794 -274.326023) (xy 289.776173 -274.301416)
			(xy 289.738052 -274.270291) (xy 289.705417 -274.233454) (xy 289.679114 -274.191858) (xy 289.659823 -274.146582)
			(xy 289.648046 -274.098798) (xy 289.644086 -274.049744) (xy 288.355024 -274.049744) (xy 288.354529 -274.074351)
			(xy 288.346634 -274.122928) (xy 288.33105 -274.169609) (xy 288.308179 -274.213186) (xy 288.278614 -274.25253)
			(xy 288.243121 -274.286622) (xy 288.202618 -274.314578) (xy 288.158156 -274.335676) (xy 288.110885 -274.349368)
			(xy 288.06203 -274.3553) (xy 288.012855 -274.353319) (xy 287.964636 -274.343475) (xy 287.91862 -274.326023)
			(xy 287.875999 -274.301416) (xy 287.837878 -274.270291) (xy 287.805243 -274.233454) (xy 287.77894 -274.191858)
			(xy 287.759649 -274.146582) (xy 287.747872 -274.098798) (xy 287.743912 -274.049744) (xy 286.455104 -274.049744)
			(xy 286.454609 -274.074351) (xy 286.446714 -274.122928) (xy 286.43113 -274.169609) (xy 286.408259 -274.213186)
			(xy 286.378694 -274.25253) (xy 286.343201 -274.286622) (xy 286.302698 -274.314578) (xy 286.258236 -274.335676)
			(xy 286.210965 -274.349368) (xy 286.16211 -274.3553) (xy 286.112935 -274.353319) (xy 286.064716 -274.343475)
			(xy 286.0187 -274.326023) (xy 285.976079 -274.301416) (xy 285.937958 -274.270291) (xy 285.905323 -274.233454)
			(xy 285.87902 -274.191858) (xy 285.859729 -274.146582) (xy 285.847952 -274.098798) (xy 285.843992 -274.049744)
			(xy 284.555184 -274.049744) (xy 284.554689 -274.074351) (xy 284.546794 -274.122928) (xy 284.53121 -274.169609)
			(xy 284.508339 -274.213186) (xy 284.478774 -274.25253) (xy 284.443281 -274.286622) (xy 284.402778 -274.314578)
			(xy 284.358316 -274.335676) (xy 284.311045 -274.349368) (xy 284.26219 -274.3553) (xy 284.213015 -274.353319)
			(xy 284.164796 -274.343475) (xy 284.11878 -274.326023) (xy 284.076159 -274.301416) (xy 284.038038 -274.270291)
			(xy 284.005403 -274.233454) (xy 283.9791 -274.191858) (xy 283.959809 -274.146582) (xy 283.948032 -274.098798)
			(xy 283.944072 -274.049744) (xy 282.65501 -274.049744) (xy 282.654515 -274.074351) (xy 282.64662 -274.122928)
			(xy 282.631036 -274.169609) (xy 282.608165 -274.213186) (xy 282.5786 -274.25253) (xy 282.543107 -274.286622)
			(xy 282.502604 -274.314578) (xy 282.458142 -274.335676) (xy 282.410871 -274.349368) (xy 282.362016 -274.3553)
			(xy 282.312841 -274.353319) (xy 282.264622 -274.343475) (xy 282.218606 -274.326023) (xy 282.175985 -274.301416)
			(xy 282.137864 -274.270291) (xy 282.105229 -274.233454) (xy 282.078926 -274.191858) (xy 282.059635 -274.146582)
			(xy 282.047858 -274.098798) (xy 282.043898 -274.049744) (xy 280.75509 -274.049744) (xy 280.754595 -274.074351)
			(xy 280.7467 -274.122928) (xy 280.731116 -274.169609) (xy 280.708245 -274.213186) (xy 280.67868 -274.25253)
			(xy 280.643187 -274.286622) (xy 280.602684 -274.314578) (xy 280.558222 -274.335676) (xy 280.510951 -274.349368)
			(xy 280.462096 -274.3553) (xy 280.412921 -274.353319) (xy 280.364702 -274.343475) (xy 280.318686 -274.326023)
			(xy 280.276065 -274.301416) (xy 280.237944 -274.270291) (xy 280.205309 -274.233454) (xy 280.179006 -274.191858)
			(xy 280.159715 -274.146582) (xy 280.147938 -274.098798) (xy 280.143978 -274.049744) (xy 278.85517 -274.049744)
			(xy 278.854675 -274.074351) (xy 278.84678 -274.122928) (xy 278.831196 -274.169609) (xy 278.808325 -274.213186)
			(xy 278.77876 -274.25253) (xy 278.743267 -274.286622) (xy 278.702764 -274.314578) (xy 278.658302 -274.335676)
			(xy 278.611031 -274.349368) (xy 278.562176 -274.3553) (xy 278.513001 -274.353319) (xy 278.464782 -274.343475)
			(xy 278.418766 -274.326023) (xy 278.376145 -274.301416) (xy 278.338024 -274.270291) (xy 278.305389 -274.233454)
			(xy 278.279086 -274.191858) (xy 278.259795 -274.146582) (xy 278.248018 -274.098798) (xy 278.244058 -274.049744)
			(xy 276.954996 -274.049744) (xy 276.954501 -274.074351) (xy 276.946606 -274.122928) (xy 276.931022 -274.169609)
			(xy 276.908151 -274.213186) (xy 276.878586 -274.25253) (xy 276.843093 -274.286622) (xy 276.80259 -274.314578)
			(xy 276.758128 -274.335676) (xy 276.710857 -274.349368) (xy 276.662002 -274.3553) (xy 276.612827 -274.353319)
			(xy 276.564608 -274.343475) (xy 276.518592 -274.326023) (xy 276.475971 -274.301416) (xy 276.43785 -274.270291)
			(xy 276.405215 -274.233454) (xy 276.378912 -274.191858) (xy 276.359621 -274.146582) (xy 276.347844 -274.098798)
			(xy 276.343884 -274.049744) (xy 196.954902 -274.049744) (xy 196.954407 -274.074351) (xy 196.946512 -274.122928)
			(xy 196.930928 -274.169609) (xy 196.908057 -274.213186) (xy 196.878492 -274.25253) (xy 196.842999 -274.286622)
			(xy 196.802496 -274.314578) (xy 196.758034 -274.335676) (xy 196.710763 -274.349368) (xy 196.661908 -274.3553)
			(xy 196.612733 -274.353319) (xy 196.564514 -274.343475) (xy 196.518498 -274.326023) (xy 196.475877 -274.301416)
			(xy 196.437756 -274.270291) (xy 196.405121 -274.233454) (xy 196.378818 -274.191858) (xy 196.359527 -274.146582)
			(xy 196.34775 -274.098798) (xy 196.34379 -274.049744) (xy 195.054982 -274.049744) (xy 195.054487 -274.074351)
			(xy 195.046592 -274.122928) (xy 195.031008 -274.169609) (xy 195.008137 -274.213186) (xy 194.978572 -274.25253)
			(xy 194.943079 -274.286622) (xy 194.902576 -274.314578) (xy 194.858114 -274.335676) (xy 194.810843 -274.349368)
			(xy 194.761988 -274.3553) (xy 194.712813 -274.353319) (xy 194.664594 -274.343475) (xy 194.618578 -274.326023)
			(xy 194.575957 -274.301416) (xy 194.537836 -274.270291) (xy 194.505201 -274.233454) (xy 194.478898 -274.191858)
			(xy 194.459607 -274.146582) (xy 194.44783 -274.098798) (xy 194.44387 -274.049744) (xy 193.155062 -274.049744)
			(xy 193.154567 -274.074351) (xy 193.146672 -274.122928) (xy 193.131088 -274.169609) (xy 193.108217 -274.213186)
			(xy 193.078652 -274.25253) (xy 193.043159 -274.286622) (xy 193.002656 -274.314578) (xy 192.958194 -274.335676)
			(xy 192.910923 -274.349368) (xy 192.862068 -274.3553) (xy 192.812893 -274.353319) (xy 192.764674 -274.343475)
			(xy 192.718658 -274.326023) (xy 192.676037 -274.301416) (xy 192.637916 -274.270291) (xy 192.605281 -274.233454)
			(xy 192.578978 -274.191858) (xy 192.559687 -274.146582) (xy 192.54791 -274.098798) (xy 192.54395 -274.049744)
			(xy 191.255142 -274.049744) (xy 191.254647 -274.074351) (xy 191.246752 -274.122928) (xy 191.231168 -274.169609)
			(xy 191.208297 -274.213186) (xy 191.178732 -274.25253) (xy 191.143239 -274.286622) (xy 191.102736 -274.314578)
			(xy 191.058274 -274.335676) (xy 191.011003 -274.349368) (xy 190.962148 -274.3553) (xy 190.912973 -274.353319)
			(xy 190.864754 -274.343475) (xy 190.818738 -274.326023) (xy 190.776117 -274.301416) (xy 190.737996 -274.270291)
			(xy 190.705361 -274.233454) (xy 190.679058 -274.191858) (xy 190.659767 -274.146582) (xy 190.64799 -274.098798)
			(xy 190.64403 -274.049744) (xy 189.354968 -274.049744) (xy 189.354473 -274.074351) (xy 189.346578 -274.122928)
			(xy 189.330994 -274.169609) (xy 189.308123 -274.213186) (xy 189.278558 -274.25253) (xy 189.243065 -274.286622)
			(xy 189.202562 -274.314578) (xy 189.1581 -274.335676) (xy 189.110829 -274.349368) (xy 189.061974 -274.3553)
			(xy 189.012799 -274.353319) (xy 188.96458 -274.343475) (xy 188.918564 -274.326023) (xy 188.875943 -274.301416)
			(xy 188.837822 -274.270291) (xy 188.805187 -274.233454) (xy 188.778884 -274.191858) (xy 188.759593 -274.146582)
			(xy 188.747816 -274.098798) (xy 188.743856 -274.049744) (xy 187.455048 -274.049744) (xy 187.454553 -274.074351)
			(xy 187.446658 -274.122928) (xy 187.431074 -274.169609) (xy 187.408203 -274.213186) (xy 187.378638 -274.25253)
			(xy 187.343145 -274.286622) (xy 187.302642 -274.314578) (xy 187.25818 -274.335676) (xy 187.210909 -274.349368)
			(xy 187.162054 -274.3553) (xy 187.112879 -274.353319) (xy 187.06466 -274.343475) (xy 187.018644 -274.326023)
			(xy 186.976023 -274.301416) (xy 186.937902 -274.270291) (xy 186.905267 -274.233454) (xy 186.878964 -274.191858)
			(xy 186.859673 -274.146582) (xy 186.847896 -274.098798) (xy 186.843936 -274.049744) (xy 185.555128 -274.049744)
			(xy 185.554633 -274.074351) (xy 185.546738 -274.122928) (xy 185.531154 -274.169609) (xy 185.508283 -274.213186)
			(xy 185.478718 -274.25253) (xy 185.443225 -274.286622) (xy 185.402722 -274.314578) (xy 185.35826 -274.335676)
			(xy 185.310989 -274.349368) (xy 185.262134 -274.3553) (xy 185.212959 -274.353319) (xy 185.16474 -274.343475)
			(xy 185.118724 -274.326023) (xy 185.076103 -274.301416) (xy 185.037982 -274.270291) (xy 185.005347 -274.233454)
			(xy 184.979044 -274.191858) (xy 184.959753 -274.146582) (xy 184.947976 -274.098798) (xy 184.944016 -274.049744)
			(xy 183.654954 -274.049744) (xy 183.654459 -274.074351) (xy 183.646564 -274.122928) (xy 183.63098 -274.169609)
			(xy 183.608109 -274.213186) (xy 183.578544 -274.25253) (xy 183.543051 -274.286622) (xy 183.502548 -274.314578)
			(xy 183.458086 -274.335676) (xy 183.410815 -274.349368) (xy 183.36196 -274.3553) (xy 183.312785 -274.353319)
			(xy 183.264566 -274.343475) (xy 183.21855 -274.326023) (xy 183.175929 -274.301416) (xy 183.137808 -274.270291)
			(xy 183.105173 -274.233454) (xy 183.07887 -274.191858) (xy 183.059579 -274.146582) (xy 183.047802 -274.098798)
			(xy 183.043842 -274.049744) (xy 181.755034 -274.049744) (xy 181.754539 -274.074351) (xy 181.746644 -274.122928)
			(xy 181.73106 -274.169609) (xy 181.708189 -274.213186) (xy 181.678624 -274.25253) (xy 181.643131 -274.286622)
			(xy 181.602628 -274.314578) (xy 181.558166 -274.335676) (xy 181.510895 -274.349368) (xy 181.46204 -274.3553)
			(xy 181.412865 -274.353319) (xy 181.364646 -274.343475) (xy 181.31863 -274.326023) (xy 181.276009 -274.301416)
			(xy 181.237888 -274.270291) (xy 181.205253 -274.233454) (xy 181.17895 -274.191858) (xy 181.159659 -274.146582)
			(xy 181.147882 -274.098798) (xy 181.143922 -274.049744) (xy 179.855114 -274.049744) (xy 179.854619 -274.074351)
			(xy 179.846724 -274.122928) (xy 179.83114 -274.169609) (xy 179.808269 -274.213186) (xy 179.778704 -274.25253)
			(xy 179.743211 -274.286622) (xy 179.702708 -274.314578) (xy 179.658246 -274.335676) (xy 179.610975 -274.349368)
			(xy 179.56212 -274.3553) (xy 179.512945 -274.353319) (xy 179.464726 -274.343475) (xy 179.41871 -274.326023)
			(xy 179.376089 -274.301416) (xy 179.337968 -274.270291) (xy 179.305333 -274.233454) (xy 179.27903 -274.191858)
			(xy 179.259739 -274.146582) (xy 179.247962 -274.098798) (xy 179.244002 -274.049744) (xy 177.95494 -274.049744)
			(xy 177.954445 -274.074351) (xy 177.94655 -274.122928) (xy 177.930966 -274.169609) (xy 177.908095 -274.213186)
			(xy 177.87853 -274.25253) (xy 177.843037 -274.286622) (xy 177.802534 -274.314578) (xy 177.758072 -274.335676)
			(xy 177.710801 -274.349368) (xy 177.661946 -274.3553) (xy 177.612771 -274.353319) (xy 177.564552 -274.343475)
			(xy 177.518536 -274.326023) (xy 177.475915 -274.301416) (xy 177.437794 -274.270291) (xy 177.405159 -274.233454)
			(xy 177.378856 -274.191858) (xy 177.359565 -274.146582) (xy 177.347788 -274.098798) (xy 177.343828 -274.049744)
			(xy 176.055015 -274.049744) (xy 176.054525 -274.074097) (xy 176.04663 -274.122674) (xy 176.031046 -274.169355)
			(xy 176.008175 -274.212932) (xy 175.97861 -274.252276) (xy 175.943117 -274.286368) (xy 175.902614 -274.314324)
			(xy 175.858152 -274.335422) (xy 175.810881 -274.349114) (xy 175.762026 -274.355046) (xy 175.712851 -274.353065)
			(xy 175.664632 -274.343221) (xy 175.618616 -274.325769) (xy 175.575995 -274.301162) (xy 175.537874 -274.270037)
			(xy 175.505239 -274.2332) (xy 175.478936 -274.191604) (xy 175.459645 -274.146328) (xy 175.447868 -274.098544)
			(xy 175.443908 -274.04949) (xy 174.155349 -274.04949) (xy 174.155354 -274.049744) (xy 174.154859 -274.074351)
			(xy 174.146964 -274.122928) (xy 174.13138 -274.169609) (xy 174.108509 -274.213186) (xy 174.078944 -274.25253)
			(xy 174.043451 -274.286622) (xy 174.002948 -274.314578) (xy 173.958486 -274.335676) (xy 173.911215 -274.349368)
			(xy 173.86236 -274.3553) (xy 173.813185 -274.353319) (xy 173.764966 -274.343475) (xy 173.71895 -274.326023)
			(xy 173.676329 -274.301416) (xy 173.638208 -274.270291) (xy 173.605573 -274.233454) (xy 173.57927 -274.191858)
			(xy 173.559979 -274.146582) (xy 173.548202 -274.098798) (xy 173.544242 -274.049744) (xy 172.25518 -274.049744)
			(xy 172.254685 -274.074351) (xy 172.24679 -274.122928) (xy 172.231206 -274.169609) (xy 172.208335 -274.213186)
			(xy 172.17877 -274.25253) (xy 172.143277 -274.286622) (xy 172.102774 -274.314578) (xy 172.058312 -274.335676)
			(xy 172.011041 -274.349368) (xy 171.962186 -274.3553) (xy 171.913011 -274.353319) (xy 171.864792 -274.343475)
			(xy 171.818776 -274.326023) (xy 171.776155 -274.301416) (xy 171.738034 -274.270291) (xy 171.705399 -274.233454)
			(xy 171.679096 -274.191858) (xy 171.659805 -274.146582) (xy 171.648028 -274.098798) (xy 171.644068 -274.049744)
			(xy 170.35526 -274.049744) (xy 170.354765 -274.074351) (xy 170.34687 -274.122928) (xy 170.331286 -274.169609)
			(xy 170.308415 -274.213186) (xy 170.27885 -274.25253) (xy 170.243357 -274.286622) (xy 170.202854 -274.314578)
			(xy 170.158392 -274.335676) (xy 170.111121 -274.349368) (xy 170.062266 -274.3553) (xy 170.013091 -274.353319)
			(xy 169.964872 -274.343475) (xy 169.918856 -274.326023) (xy 169.876235 -274.301416) (xy 169.838114 -274.270291)
			(xy 169.805479 -274.233454) (xy 169.779176 -274.191858) (xy 169.759885 -274.146582) (xy 169.748108 -274.098798)
			(xy 169.744148 -274.049744) (xy 168.45534 -274.049744) (xy 168.454845 -274.074351) (xy 168.44695 -274.122928)
			(xy 168.431366 -274.169609) (xy 168.408495 -274.213186) (xy 168.37893 -274.25253) (xy 168.343437 -274.286622)
			(xy 168.302934 -274.314578) (xy 168.258472 -274.335676) (xy 168.211201 -274.349368) (xy 168.162346 -274.3553)
			(xy 168.113171 -274.353319) (xy 168.064952 -274.343475) (xy 168.018936 -274.326023) (xy 167.976315 -274.301416)
			(xy 167.938194 -274.270291) (xy 167.905559 -274.233454) (xy 167.879256 -274.191858) (xy 167.859965 -274.146582)
			(xy 167.848188 -274.098798) (xy 167.844228 -274.049744) (xy 166.555166 -274.049744) (xy 166.554671 -274.074351)
			(xy 166.546776 -274.122928) (xy 166.531192 -274.169609) (xy 166.508321 -274.213186) (xy 166.478756 -274.25253)
			(xy 166.443263 -274.286622) (xy 166.40276 -274.314578) (xy 166.358298 -274.335676) (xy 166.311027 -274.349368)
			(xy 166.262172 -274.3553) (xy 166.212997 -274.353319) (xy 166.164778 -274.343475) (xy 166.118762 -274.326023)
			(xy 166.076141 -274.301416) (xy 166.03802 -274.270291) (xy 166.005385 -274.233454) (xy 165.979082 -274.191858)
			(xy 165.959791 -274.146582) (xy 165.948014 -274.098798) (xy 165.944054 -274.049744) (xy 164.655246 -274.049744)
			(xy 164.654751 -274.074351) (xy 164.646856 -274.122928) (xy 164.631272 -274.169609) (xy 164.608401 -274.213186)
			(xy 164.578836 -274.25253) (xy 164.543343 -274.286622) (xy 164.50284 -274.314578) (xy 164.458378 -274.335676)
			(xy 164.411107 -274.349368) (xy 164.362252 -274.3553) (xy 164.313077 -274.353319) (xy 164.264858 -274.343475)
			(xy 164.218842 -274.326023) (xy 164.176221 -274.301416) (xy 164.1381 -274.270291) (xy 164.105465 -274.233454)
			(xy 164.079162 -274.191858) (xy 164.059871 -274.146582) (xy 164.048094 -274.098798) (xy 164.044134 -274.049744)
			(xy 162.755326 -274.049744) (xy 162.754831 -274.074351) (xy 162.746936 -274.122928) (xy 162.731352 -274.169609)
			(xy 162.708481 -274.213186) (xy 162.678916 -274.25253) (xy 162.643423 -274.286622) (xy 162.60292 -274.314578)
			(xy 162.558458 -274.335676) (xy 162.511187 -274.349368) (xy 162.462332 -274.3553) (xy 162.413157 -274.353319)
			(xy 162.364938 -274.343475) (xy 162.318922 -274.326023) (xy 162.276301 -274.301416) (xy 162.23818 -274.270291)
			(xy 162.205545 -274.233454) (xy 162.179242 -274.191858) (xy 162.159951 -274.146582) (xy 162.148174 -274.098798)
			(xy 162.144214 -274.049744) (xy 160.855152 -274.049744) (xy 160.854657 -274.074351) (xy 160.846762 -274.122928)
			(xy 160.831178 -274.169609) (xy 160.808307 -274.213186) (xy 160.778742 -274.25253) (xy 160.743249 -274.286622)
			(xy 160.702746 -274.314578) (xy 160.658284 -274.335676) (xy 160.611013 -274.349368) (xy 160.562158 -274.3553)
			(xy 160.512983 -274.353319) (xy 160.464764 -274.343475) (xy 160.418748 -274.326023) (xy 160.376127 -274.301416)
			(xy 160.338006 -274.270291) (xy 160.305371 -274.233454) (xy 160.279068 -274.191858) (xy 160.259777 -274.146582)
			(xy 160.248 -274.098798) (xy 160.24404 -274.049744) (xy 80.854804 -274.049744) (xy 80.854309 -274.074351)
			(xy 80.846414 -274.122928) (xy 80.83083 -274.169609) (xy 80.807959 -274.213186) (xy 80.778394 -274.25253)
			(xy 80.742901 -274.286622) (xy 80.702398 -274.314578) (xy 80.657936 -274.335676) (xy 80.610665 -274.349368)
			(xy 80.56181 -274.3553) (xy 80.512635 -274.353319) (xy 80.464416 -274.343475) (xy 80.4184 -274.326023)
			(xy 80.375779 -274.301416) (xy 80.337658 -274.270291) (xy 80.305023 -274.233454) (xy 80.27872 -274.191858)
			(xy 80.259429 -274.146582) (xy 80.247652 -274.098798) (xy 80.243692 -274.049744) (xy 78.954884 -274.049744)
			(xy 78.954389 -274.074351) (xy 78.946494 -274.122928) (xy 78.93091 -274.169609) (xy 78.908039 -274.213186)
			(xy 78.878474 -274.25253) (xy 78.842981 -274.286622) (xy 78.802478 -274.314578) (xy 78.758016 -274.335676)
			(xy 78.710745 -274.349368) (xy 78.66189 -274.3553) (xy 78.612715 -274.353319) (xy 78.564496 -274.343475)
			(xy 78.51848 -274.326023) (xy 78.475859 -274.301416) (xy 78.437738 -274.270291) (xy 78.405103 -274.233454)
			(xy 78.3788 -274.191858) (xy 78.359509 -274.146582) (xy 78.347732 -274.098798) (xy 78.343772 -274.049744)
			(xy 77.054964 -274.049744) (xy 77.054469 -274.074351) (xy 77.046574 -274.122928) (xy 77.03099 -274.169609)
			(xy 77.008119 -274.213186) (xy 76.978554 -274.25253) (xy 76.943061 -274.286622) (xy 76.902558 -274.314578)
			(xy 76.858096 -274.335676) (xy 76.810825 -274.349368) (xy 76.76197 -274.3553) (xy 76.712795 -274.353319)
			(xy 76.664576 -274.343475) (xy 76.61856 -274.326023) (xy 76.575939 -274.301416) (xy 76.537818 -274.270291)
			(xy 76.505183 -274.233454) (xy 76.47888 -274.191858) (xy 76.459589 -274.146582) (xy 76.447812 -274.098798)
			(xy 76.443852 -274.049744) (xy 75.155044 -274.049744) (xy 75.154549 -274.074351) (xy 75.146654 -274.122928)
			(xy 75.13107 -274.169609) (xy 75.108199 -274.213186) (xy 75.078634 -274.25253) (xy 75.043141 -274.286622)
			(xy 75.002638 -274.314578) (xy 74.958176 -274.335676) (xy 74.910905 -274.349368) (xy 74.86205 -274.3553)
			(xy 74.812875 -274.353319) (xy 74.764656 -274.343475) (xy 74.71864 -274.326023) (xy 74.676019 -274.301416)
			(xy 74.637898 -274.270291) (xy 74.605263 -274.233454) (xy 74.57896 -274.191858) (xy 74.559669 -274.146582)
			(xy 74.547892 -274.098798) (xy 74.543932 -274.049744) (xy 73.25487 -274.049744) (xy 73.254375 -274.074351)
			(xy 73.24648 -274.122928) (xy 73.230896 -274.169609) (xy 73.208025 -274.213186) (xy 73.17846 -274.25253)
			(xy 73.142967 -274.286622) (xy 73.102464 -274.314578) (xy 73.058002 -274.335676) (xy 73.010731 -274.349368)
			(xy 72.961876 -274.3553) (xy 72.912701 -274.353319) (xy 72.864482 -274.343475) (xy 72.818466 -274.326023)
			(xy 72.775845 -274.301416) (xy 72.737724 -274.270291) (xy 72.705089 -274.233454) (xy 72.678786 -274.191858)
			(xy 72.659495 -274.146582) (xy 72.647718 -274.098798) (xy 72.643758 -274.049744) (xy 71.35495 -274.049744)
			(xy 71.354455 -274.074351) (xy 71.34656 -274.122928) (xy 71.330976 -274.169609) (xy 71.308105 -274.213186)
			(xy 71.27854 -274.25253) (xy 71.243047 -274.286622) (xy 71.202544 -274.314578) (xy 71.158082 -274.335676)
			(xy 71.110811 -274.349368) (xy 71.061956 -274.3553) (xy 71.012781 -274.353319) (xy 70.964562 -274.343475)
			(xy 70.918546 -274.326023) (xy 70.875925 -274.301416) (xy 70.837804 -274.270291) (xy 70.805169 -274.233454)
			(xy 70.778866 -274.191858) (xy 70.759575 -274.146582) (xy 70.747798 -274.098798) (xy 70.743838 -274.049744)
			(xy 69.45503 -274.049744) (xy 69.454535 -274.074351) (xy 69.44664 -274.122928) (xy 69.431056 -274.169609)
			(xy 69.408185 -274.213186) (xy 69.37862 -274.25253) (xy 69.343127 -274.286622) (xy 69.302624 -274.314578)
			(xy 69.258162 -274.335676) (xy 69.210891 -274.349368) (xy 69.162036 -274.3553) (xy 69.112861 -274.353319)
			(xy 69.064642 -274.343475) (xy 69.018626 -274.326023) (xy 68.976005 -274.301416) (xy 68.937884 -274.270291)
			(xy 68.905249 -274.233454) (xy 68.878946 -274.191858) (xy 68.859655 -274.146582) (xy 68.847878 -274.098798)
			(xy 68.843918 -274.049744) (xy 67.554856 -274.049744) (xy 67.554361 -274.074351) (xy 67.546466 -274.122928)
			(xy 67.530882 -274.169609) (xy 67.508011 -274.213186) (xy 67.478446 -274.25253) (xy 67.442953 -274.286622)
			(xy 67.40245 -274.314578) (xy 67.357988 -274.335676) (xy 67.310717 -274.349368) (xy 67.261862 -274.3553)
			(xy 67.212687 -274.353319) (xy 67.164468 -274.343475) (xy 67.118452 -274.326023) (xy 67.075831 -274.301416)
			(xy 67.03771 -274.270291) (xy 67.005075 -274.233454) (xy 66.978772 -274.191858) (xy 66.959481 -274.146582)
			(xy 66.947704 -274.098798) (xy 66.943744 -274.049744) (xy 65.654936 -274.049744) (xy 65.654441 -274.074351)
			(xy 65.646546 -274.122928) (xy 65.630962 -274.169609) (xy 65.608091 -274.213186) (xy 65.578526 -274.25253)
			(xy 65.543033 -274.286622) (xy 65.50253 -274.314578) (xy 65.458068 -274.335676) (xy 65.410797 -274.349368)
			(xy 65.361942 -274.3553) (xy 65.312767 -274.353319) (xy 65.264548 -274.343475) (xy 65.218532 -274.326023)
			(xy 65.175911 -274.301416) (xy 65.13779 -274.270291) (xy 65.105155 -274.233454) (xy 65.078852 -274.191858)
			(xy 65.059561 -274.146582) (xy 65.047784 -274.098798) (xy 65.043824 -274.049744) (xy 63.755016 -274.049744)
			(xy 63.754521 -274.074351) (xy 63.746626 -274.122928) (xy 63.731042 -274.169609) (xy 63.708171 -274.213186)
			(xy 63.678606 -274.25253) (xy 63.643113 -274.286622) (xy 63.60261 -274.314578) (xy 63.558148 -274.335676)
			(xy 63.510877 -274.349368) (xy 63.462022 -274.3553) (xy 63.412847 -274.353319) (xy 63.364628 -274.343475)
			(xy 63.318612 -274.326023) (xy 63.275991 -274.301416) (xy 63.23787 -274.270291) (xy 63.205235 -274.233454)
			(xy 63.178932 -274.191858) (xy 63.159641 -274.146582) (xy 63.147864 -274.098798) (xy 63.143904 -274.049744)
			(xy 61.854842 -274.049744) (xy 61.854347 -274.074351) (xy 61.846452 -274.122928) (xy 61.830868 -274.169609)
			(xy 61.807997 -274.213186) (xy 61.778432 -274.25253) (xy 61.742939 -274.286622) (xy 61.702436 -274.314578)
			(xy 61.657974 -274.335676) (xy 61.610703 -274.349368) (xy 61.561848 -274.3553) (xy 61.512673 -274.353319)
			(xy 61.464454 -274.343475) (xy 61.418438 -274.326023) (xy 61.375817 -274.301416) (xy 61.337696 -274.270291)
			(xy 61.305061 -274.233454) (xy 61.278758 -274.191858) (xy 61.259467 -274.146582) (xy 61.24769 -274.098798)
			(xy 61.24373 -274.049744) (xy 59.954917 -274.049744) (xy 59.954427 -274.074097) (xy 59.946532 -274.122674)
			(xy 59.930948 -274.169355) (xy 59.908077 -274.212932) (xy 59.878512 -274.252276) (xy 59.843019 -274.286368)
			(xy 59.802516 -274.314324) (xy 59.758054 -274.335422) (xy 59.710783 -274.349114) (xy 59.661928 -274.355046)
			(xy 59.612753 -274.353065) (xy 59.564534 -274.343221) (xy 59.518518 -274.325769) (xy 59.475897 -274.301162)
			(xy 59.437776 -274.270037) (xy 59.405141 -274.2332) (xy 59.378838 -274.191604) (xy 59.359547 -274.146328)
			(xy 59.34777 -274.098544) (xy 59.34381 -274.04949) (xy 58.055251 -274.04949) (xy 58.055256 -274.049744)
			(xy 58.054761 -274.074351) (xy 58.046866 -274.122928) (xy 58.031282 -274.169609) (xy 58.008411 -274.213186)
			(xy 57.978846 -274.25253) (xy 57.943353 -274.286622) (xy 57.90285 -274.314578) (xy 57.858388 -274.335676)
			(xy 57.811117 -274.349368) (xy 57.762262 -274.3553) (xy 57.713087 -274.353319) (xy 57.664868 -274.343475)
			(xy 57.618852 -274.326023) (xy 57.576231 -274.301416) (xy 57.53811 -274.270291) (xy 57.505475 -274.233454)
			(xy 57.479172 -274.191858) (xy 57.459881 -274.146582) (xy 57.448104 -274.098798) (xy 57.444144 -274.049744)
			(xy 56.155082 -274.049744) (xy 56.154587 -274.074351) (xy 56.146692 -274.122928) (xy 56.131108 -274.169609)
			(xy 56.108237 -274.213186) (xy 56.078672 -274.25253) (xy 56.043179 -274.286622) (xy 56.002676 -274.314578)
			(xy 55.958214 -274.335676) (xy 55.910943 -274.349368) (xy 55.862088 -274.3553) (xy 55.812913 -274.353319)
			(xy 55.764694 -274.343475) (xy 55.718678 -274.326023) (xy 55.676057 -274.301416) (xy 55.637936 -274.270291)
			(xy 55.605301 -274.233454) (xy 55.578998 -274.191858) (xy 55.559707 -274.146582) (xy 55.54793 -274.098798)
			(xy 55.54397 -274.049744) (xy 54.255162 -274.049744) (xy 54.254667 -274.074351) (xy 54.246772 -274.122928)
			(xy 54.231188 -274.169609) (xy 54.208317 -274.213186) (xy 54.178752 -274.25253) (xy 54.143259 -274.286622)
			(xy 54.102756 -274.314578) (xy 54.058294 -274.335676) (xy 54.011023 -274.349368) (xy 53.962168 -274.3553)
			(xy 53.912993 -274.353319) (xy 53.864774 -274.343475) (xy 53.818758 -274.326023) (xy 53.776137 -274.301416)
			(xy 53.738016 -274.270291) (xy 53.705381 -274.233454) (xy 53.679078 -274.191858) (xy 53.659787 -274.146582)
			(xy 53.64801 -274.098798) (xy 53.64405 -274.049744) (xy 52.355242 -274.049744) (xy 52.354747 -274.074351)
			(xy 52.346852 -274.122928) (xy 52.331268 -274.169609) (xy 52.308397 -274.213186) (xy 52.278832 -274.25253)
			(xy 52.243339 -274.286622) (xy 52.202836 -274.314578) (xy 52.158374 -274.335676) (xy 52.111103 -274.349368)
			(xy 52.062248 -274.3553) (xy 52.013073 -274.353319) (xy 51.964854 -274.343475) (xy 51.918838 -274.326023)
			(xy 51.876217 -274.301416) (xy 51.838096 -274.270291) (xy 51.805461 -274.233454) (xy 51.779158 -274.191858)
			(xy 51.759867 -274.146582) (xy 51.74809 -274.098798) (xy 51.74413 -274.049744) (xy 50.455068 -274.049744)
			(xy 50.454573 -274.074351) (xy 50.446678 -274.122928) (xy 50.431094 -274.169609) (xy 50.408223 -274.213186)
			(xy 50.378658 -274.25253) (xy 50.343165 -274.286622) (xy 50.302662 -274.314578) (xy 50.2582 -274.335676)
			(xy 50.210929 -274.349368) (xy 50.162074 -274.3553) (xy 50.112899 -274.353319) (xy 50.06468 -274.343475)
			(xy 50.018664 -274.326023) (xy 49.976043 -274.301416) (xy 49.937922 -274.270291) (xy 49.905287 -274.233454)
			(xy 49.878984 -274.191858) (xy 49.859693 -274.146582) (xy 49.847916 -274.098798) (xy 49.843956 -274.049744)
			(xy 48.555148 -274.049744) (xy 48.554653 -274.074351) (xy 48.546758 -274.122928) (xy 48.531174 -274.169609)
			(xy 48.508303 -274.213186) (xy 48.478738 -274.25253) (xy 48.443245 -274.286622) (xy 48.402742 -274.314578)
			(xy 48.35828 -274.335676) (xy 48.311009 -274.349368) (xy 48.262154 -274.3553) (xy 48.212979 -274.353319)
			(xy 48.16476 -274.343475) (xy 48.118744 -274.326023) (xy 48.076123 -274.301416) (xy 48.038002 -274.270291)
			(xy 48.005367 -274.233454) (xy 47.979064 -274.191858) (xy 47.959773 -274.146582) (xy 47.947996 -274.098798)
			(xy 47.944036 -274.049744) (xy 46.655228 -274.049744) (xy 46.654733 -274.074351) (xy 46.646838 -274.122928)
			(xy 46.631254 -274.169609) (xy 46.608383 -274.213186) (xy 46.578818 -274.25253) (xy 46.543325 -274.286622)
			(xy 46.502822 -274.314578) (xy 46.45836 -274.335676) (xy 46.411089 -274.349368) (xy 46.362234 -274.3553)
			(xy 46.313059 -274.353319) (xy 46.26484 -274.343475) (xy 46.218824 -274.326023) (xy 46.176203 -274.301416)
			(xy 46.138082 -274.270291) (xy 46.105447 -274.233454) (xy 46.079144 -274.191858) (xy 46.059853 -274.146582)
			(xy 46.048076 -274.098798) (xy 46.044116 -274.049744) (xy 44.755054 -274.049744) (xy 44.754559 -274.074351)
			(xy 44.746664 -274.122928) (xy 44.73108 -274.169609) (xy 44.708209 -274.213186) (xy 44.678644 -274.25253)
			(xy 44.643151 -274.286622) (xy 44.602648 -274.314578) (xy 44.558186 -274.335676) (xy 44.510915 -274.349368)
			(xy 44.46206 -274.3553) (xy 44.412885 -274.353319) (xy 44.364666 -274.343475) (xy 44.31865 -274.326023)
			(xy 44.276029 -274.301416) (xy 44.237908 -274.270291) (xy 44.205273 -274.233454) (xy 44.17897 -274.191858)
			(xy 44.159679 -274.146582) (xy 44.147902 -274.098798) (xy 44.143942 -274.049744) (xy 0.508 -274.049744)
			(xy 0.508 -274.999958) (xy 45.094156 -274.999958) (xy 45.098116 -274.950904) (xy 45.109893 -274.90312)
			(xy 45.129184 -274.857844) (xy 45.155487 -274.816248) (xy 45.188122 -274.779411) (xy 45.226243 -274.748286)
			(xy 45.268864 -274.723679) (xy 45.31488 -274.706227) (xy 45.363099 -274.696383) (xy 45.412274 -274.694402)
			(xy 45.461129 -274.700334) (xy 45.5084 -274.714026) (xy 45.552862 -274.735124) (xy 45.593365 -274.76308)
			(xy 45.628858 -274.797172) (xy 45.658423 -274.836516) (xy 45.681294 -274.880093) (xy 45.696878 -274.926774)
			(xy 45.704773 -274.975351) (xy 45.705268 -274.999958) (xy 46.994076 -274.999958) (xy 46.998036 -274.950904)
			(xy 47.009813 -274.90312) (xy 47.029104 -274.857844) (xy 47.055407 -274.816248) (xy 47.088042 -274.779411)
			(xy 47.126163 -274.748286) (xy 47.168784 -274.723679) (xy 47.2148 -274.706227) (xy 47.263019 -274.696383)
			(xy 47.312194 -274.694402) (xy 47.361049 -274.700334) (xy 47.40832 -274.714026) (xy 47.452782 -274.735124)
			(xy 47.493285 -274.76308) (xy 47.528778 -274.797172) (xy 47.558343 -274.836516) (xy 47.581214 -274.880093)
			(xy 47.596798 -274.926774) (xy 47.604693 -274.975351) (xy 47.605188 -274.999958) (xy 48.893996 -274.999958)
			(xy 48.897956 -274.950904) (xy 48.909733 -274.90312) (xy 48.929024 -274.857844) (xy 48.955327 -274.816248)
			(xy 48.987962 -274.779411) (xy 49.026083 -274.748286) (xy 49.068704 -274.723679) (xy 49.11472 -274.706227)
			(xy 49.162939 -274.696383) (xy 49.212114 -274.694402) (xy 49.260969 -274.700334) (xy 49.30824 -274.714026)
			(xy 49.352702 -274.735124) (xy 49.393205 -274.76308) (xy 49.428698 -274.797172) (xy 49.458263 -274.836516)
			(xy 49.481134 -274.880093) (xy 49.496718 -274.926774) (xy 49.504613 -274.975351) (xy 49.505108 -274.999958)
			(xy 50.79417 -274.999958) (xy 50.79813 -274.950904) (xy 50.809907 -274.90312) (xy 50.829198 -274.857844)
			(xy 50.855501 -274.816248) (xy 50.888136 -274.779411) (xy 50.926257 -274.748286) (xy 50.968878 -274.723679)
			(xy 51.014894 -274.706227) (xy 51.063113 -274.696383) (xy 51.112288 -274.694402) (xy 51.161143 -274.700334)
			(xy 51.208414 -274.714026) (xy 51.252876 -274.735124) (xy 51.293379 -274.76308) (xy 51.328872 -274.797172)
			(xy 51.358437 -274.836516) (xy 51.381308 -274.880093) (xy 51.396892 -274.926774) (xy 51.404787 -274.975351)
			(xy 51.405282 -274.999958) (xy 52.69409 -274.999958) (xy 52.69805 -274.950904) (xy 52.709827 -274.90312)
			(xy 52.729118 -274.857844) (xy 52.755421 -274.816248) (xy 52.788056 -274.779411) (xy 52.826177 -274.748286)
			(xy 52.868798 -274.723679) (xy 52.914814 -274.706227) (xy 52.963033 -274.696383) (xy 53.012208 -274.694402)
			(xy 53.061063 -274.700334) (xy 53.108334 -274.714026) (xy 53.152796 -274.735124) (xy 53.193299 -274.76308)
			(xy 53.228792 -274.797172) (xy 53.258357 -274.836516) (xy 53.281228 -274.880093) (xy 53.296812 -274.926774)
			(xy 53.304707 -274.975351) (xy 53.305202 -274.999958) (xy 54.59401 -274.999958) (xy 54.59797 -274.950904)
			(xy 54.609747 -274.90312) (xy 54.629038 -274.857844) (xy 54.655341 -274.816248) (xy 54.687976 -274.779411)
			(xy 54.726097 -274.748286) (xy 54.768718 -274.723679) (xy 54.814734 -274.706227) (xy 54.862953 -274.696383)
			(xy 54.912128 -274.694402) (xy 54.960983 -274.700334) (xy 55.008254 -274.714026) (xy 55.052716 -274.735124)
			(xy 55.093219 -274.76308) (xy 55.128712 -274.797172) (xy 55.158277 -274.836516) (xy 55.181148 -274.880093)
			(xy 55.196732 -274.926774) (xy 55.204627 -274.975351) (xy 55.205122 -274.999958) (xy 56.494184 -274.999958)
			(xy 56.498144 -274.950904) (xy 56.509921 -274.90312) (xy 56.529212 -274.857844) (xy 56.555515 -274.816248)
			(xy 56.58815 -274.779411) (xy 56.626271 -274.748286) (xy 56.668892 -274.723679) (xy 56.714908 -274.706227)
			(xy 56.763127 -274.696383) (xy 56.812302 -274.694402) (xy 56.861157 -274.700334) (xy 56.908428 -274.714026)
			(xy 56.95289 -274.735124) (xy 56.993393 -274.76308) (xy 57.028886 -274.797172) (xy 57.058451 -274.836516)
			(xy 57.081322 -274.880093) (xy 57.096906 -274.926774) (xy 57.104801 -274.975351) (xy 57.105296 -274.999958)
			(xy 58.394104 -274.999958) (xy 58.398064 -274.950904) (xy 58.409841 -274.90312) (xy 58.429132 -274.857844)
			(xy 58.455435 -274.816248) (xy 58.48807 -274.779411) (xy 58.526191 -274.748286) (xy 58.568812 -274.723679)
			(xy 58.614828 -274.706227) (xy 58.663047 -274.696383) (xy 58.712222 -274.694402) (xy 58.761077 -274.700334)
			(xy 58.808348 -274.714026) (xy 58.85281 -274.735124) (xy 58.893313 -274.76308) (xy 58.928806 -274.797172)
			(xy 58.958371 -274.836516) (xy 58.981242 -274.880093) (xy 58.996826 -274.926774) (xy 59.004721 -274.975351)
			(xy 59.005211 -274.999704) (xy 60.29377 -274.999704) (xy 60.29773 -274.95065) (xy 60.309507 -274.902866)
			(xy 60.328798 -274.85759) (xy 60.355101 -274.815994) (xy 60.387736 -274.779157) (xy 60.425857 -274.748032)
			(xy 60.468478 -274.723425) (xy 60.514494 -274.705973) (xy 60.562713 -274.696129) (xy 60.611888 -274.694148)
			(xy 60.660743 -274.70008) (xy 60.708014 -274.713772) (xy 60.752476 -274.73487) (xy 60.792979 -274.762826)
			(xy 60.828472 -274.796918) (xy 60.858037 -274.836262) (xy 60.880908 -274.879839) (xy 60.896492 -274.92652)
			(xy 60.904387 -274.975097) (xy 60.904882 -274.999704) (xy 60.904877 -274.999958) (xy 62.19369 -274.999958)
			(xy 62.19765 -274.950904) (xy 62.209427 -274.90312) (xy 62.228718 -274.857844) (xy 62.255021 -274.816248)
			(xy 62.287656 -274.779411) (xy 62.325777 -274.748286) (xy 62.368398 -274.723679) (xy 62.414414 -274.706227)
			(xy 62.462633 -274.696383) (xy 62.511808 -274.694402) (xy 62.560663 -274.700334) (xy 62.607934 -274.714026)
			(xy 62.652396 -274.735124) (xy 62.692899 -274.76308) (xy 62.728392 -274.797172) (xy 62.757957 -274.836516)
			(xy 62.780828 -274.880093) (xy 62.796412 -274.926774) (xy 62.804307 -274.975351) (xy 62.804797 -274.999704)
			(xy 64.093864 -274.999704) (xy 64.097824 -274.95065) (xy 64.109601 -274.902866) (xy 64.128892 -274.85759)
			(xy 64.155195 -274.815994) (xy 64.18783 -274.779157) (xy 64.225951 -274.748032) (xy 64.268572 -274.723425)
			(xy 64.314588 -274.705973) (xy 64.362807 -274.696129) (xy 64.411982 -274.694148) (xy 64.460837 -274.70008)
			(xy 64.508108 -274.713772) (xy 64.55257 -274.73487) (xy 64.593073 -274.762826) (xy 64.628566 -274.796918)
			(xy 64.658131 -274.836262) (xy 64.681002 -274.879839) (xy 64.696586 -274.92652) (xy 64.704481 -274.975097)
			(xy 64.704976 -274.999704) (xy 64.704971 -274.999958) (xy 65.993784 -274.999958) (xy 65.997744 -274.950904)
			(xy 66.009521 -274.90312) (xy 66.028812 -274.857844) (xy 66.055115 -274.816248) (xy 66.08775 -274.779411)
			(xy 66.125871 -274.748286) (xy 66.168492 -274.723679) (xy 66.214508 -274.706227) (xy 66.262727 -274.696383)
			(xy 66.311902 -274.694402) (xy 66.360757 -274.700334) (xy 66.408028 -274.714026) (xy 66.45249 -274.735124)
			(xy 66.492993 -274.76308) (xy 66.528486 -274.797172) (xy 66.558051 -274.836516) (xy 66.580922 -274.880093)
			(xy 66.596506 -274.926774) (xy 66.604401 -274.975351) (xy 66.604891 -274.999704) (xy 67.893704 -274.999704)
			(xy 67.897664 -274.95065) (xy 67.909441 -274.902866) (xy 67.928732 -274.85759) (xy 67.955035 -274.815994)
			(xy 67.98767 -274.779157) (xy 68.025791 -274.748032) (xy 68.068412 -274.723425) (xy 68.114428 -274.705973)
			(xy 68.162647 -274.696129) (xy 68.211822 -274.694148) (xy 68.260677 -274.70008) (xy 68.307948 -274.713772)
			(xy 68.35241 -274.73487) (xy 68.392913 -274.762826) (xy 68.428406 -274.796918) (xy 68.457971 -274.836262)
			(xy 68.480842 -274.879839) (xy 68.496426 -274.92652) (xy 68.504321 -274.975097) (xy 68.504816 -274.999704)
			(xy 68.504811 -274.999958) (xy 69.793624 -274.999958) (xy 69.797584 -274.950904) (xy 69.809361 -274.90312)
			(xy 69.828652 -274.857844) (xy 69.854955 -274.816248) (xy 69.88759 -274.779411) (xy 69.925711 -274.748286)
			(xy 69.968332 -274.723679) (xy 70.014348 -274.706227) (xy 70.062567 -274.696383) (xy 70.111742 -274.694402)
			(xy 70.160597 -274.700334) (xy 70.207868 -274.714026) (xy 70.25233 -274.735124) (xy 70.292833 -274.76308)
			(xy 70.328326 -274.797172) (xy 70.357891 -274.836516) (xy 70.380762 -274.880093) (xy 70.396346 -274.926774)
			(xy 70.404241 -274.975351) (xy 70.404731 -274.999704) (xy 71.693798 -274.999704) (xy 71.697758 -274.95065)
			(xy 71.709535 -274.902866) (xy 71.728826 -274.85759) (xy 71.755129 -274.815994) (xy 71.787764 -274.779157)
			(xy 71.825885 -274.748032) (xy 71.868506 -274.723425) (xy 71.914522 -274.705973) (xy 71.962741 -274.696129)
			(xy 72.011916 -274.694148) (xy 72.060771 -274.70008) (xy 72.108042 -274.713772) (xy 72.152504 -274.73487)
			(xy 72.193007 -274.762826) (xy 72.2285 -274.796918) (xy 72.258065 -274.836262) (xy 72.280936 -274.879839)
			(xy 72.29652 -274.92652) (xy 72.304415 -274.975097) (xy 72.30491 -274.999704) (xy 72.304905 -274.999958)
			(xy 73.593718 -274.999958) (xy 73.597678 -274.950904) (xy 73.609455 -274.90312) (xy 73.628746 -274.857844)
			(xy 73.655049 -274.816248) (xy 73.687684 -274.779411) (xy 73.725805 -274.748286) (xy 73.768426 -274.723679)
			(xy 73.814442 -274.706227) (xy 73.862661 -274.696383) (xy 73.911836 -274.694402) (xy 73.960691 -274.700334)
			(xy 74.007962 -274.714026) (xy 74.052424 -274.735124) (xy 74.092927 -274.76308) (xy 74.12842 -274.797172)
			(xy 74.157985 -274.836516) (xy 74.180856 -274.880093) (xy 74.19644 -274.926774) (xy 74.204335 -274.975351)
			(xy 74.204825 -274.999704) (xy 75.493892 -274.999704) (xy 75.497852 -274.95065) (xy 75.509629 -274.902866)
			(xy 75.52892 -274.85759) (xy 75.555223 -274.815994) (xy 75.587858 -274.779157) (xy 75.625979 -274.748032)
			(xy 75.6686 -274.723425) (xy 75.714616 -274.705973) (xy 75.762835 -274.696129) (xy 75.81201 -274.694148)
			(xy 75.860865 -274.70008) (xy 75.908136 -274.713772) (xy 75.952598 -274.73487) (xy 75.993101 -274.762826)
			(xy 76.028594 -274.796918) (xy 76.058159 -274.836262) (xy 76.08103 -274.879839) (xy 76.096614 -274.92652)
			(xy 76.104509 -274.975097) (xy 76.105004 -274.999704) (xy 76.104999 -274.999958) (xy 77.393812 -274.999958)
			(xy 77.397772 -274.950904) (xy 77.409549 -274.90312) (xy 77.42884 -274.857844) (xy 77.455143 -274.816248)
			(xy 77.487778 -274.779411) (xy 77.525899 -274.748286) (xy 77.56852 -274.723679) (xy 77.614536 -274.706227)
			(xy 77.662755 -274.696383) (xy 77.71193 -274.694402) (xy 77.760785 -274.700334) (xy 77.808056 -274.714026)
			(xy 77.852518 -274.735124) (xy 77.893021 -274.76308) (xy 77.928514 -274.797172) (xy 77.958079 -274.836516)
			(xy 77.98095 -274.880093) (xy 77.996534 -274.926774) (xy 78.004429 -274.975351) (xy 78.004924 -274.999958)
			(xy 79.293732 -274.999958) (xy 79.297692 -274.950904) (xy 79.309469 -274.90312) (xy 79.32876 -274.857844)
			(xy 79.355063 -274.816248) (xy 79.387698 -274.779411) (xy 79.425819 -274.748286) (xy 79.46844 -274.723679)
			(xy 79.514456 -274.706227) (xy 79.562675 -274.696383) (xy 79.61185 -274.694402) (xy 79.660705 -274.700334)
			(xy 79.707976 -274.714026) (xy 79.752438 -274.735124) (xy 79.792941 -274.76308) (xy 79.828434 -274.797172)
			(xy 79.857999 -274.836516) (xy 79.88087 -274.880093) (xy 79.896454 -274.926774) (xy 79.904349 -274.975351)
			(xy 79.904839 -274.999704) (xy 81.19416 -274.999704) (xy 81.19812 -274.95065) (xy 81.209897 -274.902866)
			(xy 81.229188 -274.85759) (xy 81.255491 -274.815994) (xy 81.288126 -274.779157) (xy 81.326247 -274.748032)
			(xy 81.368868 -274.723425) (xy 81.414884 -274.705973) (xy 81.463103 -274.696129) (xy 81.512278 -274.694148)
			(xy 81.561133 -274.70008) (xy 81.608404 -274.713772) (xy 81.652866 -274.73487) (xy 81.693369 -274.762826)
			(xy 81.728862 -274.796918) (xy 81.758427 -274.836262) (xy 81.781298 -274.879839) (xy 81.796882 -274.92652)
			(xy 81.804777 -274.975097) (xy 81.805272 -274.999704) (xy 82.14412 -274.999704) (xy 82.14808 -274.95065)
			(xy 82.159857 -274.902866) (xy 82.179148 -274.85759) (xy 82.205451 -274.815994) (xy 82.238086 -274.779157)
			(xy 82.276207 -274.748032) (xy 82.318828 -274.723425) (xy 82.364844 -274.705973) (xy 82.413063 -274.696129)
			(xy 82.462238 -274.694148) (xy 82.511093 -274.70008) (xy 82.558364 -274.713772) (xy 82.602826 -274.73487)
			(xy 82.643329 -274.762826) (xy 82.678822 -274.796918) (xy 82.708387 -274.836262) (xy 82.731258 -274.879839)
			(xy 82.746842 -274.92652) (xy 82.754737 -274.975097) (xy 82.755232 -274.999704) (xy 82.755227 -274.999958)
			(xy 161.194254 -274.999958) (xy 161.198214 -274.950904) (xy 161.209991 -274.90312) (xy 161.229282 -274.857844)
			(xy 161.255585 -274.816248) (xy 161.28822 -274.779411) (xy 161.326341 -274.748286) (xy 161.368962 -274.723679)
			(xy 161.414978 -274.706227) (xy 161.463197 -274.696383) (xy 161.512372 -274.694402) (xy 161.561227 -274.700334)
			(xy 161.608498 -274.714026) (xy 161.65296 -274.735124) (xy 161.693463 -274.76308) (xy 161.728956 -274.797172)
			(xy 161.758521 -274.836516) (xy 161.781392 -274.880093) (xy 161.796976 -274.926774) (xy 161.804871 -274.975351)
			(xy 161.805366 -274.999958) (xy 163.094174 -274.999958) (xy 163.098134 -274.950904) (xy 163.109911 -274.90312)
			(xy 163.129202 -274.857844) (xy 163.155505 -274.816248) (xy 163.18814 -274.779411) (xy 163.226261 -274.748286)
			(xy 163.268882 -274.723679) (xy 163.314898 -274.706227) (xy 163.363117 -274.696383) (xy 163.412292 -274.694402)
			(xy 163.461147 -274.700334) (xy 163.508418 -274.714026) (xy 163.55288 -274.735124) (xy 163.593383 -274.76308)
			(xy 163.628876 -274.797172) (xy 163.658441 -274.836516) (xy 163.681312 -274.880093) (xy 163.696896 -274.926774)
			(xy 163.704791 -274.975351) (xy 163.705286 -274.999958) (xy 164.994094 -274.999958) (xy 164.998054 -274.950904)
			(xy 165.009831 -274.90312) (xy 165.029122 -274.857844) (xy 165.055425 -274.816248) (xy 165.08806 -274.779411)
			(xy 165.126181 -274.748286) (xy 165.168802 -274.723679) (xy 165.214818 -274.706227) (xy 165.263037 -274.696383)
			(xy 165.312212 -274.694402) (xy 165.361067 -274.700334) (xy 165.408338 -274.714026) (xy 165.4528 -274.735124)
			(xy 165.493303 -274.76308) (xy 165.528796 -274.797172) (xy 165.558361 -274.836516) (xy 165.581232 -274.880093)
			(xy 165.596816 -274.926774) (xy 165.604711 -274.975351) (xy 165.605206 -274.999958) (xy 166.894268 -274.999958)
			(xy 166.898228 -274.950904) (xy 166.910005 -274.90312) (xy 166.929296 -274.857844) (xy 166.955599 -274.816248)
			(xy 166.988234 -274.779411) (xy 167.026355 -274.748286) (xy 167.068976 -274.723679) (xy 167.114992 -274.706227)
			(xy 167.163211 -274.696383) (xy 167.212386 -274.694402) (xy 167.261241 -274.700334) (xy 167.308512 -274.714026)
			(xy 167.352974 -274.735124) (xy 167.393477 -274.76308) (xy 167.42897 -274.797172) (xy 167.458535 -274.836516)
			(xy 167.481406 -274.880093) (xy 167.49699 -274.926774) (xy 167.504885 -274.975351) (xy 167.50538 -274.999958)
			(xy 168.794188 -274.999958) (xy 168.798148 -274.950904) (xy 168.809925 -274.90312) (xy 168.829216 -274.857844)
			(xy 168.855519 -274.816248) (xy 168.888154 -274.779411) (xy 168.926275 -274.748286) (xy 168.968896 -274.723679)
			(xy 169.014912 -274.706227) (xy 169.063131 -274.696383) (xy 169.112306 -274.694402) (xy 169.161161 -274.700334)
			(xy 169.208432 -274.714026) (xy 169.252894 -274.735124) (xy 169.293397 -274.76308) (xy 169.32889 -274.797172)
			(xy 169.358455 -274.836516) (xy 169.381326 -274.880093) (xy 169.39691 -274.926774) (xy 169.404805 -274.975351)
			(xy 169.4053 -274.999958) (xy 170.694108 -274.999958) (xy 170.698068 -274.950904) (xy 170.709845 -274.90312)
			(xy 170.729136 -274.857844) (xy 170.755439 -274.816248) (xy 170.788074 -274.779411) (xy 170.826195 -274.748286)
			(xy 170.868816 -274.723679) (xy 170.914832 -274.706227) (xy 170.963051 -274.696383) (xy 171.012226 -274.694402)
			(xy 171.061081 -274.700334) (xy 171.108352 -274.714026) (xy 171.152814 -274.735124) (xy 171.193317 -274.76308)
			(xy 171.22881 -274.797172) (xy 171.258375 -274.836516) (xy 171.281246 -274.880093) (xy 171.29683 -274.926774)
			(xy 171.304725 -274.975351) (xy 171.30522 -274.999958) (xy 172.594282 -274.999958) (xy 172.598242 -274.950904)
			(xy 172.610019 -274.90312) (xy 172.62931 -274.857844) (xy 172.655613 -274.816248) (xy 172.688248 -274.779411)
			(xy 172.726369 -274.748286) (xy 172.76899 -274.723679) (xy 172.815006 -274.706227) (xy 172.863225 -274.696383)
			(xy 172.9124 -274.694402) (xy 172.961255 -274.700334) (xy 173.008526 -274.714026) (xy 173.052988 -274.735124)
			(xy 173.093491 -274.76308) (xy 173.128984 -274.797172) (xy 173.158549 -274.836516) (xy 173.18142 -274.880093)
			(xy 173.197004 -274.926774) (xy 173.204899 -274.975351) (xy 173.205394 -274.999958) (xy 174.494202 -274.999958)
			(xy 174.498162 -274.950904) (xy 174.509939 -274.90312) (xy 174.52923 -274.857844) (xy 174.555533 -274.816248)
			(xy 174.588168 -274.779411) (xy 174.626289 -274.748286) (xy 174.66891 -274.723679) (xy 174.714926 -274.706227)
			(xy 174.763145 -274.696383) (xy 174.81232 -274.694402) (xy 174.861175 -274.700334) (xy 174.908446 -274.714026)
			(xy 174.952908 -274.735124) (xy 174.993411 -274.76308) (xy 175.028904 -274.797172) (xy 175.058469 -274.836516)
			(xy 175.08134 -274.880093) (xy 175.096924 -274.926774) (xy 175.104819 -274.975351) (xy 175.105309 -274.999704)
			(xy 176.393868 -274.999704) (xy 176.397828 -274.95065) (xy 176.409605 -274.902866) (xy 176.428896 -274.85759)
			(xy 176.455199 -274.815994) (xy 176.487834 -274.779157) (xy 176.525955 -274.748032) (xy 176.568576 -274.723425)
			(xy 176.614592 -274.705973) (xy 176.662811 -274.696129) (xy 176.711986 -274.694148) (xy 176.760841 -274.70008)
			(xy 176.808112 -274.713772) (xy 176.852574 -274.73487) (xy 176.893077 -274.762826) (xy 176.92857 -274.796918)
			(xy 176.958135 -274.836262) (xy 176.981006 -274.879839) (xy 176.99659 -274.92652) (xy 177.004485 -274.975097)
			(xy 177.00498 -274.999704) (xy 177.004975 -274.999958) (xy 178.293788 -274.999958) (xy 178.297748 -274.950904)
			(xy 178.309525 -274.90312) (xy 178.328816 -274.857844) (xy 178.355119 -274.816248) (xy 178.387754 -274.779411)
			(xy 178.425875 -274.748286) (xy 178.468496 -274.723679) (xy 178.514512 -274.706227) (xy 178.562731 -274.696383)
			(xy 178.611906 -274.694402) (xy 178.660761 -274.700334) (xy 178.708032 -274.714026) (xy 178.752494 -274.735124)
			(xy 178.792997 -274.76308) (xy 178.82849 -274.797172) (xy 178.858055 -274.836516) (xy 178.880926 -274.880093)
			(xy 178.89651 -274.926774) (xy 178.904405 -274.975351) (xy 178.904895 -274.999704) (xy 180.193962 -274.999704)
			(xy 180.197922 -274.95065) (xy 180.209699 -274.902866) (xy 180.22899 -274.85759) (xy 180.255293 -274.815994)
			(xy 180.287928 -274.779157) (xy 180.326049 -274.748032) (xy 180.36867 -274.723425) (xy 180.414686 -274.705973)
			(xy 180.462905 -274.696129) (xy 180.51208 -274.694148) (xy 180.560935 -274.70008) (xy 180.608206 -274.713772)
			(xy 180.652668 -274.73487) (xy 180.693171 -274.762826) (xy 180.728664 -274.796918) (xy 180.758229 -274.836262)
			(xy 180.7811 -274.879839) (xy 180.796684 -274.92652) (xy 180.804579 -274.975097) (xy 180.805074 -274.999704)
			(xy 180.805069 -274.999958) (xy 182.093882 -274.999958) (xy 182.097842 -274.950904) (xy 182.109619 -274.90312)
			(xy 182.12891 -274.857844) (xy 182.155213 -274.816248) (xy 182.187848 -274.779411) (xy 182.225969 -274.748286)
			(xy 182.26859 -274.723679) (xy 182.314606 -274.706227) (xy 182.362825 -274.696383) (xy 182.412 -274.694402)
			(xy 182.460855 -274.700334) (xy 182.508126 -274.714026) (xy 182.552588 -274.735124) (xy 182.593091 -274.76308)
			(xy 182.628584 -274.797172) (xy 182.658149 -274.836516) (xy 182.68102 -274.880093) (xy 182.696604 -274.926774)
			(xy 182.704499 -274.975351) (xy 182.704989 -274.999704) (xy 183.993802 -274.999704) (xy 183.997762 -274.95065)
			(xy 184.009539 -274.902866) (xy 184.02883 -274.85759) (xy 184.055133 -274.815994) (xy 184.087768 -274.779157)
			(xy 184.125889 -274.748032) (xy 184.16851 -274.723425) (xy 184.214526 -274.705973) (xy 184.262745 -274.696129)
			(xy 184.31192 -274.694148) (xy 184.360775 -274.70008) (xy 184.408046 -274.713772) (xy 184.452508 -274.73487)
			(xy 184.493011 -274.762826) (xy 184.528504 -274.796918) (xy 184.558069 -274.836262) (xy 184.58094 -274.879839)
			(xy 184.596524 -274.92652) (xy 184.604419 -274.975097) (xy 184.604914 -274.999704) (xy 184.604909 -274.999958)
			(xy 185.893722 -274.999958) (xy 185.897682 -274.950904) (xy 185.909459 -274.90312) (xy 185.92875 -274.857844)
			(xy 185.955053 -274.816248) (xy 185.987688 -274.779411) (xy 186.025809 -274.748286) (xy 186.06843 -274.723679)
			(xy 186.114446 -274.706227) (xy 186.162665 -274.696383) (xy 186.21184 -274.694402) (xy 186.260695 -274.700334)
			(xy 186.307966 -274.714026) (xy 186.352428 -274.735124) (xy 186.392931 -274.76308) (xy 186.428424 -274.797172)
			(xy 186.457989 -274.836516) (xy 186.48086 -274.880093) (xy 186.496444 -274.926774) (xy 186.504339 -274.975351)
			(xy 186.504829 -274.999704) (xy 187.793896 -274.999704) (xy 187.797856 -274.95065) (xy 187.809633 -274.902866)
			(xy 187.828924 -274.85759) (xy 187.855227 -274.815994) (xy 187.887862 -274.779157) (xy 187.925983 -274.748032)
			(xy 187.968604 -274.723425) (xy 188.01462 -274.705973) (xy 188.062839 -274.696129) (xy 188.112014 -274.694148)
			(xy 188.160869 -274.70008) (xy 188.20814 -274.713772) (xy 188.252602 -274.73487) (xy 188.293105 -274.762826)
			(xy 188.328598 -274.796918) (xy 188.358163 -274.836262) (xy 188.381034 -274.879839) (xy 188.396618 -274.92652)
			(xy 188.404513 -274.975097) (xy 188.405008 -274.999704) (xy 188.405003 -274.999958) (xy 189.693816 -274.999958)
			(xy 189.697776 -274.950904) (xy 189.709553 -274.90312) (xy 189.728844 -274.857844) (xy 189.755147 -274.816248)
			(xy 189.787782 -274.779411) (xy 189.825903 -274.748286) (xy 189.868524 -274.723679) (xy 189.91454 -274.706227)
			(xy 189.962759 -274.696383) (xy 190.011934 -274.694402) (xy 190.060789 -274.700334) (xy 190.10806 -274.714026)
			(xy 190.152522 -274.735124) (xy 190.193025 -274.76308) (xy 190.228518 -274.797172) (xy 190.258083 -274.836516)
			(xy 190.280954 -274.880093) (xy 190.296538 -274.926774) (xy 190.304433 -274.975351) (xy 190.304923 -274.999704)
			(xy 191.59399 -274.999704) (xy 191.59795 -274.95065) (xy 191.609727 -274.902866) (xy 191.629018 -274.85759)
			(xy 191.655321 -274.815994) (xy 191.687956 -274.779157) (xy 191.726077 -274.748032) (xy 191.768698 -274.723425)
			(xy 191.814714 -274.705973) (xy 191.862933 -274.696129) (xy 191.912108 -274.694148) (xy 191.960963 -274.70008)
			(xy 192.008234 -274.713772) (xy 192.052696 -274.73487) (xy 192.093199 -274.762826) (xy 192.128692 -274.796918)
			(xy 192.158257 -274.836262) (xy 192.181128 -274.879839) (xy 192.196712 -274.92652) (xy 192.204607 -274.975097)
			(xy 192.205102 -274.999704) (xy 192.205097 -274.999958) (xy 193.49391 -274.999958) (xy 193.49787 -274.950904)
			(xy 193.509647 -274.90312) (xy 193.528938 -274.857844) (xy 193.555241 -274.816248) (xy 193.587876 -274.779411)
			(xy 193.625997 -274.748286) (xy 193.668618 -274.723679) (xy 193.714634 -274.706227) (xy 193.762853 -274.696383)
			(xy 193.812028 -274.694402) (xy 193.860883 -274.700334) (xy 193.908154 -274.714026) (xy 193.952616 -274.735124)
			(xy 193.993119 -274.76308) (xy 194.028612 -274.797172) (xy 194.058177 -274.836516) (xy 194.081048 -274.880093)
			(xy 194.096632 -274.926774) (xy 194.104527 -274.975351) (xy 194.105022 -274.999958) (xy 195.39383 -274.999958)
			(xy 195.39779 -274.950904) (xy 195.409567 -274.90312) (xy 195.428858 -274.857844) (xy 195.455161 -274.816248)
			(xy 195.487796 -274.779411) (xy 195.525917 -274.748286) (xy 195.568538 -274.723679) (xy 195.614554 -274.706227)
			(xy 195.662773 -274.696383) (xy 195.711948 -274.694402) (xy 195.760803 -274.700334) (xy 195.808074 -274.714026)
			(xy 195.852536 -274.735124) (xy 195.893039 -274.76308) (xy 195.928532 -274.797172) (xy 195.958097 -274.836516)
			(xy 195.980968 -274.880093) (xy 195.996552 -274.926774) (xy 196.004447 -274.975351) (xy 196.004937 -274.999704)
			(xy 197.294258 -274.999704) (xy 197.298218 -274.95065) (xy 197.309995 -274.902866) (xy 197.329286 -274.85759)
			(xy 197.355589 -274.815994) (xy 197.388224 -274.779157) (xy 197.426345 -274.748032) (xy 197.468966 -274.723425)
			(xy 197.514982 -274.705973) (xy 197.563201 -274.696129) (xy 197.612376 -274.694148) (xy 197.661231 -274.70008)
			(xy 197.708502 -274.713772) (xy 197.752964 -274.73487) (xy 197.793467 -274.762826) (xy 197.82896 -274.796918)
			(xy 197.858525 -274.836262) (xy 197.881396 -274.879839) (xy 197.89698 -274.92652) (xy 197.904875 -274.975097)
			(xy 197.90537 -274.999704) (xy 198.244218 -274.999704) (xy 198.248178 -274.95065) (xy 198.259955 -274.902866)
			(xy 198.279246 -274.85759) (xy 198.305549 -274.815994) (xy 198.338184 -274.779157) (xy 198.376305 -274.748032)
			(xy 198.418926 -274.723425) (xy 198.464942 -274.705973) (xy 198.513161 -274.696129) (xy 198.562336 -274.694148)
			(xy 198.611191 -274.70008) (xy 198.658462 -274.713772) (xy 198.702924 -274.73487) (xy 198.743427 -274.762826)
			(xy 198.77892 -274.796918) (xy 198.808485 -274.836262) (xy 198.831356 -274.879839) (xy 198.84694 -274.92652)
			(xy 198.854835 -274.975097) (xy 198.85533 -274.999704) (xy 198.855325 -274.999958) (xy 277.294098 -274.999958)
			(xy 277.298058 -274.950904) (xy 277.309835 -274.90312) (xy 277.329126 -274.857844) (xy 277.355429 -274.816248)
			(xy 277.388064 -274.779411) (xy 277.426185 -274.748286) (xy 277.468806 -274.723679) (xy 277.514822 -274.706227)
			(xy 277.563041 -274.696383) (xy 277.612216 -274.694402) (xy 277.661071 -274.700334) (xy 277.708342 -274.714026)
			(xy 277.752804 -274.735124) (xy 277.793307 -274.76308) (xy 277.8288 -274.797172) (xy 277.858365 -274.836516)
			(xy 277.881236 -274.880093) (xy 277.89682 -274.926774) (xy 277.904715 -274.975351) (xy 277.90521 -274.999958)
			(xy 279.194018 -274.999958) (xy 279.197978 -274.950904) (xy 279.209755 -274.90312) (xy 279.229046 -274.857844)
			(xy 279.255349 -274.816248) (xy 279.287984 -274.779411) (xy 279.326105 -274.748286) (xy 279.368726 -274.723679)
			(xy 279.414742 -274.706227) (xy 279.462961 -274.696383) (xy 279.512136 -274.694402) (xy 279.560991 -274.700334)
			(xy 279.608262 -274.714026) (xy 279.652724 -274.735124) (xy 279.693227 -274.76308) (xy 279.72872 -274.797172)
			(xy 279.758285 -274.836516) (xy 279.781156 -274.880093) (xy 279.79674 -274.926774) (xy 279.804635 -274.975351)
			(xy 279.80513 -274.999958) (xy 281.093938 -274.999958) (xy 281.097898 -274.950904) (xy 281.109675 -274.90312)
			(xy 281.128966 -274.857844) (xy 281.155269 -274.816248) (xy 281.187904 -274.779411) (xy 281.226025 -274.748286)
			(xy 281.268646 -274.723679) (xy 281.314662 -274.706227) (xy 281.362881 -274.696383) (xy 281.412056 -274.694402)
			(xy 281.460911 -274.700334) (xy 281.508182 -274.714026) (xy 281.552644 -274.735124) (xy 281.593147 -274.76308)
			(xy 281.62864 -274.797172) (xy 281.658205 -274.836516) (xy 281.681076 -274.880093) (xy 281.69666 -274.926774)
			(xy 281.704555 -274.975351) (xy 281.70505 -274.999958) (xy 282.994112 -274.999958) (xy 282.998072 -274.950904)
			(xy 283.009849 -274.90312) (xy 283.02914 -274.857844) (xy 283.055443 -274.816248) (xy 283.088078 -274.779411)
			(xy 283.126199 -274.748286) (xy 283.16882 -274.723679) (xy 283.214836 -274.706227) (xy 283.263055 -274.696383)
			(xy 283.31223 -274.694402) (xy 283.361085 -274.700334) (xy 283.408356 -274.714026) (xy 283.452818 -274.735124)
			(xy 283.493321 -274.76308) (xy 283.528814 -274.797172) (xy 283.558379 -274.836516) (xy 283.58125 -274.880093)
			(xy 283.596834 -274.926774) (xy 283.604729 -274.975351) (xy 283.605224 -274.999958) (xy 284.894032 -274.999958)
			(xy 284.897992 -274.950904) (xy 284.909769 -274.90312) (xy 284.92906 -274.857844) (xy 284.955363 -274.816248)
			(xy 284.987998 -274.779411) (xy 285.026119 -274.748286) (xy 285.06874 -274.723679) (xy 285.114756 -274.706227)
			(xy 285.162975 -274.696383) (xy 285.21215 -274.694402) (xy 285.261005 -274.700334) (xy 285.308276 -274.714026)
			(xy 285.352738 -274.735124) (xy 285.393241 -274.76308) (xy 285.428734 -274.797172) (xy 285.458299 -274.836516)
			(xy 285.48117 -274.880093) (xy 285.496754 -274.926774) (xy 285.504649 -274.975351) (xy 285.505144 -274.999958)
			(xy 286.793952 -274.999958) (xy 286.797912 -274.950904) (xy 286.809689 -274.90312) (xy 286.82898 -274.857844)
			(xy 286.855283 -274.816248) (xy 286.887918 -274.779411) (xy 286.926039 -274.748286) (xy 286.96866 -274.723679)
			(xy 287.014676 -274.706227) (xy 287.062895 -274.696383) (xy 287.11207 -274.694402) (xy 287.160925 -274.700334)
			(xy 287.208196 -274.714026) (xy 287.252658 -274.735124) (xy 287.293161 -274.76308) (xy 287.328654 -274.797172)
			(xy 287.358219 -274.836516) (xy 287.38109 -274.880093) (xy 287.396674 -274.926774) (xy 287.404569 -274.975351)
			(xy 287.405064 -274.999958) (xy 288.694126 -274.999958) (xy 288.698086 -274.950904) (xy 288.709863 -274.90312)
			(xy 288.729154 -274.857844) (xy 288.755457 -274.816248) (xy 288.788092 -274.779411) (xy 288.826213 -274.748286)
			(xy 288.868834 -274.723679) (xy 288.91485 -274.706227) (xy 288.963069 -274.696383) (xy 289.012244 -274.694402)
			(xy 289.061099 -274.700334) (xy 289.10837 -274.714026) (xy 289.152832 -274.735124) (xy 289.193335 -274.76308)
			(xy 289.228828 -274.797172) (xy 289.258393 -274.836516) (xy 289.281264 -274.880093) (xy 289.296848 -274.926774)
			(xy 289.304743 -274.975351) (xy 289.305238 -274.999958) (xy 290.594046 -274.999958) (xy 290.598006 -274.950904)
			(xy 290.609783 -274.90312) (xy 290.629074 -274.857844) (xy 290.655377 -274.816248) (xy 290.688012 -274.779411)
			(xy 290.726133 -274.748286) (xy 290.768754 -274.723679) (xy 290.81477 -274.706227) (xy 290.862989 -274.696383)
			(xy 290.912164 -274.694402) (xy 290.961019 -274.700334) (xy 291.00829 -274.714026) (xy 291.052752 -274.735124)
			(xy 291.093255 -274.76308) (xy 291.128748 -274.797172) (xy 291.158313 -274.836516) (xy 291.181184 -274.880093)
			(xy 291.196768 -274.926774) (xy 291.204663 -274.975351) (xy 291.205153 -274.999704) (xy 292.493712 -274.999704)
			(xy 292.497672 -274.95065) (xy 292.509449 -274.902866) (xy 292.52874 -274.85759) (xy 292.555043 -274.815994)
			(xy 292.587678 -274.779157) (xy 292.625799 -274.748032) (xy 292.66842 -274.723425) (xy 292.714436 -274.705973)
			(xy 292.762655 -274.696129) (xy 292.81183 -274.694148) (xy 292.860685 -274.70008) (xy 292.907956 -274.713772)
			(xy 292.952418 -274.73487) (xy 292.992921 -274.762826) (xy 293.028414 -274.796918) (xy 293.057979 -274.836262)
			(xy 293.08085 -274.879839) (xy 293.096434 -274.92652) (xy 293.104329 -274.975097) (xy 293.104824 -274.999704)
			(xy 293.104819 -274.999958) (xy 294.393632 -274.999958) (xy 294.397592 -274.950904) (xy 294.409369 -274.90312)
			(xy 294.42866 -274.857844) (xy 294.454963 -274.816248) (xy 294.487598 -274.779411) (xy 294.525719 -274.748286)
			(xy 294.56834 -274.723679) (xy 294.614356 -274.706227) (xy 294.662575 -274.696383) (xy 294.71175 -274.694402)
			(xy 294.760605 -274.700334) (xy 294.807876 -274.714026) (xy 294.852338 -274.735124) (xy 294.892841 -274.76308)
			(xy 294.928334 -274.797172) (xy 294.957899 -274.836516) (xy 294.98077 -274.880093) (xy 294.996354 -274.926774)
			(xy 295.004249 -274.975351) (xy 295.004739 -274.999704) (xy 296.293806 -274.999704) (xy 296.297766 -274.95065)
			(xy 296.309543 -274.902866) (xy 296.328834 -274.85759) (xy 296.355137 -274.815994) (xy 296.387772 -274.779157)
			(xy 296.425893 -274.748032) (xy 296.468514 -274.723425) (xy 296.51453 -274.705973) (xy 296.562749 -274.696129)
			(xy 296.611924 -274.694148) (xy 296.660779 -274.70008) (xy 296.70805 -274.713772) (xy 296.752512 -274.73487)
			(xy 296.793015 -274.762826) (xy 296.828508 -274.796918) (xy 296.858073 -274.836262) (xy 296.880944 -274.879839)
			(xy 296.896528 -274.92652) (xy 296.904423 -274.975097) (xy 296.904918 -274.999704) (xy 296.904913 -274.999958)
			(xy 298.193726 -274.999958) (xy 298.197686 -274.950904) (xy 298.209463 -274.90312) (xy 298.228754 -274.857844)
			(xy 298.255057 -274.816248) (xy 298.287692 -274.779411) (xy 298.325813 -274.748286) (xy 298.368434 -274.723679)
			(xy 298.41445 -274.706227) (xy 298.462669 -274.696383) (xy 298.511844 -274.694402) (xy 298.560699 -274.700334)
			(xy 298.60797 -274.714026) (xy 298.652432 -274.735124) (xy 298.692935 -274.76308) (xy 298.728428 -274.797172)
			(xy 298.757993 -274.836516) (xy 298.780864 -274.880093) (xy 298.796448 -274.926774) (xy 298.804343 -274.975351)
			(xy 298.804833 -274.999704) (xy 300.093646 -274.999704) (xy 300.097606 -274.95065) (xy 300.109383 -274.902866)
			(xy 300.128674 -274.85759) (xy 300.154977 -274.815994) (xy 300.187612 -274.779157) (xy 300.225733 -274.748032)
			(xy 300.268354 -274.723425) (xy 300.31437 -274.705973) (xy 300.362589 -274.696129) (xy 300.411764 -274.694148)
			(xy 300.460619 -274.70008) (xy 300.50789 -274.713772) (xy 300.552352 -274.73487) (xy 300.592855 -274.762826)
			(xy 300.628348 -274.796918) (xy 300.657913 -274.836262) (xy 300.680784 -274.879839) (xy 300.696368 -274.92652)
			(xy 300.704263 -274.975097) (xy 300.704758 -274.999704) (xy 300.704753 -274.999958) (xy 301.993566 -274.999958)
			(xy 301.997526 -274.950904) (xy 302.009303 -274.90312) (xy 302.028594 -274.857844) (xy 302.054897 -274.816248)
			(xy 302.087532 -274.779411) (xy 302.125653 -274.748286) (xy 302.168274 -274.723679) (xy 302.21429 -274.706227)
			(xy 302.262509 -274.696383) (xy 302.311684 -274.694402) (xy 302.360539 -274.700334) (xy 302.40781 -274.714026)
			(xy 302.452272 -274.735124) (xy 302.492775 -274.76308) (xy 302.528268 -274.797172) (xy 302.557833 -274.836516)
			(xy 302.580704 -274.880093) (xy 302.596288 -274.926774) (xy 302.604183 -274.975351) (xy 302.604673 -274.999704)
			(xy 303.89374 -274.999704) (xy 303.8977 -274.95065) (xy 303.909477 -274.902866) (xy 303.928768 -274.85759)
			(xy 303.955071 -274.815994) (xy 303.987706 -274.779157) (xy 304.025827 -274.748032) (xy 304.068448 -274.723425)
			(xy 304.114464 -274.705973) (xy 304.162683 -274.696129) (xy 304.211858 -274.694148) (xy 304.260713 -274.70008)
			(xy 304.307984 -274.713772) (xy 304.352446 -274.73487) (xy 304.392949 -274.762826) (xy 304.428442 -274.796918)
			(xy 304.458007 -274.836262) (xy 304.480878 -274.879839) (xy 304.496462 -274.92652) (xy 304.504357 -274.975097)
			(xy 304.504852 -274.999704) (xy 304.504847 -274.999958) (xy 305.79366 -274.999958) (xy 305.79762 -274.950904)
			(xy 305.809397 -274.90312) (xy 305.828688 -274.857844) (xy 305.854991 -274.816248) (xy 305.887626 -274.779411)
			(xy 305.925747 -274.748286) (xy 305.968368 -274.723679) (xy 306.014384 -274.706227) (xy 306.062603 -274.696383)
			(xy 306.111778 -274.694402) (xy 306.160633 -274.700334) (xy 306.207904 -274.714026) (xy 306.252366 -274.735124)
			(xy 306.292869 -274.76308) (xy 306.328362 -274.797172) (xy 306.357927 -274.836516) (xy 306.380798 -274.880093)
			(xy 306.396382 -274.926774) (xy 306.404277 -274.975351) (xy 306.404767 -274.999704) (xy 307.693834 -274.999704)
			(xy 307.697794 -274.95065) (xy 307.709571 -274.902866) (xy 307.728862 -274.85759) (xy 307.755165 -274.815994)
			(xy 307.7878 -274.779157) (xy 307.825921 -274.748032) (xy 307.868542 -274.723425) (xy 307.914558 -274.705973)
			(xy 307.962777 -274.696129) (xy 308.011952 -274.694148) (xy 308.060807 -274.70008) (xy 308.108078 -274.713772)
			(xy 308.15254 -274.73487) (xy 308.193043 -274.762826) (xy 308.228536 -274.796918) (xy 308.258101 -274.836262)
			(xy 308.280972 -274.879839) (xy 308.296556 -274.92652) (xy 308.304451 -274.975097) (xy 308.304946 -274.999704)
			(xy 308.304941 -274.999958) (xy 309.593754 -274.999958) (xy 309.597714 -274.950904) (xy 309.609491 -274.90312)
			(xy 309.628782 -274.857844) (xy 309.655085 -274.816248) (xy 309.68772 -274.779411) (xy 309.725841 -274.748286)
			(xy 309.768462 -274.723679) (xy 309.814478 -274.706227) (xy 309.862697 -274.696383) (xy 309.911872 -274.694402)
			(xy 309.960727 -274.700334) (xy 310.007998 -274.714026) (xy 310.05246 -274.735124) (xy 310.092963 -274.76308)
			(xy 310.128456 -274.797172) (xy 310.158021 -274.836516) (xy 310.180892 -274.880093) (xy 310.196476 -274.926774)
			(xy 310.204371 -274.975351) (xy 310.204866 -274.999958) (xy 311.493674 -274.999958) (xy 311.497634 -274.950904)
			(xy 311.509411 -274.90312) (xy 311.528702 -274.857844) (xy 311.555005 -274.816248) (xy 311.58764 -274.779411)
			(xy 311.625761 -274.748286) (xy 311.668382 -274.723679) (xy 311.714398 -274.706227) (xy 311.762617 -274.696383)
			(xy 311.811792 -274.694402) (xy 311.860647 -274.700334) (xy 311.907918 -274.714026) (xy 311.95238 -274.735124)
			(xy 311.992883 -274.76308) (xy 312.028376 -274.797172) (xy 312.057941 -274.836516) (xy 312.080812 -274.880093)
			(xy 312.096396 -274.926774) (xy 312.104291 -274.975351) (xy 312.104781 -274.999704) (xy 313.394102 -274.999704)
			(xy 313.398062 -274.95065) (xy 313.409839 -274.902866) (xy 313.42913 -274.85759) (xy 313.455433 -274.815994)
			(xy 313.488068 -274.779157) (xy 313.526189 -274.748032) (xy 313.56881 -274.723425) (xy 313.614826 -274.705973)
			(xy 313.663045 -274.696129) (xy 313.71222 -274.694148) (xy 313.761075 -274.70008) (xy 313.808346 -274.713772)
			(xy 313.852808 -274.73487) (xy 313.893311 -274.762826) (xy 313.928804 -274.796918) (xy 313.958369 -274.836262)
			(xy 313.98124 -274.879839) (xy 313.996824 -274.92652) (xy 314.004719 -274.975097) (xy 314.005214 -274.999704)
			(xy 314.344062 -274.999704) (xy 314.348022 -274.95065) (xy 314.359799 -274.902866) (xy 314.37909 -274.85759)
			(xy 314.405393 -274.815994) (xy 314.438028 -274.779157) (xy 314.476149 -274.748032) (xy 314.51877 -274.723425)
			(xy 314.564786 -274.705973) (xy 314.613005 -274.696129) (xy 314.66218 -274.694148) (xy 314.711035 -274.70008)
			(xy 314.758306 -274.713772) (xy 314.802768 -274.73487) (xy 314.843271 -274.762826) (xy 314.878764 -274.796918)
			(xy 314.908329 -274.836262) (xy 314.9312 -274.879839) (xy 314.946784 -274.92652) (xy 314.954679 -274.975097)
			(xy 314.955174 -274.999704) (xy 314.955169 -274.999958) (xy 393.394196 -274.999958) (xy 393.398156 -274.950904)
			(xy 393.409933 -274.90312) (xy 393.429224 -274.857844) (xy 393.455527 -274.816248) (xy 393.488162 -274.779411)
			(xy 393.526283 -274.748286) (xy 393.568904 -274.723679) (xy 393.61492 -274.706227) (xy 393.663139 -274.696383)
			(xy 393.712314 -274.694402) (xy 393.761169 -274.700334) (xy 393.80844 -274.714026) (xy 393.852902 -274.735124)
			(xy 393.893405 -274.76308) (xy 393.928898 -274.797172) (xy 393.958463 -274.836516) (xy 393.981334 -274.880093)
			(xy 393.996918 -274.926774) (xy 394.004813 -274.975351) (xy 394.005308 -274.999958) (xy 395.294116 -274.999958)
			(xy 395.298076 -274.950904) (xy 395.309853 -274.90312) (xy 395.329144 -274.857844) (xy 395.355447 -274.816248)
			(xy 395.388082 -274.779411) (xy 395.426203 -274.748286) (xy 395.468824 -274.723679) (xy 395.51484 -274.706227)
			(xy 395.563059 -274.696383) (xy 395.612234 -274.694402) (xy 395.661089 -274.700334) (xy 395.70836 -274.714026)
			(xy 395.752822 -274.735124) (xy 395.793325 -274.76308) (xy 395.828818 -274.797172) (xy 395.858383 -274.836516)
			(xy 395.881254 -274.880093) (xy 395.896838 -274.926774) (xy 395.904733 -274.975351) (xy 395.905228 -274.999958)
			(xy 397.194036 -274.999958) (xy 397.197996 -274.950904) (xy 397.209773 -274.90312) (xy 397.229064 -274.857844)
			(xy 397.255367 -274.816248) (xy 397.288002 -274.779411) (xy 397.326123 -274.748286) (xy 397.368744 -274.723679)
			(xy 397.41476 -274.706227) (xy 397.462979 -274.696383) (xy 397.512154 -274.694402) (xy 397.561009 -274.700334)
			(xy 397.60828 -274.714026) (xy 397.652742 -274.735124) (xy 397.693245 -274.76308) (xy 397.728738 -274.797172)
			(xy 397.758303 -274.836516) (xy 397.781174 -274.880093) (xy 397.796758 -274.926774) (xy 397.804653 -274.975351)
			(xy 397.805148 -274.999958) (xy 399.09421 -274.999958) (xy 399.09817 -274.950904) (xy 399.109947 -274.90312)
			(xy 399.129238 -274.857844) (xy 399.155541 -274.816248) (xy 399.188176 -274.779411) (xy 399.226297 -274.748286)
			(xy 399.268918 -274.723679) (xy 399.314934 -274.706227) (xy 399.363153 -274.696383) (xy 399.412328 -274.694402)
			(xy 399.461183 -274.700334) (xy 399.508454 -274.714026) (xy 399.552916 -274.735124) (xy 399.593419 -274.76308)
			(xy 399.628912 -274.797172) (xy 399.658477 -274.836516) (xy 399.681348 -274.880093) (xy 399.696932 -274.926774)
			(xy 399.704827 -274.975351) (xy 399.705322 -274.999958) (xy 400.99413 -274.999958) (xy 400.99809 -274.950904)
			(xy 401.009867 -274.90312) (xy 401.029158 -274.857844) (xy 401.055461 -274.816248) (xy 401.088096 -274.779411)
			(xy 401.126217 -274.748286) (xy 401.168838 -274.723679) (xy 401.214854 -274.706227) (xy 401.263073 -274.696383)
			(xy 401.312248 -274.694402) (xy 401.361103 -274.700334) (xy 401.408374 -274.714026) (xy 401.452836 -274.735124)
			(xy 401.493339 -274.76308) (xy 401.528832 -274.797172) (xy 401.558397 -274.836516) (xy 401.581268 -274.880093)
			(xy 401.596852 -274.926774) (xy 401.604747 -274.975351) (xy 401.605242 -274.999958) (xy 402.89405 -274.999958)
			(xy 402.89801 -274.950904) (xy 402.909787 -274.90312) (xy 402.929078 -274.857844) (xy 402.955381 -274.816248)
			(xy 402.988016 -274.779411) (xy 403.026137 -274.748286) (xy 403.068758 -274.723679) (xy 403.114774 -274.706227)
			(xy 403.162993 -274.696383) (xy 403.212168 -274.694402) (xy 403.261023 -274.700334) (xy 403.308294 -274.714026)
			(xy 403.352756 -274.735124) (xy 403.393259 -274.76308) (xy 403.428752 -274.797172) (xy 403.458317 -274.836516)
			(xy 403.481188 -274.880093) (xy 403.496772 -274.926774) (xy 403.504667 -274.975351) (xy 403.505162 -274.999958)
			(xy 404.794224 -274.999958) (xy 404.798184 -274.950904) (xy 404.809961 -274.90312) (xy 404.829252 -274.857844)
			(xy 404.855555 -274.816248) (xy 404.88819 -274.779411) (xy 404.926311 -274.748286) (xy 404.968932 -274.723679)
			(xy 405.014948 -274.706227) (xy 405.063167 -274.696383) (xy 405.112342 -274.694402) (xy 405.161197 -274.700334)
			(xy 405.208468 -274.714026) (xy 405.25293 -274.735124) (xy 405.293433 -274.76308) (xy 405.328926 -274.797172)
			(xy 405.358491 -274.836516) (xy 405.381362 -274.880093) (xy 405.396946 -274.926774) (xy 405.404841 -274.975351)
			(xy 405.405336 -274.999958) (xy 406.694144 -274.999958) (xy 406.698104 -274.950904) (xy 406.709881 -274.90312)
			(xy 406.729172 -274.857844) (xy 406.755475 -274.816248) (xy 406.78811 -274.779411) (xy 406.826231 -274.748286)
			(xy 406.868852 -274.723679) (xy 406.914868 -274.706227) (xy 406.963087 -274.696383) (xy 407.012262 -274.694402)
			(xy 407.061117 -274.700334) (xy 407.108388 -274.714026) (xy 407.15285 -274.735124) (xy 407.193353 -274.76308)
			(xy 407.228846 -274.797172) (xy 407.258411 -274.836516) (xy 407.281282 -274.880093) (xy 407.296866 -274.926774)
			(xy 407.304761 -274.975351) (xy 407.305251 -274.999704) (xy 408.59381 -274.999704) (xy 408.59777 -274.95065)
			(xy 408.609547 -274.902866) (xy 408.628838 -274.85759) (xy 408.655141 -274.815994) (xy 408.687776 -274.779157)
			(xy 408.725897 -274.748032) (xy 408.768518 -274.723425) (xy 408.814534 -274.705973) (xy 408.862753 -274.696129)
			(xy 408.911928 -274.694148) (xy 408.960783 -274.70008) (xy 409.008054 -274.713772) (xy 409.052516 -274.73487)
			(xy 409.093019 -274.762826) (xy 409.128512 -274.796918) (xy 409.158077 -274.836262) (xy 409.180948 -274.879839)
			(xy 409.196532 -274.92652) (xy 409.204427 -274.975097) (xy 409.204922 -274.999704) (xy 409.204917 -274.999958)
			(xy 410.49373 -274.999958) (xy 410.49769 -274.950904) (xy 410.509467 -274.90312) (xy 410.528758 -274.857844)
			(xy 410.555061 -274.816248) (xy 410.587696 -274.779411) (xy 410.625817 -274.748286) (xy 410.668438 -274.723679)
			(xy 410.714454 -274.706227) (xy 410.762673 -274.696383) (xy 410.811848 -274.694402) (xy 410.860703 -274.700334)
			(xy 410.907974 -274.714026) (xy 410.952436 -274.735124) (xy 410.992939 -274.76308) (xy 411.028432 -274.797172)
			(xy 411.057997 -274.836516) (xy 411.080868 -274.880093) (xy 411.096452 -274.926774) (xy 411.104347 -274.975351)
			(xy 411.104837 -274.999704) (xy 412.393904 -274.999704) (xy 412.397864 -274.95065) (xy 412.409641 -274.902866)
			(xy 412.428932 -274.85759) (xy 412.455235 -274.815994) (xy 412.48787 -274.779157) (xy 412.525991 -274.748032)
			(xy 412.568612 -274.723425) (xy 412.614628 -274.705973) (xy 412.662847 -274.696129) (xy 412.712022 -274.694148)
			(xy 412.760877 -274.70008) (xy 412.808148 -274.713772) (xy 412.85261 -274.73487) (xy 412.893113 -274.762826)
			(xy 412.928606 -274.796918) (xy 412.958171 -274.836262) (xy 412.981042 -274.879839) (xy 412.996626 -274.92652)
			(xy 413.004521 -274.975097) (xy 413.005016 -274.999704) (xy 413.005011 -274.999958) (xy 414.293824 -274.999958)
			(xy 414.297784 -274.950904) (xy 414.309561 -274.90312) (xy 414.328852 -274.857844) (xy 414.355155 -274.816248)
			(xy 414.38779 -274.779411) (xy 414.425911 -274.748286) (xy 414.468532 -274.723679) (xy 414.514548 -274.706227)
			(xy 414.562767 -274.696383) (xy 414.611942 -274.694402) (xy 414.660797 -274.700334) (xy 414.708068 -274.714026)
			(xy 414.75253 -274.735124) (xy 414.793033 -274.76308) (xy 414.828526 -274.797172) (xy 414.858091 -274.836516)
			(xy 414.880962 -274.880093) (xy 414.896546 -274.926774) (xy 414.904441 -274.975351) (xy 414.904931 -274.999704)
			(xy 416.193744 -274.999704) (xy 416.197704 -274.95065) (xy 416.209481 -274.902866) (xy 416.228772 -274.85759)
			(xy 416.255075 -274.815994) (xy 416.28771 -274.779157) (xy 416.325831 -274.748032) (xy 416.368452 -274.723425)
			(xy 416.414468 -274.705973) (xy 416.462687 -274.696129) (xy 416.511862 -274.694148) (xy 416.560717 -274.70008)
			(xy 416.607988 -274.713772) (xy 416.65245 -274.73487) (xy 416.692953 -274.762826) (xy 416.728446 -274.796918)
			(xy 416.758011 -274.836262) (xy 416.780882 -274.879839) (xy 416.796466 -274.92652) (xy 416.804361 -274.975097)
			(xy 416.804856 -274.999704) (xy 416.804851 -274.999958) (xy 418.093664 -274.999958) (xy 418.097624 -274.950904)
			(xy 418.109401 -274.90312) (xy 418.128692 -274.857844) (xy 418.154995 -274.816248) (xy 418.18763 -274.779411)
			(xy 418.225751 -274.748286) (xy 418.268372 -274.723679) (xy 418.314388 -274.706227) (xy 418.362607 -274.696383)
			(xy 418.411782 -274.694402) (xy 418.460637 -274.700334) (xy 418.507908 -274.714026) (xy 418.55237 -274.735124)
			(xy 418.592873 -274.76308) (xy 418.628366 -274.797172) (xy 418.657931 -274.836516) (xy 418.680802 -274.880093)
			(xy 418.696386 -274.926774) (xy 418.704281 -274.975351) (xy 418.704771 -274.999704) (xy 419.993838 -274.999704)
			(xy 419.997798 -274.95065) (xy 420.009575 -274.902866) (xy 420.028866 -274.85759) (xy 420.055169 -274.815994)
			(xy 420.087804 -274.779157) (xy 420.125925 -274.748032) (xy 420.168546 -274.723425) (xy 420.214562 -274.705973)
			(xy 420.262781 -274.696129) (xy 420.311956 -274.694148) (xy 420.360811 -274.70008) (xy 420.408082 -274.713772)
			(xy 420.452544 -274.73487) (xy 420.493047 -274.762826) (xy 420.52854 -274.796918) (xy 420.558105 -274.836262)
			(xy 420.580976 -274.879839) (xy 420.59656 -274.92652) (xy 420.604455 -274.975097) (xy 420.60495 -274.999704)
			(xy 420.604945 -274.999958) (xy 421.893758 -274.999958) (xy 421.897718 -274.950904) (xy 421.909495 -274.90312)
			(xy 421.928786 -274.857844) (xy 421.955089 -274.816248) (xy 421.987724 -274.779411) (xy 422.025845 -274.748286)
			(xy 422.068466 -274.723679) (xy 422.114482 -274.706227) (xy 422.162701 -274.696383) (xy 422.211876 -274.694402)
			(xy 422.260731 -274.700334) (xy 422.308002 -274.714026) (xy 422.352464 -274.735124) (xy 422.392967 -274.76308)
			(xy 422.42846 -274.797172) (xy 422.458025 -274.836516) (xy 422.480896 -274.880093) (xy 422.49648 -274.926774)
			(xy 422.504375 -274.975351) (xy 422.504865 -274.999704) (xy 423.793932 -274.999704) (xy 423.797892 -274.95065)
			(xy 423.809669 -274.902866) (xy 423.82896 -274.85759) (xy 423.855263 -274.815994) (xy 423.887898 -274.779157)
			(xy 423.926019 -274.748032) (xy 423.96864 -274.723425) (xy 424.014656 -274.705973) (xy 424.062875 -274.696129)
			(xy 424.11205 -274.694148) (xy 424.160905 -274.70008) (xy 424.208176 -274.713772) (xy 424.252638 -274.73487)
			(xy 424.293141 -274.762826) (xy 424.328634 -274.796918) (xy 424.358199 -274.836262) (xy 424.38107 -274.879839)
			(xy 424.396654 -274.92652) (xy 424.404549 -274.975097) (xy 424.405044 -274.999704) (xy 424.405039 -274.999958)
			(xy 425.693852 -274.999958) (xy 425.697812 -274.950904) (xy 425.709589 -274.90312) (xy 425.72888 -274.857844)
			(xy 425.755183 -274.816248) (xy 425.787818 -274.779411) (xy 425.825939 -274.748286) (xy 425.86856 -274.723679)
			(xy 425.914576 -274.706227) (xy 425.962795 -274.696383) (xy 426.01197 -274.694402) (xy 426.060825 -274.700334)
			(xy 426.108096 -274.714026) (xy 426.152558 -274.735124) (xy 426.193061 -274.76308) (xy 426.228554 -274.797172)
			(xy 426.258119 -274.836516) (xy 426.28099 -274.880093) (xy 426.296574 -274.926774) (xy 426.304469 -274.975351)
			(xy 426.304964 -274.999958) (xy 427.593772 -274.999958) (xy 427.597732 -274.950904) (xy 427.609509 -274.90312)
			(xy 427.6288 -274.857844) (xy 427.655103 -274.816248) (xy 427.687738 -274.779411) (xy 427.725859 -274.748286)
			(xy 427.76848 -274.723679) (xy 427.814496 -274.706227) (xy 427.862715 -274.696383) (xy 427.91189 -274.694402)
			(xy 427.960745 -274.700334) (xy 428.008016 -274.714026) (xy 428.052478 -274.735124) (xy 428.092981 -274.76308)
			(xy 428.128474 -274.797172) (xy 428.158039 -274.836516) (xy 428.18091 -274.880093) (xy 428.196494 -274.926774)
			(xy 428.204389 -274.975351) (xy 428.204879 -274.999704) (xy 429.4942 -274.999704) (xy 429.49816 -274.95065)
			(xy 429.509937 -274.902866) (xy 429.529228 -274.85759) (xy 429.555531 -274.815994) (xy 429.588166 -274.779157)
			(xy 429.626287 -274.748032) (xy 429.668908 -274.723425) (xy 429.714924 -274.705973) (xy 429.763143 -274.696129)
			(xy 429.812318 -274.694148) (xy 429.861173 -274.70008) (xy 429.908444 -274.713772) (xy 429.952906 -274.73487)
			(xy 429.993409 -274.762826) (xy 430.028902 -274.796918) (xy 430.058467 -274.836262) (xy 430.081338 -274.879839)
			(xy 430.096922 -274.92652) (xy 430.104817 -274.975097) (xy 430.105312 -274.999704) (xy 430.44416 -274.999704)
			(xy 430.44812 -274.95065) (xy 430.459897 -274.902866) (xy 430.479188 -274.85759) (xy 430.505491 -274.815994)
			(xy 430.538126 -274.779157) (xy 430.576247 -274.748032) (xy 430.618868 -274.723425) (xy 430.664884 -274.705973)
			(xy 430.713103 -274.696129) (xy 430.762278 -274.694148) (xy 430.811133 -274.70008) (xy 430.858404 -274.713772)
			(xy 430.902866 -274.73487) (xy 430.943369 -274.762826) (xy 430.978862 -274.796918) (xy 431.008427 -274.836262)
			(xy 431.031298 -274.879839) (xy 431.046882 -274.92652) (xy 431.054777 -274.975097) (xy 431.055272 -274.999704)
			(xy 431.054777 -275.024311) (xy 431.046882 -275.072888) (xy 431.031298 -275.119569) (xy 431.008427 -275.163146)
			(xy 430.978862 -275.20249) (xy 430.943369 -275.236582) (xy 430.902866 -275.264538) (xy 430.858404 -275.285636)
			(xy 430.811133 -275.299328) (xy 430.762278 -275.30526) (xy 430.713103 -275.303279) (xy 430.664884 -275.293435)
			(xy 430.618868 -275.275983) (xy 430.576247 -275.251376) (xy 430.538126 -275.220251) (xy 430.505491 -275.183414)
			(xy 430.479188 -275.141818) (xy 430.459897 -275.096542) (xy 430.44812 -275.048758) (xy 430.44416 -274.999704)
			(xy 430.105312 -274.999704) (xy 430.104817 -275.024311) (xy 430.096922 -275.072888) (xy 430.081338 -275.119569)
			(xy 430.058467 -275.163146) (xy 430.028902 -275.20249) (xy 429.993409 -275.236582) (xy 429.952906 -275.264538)
			(xy 429.908444 -275.285636) (xy 429.861173 -275.299328) (xy 429.812318 -275.30526) (xy 429.763143 -275.303279)
			(xy 429.714924 -275.293435) (xy 429.668908 -275.275983) (xy 429.626287 -275.251376) (xy 429.588166 -275.220251)
			(xy 429.555531 -275.183414) (xy 429.529228 -275.141818) (xy 429.509937 -275.096542) (xy 429.49816 -275.048758)
			(xy 429.4942 -274.999704) (xy 428.204879 -274.999704) (xy 428.204884 -274.999958) (xy 428.204389 -275.024565)
			(xy 428.196494 -275.073142) (xy 428.18091 -275.119823) (xy 428.158039 -275.1634) (xy 428.128474 -275.202744)
			(xy 428.092981 -275.236836) (xy 428.052478 -275.264792) (xy 428.008016 -275.28589) (xy 427.960745 -275.299582)
			(xy 427.91189 -275.305514) (xy 427.862715 -275.303533) (xy 427.814496 -275.293689) (xy 427.76848 -275.276237)
			(xy 427.725859 -275.25163) (xy 427.687738 -275.220505) (xy 427.655103 -275.183668) (xy 427.6288 -275.142072)
			(xy 427.609509 -275.096796) (xy 427.597732 -275.049012) (xy 427.593772 -274.999958) (xy 426.304964 -274.999958)
			(xy 426.304469 -275.024565) (xy 426.296574 -275.073142) (xy 426.28099 -275.119823) (xy 426.258119 -275.1634)
			(xy 426.228554 -275.202744) (xy 426.193061 -275.236836) (xy 426.152558 -275.264792) (xy 426.108096 -275.28589)
			(xy 426.060825 -275.299582) (xy 426.01197 -275.305514) (xy 425.962795 -275.303533) (xy 425.914576 -275.293689)
			(xy 425.86856 -275.276237) (xy 425.825939 -275.25163) (xy 425.787818 -275.220505) (xy 425.755183 -275.183668)
			(xy 425.72888 -275.142072) (xy 425.709589 -275.096796) (xy 425.697812 -275.049012) (xy 425.693852 -274.999958)
			(xy 424.405039 -274.999958) (xy 424.404549 -275.024311) (xy 424.396654 -275.072888) (xy 424.38107 -275.119569)
			(xy 424.358199 -275.163146) (xy 424.328634 -275.20249) (xy 424.293141 -275.236582) (xy 424.252638 -275.264538)
			(xy 424.208176 -275.285636) (xy 424.160905 -275.299328) (xy 424.11205 -275.30526) (xy 424.062875 -275.303279)
			(xy 424.014656 -275.293435) (xy 423.96864 -275.275983) (xy 423.926019 -275.251376) (xy 423.887898 -275.220251)
			(xy 423.855263 -275.183414) (xy 423.82896 -275.141818) (xy 423.809669 -275.096542) (xy 423.797892 -275.048758)
			(xy 423.793932 -274.999704) (xy 422.504865 -274.999704) (xy 422.50487 -274.999958) (xy 422.504375 -275.024565)
			(xy 422.49648 -275.073142) (xy 422.480896 -275.119823) (xy 422.458025 -275.1634) (xy 422.42846 -275.202744)
			(xy 422.392967 -275.236836) (xy 422.352464 -275.264792) (xy 422.308002 -275.28589) (xy 422.260731 -275.299582)
			(xy 422.211876 -275.305514) (xy 422.162701 -275.303533) (xy 422.114482 -275.293689) (xy 422.068466 -275.276237)
			(xy 422.025845 -275.25163) (xy 421.987724 -275.220505) (xy 421.955089 -275.183668) (xy 421.928786 -275.142072)
			(xy 421.909495 -275.096796) (xy 421.897718 -275.049012) (xy 421.893758 -274.999958) (xy 420.604945 -274.999958)
			(xy 420.604455 -275.024311) (xy 420.59656 -275.072888) (xy 420.580976 -275.119569) (xy 420.558105 -275.163146)
			(xy 420.52854 -275.20249) (xy 420.493047 -275.236582) (xy 420.452544 -275.264538) (xy 420.408082 -275.285636)
			(xy 420.360811 -275.299328) (xy 420.311956 -275.30526) (xy 420.262781 -275.303279) (xy 420.214562 -275.293435)
			(xy 420.168546 -275.275983) (xy 420.125925 -275.251376) (xy 420.087804 -275.220251) (xy 420.055169 -275.183414)
			(xy 420.028866 -275.141818) (xy 420.009575 -275.096542) (xy 419.997798 -275.048758) (xy 419.993838 -274.999704)
			(xy 418.704771 -274.999704) (xy 418.704776 -274.999958) (xy 418.704281 -275.024565) (xy 418.696386 -275.073142)
			(xy 418.680802 -275.119823) (xy 418.657931 -275.1634) (xy 418.628366 -275.202744) (xy 418.592873 -275.236836)
			(xy 418.55237 -275.264792) (xy 418.507908 -275.28589) (xy 418.460637 -275.299582) (xy 418.411782 -275.305514)
			(xy 418.362607 -275.303533) (xy 418.314388 -275.293689) (xy 418.268372 -275.276237) (xy 418.225751 -275.25163)
			(xy 418.18763 -275.220505) (xy 418.154995 -275.183668) (xy 418.128692 -275.142072) (xy 418.109401 -275.096796)
			(xy 418.097624 -275.049012) (xy 418.093664 -274.999958) (xy 416.804851 -274.999958) (xy 416.804361 -275.024311)
			(xy 416.796466 -275.072888) (xy 416.780882 -275.119569) (xy 416.758011 -275.163146) (xy 416.728446 -275.20249)
			(xy 416.692953 -275.236582) (xy 416.65245 -275.264538) (xy 416.607988 -275.285636) (xy 416.560717 -275.299328)
			(xy 416.511862 -275.30526) (xy 416.462687 -275.303279) (xy 416.414468 -275.293435) (xy 416.368452 -275.275983)
			(xy 416.325831 -275.251376) (xy 416.28771 -275.220251) (xy 416.255075 -275.183414) (xy 416.228772 -275.141818)
			(xy 416.209481 -275.096542) (xy 416.197704 -275.048758) (xy 416.193744 -274.999704) (xy 414.904931 -274.999704)
			(xy 414.904936 -274.999958) (xy 414.904441 -275.024565) (xy 414.896546 -275.073142) (xy 414.880962 -275.119823)
			(xy 414.858091 -275.1634) (xy 414.828526 -275.202744) (xy 414.793033 -275.236836) (xy 414.75253 -275.264792)
			(xy 414.708068 -275.28589) (xy 414.660797 -275.299582) (xy 414.611942 -275.305514) (xy 414.562767 -275.303533)
			(xy 414.514548 -275.293689) (xy 414.468532 -275.276237) (xy 414.425911 -275.25163) (xy 414.38779 -275.220505)
			(xy 414.355155 -275.183668) (xy 414.328852 -275.142072) (xy 414.309561 -275.096796) (xy 414.297784 -275.049012)
			(xy 414.293824 -274.999958) (xy 413.005011 -274.999958) (xy 413.004521 -275.024311) (xy 412.996626 -275.072888)
			(xy 412.981042 -275.119569) (xy 412.958171 -275.163146) (xy 412.928606 -275.20249) (xy 412.893113 -275.236582)
			(xy 412.85261 -275.264538) (xy 412.808148 -275.285636) (xy 412.760877 -275.299328) (xy 412.712022 -275.30526)
			(xy 412.662847 -275.303279) (xy 412.614628 -275.293435) (xy 412.568612 -275.275983) (xy 412.525991 -275.251376)
			(xy 412.48787 -275.220251) (xy 412.455235 -275.183414) (xy 412.428932 -275.141818) (xy 412.409641 -275.096542)
			(xy 412.397864 -275.048758) (xy 412.393904 -274.999704) (xy 411.104837 -274.999704) (xy 411.104842 -274.999958)
			(xy 411.104347 -275.024565) (xy 411.096452 -275.073142) (xy 411.080868 -275.119823) (xy 411.057997 -275.1634)
			(xy 411.028432 -275.202744) (xy 410.992939 -275.236836) (xy 410.952436 -275.264792) (xy 410.907974 -275.28589)
			(xy 410.860703 -275.299582) (xy 410.811848 -275.305514) (xy 410.762673 -275.303533) (xy 410.714454 -275.293689)
			(xy 410.668438 -275.276237) (xy 410.625817 -275.25163) (xy 410.587696 -275.220505) (xy 410.555061 -275.183668)
			(xy 410.528758 -275.142072) (xy 410.509467 -275.096796) (xy 410.49769 -275.049012) (xy 410.49373 -274.999958)
			(xy 409.204917 -274.999958) (xy 409.204427 -275.024311) (xy 409.196532 -275.072888) (xy 409.180948 -275.119569)
			(xy 409.158077 -275.163146) (xy 409.128512 -275.20249) (xy 409.093019 -275.236582) (xy 409.052516 -275.264538)
			(xy 409.008054 -275.285636) (xy 408.960783 -275.299328) (xy 408.911928 -275.30526) (xy 408.862753 -275.303279)
			(xy 408.814534 -275.293435) (xy 408.768518 -275.275983) (xy 408.725897 -275.251376) (xy 408.687776 -275.220251)
			(xy 408.655141 -275.183414) (xy 408.628838 -275.141818) (xy 408.609547 -275.096542) (xy 408.59777 -275.048758)
			(xy 408.59381 -274.999704) (xy 407.305251 -274.999704) (xy 407.305256 -274.999958) (xy 407.304761 -275.024565)
			(xy 407.296866 -275.073142) (xy 407.281282 -275.119823) (xy 407.258411 -275.1634) (xy 407.228846 -275.202744)
			(xy 407.193353 -275.236836) (xy 407.15285 -275.264792) (xy 407.108388 -275.28589) (xy 407.061117 -275.299582)
			(xy 407.012262 -275.305514) (xy 406.963087 -275.303533) (xy 406.914868 -275.293689) (xy 406.868852 -275.276237)
			(xy 406.826231 -275.25163) (xy 406.78811 -275.220505) (xy 406.755475 -275.183668) (xy 406.729172 -275.142072)
			(xy 406.709881 -275.096796) (xy 406.698104 -275.049012) (xy 406.694144 -274.999958) (xy 405.405336 -274.999958)
			(xy 405.404841 -275.024565) (xy 405.396946 -275.073142) (xy 405.381362 -275.119823) (xy 405.358491 -275.1634)
			(xy 405.328926 -275.202744) (xy 405.293433 -275.236836) (xy 405.25293 -275.264792) (xy 405.208468 -275.28589)
			(xy 405.161197 -275.299582) (xy 405.112342 -275.305514) (xy 405.063167 -275.303533) (xy 405.014948 -275.293689)
			(xy 404.968932 -275.276237) (xy 404.926311 -275.25163) (xy 404.88819 -275.220505) (xy 404.855555 -275.183668)
			(xy 404.829252 -275.142072) (xy 404.809961 -275.096796) (xy 404.798184 -275.049012) (xy 404.794224 -274.999958)
			(xy 403.505162 -274.999958) (xy 403.504667 -275.024565) (xy 403.496772 -275.073142) (xy 403.481188 -275.119823)
			(xy 403.458317 -275.1634) (xy 403.428752 -275.202744) (xy 403.393259 -275.236836) (xy 403.352756 -275.264792)
			(xy 403.308294 -275.28589) (xy 403.261023 -275.299582) (xy 403.212168 -275.305514) (xy 403.162993 -275.303533)
			(xy 403.114774 -275.293689) (xy 403.068758 -275.276237) (xy 403.026137 -275.25163) (xy 402.988016 -275.220505)
			(xy 402.955381 -275.183668) (xy 402.929078 -275.142072) (xy 402.909787 -275.096796) (xy 402.89801 -275.049012)
			(xy 402.89405 -274.999958) (xy 401.605242 -274.999958) (xy 401.604747 -275.024565) (xy 401.596852 -275.073142)
			(xy 401.581268 -275.119823) (xy 401.558397 -275.1634) (xy 401.528832 -275.202744) (xy 401.493339 -275.236836)
			(xy 401.452836 -275.264792) (xy 401.408374 -275.28589) (xy 401.361103 -275.299582) (xy 401.312248 -275.305514)
			(xy 401.263073 -275.303533) (xy 401.214854 -275.293689) (xy 401.168838 -275.276237) (xy 401.126217 -275.25163)
			(xy 401.088096 -275.220505) (xy 401.055461 -275.183668) (xy 401.029158 -275.142072) (xy 401.009867 -275.096796)
			(xy 400.99809 -275.049012) (xy 400.99413 -274.999958) (xy 399.705322 -274.999958) (xy 399.704827 -275.024565)
			(xy 399.696932 -275.073142) (xy 399.681348 -275.119823) (xy 399.658477 -275.1634) (xy 399.628912 -275.202744)
			(xy 399.593419 -275.236836) (xy 399.552916 -275.264792) (xy 399.508454 -275.28589) (xy 399.461183 -275.299582)
			(xy 399.412328 -275.305514) (xy 399.363153 -275.303533) (xy 399.314934 -275.293689) (xy 399.268918 -275.276237)
			(xy 399.226297 -275.25163) (xy 399.188176 -275.220505) (xy 399.155541 -275.183668) (xy 399.129238 -275.142072)
			(xy 399.109947 -275.096796) (xy 399.09817 -275.049012) (xy 399.09421 -274.999958) (xy 397.805148 -274.999958)
			(xy 397.804653 -275.024565) (xy 397.796758 -275.073142) (xy 397.781174 -275.119823) (xy 397.758303 -275.1634)
			(xy 397.728738 -275.202744) (xy 397.693245 -275.236836) (xy 397.652742 -275.264792) (xy 397.60828 -275.28589)
			(xy 397.561009 -275.299582) (xy 397.512154 -275.305514) (xy 397.462979 -275.303533) (xy 397.41476 -275.293689)
			(xy 397.368744 -275.276237) (xy 397.326123 -275.25163) (xy 397.288002 -275.220505) (xy 397.255367 -275.183668)
			(xy 397.229064 -275.142072) (xy 397.209773 -275.096796) (xy 397.197996 -275.049012) (xy 397.194036 -274.999958)
			(xy 395.905228 -274.999958) (xy 395.904733 -275.024565) (xy 395.896838 -275.073142) (xy 395.881254 -275.119823)
			(xy 395.858383 -275.1634) (xy 395.828818 -275.202744) (xy 395.793325 -275.236836) (xy 395.752822 -275.264792)
			(xy 395.70836 -275.28589) (xy 395.661089 -275.299582) (xy 395.612234 -275.305514) (xy 395.563059 -275.303533)
			(xy 395.51484 -275.293689) (xy 395.468824 -275.276237) (xy 395.426203 -275.25163) (xy 395.388082 -275.220505)
			(xy 395.355447 -275.183668) (xy 395.329144 -275.142072) (xy 395.309853 -275.096796) (xy 395.298076 -275.049012)
			(xy 395.294116 -274.999958) (xy 394.005308 -274.999958) (xy 394.004813 -275.024565) (xy 393.996918 -275.073142)
			(xy 393.981334 -275.119823) (xy 393.958463 -275.1634) (xy 393.928898 -275.202744) (xy 393.893405 -275.236836)
			(xy 393.852902 -275.264792) (xy 393.80844 -275.28589) (xy 393.761169 -275.299582) (xy 393.712314 -275.305514)
			(xy 393.663139 -275.303533) (xy 393.61492 -275.293689) (xy 393.568904 -275.276237) (xy 393.526283 -275.25163)
			(xy 393.488162 -275.220505) (xy 393.455527 -275.183668) (xy 393.429224 -275.142072) (xy 393.409933 -275.096796)
			(xy 393.398156 -275.049012) (xy 393.394196 -274.999958) (xy 314.955169 -274.999958) (xy 314.954679 -275.024311)
			(xy 314.946784 -275.072888) (xy 314.9312 -275.119569) (xy 314.908329 -275.163146) (xy 314.878764 -275.20249)
			(xy 314.843271 -275.236582) (xy 314.802768 -275.264538) (xy 314.758306 -275.285636) (xy 314.711035 -275.299328)
			(xy 314.66218 -275.30526) (xy 314.613005 -275.303279) (xy 314.564786 -275.293435) (xy 314.51877 -275.275983)
			(xy 314.476149 -275.251376) (xy 314.438028 -275.220251) (xy 314.405393 -275.183414) (xy 314.37909 -275.141818)
			(xy 314.359799 -275.096542) (xy 314.348022 -275.048758) (xy 314.344062 -274.999704) (xy 314.005214 -274.999704)
			(xy 314.004719 -275.024311) (xy 313.996824 -275.072888) (xy 313.98124 -275.119569) (xy 313.958369 -275.163146)
			(xy 313.928804 -275.20249) (xy 313.893311 -275.236582) (xy 313.852808 -275.264538) (xy 313.808346 -275.285636)
			(xy 313.761075 -275.299328) (xy 313.71222 -275.30526) (xy 313.663045 -275.303279) (xy 313.614826 -275.293435)
			(xy 313.56881 -275.275983) (xy 313.526189 -275.251376) (xy 313.488068 -275.220251) (xy 313.455433 -275.183414)
			(xy 313.42913 -275.141818) (xy 313.409839 -275.096542) (xy 313.398062 -275.048758) (xy 313.394102 -274.999704)
			(xy 312.104781 -274.999704) (xy 312.104786 -274.999958) (xy 312.104291 -275.024565) (xy 312.096396 -275.073142)
			(xy 312.080812 -275.119823) (xy 312.057941 -275.1634) (xy 312.028376 -275.202744) (xy 311.992883 -275.236836)
			(xy 311.95238 -275.264792) (xy 311.907918 -275.28589) (xy 311.860647 -275.299582) (xy 311.811792 -275.305514)
			(xy 311.762617 -275.303533) (xy 311.714398 -275.293689) (xy 311.668382 -275.276237) (xy 311.625761 -275.25163)
			(xy 311.58764 -275.220505) (xy 311.555005 -275.183668) (xy 311.528702 -275.142072) (xy 311.509411 -275.096796)
			(xy 311.497634 -275.049012) (xy 311.493674 -274.999958) (xy 310.204866 -274.999958) (xy 310.204371 -275.024565)
			(xy 310.196476 -275.073142) (xy 310.180892 -275.119823) (xy 310.158021 -275.1634) (xy 310.128456 -275.202744)
			(xy 310.092963 -275.236836) (xy 310.05246 -275.264792) (xy 310.007998 -275.28589) (xy 309.960727 -275.299582)
			(xy 309.911872 -275.305514) (xy 309.862697 -275.303533) (xy 309.814478 -275.293689) (xy 309.768462 -275.276237)
			(xy 309.725841 -275.25163) (xy 309.68772 -275.220505) (xy 309.655085 -275.183668) (xy 309.628782 -275.142072)
			(xy 309.609491 -275.096796) (xy 309.597714 -275.049012) (xy 309.593754 -274.999958) (xy 308.304941 -274.999958)
			(xy 308.304451 -275.024311) (xy 308.296556 -275.072888) (xy 308.280972 -275.119569) (xy 308.258101 -275.163146)
			(xy 308.228536 -275.20249) (xy 308.193043 -275.236582) (xy 308.15254 -275.264538) (xy 308.108078 -275.285636)
			(xy 308.060807 -275.299328) (xy 308.011952 -275.30526) (xy 307.962777 -275.303279) (xy 307.914558 -275.293435)
			(xy 307.868542 -275.275983) (xy 307.825921 -275.251376) (xy 307.7878 -275.220251) (xy 307.755165 -275.183414)
			(xy 307.728862 -275.141818) (xy 307.709571 -275.096542) (xy 307.697794 -275.048758) (xy 307.693834 -274.999704)
			(xy 306.404767 -274.999704) (xy 306.404772 -274.999958) (xy 306.404277 -275.024565) (xy 306.396382 -275.073142)
			(xy 306.380798 -275.119823) (xy 306.357927 -275.1634) (xy 306.328362 -275.202744) (xy 306.292869 -275.236836)
			(xy 306.252366 -275.264792) (xy 306.207904 -275.28589) (xy 306.160633 -275.299582) (xy 306.111778 -275.305514)
			(xy 306.062603 -275.303533) (xy 306.014384 -275.293689) (xy 305.968368 -275.276237) (xy 305.925747 -275.25163)
			(xy 305.887626 -275.220505) (xy 305.854991 -275.183668) (xy 305.828688 -275.142072) (xy 305.809397 -275.096796)
			(xy 305.79762 -275.049012) (xy 305.79366 -274.999958) (xy 304.504847 -274.999958) (xy 304.504357 -275.024311)
			(xy 304.496462 -275.072888) (xy 304.480878 -275.119569) (xy 304.458007 -275.163146) (xy 304.428442 -275.20249)
			(xy 304.392949 -275.236582) (xy 304.352446 -275.264538) (xy 304.307984 -275.285636) (xy 304.260713 -275.299328)
			(xy 304.211858 -275.30526) (xy 304.162683 -275.303279) (xy 304.114464 -275.293435) (xy 304.068448 -275.275983)
			(xy 304.025827 -275.251376) (xy 303.987706 -275.220251) (xy 303.955071 -275.183414) (xy 303.928768 -275.141818)
			(xy 303.909477 -275.096542) (xy 303.8977 -275.048758) (xy 303.89374 -274.999704) (xy 302.604673 -274.999704)
			(xy 302.604678 -274.999958) (xy 302.604183 -275.024565) (xy 302.596288 -275.073142) (xy 302.580704 -275.119823)
			(xy 302.557833 -275.1634) (xy 302.528268 -275.202744) (xy 302.492775 -275.236836) (xy 302.452272 -275.264792)
			(xy 302.40781 -275.28589) (xy 302.360539 -275.299582) (xy 302.311684 -275.305514) (xy 302.262509 -275.303533)
			(xy 302.21429 -275.293689) (xy 302.168274 -275.276237) (xy 302.125653 -275.25163) (xy 302.087532 -275.220505)
			(xy 302.054897 -275.183668) (xy 302.028594 -275.142072) (xy 302.009303 -275.096796) (xy 301.997526 -275.049012)
			(xy 301.993566 -274.999958) (xy 300.704753 -274.999958) (xy 300.704263 -275.024311) (xy 300.696368 -275.072888)
			(xy 300.680784 -275.119569) (xy 300.657913 -275.163146) (xy 300.628348 -275.20249) (xy 300.592855 -275.236582)
			(xy 300.552352 -275.264538) (xy 300.50789 -275.285636) (xy 300.460619 -275.299328) (xy 300.411764 -275.30526)
			(xy 300.362589 -275.303279) (xy 300.31437 -275.293435) (xy 300.268354 -275.275983) (xy 300.225733 -275.251376)
			(xy 300.187612 -275.220251) (xy 300.154977 -275.183414) (xy 300.128674 -275.141818) (xy 300.109383 -275.096542)
			(xy 300.097606 -275.048758) (xy 300.093646 -274.999704) (xy 298.804833 -274.999704) (xy 298.804838 -274.999958)
			(xy 298.804343 -275.024565) (xy 298.796448 -275.073142) (xy 298.780864 -275.119823) (xy 298.757993 -275.1634)
			(xy 298.728428 -275.202744) (xy 298.692935 -275.236836) (xy 298.652432 -275.264792) (xy 298.60797 -275.28589)
			(xy 298.560699 -275.299582) (xy 298.511844 -275.305514) (xy 298.462669 -275.303533) (xy 298.41445 -275.293689)
			(xy 298.368434 -275.276237) (xy 298.325813 -275.25163) (xy 298.287692 -275.220505) (xy 298.255057 -275.183668)
			(xy 298.228754 -275.142072) (xy 298.209463 -275.096796) (xy 298.197686 -275.049012) (xy 298.193726 -274.999958)
			(xy 296.904913 -274.999958) (xy 296.904423 -275.024311) (xy 296.896528 -275.072888) (xy 296.880944 -275.119569)
			(xy 296.858073 -275.163146) (xy 296.828508 -275.20249) (xy 296.793015 -275.236582) (xy 296.752512 -275.264538)
			(xy 296.70805 -275.285636) (xy 296.660779 -275.299328) (xy 296.611924 -275.30526) (xy 296.562749 -275.303279)
			(xy 296.51453 -275.293435) (xy 296.468514 -275.275983) (xy 296.425893 -275.251376) (xy 296.387772 -275.220251)
			(xy 296.355137 -275.183414) (xy 296.328834 -275.141818) (xy 296.309543 -275.096542) (xy 296.297766 -275.048758)
			(xy 296.293806 -274.999704) (xy 295.004739 -274.999704) (xy 295.004744 -274.999958) (xy 295.004249 -275.024565)
			(xy 294.996354 -275.073142) (xy 294.98077 -275.119823) (xy 294.957899 -275.1634) (xy 294.928334 -275.202744)
			(xy 294.892841 -275.236836) (xy 294.852338 -275.264792) (xy 294.807876 -275.28589) (xy 294.760605 -275.299582)
			(xy 294.71175 -275.305514) (xy 294.662575 -275.303533) (xy 294.614356 -275.293689) (xy 294.56834 -275.276237)
			(xy 294.525719 -275.25163) (xy 294.487598 -275.220505) (xy 294.454963 -275.183668) (xy 294.42866 -275.142072)
			(xy 294.409369 -275.096796) (xy 294.397592 -275.049012) (xy 294.393632 -274.999958) (xy 293.104819 -274.999958)
			(xy 293.104329 -275.024311) (xy 293.096434 -275.072888) (xy 293.08085 -275.119569) (xy 293.057979 -275.163146)
			(xy 293.028414 -275.20249) (xy 292.992921 -275.236582) (xy 292.952418 -275.264538) (xy 292.907956 -275.285636)
			(xy 292.860685 -275.299328) (xy 292.81183 -275.30526) (xy 292.762655 -275.303279) (xy 292.714436 -275.293435)
			(xy 292.66842 -275.275983) (xy 292.625799 -275.251376) (xy 292.587678 -275.220251) (xy 292.555043 -275.183414)
			(xy 292.52874 -275.141818) (xy 292.509449 -275.096542) (xy 292.497672 -275.048758) (xy 292.493712 -274.999704)
			(xy 291.205153 -274.999704) (xy 291.205158 -274.999958) (xy 291.204663 -275.024565) (xy 291.196768 -275.073142)
			(xy 291.181184 -275.119823) (xy 291.158313 -275.1634) (xy 291.128748 -275.202744) (xy 291.093255 -275.236836)
			(xy 291.052752 -275.264792) (xy 291.00829 -275.28589) (xy 290.961019 -275.299582) (xy 290.912164 -275.305514)
			(xy 290.862989 -275.303533) (xy 290.81477 -275.293689) (xy 290.768754 -275.276237) (xy 290.726133 -275.25163)
			(xy 290.688012 -275.220505) (xy 290.655377 -275.183668) (xy 290.629074 -275.142072) (xy 290.609783 -275.096796)
			(xy 290.598006 -275.049012) (xy 290.594046 -274.999958) (xy 289.305238 -274.999958) (xy 289.304743 -275.024565)
			(xy 289.296848 -275.073142) (xy 289.281264 -275.119823) (xy 289.258393 -275.1634) (xy 289.228828 -275.202744)
			(xy 289.193335 -275.236836) (xy 289.152832 -275.264792) (xy 289.10837 -275.28589) (xy 289.061099 -275.299582)
			(xy 289.012244 -275.305514) (xy 288.963069 -275.303533) (xy 288.91485 -275.293689) (xy 288.868834 -275.276237)
			(xy 288.826213 -275.25163) (xy 288.788092 -275.220505) (xy 288.755457 -275.183668) (xy 288.729154 -275.142072)
			(xy 288.709863 -275.096796) (xy 288.698086 -275.049012) (xy 288.694126 -274.999958) (xy 287.405064 -274.999958)
			(xy 287.404569 -275.024565) (xy 287.396674 -275.073142) (xy 287.38109 -275.119823) (xy 287.358219 -275.1634)
			(xy 287.328654 -275.202744) (xy 287.293161 -275.236836) (xy 287.252658 -275.264792) (xy 287.208196 -275.28589)
			(xy 287.160925 -275.299582) (xy 287.11207 -275.305514) (xy 287.062895 -275.303533) (xy 287.014676 -275.293689)
			(xy 286.96866 -275.276237) (xy 286.926039 -275.25163) (xy 286.887918 -275.220505) (xy 286.855283 -275.183668)
			(xy 286.82898 -275.142072) (xy 286.809689 -275.096796) (xy 286.797912 -275.049012) (xy 286.793952 -274.999958)
			(xy 285.505144 -274.999958) (xy 285.504649 -275.024565) (xy 285.496754 -275.073142) (xy 285.48117 -275.119823)
			(xy 285.458299 -275.1634) (xy 285.428734 -275.202744) (xy 285.393241 -275.236836) (xy 285.352738 -275.264792)
			(xy 285.308276 -275.28589) (xy 285.261005 -275.299582) (xy 285.21215 -275.305514) (xy 285.162975 -275.303533)
			(xy 285.114756 -275.293689) (xy 285.06874 -275.276237) (xy 285.026119 -275.25163) (xy 284.987998 -275.220505)
			(xy 284.955363 -275.183668) (xy 284.92906 -275.142072) (xy 284.909769 -275.096796) (xy 284.897992 -275.049012)
			(xy 284.894032 -274.999958) (xy 283.605224 -274.999958) (xy 283.604729 -275.024565) (xy 283.596834 -275.073142)
			(xy 283.58125 -275.119823) (xy 283.558379 -275.1634) (xy 283.528814 -275.202744) (xy 283.493321 -275.236836)
			(xy 283.452818 -275.264792) (xy 283.408356 -275.28589) (xy 283.361085 -275.299582) (xy 283.31223 -275.305514)
			(xy 283.263055 -275.303533) (xy 283.214836 -275.293689) (xy 283.16882 -275.276237) (xy 283.126199 -275.25163)
			(xy 283.088078 -275.220505) (xy 283.055443 -275.183668) (xy 283.02914 -275.142072) (xy 283.009849 -275.096796)
			(xy 282.998072 -275.049012) (xy 282.994112 -274.999958) (xy 281.70505 -274.999958) (xy 281.704555 -275.024565)
			(xy 281.69666 -275.073142) (xy 281.681076 -275.119823) (xy 281.658205 -275.1634) (xy 281.62864 -275.202744)
			(xy 281.593147 -275.236836) (xy 281.552644 -275.264792) (xy 281.508182 -275.28589) (xy 281.460911 -275.299582)
			(xy 281.412056 -275.305514) (xy 281.362881 -275.303533) (xy 281.314662 -275.293689) (xy 281.268646 -275.276237)
			(xy 281.226025 -275.25163) (xy 281.187904 -275.220505) (xy 281.155269 -275.183668) (xy 281.128966 -275.142072)
			(xy 281.109675 -275.096796) (xy 281.097898 -275.049012) (xy 281.093938 -274.999958) (xy 279.80513 -274.999958)
			(xy 279.804635 -275.024565) (xy 279.79674 -275.073142) (xy 279.781156 -275.119823) (xy 279.758285 -275.1634)
			(xy 279.72872 -275.202744) (xy 279.693227 -275.236836) (xy 279.652724 -275.264792) (xy 279.608262 -275.28589)
			(xy 279.560991 -275.299582) (xy 279.512136 -275.305514) (xy 279.462961 -275.303533) (xy 279.414742 -275.293689)
			(xy 279.368726 -275.276237) (xy 279.326105 -275.25163) (xy 279.287984 -275.220505) (xy 279.255349 -275.183668)
			(xy 279.229046 -275.142072) (xy 279.209755 -275.096796) (xy 279.197978 -275.049012) (xy 279.194018 -274.999958)
			(xy 277.90521 -274.999958) (xy 277.904715 -275.024565) (xy 277.89682 -275.073142) (xy 277.881236 -275.119823)
			(xy 277.858365 -275.1634) (xy 277.8288 -275.202744) (xy 277.793307 -275.236836) (xy 277.752804 -275.264792)
			(xy 277.708342 -275.28589) (xy 277.661071 -275.299582) (xy 277.612216 -275.305514) (xy 277.563041 -275.303533)
			(xy 277.514822 -275.293689) (xy 277.468806 -275.276237) (xy 277.426185 -275.25163) (xy 277.388064 -275.220505)
			(xy 277.355429 -275.183668) (xy 277.329126 -275.142072) (xy 277.309835 -275.096796) (xy 277.298058 -275.049012)
			(xy 277.294098 -274.999958) (xy 198.855325 -274.999958) (xy 198.854835 -275.024311) (xy 198.84694 -275.072888)
			(xy 198.831356 -275.119569) (xy 198.808485 -275.163146) (xy 198.77892 -275.20249) (xy 198.743427 -275.236582)
			(xy 198.702924 -275.264538) (xy 198.658462 -275.285636) (xy 198.611191 -275.299328) (xy 198.562336 -275.30526)
			(xy 198.513161 -275.303279) (xy 198.464942 -275.293435) (xy 198.418926 -275.275983) (xy 198.376305 -275.251376)
			(xy 198.338184 -275.220251) (xy 198.305549 -275.183414) (xy 198.279246 -275.141818) (xy 198.259955 -275.096542)
			(xy 198.248178 -275.048758) (xy 198.244218 -274.999704) (xy 197.90537 -274.999704) (xy 197.904875 -275.024311)
			(xy 197.89698 -275.072888) (xy 197.881396 -275.119569) (xy 197.858525 -275.163146) (xy 197.82896 -275.20249)
			(xy 197.793467 -275.236582) (xy 197.752964 -275.264538) (xy 197.708502 -275.285636) (xy 197.661231 -275.299328)
			(xy 197.612376 -275.30526) (xy 197.563201 -275.303279) (xy 197.514982 -275.293435) (xy 197.468966 -275.275983)
			(xy 197.426345 -275.251376) (xy 197.388224 -275.220251) (xy 197.355589 -275.183414) (xy 197.329286 -275.141818)
			(xy 197.309995 -275.096542) (xy 197.298218 -275.048758) (xy 197.294258 -274.999704) (xy 196.004937 -274.999704)
			(xy 196.004942 -274.999958) (xy 196.004447 -275.024565) (xy 195.996552 -275.073142) (xy 195.980968 -275.119823)
			(xy 195.958097 -275.1634) (xy 195.928532 -275.202744) (xy 195.893039 -275.236836) (xy 195.852536 -275.264792)
			(xy 195.808074 -275.28589) (xy 195.760803 -275.299582) (xy 195.711948 -275.305514) (xy 195.662773 -275.303533)
			(xy 195.614554 -275.293689) (xy 195.568538 -275.276237) (xy 195.525917 -275.25163) (xy 195.487796 -275.220505)
			(xy 195.455161 -275.183668) (xy 195.428858 -275.142072) (xy 195.409567 -275.096796) (xy 195.39779 -275.049012)
			(xy 195.39383 -274.999958) (xy 194.105022 -274.999958) (xy 194.104527 -275.024565) (xy 194.096632 -275.073142)
			(xy 194.081048 -275.119823) (xy 194.058177 -275.1634) (xy 194.028612 -275.202744) (xy 193.993119 -275.236836)
			(xy 193.952616 -275.264792) (xy 193.908154 -275.28589) (xy 193.860883 -275.299582) (xy 193.812028 -275.305514)
			(xy 193.762853 -275.303533) (xy 193.714634 -275.293689) (xy 193.668618 -275.276237) (xy 193.625997 -275.25163)
			(xy 193.587876 -275.220505) (xy 193.555241 -275.183668) (xy 193.528938 -275.142072) (xy 193.509647 -275.096796)
			(xy 193.49787 -275.049012) (xy 193.49391 -274.999958) (xy 192.205097 -274.999958) (xy 192.204607 -275.024311)
			(xy 192.196712 -275.072888) (xy 192.181128 -275.119569) (xy 192.158257 -275.163146) (xy 192.128692 -275.20249)
			(xy 192.093199 -275.236582) (xy 192.052696 -275.264538) (xy 192.008234 -275.285636) (xy 191.960963 -275.299328)
			(xy 191.912108 -275.30526) (xy 191.862933 -275.303279) (xy 191.814714 -275.293435) (xy 191.768698 -275.275983)
			(xy 191.726077 -275.251376) (xy 191.687956 -275.220251) (xy 191.655321 -275.183414) (xy 191.629018 -275.141818)
			(xy 191.609727 -275.096542) (xy 191.59795 -275.048758) (xy 191.59399 -274.999704) (xy 190.304923 -274.999704)
			(xy 190.304928 -274.999958) (xy 190.304433 -275.024565) (xy 190.296538 -275.073142) (xy 190.280954 -275.119823)
			(xy 190.258083 -275.1634) (xy 190.228518 -275.202744) (xy 190.193025 -275.236836) (xy 190.152522 -275.264792)
			(xy 190.10806 -275.28589) (xy 190.060789 -275.299582) (xy 190.011934 -275.305514) (xy 189.962759 -275.303533)
			(xy 189.91454 -275.293689) (xy 189.868524 -275.276237) (xy 189.825903 -275.25163) (xy 189.787782 -275.220505)
			(xy 189.755147 -275.183668) (xy 189.728844 -275.142072) (xy 189.709553 -275.096796) (xy 189.697776 -275.049012)
			(xy 189.693816 -274.999958) (xy 188.405003 -274.999958) (xy 188.404513 -275.024311) (xy 188.396618 -275.072888)
			(xy 188.381034 -275.119569) (xy 188.358163 -275.163146) (xy 188.328598 -275.20249) (xy 188.293105 -275.236582)
			(xy 188.252602 -275.264538) (xy 188.20814 -275.285636) (xy 188.160869 -275.299328) (xy 188.112014 -275.30526)
			(xy 188.062839 -275.303279) (xy 188.01462 -275.293435) (xy 187.968604 -275.275983) (xy 187.925983 -275.251376)
			(xy 187.887862 -275.220251) (xy 187.855227 -275.183414) (xy 187.828924 -275.141818) (xy 187.809633 -275.096542)
			(xy 187.797856 -275.048758) (xy 187.793896 -274.999704) (xy 186.504829 -274.999704) (xy 186.504834 -274.999958)
			(xy 186.504339 -275.024565) (xy 186.496444 -275.073142) (xy 186.48086 -275.119823) (xy 186.457989 -275.1634)
			(xy 186.428424 -275.202744) (xy 186.392931 -275.236836) (xy 186.352428 -275.264792) (xy 186.307966 -275.28589)
			(xy 186.260695 -275.299582) (xy 186.21184 -275.305514) (xy 186.162665 -275.303533) (xy 186.114446 -275.293689)
			(xy 186.06843 -275.276237) (xy 186.025809 -275.25163) (xy 185.987688 -275.220505) (xy 185.955053 -275.183668)
			(xy 185.92875 -275.142072) (xy 185.909459 -275.096796) (xy 185.897682 -275.049012) (xy 185.893722 -274.999958)
			(xy 184.604909 -274.999958) (xy 184.604419 -275.024311) (xy 184.596524 -275.072888) (xy 184.58094 -275.119569)
			(xy 184.558069 -275.163146) (xy 184.528504 -275.20249) (xy 184.493011 -275.236582) (xy 184.452508 -275.264538)
			(xy 184.408046 -275.285636) (xy 184.360775 -275.299328) (xy 184.31192 -275.30526) (xy 184.262745 -275.303279)
			(xy 184.214526 -275.293435) (xy 184.16851 -275.275983) (xy 184.125889 -275.251376) (xy 184.087768 -275.220251)
			(xy 184.055133 -275.183414) (xy 184.02883 -275.141818) (xy 184.009539 -275.096542) (xy 183.997762 -275.048758)
			(xy 183.993802 -274.999704) (xy 182.704989 -274.999704) (xy 182.704994 -274.999958) (xy 182.704499 -275.024565)
			(xy 182.696604 -275.073142) (xy 182.68102 -275.119823) (xy 182.658149 -275.1634) (xy 182.628584 -275.202744)
			(xy 182.593091 -275.236836) (xy 182.552588 -275.264792) (xy 182.508126 -275.28589) (xy 182.460855 -275.299582)
			(xy 182.412 -275.305514) (xy 182.362825 -275.303533) (xy 182.314606 -275.293689) (xy 182.26859 -275.276237)
			(xy 182.225969 -275.25163) (xy 182.187848 -275.220505) (xy 182.155213 -275.183668) (xy 182.12891 -275.142072)
			(xy 182.109619 -275.096796) (xy 182.097842 -275.049012) (xy 182.093882 -274.999958) (xy 180.805069 -274.999958)
			(xy 180.804579 -275.024311) (xy 180.796684 -275.072888) (xy 180.7811 -275.119569) (xy 180.758229 -275.163146)
			(xy 180.728664 -275.20249) (xy 180.693171 -275.236582) (xy 180.652668 -275.264538) (xy 180.608206 -275.285636)
			(xy 180.560935 -275.299328) (xy 180.51208 -275.30526) (xy 180.462905 -275.303279) (xy 180.414686 -275.293435)
			(xy 180.36867 -275.275983) (xy 180.326049 -275.251376) (xy 180.287928 -275.220251) (xy 180.255293 -275.183414)
			(xy 180.22899 -275.141818) (xy 180.209699 -275.096542) (xy 180.197922 -275.048758) (xy 180.193962 -274.999704)
			(xy 178.904895 -274.999704) (xy 178.9049 -274.999958) (xy 178.904405 -275.024565) (xy 178.89651 -275.073142)
			(xy 178.880926 -275.119823) (xy 178.858055 -275.1634) (xy 178.82849 -275.202744) (xy 178.792997 -275.236836)
			(xy 178.752494 -275.264792) (xy 178.708032 -275.28589) (xy 178.660761 -275.299582) (xy 178.611906 -275.305514)
			(xy 178.562731 -275.303533) (xy 178.514512 -275.293689) (xy 178.468496 -275.276237) (xy 178.425875 -275.25163)
			(xy 178.387754 -275.220505) (xy 178.355119 -275.183668) (xy 178.328816 -275.142072) (xy 178.309525 -275.096796)
			(xy 178.297748 -275.049012) (xy 178.293788 -274.999958) (xy 177.004975 -274.999958) (xy 177.004485 -275.024311)
			(xy 176.99659 -275.072888) (xy 176.981006 -275.119569) (xy 176.958135 -275.163146) (xy 176.92857 -275.20249)
			(xy 176.893077 -275.236582) (xy 176.852574 -275.264538) (xy 176.808112 -275.285636) (xy 176.760841 -275.299328)
			(xy 176.711986 -275.30526) (xy 176.662811 -275.303279) (xy 176.614592 -275.293435) (xy 176.568576 -275.275983)
			(xy 176.525955 -275.251376) (xy 176.487834 -275.220251) (xy 176.455199 -275.183414) (xy 176.428896 -275.141818)
			(xy 176.409605 -275.096542) (xy 176.397828 -275.048758) (xy 176.393868 -274.999704) (xy 175.105309 -274.999704)
			(xy 175.105314 -274.999958) (xy 175.104819 -275.024565) (xy 175.096924 -275.073142) (xy 175.08134 -275.119823)
			(xy 175.058469 -275.1634) (xy 175.028904 -275.202744) (xy 174.993411 -275.236836) (xy 174.952908 -275.264792)
			(xy 174.908446 -275.28589) (xy 174.861175 -275.299582) (xy 174.81232 -275.305514) (xy 174.763145 -275.303533)
			(xy 174.714926 -275.293689) (xy 174.66891 -275.276237) (xy 174.626289 -275.25163) (xy 174.588168 -275.220505)
			(xy 174.555533 -275.183668) (xy 174.52923 -275.142072) (xy 174.509939 -275.096796) (xy 174.498162 -275.049012)
			(xy 174.494202 -274.999958) (xy 173.205394 -274.999958) (xy 173.204899 -275.024565) (xy 173.197004 -275.073142)
			(xy 173.18142 -275.119823) (xy 173.158549 -275.1634) (xy 173.128984 -275.202744) (xy 173.093491 -275.236836)
			(xy 173.052988 -275.264792) (xy 173.008526 -275.28589) (xy 172.961255 -275.299582) (xy 172.9124 -275.305514)
			(xy 172.863225 -275.303533) (xy 172.815006 -275.293689) (xy 172.76899 -275.276237) (xy 172.726369 -275.25163)
			(xy 172.688248 -275.220505) (xy 172.655613 -275.183668) (xy 172.62931 -275.142072) (xy 172.610019 -275.096796)
			(xy 172.598242 -275.049012) (xy 172.594282 -274.999958) (xy 171.30522 -274.999958) (xy 171.304725 -275.024565)
			(xy 171.29683 -275.073142) (xy 171.281246 -275.119823) (xy 171.258375 -275.1634) (xy 171.22881 -275.202744)
			(xy 171.193317 -275.236836) (xy 171.152814 -275.264792) (xy 171.108352 -275.28589) (xy 171.061081 -275.299582)
			(xy 171.012226 -275.305514) (xy 170.963051 -275.303533) (xy 170.914832 -275.293689) (xy 170.868816 -275.276237)
			(xy 170.826195 -275.25163) (xy 170.788074 -275.220505) (xy 170.755439 -275.183668) (xy 170.729136 -275.142072)
			(xy 170.709845 -275.096796) (xy 170.698068 -275.049012) (xy 170.694108 -274.999958) (xy 169.4053 -274.999958)
			(xy 169.404805 -275.024565) (xy 169.39691 -275.073142) (xy 169.381326 -275.119823) (xy 169.358455 -275.1634)
			(xy 169.32889 -275.202744) (xy 169.293397 -275.236836) (xy 169.252894 -275.264792) (xy 169.208432 -275.28589)
			(xy 169.161161 -275.299582) (xy 169.112306 -275.305514) (xy 169.063131 -275.303533) (xy 169.014912 -275.293689)
			(xy 168.968896 -275.276237) (xy 168.926275 -275.25163) (xy 168.888154 -275.220505) (xy 168.855519 -275.183668)
			(xy 168.829216 -275.142072) (xy 168.809925 -275.096796) (xy 168.798148 -275.049012) (xy 168.794188 -274.999958)
			(xy 167.50538 -274.999958) (xy 167.504885 -275.024565) (xy 167.49699 -275.073142) (xy 167.481406 -275.119823)
			(xy 167.458535 -275.1634) (xy 167.42897 -275.202744) (xy 167.393477 -275.236836) (xy 167.352974 -275.264792)
			(xy 167.308512 -275.28589) (xy 167.261241 -275.299582) (xy 167.212386 -275.305514) (xy 167.163211 -275.303533)
			(xy 167.114992 -275.293689) (xy 167.068976 -275.276237) (xy 167.026355 -275.25163) (xy 166.988234 -275.220505)
			(xy 166.955599 -275.183668) (xy 166.929296 -275.142072) (xy 166.910005 -275.096796) (xy 166.898228 -275.049012)
			(xy 166.894268 -274.999958) (xy 165.605206 -274.999958) (xy 165.604711 -275.024565) (xy 165.596816 -275.073142)
			(xy 165.581232 -275.119823) (xy 165.558361 -275.1634) (xy 165.528796 -275.202744) (xy 165.493303 -275.236836)
			(xy 165.4528 -275.264792) (xy 165.408338 -275.28589) (xy 165.361067 -275.299582) (xy 165.312212 -275.305514)
			(xy 165.263037 -275.303533) (xy 165.214818 -275.293689) (xy 165.168802 -275.276237) (xy 165.126181 -275.25163)
			(xy 165.08806 -275.220505) (xy 165.055425 -275.183668) (xy 165.029122 -275.142072) (xy 165.009831 -275.096796)
			(xy 164.998054 -275.049012) (xy 164.994094 -274.999958) (xy 163.705286 -274.999958) (xy 163.704791 -275.024565)
			(xy 163.696896 -275.073142) (xy 163.681312 -275.119823) (xy 163.658441 -275.1634) (xy 163.628876 -275.202744)
			(xy 163.593383 -275.236836) (xy 163.55288 -275.264792) (xy 163.508418 -275.28589) (xy 163.461147 -275.299582)
			(xy 163.412292 -275.305514) (xy 163.363117 -275.303533) (xy 163.314898 -275.293689) (xy 163.268882 -275.276237)
			(xy 163.226261 -275.25163) (xy 163.18814 -275.220505) (xy 163.155505 -275.183668) (xy 163.129202 -275.142072)
			(xy 163.109911 -275.096796) (xy 163.098134 -275.049012) (xy 163.094174 -274.999958) (xy 161.805366 -274.999958)
			(xy 161.804871 -275.024565) (xy 161.796976 -275.073142) (xy 161.781392 -275.119823) (xy 161.758521 -275.1634)
			(xy 161.728956 -275.202744) (xy 161.693463 -275.236836) (xy 161.65296 -275.264792) (xy 161.608498 -275.28589)
			(xy 161.561227 -275.299582) (xy 161.512372 -275.305514) (xy 161.463197 -275.303533) (xy 161.414978 -275.293689)
			(xy 161.368962 -275.276237) (xy 161.326341 -275.25163) (xy 161.28822 -275.220505) (xy 161.255585 -275.183668)
			(xy 161.229282 -275.142072) (xy 161.209991 -275.096796) (xy 161.198214 -275.049012) (xy 161.194254 -274.999958)
			(xy 82.755227 -274.999958) (xy 82.754737 -275.024311) (xy 82.746842 -275.072888) (xy 82.731258 -275.119569)
			(xy 82.708387 -275.163146) (xy 82.678822 -275.20249) (xy 82.643329 -275.236582) (xy 82.602826 -275.264538)
			(xy 82.558364 -275.285636) (xy 82.511093 -275.299328) (xy 82.462238 -275.30526) (xy 82.413063 -275.303279)
			(xy 82.364844 -275.293435) (xy 82.318828 -275.275983) (xy 82.276207 -275.251376) (xy 82.238086 -275.220251)
			(xy 82.205451 -275.183414) (xy 82.179148 -275.141818) (xy 82.159857 -275.096542) (xy 82.14808 -275.048758)
			(xy 82.14412 -274.999704) (xy 81.805272 -274.999704) (xy 81.804777 -275.024311) (xy 81.796882 -275.072888)
			(xy 81.781298 -275.119569) (xy 81.758427 -275.163146) (xy 81.728862 -275.20249) (xy 81.693369 -275.236582)
			(xy 81.652866 -275.264538) (xy 81.608404 -275.285636) (xy 81.561133 -275.299328) (xy 81.512278 -275.30526)
			(xy 81.463103 -275.303279) (xy 81.414884 -275.293435) (xy 81.368868 -275.275983) (xy 81.326247 -275.251376)
			(xy 81.288126 -275.220251) (xy 81.255491 -275.183414) (xy 81.229188 -275.141818) (xy 81.209897 -275.096542)
			(xy 81.19812 -275.048758) (xy 81.19416 -274.999704) (xy 79.904839 -274.999704) (xy 79.904844 -274.999958)
			(xy 79.904349 -275.024565) (xy 79.896454 -275.073142) (xy 79.88087 -275.119823) (xy 79.857999 -275.1634)
			(xy 79.828434 -275.202744) (xy 79.792941 -275.236836) (xy 79.752438 -275.264792) (xy 79.707976 -275.28589)
			(xy 79.660705 -275.299582) (xy 79.61185 -275.305514) (xy 79.562675 -275.303533) (xy 79.514456 -275.293689)
			(xy 79.46844 -275.276237) (xy 79.425819 -275.25163) (xy 79.387698 -275.220505) (xy 79.355063 -275.183668)
			(xy 79.32876 -275.142072) (xy 79.309469 -275.096796) (xy 79.297692 -275.049012) (xy 79.293732 -274.999958)
			(xy 78.004924 -274.999958) (xy 78.004429 -275.024565) (xy 77.996534 -275.073142) (xy 77.98095 -275.119823)
			(xy 77.958079 -275.1634) (xy 77.928514 -275.202744) (xy 77.893021 -275.236836) (xy 77.852518 -275.264792)
			(xy 77.808056 -275.28589) (xy 77.760785 -275.299582) (xy 77.71193 -275.305514) (xy 77.662755 -275.303533)
			(xy 77.614536 -275.293689) (xy 77.56852 -275.276237) (xy 77.525899 -275.25163) (xy 77.487778 -275.220505)
			(xy 77.455143 -275.183668) (xy 77.42884 -275.142072) (xy 77.409549 -275.096796) (xy 77.397772 -275.049012)
			(xy 77.393812 -274.999958) (xy 76.104999 -274.999958) (xy 76.104509 -275.024311) (xy 76.096614 -275.072888)
			(xy 76.08103 -275.119569) (xy 76.058159 -275.163146) (xy 76.028594 -275.20249) (xy 75.993101 -275.236582)
			(xy 75.952598 -275.264538) (xy 75.908136 -275.285636) (xy 75.860865 -275.299328) (xy 75.81201 -275.30526)
			(xy 75.762835 -275.303279) (xy 75.714616 -275.293435) (xy 75.6686 -275.275983) (xy 75.625979 -275.251376)
			(xy 75.587858 -275.220251) (xy 75.555223 -275.183414) (xy 75.52892 -275.141818) (xy 75.509629 -275.096542)
			(xy 75.497852 -275.048758) (xy 75.493892 -274.999704) (xy 74.204825 -274.999704) (xy 74.20483 -274.999958)
			(xy 74.204335 -275.024565) (xy 74.19644 -275.073142) (xy 74.180856 -275.119823) (xy 74.157985 -275.1634)
			(xy 74.12842 -275.202744) (xy 74.092927 -275.236836) (xy 74.052424 -275.264792) (xy 74.007962 -275.28589)
			(xy 73.960691 -275.299582) (xy 73.911836 -275.305514) (xy 73.862661 -275.303533) (xy 73.814442 -275.293689)
			(xy 73.768426 -275.276237) (xy 73.725805 -275.25163) (xy 73.687684 -275.220505) (xy 73.655049 -275.183668)
			(xy 73.628746 -275.142072) (xy 73.609455 -275.096796) (xy 73.597678 -275.049012) (xy 73.593718 -274.999958)
			(xy 72.304905 -274.999958) (xy 72.304415 -275.024311) (xy 72.29652 -275.072888) (xy 72.280936 -275.119569)
			(xy 72.258065 -275.163146) (xy 72.2285 -275.20249) (xy 72.193007 -275.236582) (xy 72.152504 -275.264538)
			(xy 72.108042 -275.285636) (xy 72.060771 -275.299328) (xy 72.011916 -275.30526) (xy 71.962741 -275.303279)
			(xy 71.914522 -275.293435) (xy 71.868506 -275.275983) (xy 71.825885 -275.251376) (xy 71.787764 -275.220251)
			(xy 71.755129 -275.183414) (xy 71.728826 -275.141818) (xy 71.709535 -275.096542) (xy 71.697758 -275.048758)
			(xy 71.693798 -274.999704) (xy 70.404731 -274.999704) (xy 70.404736 -274.999958) (xy 70.404241 -275.024565)
			(xy 70.396346 -275.073142) (xy 70.380762 -275.119823) (xy 70.357891 -275.1634) (xy 70.328326 -275.202744)
			(xy 70.292833 -275.236836) (xy 70.25233 -275.264792) (xy 70.207868 -275.28589) (xy 70.160597 -275.299582)
			(xy 70.111742 -275.305514) (xy 70.062567 -275.303533) (xy 70.014348 -275.293689) (xy 69.968332 -275.276237)
			(xy 69.925711 -275.25163) (xy 69.88759 -275.220505) (xy 69.854955 -275.183668) (xy 69.828652 -275.142072)
			(xy 69.809361 -275.096796) (xy 69.797584 -275.049012) (xy 69.793624 -274.999958) (xy 68.504811 -274.999958)
			(xy 68.504321 -275.024311) (xy 68.496426 -275.072888) (xy 68.480842 -275.119569) (xy 68.457971 -275.163146)
			(xy 68.428406 -275.20249) (xy 68.392913 -275.236582) (xy 68.35241 -275.264538) (xy 68.307948 -275.285636)
			(xy 68.260677 -275.299328) (xy 68.211822 -275.30526) (xy 68.162647 -275.303279) (xy 68.114428 -275.293435)
			(xy 68.068412 -275.275983) (xy 68.025791 -275.251376) (xy 67.98767 -275.220251) (xy 67.955035 -275.183414)
			(xy 67.928732 -275.141818) (xy 67.909441 -275.096542) (xy 67.897664 -275.048758) (xy 67.893704 -274.999704)
			(xy 66.604891 -274.999704) (xy 66.604896 -274.999958) (xy 66.604401 -275.024565) (xy 66.596506 -275.073142)
			(xy 66.580922 -275.119823) (xy 66.558051 -275.1634) (xy 66.528486 -275.202744) (xy 66.492993 -275.236836)
			(xy 66.45249 -275.264792) (xy 66.408028 -275.28589) (xy 66.360757 -275.299582) (xy 66.311902 -275.305514)
			(xy 66.262727 -275.303533) (xy 66.214508 -275.293689) (xy 66.168492 -275.276237) (xy 66.125871 -275.25163)
			(xy 66.08775 -275.220505) (xy 66.055115 -275.183668) (xy 66.028812 -275.142072) (xy 66.009521 -275.096796)
			(xy 65.997744 -275.049012) (xy 65.993784 -274.999958) (xy 64.704971 -274.999958) (xy 64.704481 -275.024311)
			(xy 64.696586 -275.072888) (xy 64.681002 -275.119569) (xy 64.658131 -275.163146) (xy 64.628566 -275.20249)
			(xy 64.593073 -275.236582) (xy 64.55257 -275.264538) (xy 64.508108 -275.285636) (xy 64.460837 -275.299328)
			(xy 64.411982 -275.30526) (xy 64.362807 -275.303279) (xy 64.314588 -275.293435) (xy 64.268572 -275.275983)
			(xy 64.225951 -275.251376) (xy 64.18783 -275.220251) (xy 64.155195 -275.183414) (xy 64.128892 -275.141818)
			(xy 64.109601 -275.096542) (xy 64.097824 -275.048758) (xy 64.093864 -274.999704) (xy 62.804797 -274.999704)
			(xy 62.804802 -274.999958) (xy 62.804307 -275.024565) (xy 62.796412 -275.073142) (xy 62.780828 -275.119823)
			(xy 62.757957 -275.1634) (xy 62.728392 -275.202744) (xy 62.692899 -275.236836) (xy 62.652396 -275.264792)
			(xy 62.607934 -275.28589) (xy 62.560663 -275.299582) (xy 62.511808 -275.305514) (xy 62.462633 -275.303533)
			(xy 62.414414 -275.293689) (xy 62.368398 -275.276237) (xy 62.325777 -275.25163) (xy 62.287656 -275.220505)
			(xy 62.255021 -275.183668) (xy 62.228718 -275.142072) (xy 62.209427 -275.096796) (xy 62.19765 -275.049012)
			(xy 62.19369 -274.999958) (xy 60.904877 -274.999958) (xy 60.904387 -275.024311) (xy 60.896492 -275.072888)
			(xy 60.880908 -275.119569) (xy 60.858037 -275.163146) (xy 60.828472 -275.20249) (xy 60.792979 -275.236582)
			(xy 60.752476 -275.264538) (xy 60.708014 -275.285636) (xy 60.660743 -275.299328) (xy 60.611888 -275.30526)
			(xy 60.562713 -275.303279) (xy 60.514494 -275.293435) (xy 60.468478 -275.275983) (xy 60.425857 -275.251376)
			(xy 60.387736 -275.220251) (xy 60.355101 -275.183414) (xy 60.328798 -275.141818) (xy 60.309507 -275.096542)
			(xy 60.29773 -275.048758) (xy 60.29377 -274.999704) (xy 59.005211 -274.999704) (xy 59.005216 -274.999958)
			(xy 59.004721 -275.024565) (xy 58.996826 -275.073142) (xy 58.981242 -275.119823) (xy 58.958371 -275.1634)
			(xy 58.928806 -275.202744) (xy 58.893313 -275.236836) (xy 58.85281 -275.264792) (xy 58.808348 -275.28589)
			(xy 58.761077 -275.299582) (xy 58.712222 -275.305514) (xy 58.663047 -275.303533) (xy 58.614828 -275.293689)
			(xy 58.568812 -275.276237) (xy 58.526191 -275.25163) (xy 58.48807 -275.220505) (xy 58.455435 -275.183668)
			(xy 58.429132 -275.142072) (xy 58.409841 -275.096796) (xy 58.398064 -275.049012) (xy 58.394104 -274.999958)
			(xy 57.105296 -274.999958) (xy 57.104801 -275.024565) (xy 57.096906 -275.073142) (xy 57.081322 -275.119823)
			(xy 57.058451 -275.1634) (xy 57.028886 -275.202744) (xy 56.993393 -275.236836) (xy 56.95289 -275.264792)
			(xy 56.908428 -275.28589) (xy 56.861157 -275.299582) (xy 56.812302 -275.305514) (xy 56.763127 -275.303533)
			(xy 56.714908 -275.293689) (xy 56.668892 -275.276237) (xy 56.626271 -275.25163) (xy 56.58815 -275.220505)
			(xy 56.555515 -275.183668) (xy 56.529212 -275.142072) (xy 56.509921 -275.096796) (xy 56.498144 -275.049012)
			(xy 56.494184 -274.999958) (xy 55.205122 -274.999958) (xy 55.204627 -275.024565) (xy 55.196732 -275.073142)
			(xy 55.181148 -275.119823) (xy 55.158277 -275.1634) (xy 55.128712 -275.202744) (xy 55.093219 -275.236836)
			(xy 55.052716 -275.264792) (xy 55.008254 -275.28589) (xy 54.960983 -275.299582) (xy 54.912128 -275.305514)
			(xy 54.862953 -275.303533) (xy 54.814734 -275.293689) (xy 54.768718 -275.276237) (xy 54.726097 -275.25163)
			(xy 54.687976 -275.220505) (xy 54.655341 -275.183668) (xy 54.629038 -275.142072) (xy 54.609747 -275.096796)
			(xy 54.59797 -275.049012) (xy 54.59401 -274.999958) (xy 53.305202 -274.999958) (xy 53.304707 -275.024565)
			(xy 53.296812 -275.073142) (xy 53.281228 -275.119823) (xy 53.258357 -275.1634) (xy 53.228792 -275.202744)
			(xy 53.193299 -275.236836) (xy 53.152796 -275.264792) (xy 53.108334 -275.28589) (xy 53.061063 -275.299582)
			(xy 53.012208 -275.305514) (xy 52.963033 -275.303533) (xy 52.914814 -275.293689) (xy 52.868798 -275.276237)
			(xy 52.826177 -275.25163) (xy 52.788056 -275.220505) (xy 52.755421 -275.183668) (xy 52.729118 -275.142072)
			(xy 52.709827 -275.096796) (xy 52.69805 -275.049012) (xy 52.69409 -274.999958) (xy 51.405282 -274.999958)
			(xy 51.404787 -275.024565) (xy 51.396892 -275.073142) (xy 51.381308 -275.119823) (xy 51.358437 -275.1634)
			(xy 51.328872 -275.202744) (xy 51.293379 -275.236836) (xy 51.252876 -275.264792) (xy 51.208414 -275.28589)
			(xy 51.161143 -275.299582) (xy 51.112288 -275.305514) (xy 51.063113 -275.303533) (xy 51.014894 -275.293689)
			(xy 50.968878 -275.276237) (xy 50.926257 -275.25163) (xy 50.888136 -275.220505) (xy 50.855501 -275.183668)
			(xy 50.829198 -275.142072) (xy 50.809907 -275.096796) (xy 50.79813 -275.049012) (xy 50.79417 -274.999958)
			(xy 49.505108 -274.999958) (xy 49.504613 -275.024565) (xy 49.496718 -275.073142) (xy 49.481134 -275.119823)
			(xy 49.458263 -275.1634) (xy 49.428698 -275.202744) (xy 49.393205 -275.236836) (xy 49.352702 -275.264792)
			(xy 49.30824 -275.28589) (xy 49.260969 -275.299582) (xy 49.212114 -275.305514) (xy 49.162939 -275.303533)
			(xy 49.11472 -275.293689) (xy 49.068704 -275.276237) (xy 49.026083 -275.25163) (xy 48.987962 -275.220505)
			(xy 48.955327 -275.183668) (xy 48.929024 -275.142072) (xy 48.909733 -275.096796) (xy 48.897956 -275.049012)
			(xy 48.893996 -274.999958) (xy 47.605188 -274.999958) (xy 47.604693 -275.024565) (xy 47.596798 -275.073142)
			(xy 47.581214 -275.119823) (xy 47.558343 -275.1634) (xy 47.528778 -275.202744) (xy 47.493285 -275.236836)
			(xy 47.452782 -275.264792) (xy 47.40832 -275.28589) (xy 47.361049 -275.299582) (xy 47.312194 -275.305514)
			(xy 47.263019 -275.303533) (xy 47.2148 -275.293689) (xy 47.168784 -275.276237) (xy 47.126163 -275.25163)
			(xy 47.088042 -275.220505) (xy 47.055407 -275.183668) (xy 47.029104 -275.142072) (xy 47.009813 -275.096796)
			(xy 46.998036 -275.049012) (xy 46.994076 -274.999958) (xy 45.705268 -274.999958) (xy 45.704773 -275.024565)
			(xy 45.696878 -275.073142) (xy 45.681294 -275.119823) (xy 45.658423 -275.1634) (xy 45.628858 -275.202744)
			(xy 45.593365 -275.236836) (xy 45.552862 -275.264792) (xy 45.5084 -275.28589) (xy 45.461129 -275.299582)
			(xy 45.412274 -275.305514) (xy 45.363099 -275.303533) (xy 45.31488 -275.293689) (xy 45.268864 -275.276237)
			(xy 45.226243 -275.25163) (xy 45.188122 -275.220505) (xy 45.155487 -275.183668) (xy 45.129184 -275.142072)
			(xy 45.109893 -275.096796) (xy 45.098116 -275.049012) (xy 45.094156 -274.999958) (xy 0.508 -274.999958)
			(xy 0.508 -275.949918) (xy 45.094156 -275.949918) (xy 45.098116 -275.900864) (xy 45.109893 -275.85308)
			(xy 45.129184 -275.807804) (xy 45.155487 -275.766208) (xy 45.188122 -275.729371) (xy 45.226243 -275.698246)
			(xy 45.268864 -275.673639) (xy 45.31488 -275.656187) (xy 45.363099 -275.646343) (xy 45.412274 -275.644362)
			(xy 45.461129 -275.650294) (xy 45.5084 -275.663986) (xy 45.552862 -275.685084) (xy 45.593365 -275.71304)
			(xy 45.628858 -275.747132) (xy 45.658423 -275.786476) (xy 45.681294 -275.830053) (xy 45.696878 -275.876734)
			(xy 45.704773 -275.925311) (xy 45.705268 -275.949918) (xy 46.994076 -275.949918) (xy 46.998036 -275.900864)
			(xy 47.009813 -275.85308) (xy 47.029104 -275.807804) (xy 47.055407 -275.766208) (xy 47.088042 -275.729371)
			(xy 47.126163 -275.698246) (xy 47.168784 -275.673639) (xy 47.2148 -275.656187) (xy 47.263019 -275.646343)
			(xy 47.312194 -275.644362) (xy 47.361049 -275.650294) (xy 47.40832 -275.663986) (xy 47.452782 -275.685084)
			(xy 47.493285 -275.71304) (xy 47.528778 -275.747132) (xy 47.558343 -275.786476) (xy 47.581214 -275.830053)
			(xy 47.596798 -275.876734) (xy 47.604693 -275.925311) (xy 47.605188 -275.949918) (xy 48.893996 -275.949918)
			(xy 48.897956 -275.900864) (xy 48.909733 -275.85308) (xy 48.929024 -275.807804) (xy 48.955327 -275.766208)
			(xy 48.987962 -275.729371) (xy 49.026083 -275.698246) (xy 49.068704 -275.673639) (xy 49.11472 -275.656187)
			(xy 49.162939 -275.646343) (xy 49.212114 -275.644362) (xy 49.260969 -275.650294) (xy 49.30824 -275.663986)
			(xy 49.352702 -275.685084) (xy 49.393205 -275.71304) (xy 49.428698 -275.747132) (xy 49.458263 -275.786476)
			(xy 49.481134 -275.830053) (xy 49.496718 -275.876734) (xy 49.504613 -275.925311) (xy 49.505108 -275.949918)
			(xy 50.79417 -275.949918) (xy 50.79813 -275.900864) (xy 50.809907 -275.85308) (xy 50.829198 -275.807804)
			(xy 50.855501 -275.766208) (xy 50.888136 -275.729371) (xy 50.926257 -275.698246) (xy 50.968878 -275.673639)
			(xy 51.014894 -275.656187) (xy 51.063113 -275.646343) (xy 51.112288 -275.644362) (xy 51.161143 -275.650294)
			(xy 51.208414 -275.663986) (xy 51.252876 -275.685084) (xy 51.293379 -275.71304) (xy 51.328872 -275.747132)
			(xy 51.358437 -275.786476) (xy 51.381308 -275.830053) (xy 51.396892 -275.876734) (xy 51.404787 -275.925311)
			(xy 51.405282 -275.949918) (xy 52.69409 -275.949918) (xy 52.69805 -275.900864) (xy 52.709827 -275.85308)
			(xy 52.729118 -275.807804) (xy 52.755421 -275.766208) (xy 52.788056 -275.729371) (xy 52.826177 -275.698246)
			(xy 52.868798 -275.673639) (xy 52.914814 -275.656187) (xy 52.963033 -275.646343) (xy 53.012208 -275.644362)
			(xy 53.061063 -275.650294) (xy 53.108334 -275.663986) (xy 53.152796 -275.685084) (xy 53.193299 -275.71304)
			(xy 53.228792 -275.747132) (xy 53.258357 -275.786476) (xy 53.281228 -275.830053) (xy 53.296812 -275.876734)
			(xy 53.304707 -275.925311) (xy 53.305202 -275.949918) (xy 54.59401 -275.949918) (xy 54.59797 -275.900864)
			(xy 54.609747 -275.85308) (xy 54.629038 -275.807804) (xy 54.655341 -275.766208) (xy 54.687976 -275.729371)
			(xy 54.726097 -275.698246) (xy 54.768718 -275.673639) (xy 54.814734 -275.656187) (xy 54.862953 -275.646343)
			(xy 54.912128 -275.644362) (xy 54.960983 -275.650294) (xy 55.008254 -275.663986) (xy 55.052716 -275.685084)
			(xy 55.093219 -275.71304) (xy 55.128712 -275.747132) (xy 55.158277 -275.786476) (xy 55.181148 -275.830053)
			(xy 55.196732 -275.876734) (xy 55.204627 -275.925311) (xy 55.205122 -275.949918) (xy 56.494184 -275.949918)
			(xy 56.498144 -275.900864) (xy 56.509921 -275.85308) (xy 56.529212 -275.807804) (xy 56.555515 -275.766208)
			(xy 56.58815 -275.729371) (xy 56.626271 -275.698246) (xy 56.668892 -275.673639) (xy 56.714908 -275.656187)
			(xy 56.763127 -275.646343) (xy 56.812302 -275.644362) (xy 56.861157 -275.650294) (xy 56.908428 -275.663986)
			(xy 56.95289 -275.685084) (xy 56.993393 -275.71304) (xy 57.028886 -275.747132) (xy 57.058451 -275.786476)
			(xy 57.081322 -275.830053) (xy 57.096906 -275.876734) (xy 57.104801 -275.925311) (xy 57.105296 -275.949918)
			(xy 58.394104 -275.949918) (xy 58.398064 -275.900864) (xy 58.409841 -275.85308) (xy 58.429132 -275.807804)
			(xy 58.455435 -275.766208) (xy 58.48807 -275.729371) (xy 58.526191 -275.698246) (xy 58.568812 -275.673639)
			(xy 58.614828 -275.656187) (xy 58.663047 -275.646343) (xy 58.712222 -275.644362) (xy 58.761077 -275.650294)
			(xy 58.808348 -275.663986) (xy 58.85281 -275.685084) (xy 58.893313 -275.71304) (xy 58.928806 -275.747132)
			(xy 58.958371 -275.786476) (xy 58.981242 -275.830053) (xy 58.996826 -275.876734) (xy 59.004721 -275.925311)
			(xy 59.005211 -275.949664) (xy 60.29377 -275.949664) (xy 60.29773 -275.90061) (xy 60.309507 -275.852826)
			(xy 60.328798 -275.80755) (xy 60.355101 -275.765954) (xy 60.387736 -275.729117) (xy 60.425857 -275.697992)
			(xy 60.468478 -275.673385) (xy 60.514494 -275.655933) (xy 60.562713 -275.646089) (xy 60.611888 -275.644108)
			(xy 60.660743 -275.65004) (xy 60.708014 -275.663732) (xy 60.752476 -275.68483) (xy 60.792979 -275.712786)
			(xy 60.828472 -275.746878) (xy 60.858037 -275.786222) (xy 60.880908 -275.829799) (xy 60.896492 -275.87648)
			(xy 60.904387 -275.925057) (xy 60.904882 -275.949664) (xy 60.904877 -275.949918) (xy 62.19369 -275.949918)
			(xy 62.19765 -275.900864) (xy 62.209427 -275.85308) (xy 62.228718 -275.807804) (xy 62.255021 -275.766208)
			(xy 62.287656 -275.729371) (xy 62.325777 -275.698246) (xy 62.368398 -275.673639) (xy 62.414414 -275.656187)
			(xy 62.462633 -275.646343) (xy 62.511808 -275.644362) (xy 62.560663 -275.650294) (xy 62.607934 -275.663986)
			(xy 62.652396 -275.685084) (xy 62.692899 -275.71304) (xy 62.728392 -275.747132) (xy 62.757957 -275.786476)
			(xy 62.780828 -275.830053) (xy 62.796412 -275.876734) (xy 62.804307 -275.925311) (xy 62.804797 -275.949664)
			(xy 64.093864 -275.949664) (xy 64.097824 -275.90061) (xy 64.109601 -275.852826) (xy 64.128892 -275.80755)
			(xy 64.155195 -275.765954) (xy 64.18783 -275.729117) (xy 64.225951 -275.697992) (xy 64.268572 -275.673385)
			(xy 64.314588 -275.655933) (xy 64.362807 -275.646089) (xy 64.411982 -275.644108) (xy 64.460837 -275.65004)
			(xy 64.508108 -275.663732) (xy 64.55257 -275.68483) (xy 64.593073 -275.712786) (xy 64.628566 -275.746878)
			(xy 64.658131 -275.786222) (xy 64.681002 -275.829799) (xy 64.696586 -275.87648) (xy 64.704481 -275.925057)
			(xy 64.704976 -275.949664) (xy 64.704971 -275.949918) (xy 65.993784 -275.949918) (xy 65.997744 -275.900864)
			(xy 66.009521 -275.85308) (xy 66.028812 -275.807804) (xy 66.055115 -275.766208) (xy 66.08775 -275.729371)
			(xy 66.125871 -275.698246) (xy 66.168492 -275.673639) (xy 66.214508 -275.656187) (xy 66.262727 -275.646343)
			(xy 66.311902 -275.644362) (xy 66.360757 -275.650294) (xy 66.408028 -275.663986) (xy 66.45249 -275.685084)
			(xy 66.492993 -275.71304) (xy 66.528486 -275.747132) (xy 66.558051 -275.786476) (xy 66.580922 -275.830053)
			(xy 66.596506 -275.876734) (xy 66.604401 -275.925311) (xy 66.604891 -275.949664) (xy 67.893704 -275.949664)
			(xy 67.897664 -275.90061) (xy 67.909441 -275.852826) (xy 67.928732 -275.80755) (xy 67.955035 -275.765954)
			(xy 67.98767 -275.729117) (xy 68.025791 -275.697992) (xy 68.068412 -275.673385) (xy 68.114428 -275.655933)
			(xy 68.162647 -275.646089) (xy 68.211822 -275.644108) (xy 68.260677 -275.65004) (xy 68.307948 -275.663732)
			(xy 68.35241 -275.68483) (xy 68.392913 -275.712786) (xy 68.428406 -275.746878) (xy 68.457971 -275.786222)
			(xy 68.480842 -275.829799) (xy 68.496426 -275.87648) (xy 68.504321 -275.925057) (xy 68.504816 -275.949664)
			(xy 68.504811 -275.949918) (xy 69.793624 -275.949918) (xy 69.797584 -275.900864) (xy 69.809361 -275.85308)
			(xy 69.828652 -275.807804) (xy 69.854955 -275.766208) (xy 69.88759 -275.729371) (xy 69.925711 -275.698246)
			(xy 69.968332 -275.673639) (xy 70.014348 -275.656187) (xy 70.062567 -275.646343) (xy 70.111742 -275.644362)
			(xy 70.160597 -275.650294) (xy 70.207868 -275.663986) (xy 70.25233 -275.685084) (xy 70.292833 -275.71304)
			(xy 70.328326 -275.747132) (xy 70.357891 -275.786476) (xy 70.380762 -275.830053) (xy 70.396346 -275.876734)
			(xy 70.404241 -275.925311) (xy 70.404731 -275.949664) (xy 71.693798 -275.949664) (xy 71.697758 -275.90061)
			(xy 71.709535 -275.852826) (xy 71.728826 -275.80755) (xy 71.755129 -275.765954) (xy 71.787764 -275.729117)
			(xy 71.825885 -275.697992) (xy 71.868506 -275.673385) (xy 71.914522 -275.655933) (xy 71.962741 -275.646089)
			(xy 72.011916 -275.644108) (xy 72.060771 -275.65004) (xy 72.108042 -275.663732) (xy 72.152504 -275.68483)
			(xy 72.193007 -275.712786) (xy 72.2285 -275.746878) (xy 72.258065 -275.786222) (xy 72.280936 -275.829799)
			(xy 72.29652 -275.87648) (xy 72.304415 -275.925057) (xy 72.30491 -275.949664) (xy 72.304905 -275.949918)
			(xy 73.593718 -275.949918) (xy 73.597678 -275.900864) (xy 73.609455 -275.85308) (xy 73.628746 -275.807804)
			(xy 73.655049 -275.766208) (xy 73.687684 -275.729371) (xy 73.725805 -275.698246) (xy 73.768426 -275.673639)
			(xy 73.814442 -275.656187) (xy 73.862661 -275.646343) (xy 73.911836 -275.644362) (xy 73.960691 -275.650294)
			(xy 74.007962 -275.663986) (xy 74.052424 -275.685084) (xy 74.092927 -275.71304) (xy 74.12842 -275.747132)
			(xy 74.157985 -275.786476) (xy 74.180856 -275.830053) (xy 74.19644 -275.876734) (xy 74.204335 -275.925311)
			(xy 74.204825 -275.949664) (xy 75.493892 -275.949664) (xy 75.497852 -275.90061) (xy 75.509629 -275.852826)
			(xy 75.52892 -275.80755) (xy 75.555223 -275.765954) (xy 75.587858 -275.729117) (xy 75.625979 -275.697992)
			(xy 75.6686 -275.673385) (xy 75.714616 -275.655933) (xy 75.762835 -275.646089) (xy 75.81201 -275.644108)
			(xy 75.860865 -275.65004) (xy 75.908136 -275.663732) (xy 75.952598 -275.68483) (xy 75.993101 -275.712786)
			(xy 76.028594 -275.746878) (xy 76.058159 -275.786222) (xy 76.08103 -275.829799) (xy 76.096614 -275.87648)
			(xy 76.104509 -275.925057) (xy 76.105004 -275.949664) (xy 76.104999 -275.949918) (xy 77.393812 -275.949918)
			(xy 77.397772 -275.900864) (xy 77.409549 -275.85308) (xy 77.42884 -275.807804) (xy 77.455143 -275.766208)
			(xy 77.487778 -275.729371) (xy 77.525899 -275.698246) (xy 77.56852 -275.673639) (xy 77.614536 -275.656187)
			(xy 77.662755 -275.646343) (xy 77.71193 -275.644362) (xy 77.760785 -275.650294) (xy 77.808056 -275.663986)
			(xy 77.852518 -275.685084) (xy 77.893021 -275.71304) (xy 77.928514 -275.747132) (xy 77.958079 -275.786476)
			(xy 77.98095 -275.830053) (xy 77.996534 -275.876734) (xy 78.004429 -275.925311) (xy 78.004924 -275.949918)
			(xy 79.293732 -275.949918) (xy 79.297692 -275.900864) (xy 79.309469 -275.85308) (xy 79.32876 -275.807804)
			(xy 79.355063 -275.766208) (xy 79.387698 -275.729371) (xy 79.425819 -275.698246) (xy 79.46844 -275.673639)
			(xy 79.514456 -275.656187) (xy 79.562675 -275.646343) (xy 79.61185 -275.644362) (xy 79.660705 -275.650294)
			(xy 79.707976 -275.663986) (xy 79.752438 -275.685084) (xy 79.792941 -275.71304) (xy 79.828434 -275.747132)
			(xy 79.857999 -275.786476) (xy 79.88087 -275.830053) (xy 79.896454 -275.876734) (xy 79.904349 -275.925311)
			(xy 79.904844 -275.949918) (xy 161.194254 -275.949918) (xy 161.198214 -275.900864) (xy 161.209991 -275.85308)
			(xy 161.229282 -275.807804) (xy 161.255585 -275.766208) (xy 161.28822 -275.729371) (xy 161.326341 -275.698246)
			(xy 161.368962 -275.673639) (xy 161.414978 -275.656187) (xy 161.463197 -275.646343) (xy 161.512372 -275.644362)
			(xy 161.561227 -275.650294) (xy 161.608498 -275.663986) (xy 161.65296 -275.685084) (xy 161.693463 -275.71304)
			(xy 161.728956 -275.747132) (xy 161.758521 -275.786476) (xy 161.781392 -275.830053) (xy 161.796976 -275.876734)
			(xy 161.804871 -275.925311) (xy 161.805366 -275.949918) (xy 163.094174 -275.949918) (xy 163.098134 -275.900864)
			(xy 163.109911 -275.85308) (xy 163.129202 -275.807804) (xy 163.155505 -275.766208) (xy 163.18814 -275.729371)
			(xy 163.226261 -275.698246) (xy 163.268882 -275.673639) (xy 163.314898 -275.656187) (xy 163.363117 -275.646343)
			(xy 163.412292 -275.644362) (xy 163.461147 -275.650294) (xy 163.508418 -275.663986) (xy 163.55288 -275.685084)
			(xy 163.593383 -275.71304) (xy 163.628876 -275.747132) (xy 163.658441 -275.786476) (xy 163.681312 -275.830053)
			(xy 163.696896 -275.876734) (xy 163.704791 -275.925311) (xy 163.705286 -275.949918) (xy 164.994094 -275.949918)
			(xy 164.998054 -275.900864) (xy 165.009831 -275.85308) (xy 165.029122 -275.807804) (xy 165.055425 -275.766208)
			(xy 165.08806 -275.729371) (xy 165.126181 -275.698246) (xy 165.168802 -275.673639) (xy 165.214818 -275.656187)
			(xy 165.263037 -275.646343) (xy 165.312212 -275.644362) (xy 165.361067 -275.650294) (xy 165.408338 -275.663986)
			(xy 165.4528 -275.685084) (xy 165.493303 -275.71304) (xy 165.528796 -275.747132) (xy 165.558361 -275.786476)
			(xy 165.581232 -275.830053) (xy 165.596816 -275.876734) (xy 165.604711 -275.925311) (xy 165.605206 -275.949918)
			(xy 166.894268 -275.949918) (xy 166.898228 -275.900864) (xy 166.910005 -275.85308) (xy 166.929296 -275.807804)
			(xy 166.955599 -275.766208) (xy 166.988234 -275.729371) (xy 167.026355 -275.698246) (xy 167.068976 -275.673639)
			(xy 167.114992 -275.656187) (xy 167.163211 -275.646343) (xy 167.212386 -275.644362) (xy 167.261241 -275.650294)
			(xy 167.308512 -275.663986) (xy 167.352974 -275.685084) (xy 167.393477 -275.71304) (xy 167.42897 -275.747132)
			(xy 167.458535 -275.786476) (xy 167.481406 -275.830053) (xy 167.49699 -275.876734) (xy 167.504885 -275.925311)
			(xy 167.50538 -275.949918) (xy 168.794188 -275.949918) (xy 168.798148 -275.900864) (xy 168.809925 -275.85308)
			(xy 168.829216 -275.807804) (xy 168.855519 -275.766208) (xy 168.888154 -275.729371) (xy 168.926275 -275.698246)
			(xy 168.968896 -275.673639) (xy 169.014912 -275.656187) (xy 169.063131 -275.646343) (xy 169.112306 -275.644362)
			(xy 169.161161 -275.650294) (xy 169.208432 -275.663986) (xy 169.252894 -275.685084) (xy 169.293397 -275.71304)
			(xy 169.32889 -275.747132) (xy 169.358455 -275.786476) (xy 169.381326 -275.830053) (xy 169.39691 -275.876734)
			(xy 169.404805 -275.925311) (xy 169.4053 -275.949918) (xy 170.694108 -275.949918) (xy 170.698068 -275.900864)
			(xy 170.709845 -275.85308) (xy 170.729136 -275.807804) (xy 170.755439 -275.766208) (xy 170.788074 -275.729371)
			(xy 170.826195 -275.698246) (xy 170.868816 -275.673639) (xy 170.914832 -275.656187) (xy 170.963051 -275.646343)
			(xy 171.012226 -275.644362) (xy 171.061081 -275.650294) (xy 171.108352 -275.663986) (xy 171.152814 -275.685084)
			(xy 171.193317 -275.71304) (xy 171.22881 -275.747132) (xy 171.258375 -275.786476) (xy 171.281246 -275.830053)
			(xy 171.29683 -275.876734) (xy 171.304725 -275.925311) (xy 171.30522 -275.949918) (xy 172.594282 -275.949918)
			(xy 172.598242 -275.900864) (xy 172.610019 -275.85308) (xy 172.62931 -275.807804) (xy 172.655613 -275.766208)
			(xy 172.688248 -275.729371) (xy 172.726369 -275.698246) (xy 172.76899 -275.673639) (xy 172.815006 -275.656187)
			(xy 172.863225 -275.646343) (xy 172.9124 -275.644362) (xy 172.961255 -275.650294) (xy 173.008526 -275.663986)
			(xy 173.052988 -275.685084) (xy 173.093491 -275.71304) (xy 173.128984 -275.747132) (xy 173.158549 -275.786476)
			(xy 173.18142 -275.830053) (xy 173.197004 -275.876734) (xy 173.204899 -275.925311) (xy 173.205394 -275.949918)
			(xy 174.494202 -275.949918) (xy 174.498162 -275.900864) (xy 174.509939 -275.85308) (xy 174.52923 -275.807804)
			(xy 174.555533 -275.766208) (xy 174.588168 -275.729371) (xy 174.626289 -275.698246) (xy 174.66891 -275.673639)
			(xy 174.714926 -275.656187) (xy 174.763145 -275.646343) (xy 174.81232 -275.644362) (xy 174.861175 -275.650294)
			(xy 174.908446 -275.663986) (xy 174.952908 -275.685084) (xy 174.993411 -275.71304) (xy 175.028904 -275.747132)
			(xy 175.058469 -275.786476) (xy 175.08134 -275.830053) (xy 175.096924 -275.876734) (xy 175.104819 -275.925311)
			(xy 175.105309 -275.949664) (xy 176.393868 -275.949664) (xy 176.397828 -275.90061) (xy 176.409605 -275.852826)
			(xy 176.428896 -275.80755) (xy 176.455199 -275.765954) (xy 176.487834 -275.729117) (xy 176.525955 -275.697992)
			(xy 176.568576 -275.673385) (xy 176.614592 -275.655933) (xy 176.662811 -275.646089) (xy 176.711986 -275.644108)
			(xy 176.760841 -275.65004) (xy 176.808112 -275.663732) (xy 176.852574 -275.68483) (xy 176.893077 -275.712786)
			(xy 176.92857 -275.746878) (xy 176.958135 -275.786222) (xy 176.981006 -275.829799) (xy 176.99659 -275.87648)
			(xy 177.004485 -275.925057) (xy 177.00498 -275.949664) (xy 177.004975 -275.949918) (xy 178.293788 -275.949918)
			(xy 178.297748 -275.900864) (xy 178.309525 -275.85308) (xy 178.328816 -275.807804) (xy 178.355119 -275.766208)
			(xy 178.387754 -275.729371) (xy 178.425875 -275.698246) (xy 178.468496 -275.673639) (xy 178.514512 -275.656187)
			(xy 178.562731 -275.646343) (xy 178.611906 -275.644362) (xy 178.660761 -275.650294) (xy 178.708032 -275.663986)
			(xy 178.752494 -275.685084) (xy 178.792997 -275.71304) (xy 178.82849 -275.747132) (xy 178.858055 -275.786476)
			(xy 178.880926 -275.830053) (xy 178.89651 -275.876734) (xy 178.904405 -275.925311) (xy 178.904895 -275.949664)
			(xy 180.193962 -275.949664) (xy 180.197922 -275.90061) (xy 180.209699 -275.852826) (xy 180.22899 -275.80755)
			(xy 180.255293 -275.765954) (xy 180.287928 -275.729117) (xy 180.326049 -275.697992) (xy 180.36867 -275.673385)
			(xy 180.414686 -275.655933) (xy 180.462905 -275.646089) (xy 180.51208 -275.644108) (xy 180.560935 -275.65004)
			(xy 180.608206 -275.663732) (xy 180.652668 -275.68483) (xy 180.693171 -275.712786) (xy 180.728664 -275.746878)
			(xy 180.758229 -275.786222) (xy 180.7811 -275.829799) (xy 180.796684 -275.87648) (xy 180.804579 -275.925057)
			(xy 180.805074 -275.949664) (xy 180.805069 -275.949918) (xy 182.093882 -275.949918) (xy 182.097842 -275.900864)
			(xy 182.109619 -275.85308) (xy 182.12891 -275.807804) (xy 182.155213 -275.766208) (xy 182.187848 -275.729371)
			(xy 182.225969 -275.698246) (xy 182.26859 -275.673639) (xy 182.314606 -275.656187) (xy 182.362825 -275.646343)
			(xy 182.412 -275.644362) (xy 182.460855 -275.650294) (xy 182.508126 -275.663986) (xy 182.552588 -275.685084)
			(xy 182.593091 -275.71304) (xy 182.628584 -275.747132) (xy 182.658149 -275.786476) (xy 182.68102 -275.830053)
			(xy 182.696604 -275.876734) (xy 182.704499 -275.925311) (xy 182.704989 -275.949664) (xy 183.993802 -275.949664)
			(xy 183.997762 -275.90061) (xy 184.009539 -275.852826) (xy 184.02883 -275.80755) (xy 184.055133 -275.765954)
			(xy 184.087768 -275.729117) (xy 184.125889 -275.697992) (xy 184.16851 -275.673385) (xy 184.214526 -275.655933)
			(xy 184.262745 -275.646089) (xy 184.31192 -275.644108) (xy 184.360775 -275.65004) (xy 184.408046 -275.663732)
			(xy 184.452508 -275.68483) (xy 184.493011 -275.712786) (xy 184.528504 -275.746878) (xy 184.558069 -275.786222)
			(xy 184.58094 -275.829799) (xy 184.596524 -275.87648) (xy 184.604419 -275.925057) (xy 184.604914 -275.949664)
			(xy 184.604909 -275.949918) (xy 185.893722 -275.949918) (xy 185.897682 -275.900864) (xy 185.909459 -275.85308)
			(xy 185.92875 -275.807804) (xy 185.955053 -275.766208) (xy 185.987688 -275.729371) (xy 186.025809 -275.698246)
			(xy 186.06843 -275.673639) (xy 186.114446 -275.656187) (xy 186.162665 -275.646343) (xy 186.21184 -275.644362)
			(xy 186.260695 -275.650294) (xy 186.307966 -275.663986) (xy 186.352428 -275.685084) (xy 186.392931 -275.71304)
			(xy 186.428424 -275.747132) (xy 186.457989 -275.786476) (xy 186.48086 -275.830053) (xy 186.496444 -275.876734)
			(xy 186.504339 -275.925311) (xy 186.504829 -275.949664) (xy 187.793896 -275.949664) (xy 187.797856 -275.90061)
			(xy 187.809633 -275.852826) (xy 187.828924 -275.80755) (xy 187.855227 -275.765954) (xy 187.887862 -275.729117)
			(xy 187.925983 -275.697992) (xy 187.968604 -275.673385) (xy 188.01462 -275.655933) (xy 188.062839 -275.646089)
			(xy 188.112014 -275.644108) (xy 188.160869 -275.65004) (xy 188.20814 -275.663732) (xy 188.252602 -275.68483)
			(xy 188.293105 -275.712786) (xy 188.328598 -275.746878) (xy 188.358163 -275.786222) (xy 188.381034 -275.829799)
			(xy 188.396618 -275.87648) (xy 188.404513 -275.925057) (xy 188.405008 -275.949664) (xy 188.405003 -275.949918)
			(xy 189.693816 -275.949918) (xy 189.697776 -275.900864) (xy 189.709553 -275.85308) (xy 189.728844 -275.807804)
			(xy 189.755147 -275.766208) (xy 189.787782 -275.729371) (xy 189.825903 -275.698246) (xy 189.868524 -275.673639)
			(xy 189.91454 -275.656187) (xy 189.962759 -275.646343) (xy 190.011934 -275.644362) (xy 190.060789 -275.650294)
			(xy 190.10806 -275.663986) (xy 190.152522 -275.685084) (xy 190.193025 -275.71304) (xy 190.228518 -275.747132)
			(xy 190.258083 -275.786476) (xy 190.280954 -275.830053) (xy 190.296538 -275.876734) (xy 190.304433 -275.925311)
			(xy 190.304923 -275.949664) (xy 191.59399 -275.949664) (xy 191.59795 -275.90061) (xy 191.609727 -275.852826)
			(xy 191.629018 -275.80755) (xy 191.655321 -275.765954) (xy 191.687956 -275.729117) (xy 191.726077 -275.697992)
			(xy 191.768698 -275.673385) (xy 191.814714 -275.655933) (xy 191.862933 -275.646089) (xy 191.912108 -275.644108)
			(xy 191.960963 -275.65004) (xy 192.008234 -275.663732) (xy 192.052696 -275.68483) (xy 192.093199 -275.712786)
			(xy 192.128692 -275.746878) (xy 192.158257 -275.786222) (xy 192.181128 -275.829799) (xy 192.196712 -275.87648)
			(xy 192.204607 -275.925057) (xy 192.205102 -275.949664) (xy 192.205097 -275.949918) (xy 193.49391 -275.949918)
			(xy 193.49787 -275.900864) (xy 193.509647 -275.85308) (xy 193.528938 -275.807804) (xy 193.555241 -275.766208)
			(xy 193.587876 -275.729371) (xy 193.625997 -275.698246) (xy 193.668618 -275.673639) (xy 193.714634 -275.656187)
			(xy 193.762853 -275.646343) (xy 193.812028 -275.644362) (xy 193.860883 -275.650294) (xy 193.908154 -275.663986)
			(xy 193.952616 -275.685084) (xy 193.993119 -275.71304) (xy 194.028612 -275.747132) (xy 194.058177 -275.786476)
			(xy 194.081048 -275.830053) (xy 194.096632 -275.876734) (xy 194.104527 -275.925311) (xy 194.105022 -275.949918)
			(xy 195.39383 -275.949918) (xy 195.39779 -275.900864) (xy 195.409567 -275.85308) (xy 195.428858 -275.807804)
			(xy 195.455161 -275.766208) (xy 195.487796 -275.729371) (xy 195.525917 -275.698246) (xy 195.568538 -275.673639)
			(xy 195.614554 -275.656187) (xy 195.662773 -275.646343) (xy 195.711948 -275.644362) (xy 195.760803 -275.650294)
			(xy 195.808074 -275.663986) (xy 195.852536 -275.685084) (xy 195.893039 -275.71304) (xy 195.928532 -275.747132)
			(xy 195.958097 -275.786476) (xy 195.980968 -275.830053) (xy 195.996552 -275.876734) (xy 196.004447 -275.925311)
			(xy 196.004942 -275.949918) (xy 277.294098 -275.949918) (xy 277.298058 -275.900864) (xy 277.309835 -275.85308)
			(xy 277.329126 -275.807804) (xy 277.355429 -275.766208) (xy 277.388064 -275.729371) (xy 277.426185 -275.698246)
			(xy 277.468806 -275.673639) (xy 277.514822 -275.656187) (xy 277.563041 -275.646343) (xy 277.612216 -275.644362)
			(xy 277.661071 -275.650294) (xy 277.708342 -275.663986) (xy 277.752804 -275.685084) (xy 277.793307 -275.71304)
			(xy 277.8288 -275.747132) (xy 277.858365 -275.786476) (xy 277.881236 -275.830053) (xy 277.89682 -275.876734)
			(xy 277.904715 -275.925311) (xy 277.90521 -275.949918) (xy 279.194018 -275.949918) (xy 279.197978 -275.900864)
			(xy 279.209755 -275.85308) (xy 279.229046 -275.807804) (xy 279.255349 -275.766208) (xy 279.287984 -275.729371)
			(xy 279.326105 -275.698246) (xy 279.368726 -275.673639) (xy 279.414742 -275.656187) (xy 279.462961 -275.646343)
			(xy 279.512136 -275.644362) (xy 279.560991 -275.650294) (xy 279.608262 -275.663986) (xy 279.652724 -275.685084)
			(xy 279.693227 -275.71304) (xy 279.72872 -275.747132) (xy 279.758285 -275.786476) (xy 279.781156 -275.830053)
			(xy 279.79674 -275.876734) (xy 279.804635 -275.925311) (xy 279.80513 -275.949918) (xy 281.093938 -275.949918)
			(xy 281.097898 -275.900864) (xy 281.109675 -275.85308) (xy 281.128966 -275.807804) (xy 281.155269 -275.766208)
			(xy 281.187904 -275.729371) (xy 281.226025 -275.698246) (xy 281.268646 -275.673639) (xy 281.314662 -275.656187)
			(xy 281.362881 -275.646343) (xy 281.412056 -275.644362) (xy 281.460911 -275.650294) (xy 281.508182 -275.663986)
			(xy 281.552644 -275.685084) (xy 281.593147 -275.71304) (xy 281.62864 -275.747132) (xy 281.658205 -275.786476)
			(xy 281.681076 -275.830053) (xy 281.69666 -275.876734) (xy 281.704555 -275.925311) (xy 281.70505 -275.949918)
			(xy 282.994112 -275.949918) (xy 282.998072 -275.900864) (xy 283.009849 -275.85308) (xy 283.02914 -275.807804)
			(xy 283.055443 -275.766208) (xy 283.088078 -275.729371) (xy 283.126199 -275.698246) (xy 283.16882 -275.673639)
			(xy 283.214836 -275.656187) (xy 283.263055 -275.646343) (xy 283.31223 -275.644362) (xy 283.361085 -275.650294)
			(xy 283.408356 -275.663986) (xy 283.452818 -275.685084) (xy 283.493321 -275.71304) (xy 283.528814 -275.747132)
			(xy 283.558379 -275.786476) (xy 283.58125 -275.830053) (xy 283.596834 -275.876734) (xy 283.604729 -275.925311)
			(xy 283.605224 -275.949918) (xy 284.894032 -275.949918) (xy 284.897992 -275.900864) (xy 284.909769 -275.85308)
			(xy 284.92906 -275.807804) (xy 284.955363 -275.766208) (xy 284.987998 -275.729371) (xy 285.026119 -275.698246)
			(xy 285.06874 -275.673639) (xy 285.114756 -275.656187) (xy 285.162975 -275.646343) (xy 285.21215 -275.644362)
			(xy 285.261005 -275.650294) (xy 285.308276 -275.663986) (xy 285.352738 -275.685084) (xy 285.393241 -275.71304)
			(xy 285.428734 -275.747132) (xy 285.458299 -275.786476) (xy 285.48117 -275.830053) (xy 285.496754 -275.876734)
			(xy 285.504649 -275.925311) (xy 285.505144 -275.949918) (xy 286.793952 -275.949918) (xy 286.797912 -275.900864)
			(xy 286.809689 -275.85308) (xy 286.82898 -275.807804) (xy 286.855283 -275.766208) (xy 286.887918 -275.729371)
			(xy 286.926039 -275.698246) (xy 286.96866 -275.673639) (xy 287.014676 -275.656187) (xy 287.062895 -275.646343)
			(xy 287.11207 -275.644362) (xy 287.160925 -275.650294) (xy 287.208196 -275.663986) (xy 287.252658 -275.685084)
			(xy 287.293161 -275.71304) (xy 287.328654 -275.747132) (xy 287.358219 -275.786476) (xy 287.38109 -275.830053)
			(xy 287.396674 -275.876734) (xy 287.404569 -275.925311) (xy 287.405064 -275.949918) (xy 288.694126 -275.949918)
			(xy 288.698086 -275.900864) (xy 288.709863 -275.85308) (xy 288.729154 -275.807804) (xy 288.755457 -275.766208)
			(xy 288.788092 -275.729371) (xy 288.826213 -275.698246) (xy 288.868834 -275.673639) (xy 288.91485 -275.656187)
			(xy 288.963069 -275.646343) (xy 289.012244 -275.644362) (xy 289.061099 -275.650294) (xy 289.10837 -275.663986)
			(xy 289.152832 -275.685084) (xy 289.193335 -275.71304) (xy 289.228828 -275.747132) (xy 289.258393 -275.786476)
			(xy 289.281264 -275.830053) (xy 289.296848 -275.876734) (xy 289.304743 -275.925311) (xy 289.305238 -275.949918)
			(xy 290.594046 -275.949918) (xy 290.598006 -275.900864) (xy 290.609783 -275.85308) (xy 290.629074 -275.807804)
			(xy 290.655377 -275.766208) (xy 290.688012 -275.729371) (xy 290.726133 -275.698246) (xy 290.768754 -275.673639)
			(xy 290.81477 -275.656187) (xy 290.862989 -275.646343) (xy 290.912164 -275.644362) (xy 290.961019 -275.650294)
			(xy 291.00829 -275.663986) (xy 291.052752 -275.685084) (xy 291.093255 -275.71304) (xy 291.128748 -275.747132)
			(xy 291.158313 -275.786476) (xy 291.181184 -275.830053) (xy 291.196768 -275.876734) (xy 291.204663 -275.925311)
			(xy 291.205153 -275.949664) (xy 292.493712 -275.949664) (xy 292.497672 -275.90061) (xy 292.509449 -275.852826)
			(xy 292.52874 -275.80755) (xy 292.555043 -275.765954) (xy 292.587678 -275.729117) (xy 292.625799 -275.697992)
			(xy 292.66842 -275.673385) (xy 292.714436 -275.655933) (xy 292.762655 -275.646089) (xy 292.81183 -275.644108)
			(xy 292.860685 -275.65004) (xy 292.907956 -275.663732) (xy 292.952418 -275.68483) (xy 292.992921 -275.712786)
			(xy 293.028414 -275.746878) (xy 293.057979 -275.786222) (xy 293.08085 -275.829799) (xy 293.096434 -275.87648)
			(xy 293.104329 -275.925057) (xy 293.104824 -275.949664) (xy 293.104819 -275.949918) (xy 294.393632 -275.949918)
			(xy 294.397592 -275.900864) (xy 294.409369 -275.85308) (xy 294.42866 -275.807804) (xy 294.454963 -275.766208)
			(xy 294.487598 -275.729371) (xy 294.525719 -275.698246) (xy 294.56834 -275.673639) (xy 294.614356 -275.656187)
			(xy 294.662575 -275.646343) (xy 294.71175 -275.644362) (xy 294.760605 -275.650294) (xy 294.807876 -275.663986)
			(xy 294.852338 -275.685084) (xy 294.892841 -275.71304) (xy 294.928334 -275.747132) (xy 294.957899 -275.786476)
			(xy 294.98077 -275.830053) (xy 294.996354 -275.876734) (xy 295.004249 -275.925311) (xy 295.004739 -275.949664)
			(xy 296.293806 -275.949664) (xy 296.297766 -275.90061) (xy 296.309543 -275.852826) (xy 296.328834 -275.80755)
			(xy 296.355137 -275.765954) (xy 296.387772 -275.729117) (xy 296.425893 -275.697992) (xy 296.468514 -275.673385)
			(xy 296.51453 -275.655933) (xy 296.562749 -275.646089) (xy 296.611924 -275.644108) (xy 296.660779 -275.65004)
			(xy 296.70805 -275.663732) (xy 296.752512 -275.68483) (xy 296.793015 -275.712786) (xy 296.828508 -275.746878)
			(xy 296.858073 -275.786222) (xy 296.880944 -275.829799) (xy 296.896528 -275.87648) (xy 296.904423 -275.925057)
			(xy 296.904918 -275.949664) (xy 296.904913 -275.949918) (xy 298.193726 -275.949918) (xy 298.197686 -275.900864)
			(xy 298.209463 -275.85308) (xy 298.228754 -275.807804) (xy 298.255057 -275.766208) (xy 298.287692 -275.729371)
			(xy 298.325813 -275.698246) (xy 298.368434 -275.673639) (xy 298.41445 -275.656187) (xy 298.462669 -275.646343)
			(xy 298.511844 -275.644362) (xy 298.560699 -275.650294) (xy 298.60797 -275.663986) (xy 298.652432 -275.685084)
			(xy 298.692935 -275.71304) (xy 298.728428 -275.747132) (xy 298.757993 -275.786476) (xy 298.780864 -275.830053)
			(xy 298.796448 -275.876734) (xy 298.804343 -275.925311) (xy 298.804833 -275.949664) (xy 300.093646 -275.949664)
			(xy 300.097606 -275.90061) (xy 300.109383 -275.852826) (xy 300.128674 -275.80755) (xy 300.154977 -275.765954)
			(xy 300.187612 -275.729117) (xy 300.225733 -275.697992) (xy 300.268354 -275.673385) (xy 300.31437 -275.655933)
			(xy 300.362589 -275.646089) (xy 300.411764 -275.644108) (xy 300.460619 -275.65004) (xy 300.50789 -275.663732)
			(xy 300.552352 -275.68483) (xy 300.592855 -275.712786) (xy 300.628348 -275.746878) (xy 300.657913 -275.786222)
			(xy 300.680784 -275.829799) (xy 300.696368 -275.87648) (xy 300.704263 -275.925057) (xy 300.704758 -275.949664)
			(xy 300.704753 -275.949918) (xy 301.993566 -275.949918) (xy 301.997526 -275.900864) (xy 302.009303 -275.85308)
			(xy 302.028594 -275.807804) (xy 302.054897 -275.766208) (xy 302.087532 -275.729371) (xy 302.125653 -275.698246)
			(xy 302.168274 -275.673639) (xy 302.21429 -275.656187) (xy 302.262509 -275.646343) (xy 302.311684 -275.644362)
			(xy 302.360539 -275.650294) (xy 302.40781 -275.663986) (xy 302.452272 -275.685084) (xy 302.492775 -275.71304)
			(xy 302.528268 -275.747132) (xy 302.557833 -275.786476) (xy 302.580704 -275.830053) (xy 302.596288 -275.876734)
			(xy 302.604183 -275.925311) (xy 302.604673 -275.949664) (xy 303.89374 -275.949664) (xy 303.8977 -275.90061)
			(xy 303.909477 -275.852826) (xy 303.928768 -275.80755) (xy 303.955071 -275.765954) (xy 303.987706 -275.729117)
			(xy 304.025827 -275.697992) (xy 304.068448 -275.673385) (xy 304.114464 -275.655933) (xy 304.162683 -275.646089)
			(xy 304.211858 -275.644108) (xy 304.260713 -275.65004) (xy 304.307984 -275.663732) (xy 304.352446 -275.68483)
			(xy 304.392949 -275.712786) (xy 304.428442 -275.746878) (xy 304.458007 -275.786222) (xy 304.480878 -275.829799)
			(xy 304.496462 -275.87648) (xy 304.504357 -275.925057) (xy 304.504852 -275.949664) (xy 304.504847 -275.949918)
			(xy 305.79366 -275.949918) (xy 305.79762 -275.900864) (xy 305.809397 -275.85308) (xy 305.828688 -275.807804)
			(xy 305.854991 -275.766208) (xy 305.887626 -275.729371) (xy 305.925747 -275.698246) (xy 305.968368 -275.673639)
			(xy 306.014384 -275.656187) (xy 306.062603 -275.646343) (xy 306.111778 -275.644362) (xy 306.160633 -275.650294)
			(xy 306.207904 -275.663986) (xy 306.252366 -275.685084) (xy 306.292869 -275.71304) (xy 306.328362 -275.747132)
			(xy 306.357927 -275.786476) (xy 306.380798 -275.830053) (xy 306.396382 -275.876734) (xy 306.404277 -275.925311)
			(xy 306.404767 -275.949664) (xy 307.693834 -275.949664) (xy 307.697794 -275.90061) (xy 307.709571 -275.852826)
			(xy 307.728862 -275.80755) (xy 307.755165 -275.765954) (xy 307.7878 -275.729117) (xy 307.825921 -275.697992)
			(xy 307.868542 -275.673385) (xy 307.914558 -275.655933) (xy 307.962777 -275.646089) (xy 308.011952 -275.644108)
			(xy 308.060807 -275.65004) (xy 308.108078 -275.663732) (xy 308.15254 -275.68483) (xy 308.193043 -275.712786)
			(xy 308.228536 -275.746878) (xy 308.258101 -275.786222) (xy 308.280972 -275.829799) (xy 308.296556 -275.87648)
			(xy 308.304451 -275.925057) (xy 308.304946 -275.949664) (xy 308.304941 -275.949918) (xy 309.593754 -275.949918)
			(xy 309.597714 -275.900864) (xy 309.609491 -275.85308) (xy 309.628782 -275.807804) (xy 309.655085 -275.766208)
			(xy 309.68772 -275.729371) (xy 309.725841 -275.698246) (xy 309.768462 -275.673639) (xy 309.814478 -275.656187)
			(xy 309.862697 -275.646343) (xy 309.911872 -275.644362) (xy 309.960727 -275.650294) (xy 310.007998 -275.663986)
			(xy 310.05246 -275.685084) (xy 310.092963 -275.71304) (xy 310.128456 -275.747132) (xy 310.158021 -275.786476)
			(xy 310.180892 -275.830053) (xy 310.196476 -275.876734) (xy 310.204371 -275.925311) (xy 310.204866 -275.949918)
			(xy 311.493674 -275.949918) (xy 311.497634 -275.900864) (xy 311.509411 -275.85308) (xy 311.528702 -275.807804)
			(xy 311.555005 -275.766208) (xy 311.58764 -275.729371) (xy 311.625761 -275.698246) (xy 311.668382 -275.673639)
			(xy 311.714398 -275.656187) (xy 311.762617 -275.646343) (xy 311.811792 -275.644362) (xy 311.860647 -275.650294)
			(xy 311.907918 -275.663986) (xy 311.95238 -275.685084) (xy 311.992883 -275.71304) (xy 312.028376 -275.747132)
			(xy 312.057941 -275.786476) (xy 312.080812 -275.830053) (xy 312.096396 -275.876734) (xy 312.104291 -275.925311)
			(xy 312.104786 -275.949918) (xy 393.394196 -275.949918) (xy 393.398156 -275.900864) (xy 393.409933 -275.85308)
			(xy 393.429224 -275.807804) (xy 393.455527 -275.766208) (xy 393.488162 -275.729371) (xy 393.526283 -275.698246)
			(xy 393.568904 -275.673639) (xy 393.61492 -275.656187) (xy 393.663139 -275.646343) (xy 393.712314 -275.644362)
			(xy 393.761169 -275.650294) (xy 393.80844 -275.663986) (xy 393.852902 -275.685084) (xy 393.893405 -275.71304)
			(xy 393.928898 -275.747132) (xy 393.958463 -275.786476) (xy 393.981334 -275.830053) (xy 393.996918 -275.876734)
			(xy 394.004813 -275.925311) (xy 394.005308 -275.949918) (xy 395.294116 -275.949918) (xy 395.298076 -275.900864)
			(xy 395.309853 -275.85308) (xy 395.329144 -275.807804) (xy 395.355447 -275.766208) (xy 395.388082 -275.729371)
			(xy 395.426203 -275.698246) (xy 395.468824 -275.673639) (xy 395.51484 -275.656187) (xy 395.563059 -275.646343)
			(xy 395.612234 -275.644362) (xy 395.661089 -275.650294) (xy 395.70836 -275.663986) (xy 395.752822 -275.685084)
			(xy 395.793325 -275.71304) (xy 395.828818 -275.747132) (xy 395.858383 -275.786476) (xy 395.881254 -275.830053)
			(xy 395.896838 -275.876734) (xy 395.904733 -275.925311) (xy 395.905228 -275.949918) (xy 397.194036 -275.949918)
			(xy 397.197996 -275.900864) (xy 397.209773 -275.85308) (xy 397.229064 -275.807804) (xy 397.255367 -275.766208)
			(xy 397.288002 -275.729371) (xy 397.326123 -275.698246) (xy 397.368744 -275.673639) (xy 397.41476 -275.656187)
			(xy 397.462979 -275.646343) (xy 397.512154 -275.644362) (xy 397.561009 -275.650294) (xy 397.60828 -275.663986)
			(xy 397.652742 -275.685084) (xy 397.693245 -275.71304) (xy 397.728738 -275.747132) (xy 397.758303 -275.786476)
			(xy 397.781174 -275.830053) (xy 397.796758 -275.876734) (xy 397.804653 -275.925311) (xy 397.805148 -275.949918)
			(xy 399.09421 -275.949918) (xy 399.09817 -275.900864) (xy 399.109947 -275.85308) (xy 399.129238 -275.807804)
			(xy 399.155541 -275.766208) (xy 399.188176 -275.729371) (xy 399.226297 -275.698246) (xy 399.268918 -275.673639)
			(xy 399.314934 -275.656187) (xy 399.363153 -275.646343) (xy 399.412328 -275.644362) (xy 399.461183 -275.650294)
			(xy 399.508454 -275.663986) (xy 399.552916 -275.685084) (xy 399.593419 -275.71304) (xy 399.628912 -275.747132)
			(xy 399.658477 -275.786476) (xy 399.681348 -275.830053) (xy 399.696932 -275.876734) (xy 399.704827 -275.925311)
			(xy 399.705322 -275.949918) (xy 400.99413 -275.949918) (xy 400.99809 -275.900864) (xy 401.009867 -275.85308)
			(xy 401.029158 -275.807804) (xy 401.055461 -275.766208) (xy 401.088096 -275.729371) (xy 401.126217 -275.698246)
			(xy 401.168838 -275.673639) (xy 401.214854 -275.656187) (xy 401.263073 -275.646343) (xy 401.312248 -275.644362)
			(xy 401.361103 -275.650294) (xy 401.408374 -275.663986) (xy 401.452836 -275.685084) (xy 401.493339 -275.71304)
			(xy 401.528832 -275.747132) (xy 401.558397 -275.786476) (xy 401.581268 -275.830053) (xy 401.596852 -275.876734)
			(xy 401.604747 -275.925311) (xy 401.605242 -275.949918) (xy 402.89405 -275.949918) (xy 402.89801 -275.900864)
			(xy 402.909787 -275.85308) (xy 402.929078 -275.807804) (xy 402.955381 -275.766208) (xy 402.988016 -275.729371)
			(xy 403.026137 -275.698246) (xy 403.068758 -275.673639) (xy 403.114774 -275.656187) (xy 403.162993 -275.646343)
			(xy 403.212168 -275.644362) (xy 403.261023 -275.650294) (xy 403.308294 -275.663986) (xy 403.352756 -275.685084)
			(xy 403.393259 -275.71304) (xy 403.428752 -275.747132) (xy 403.458317 -275.786476) (xy 403.481188 -275.830053)
			(xy 403.496772 -275.876734) (xy 403.504667 -275.925311) (xy 403.505162 -275.949918) (xy 404.794224 -275.949918)
			(xy 404.798184 -275.900864) (xy 404.809961 -275.85308) (xy 404.829252 -275.807804) (xy 404.855555 -275.766208)
			(xy 404.88819 -275.729371) (xy 404.926311 -275.698246) (xy 404.968932 -275.673639) (xy 405.014948 -275.656187)
			(xy 405.063167 -275.646343) (xy 405.112342 -275.644362) (xy 405.161197 -275.650294) (xy 405.208468 -275.663986)
			(xy 405.25293 -275.685084) (xy 405.293433 -275.71304) (xy 405.328926 -275.747132) (xy 405.358491 -275.786476)
			(xy 405.381362 -275.830053) (xy 405.396946 -275.876734) (xy 405.404841 -275.925311) (xy 405.405336 -275.949918)
			(xy 406.694144 -275.949918) (xy 406.698104 -275.900864) (xy 406.709881 -275.85308) (xy 406.729172 -275.807804)
			(xy 406.755475 -275.766208) (xy 406.78811 -275.729371) (xy 406.826231 -275.698246) (xy 406.868852 -275.673639)
			(xy 406.914868 -275.656187) (xy 406.963087 -275.646343) (xy 407.012262 -275.644362) (xy 407.061117 -275.650294)
			(xy 407.108388 -275.663986) (xy 407.15285 -275.685084) (xy 407.193353 -275.71304) (xy 407.228846 -275.747132)
			(xy 407.258411 -275.786476) (xy 407.281282 -275.830053) (xy 407.296866 -275.876734) (xy 407.304761 -275.925311)
			(xy 407.305251 -275.949664) (xy 408.59381 -275.949664) (xy 408.59777 -275.90061) (xy 408.609547 -275.852826)
			(xy 408.628838 -275.80755) (xy 408.655141 -275.765954) (xy 408.687776 -275.729117) (xy 408.725897 -275.697992)
			(xy 408.768518 -275.673385) (xy 408.814534 -275.655933) (xy 408.862753 -275.646089) (xy 408.911928 -275.644108)
			(xy 408.960783 -275.65004) (xy 409.008054 -275.663732) (xy 409.052516 -275.68483) (xy 409.093019 -275.712786)
			(xy 409.128512 -275.746878) (xy 409.158077 -275.786222) (xy 409.180948 -275.829799) (xy 409.196532 -275.87648)
			(xy 409.204427 -275.925057) (xy 409.204922 -275.949664) (xy 409.204917 -275.949918) (xy 410.49373 -275.949918)
			(xy 410.49769 -275.900864) (xy 410.509467 -275.85308) (xy 410.528758 -275.807804) (xy 410.555061 -275.766208)
			(xy 410.587696 -275.729371) (xy 410.625817 -275.698246) (xy 410.668438 -275.673639) (xy 410.714454 -275.656187)
			(xy 410.762673 -275.646343) (xy 410.811848 -275.644362) (xy 410.860703 -275.650294) (xy 410.907974 -275.663986)
			(xy 410.952436 -275.685084) (xy 410.992939 -275.71304) (xy 411.028432 -275.747132) (xy 411.057997 -275.786476)
			(xy 411.080868 -275.830053) (xy 411.096452 -275.876734) (xy 411.104347 -275.925311) (xy 411.104837 -275.949664)
			(xy 412.393904 -275.949664) (xy 412.397864 -275.90061) (xy 412.409641 -275.852826) (xy 412.428932 -275.80755)
			(xy 412.455235 -275.765954) (xy 412.48787 -275.729117) (xy 412.525991 -275.697992) (xy 412.568612 -275.673385)
			(xy 412.614628 -275.655933) (xy 412.662847 -275.646089) (xy 412.712022 -275.644108) (xy 412.760877 -275.65004)
			(xy 412.808148 -275.663732) (xy 412.85261 -275.68483) (xy 412.893113 -275.712786) (xy 412.928606 -275.746878)
			(xy 412.958171 -275.786222) (xy 412.981042 -275.829799) (xy 412.996626 -275.87648) (xy 413.004521 -275.925057)
			(xy 413.005016 -275.949664) (xy 413.005011 -275.949918) (xy 414.293824 -275.949918) (xy 414.297784 -275.900864)
			(xy 414.309561 -275.85308) (xy 414.328852 -275.807804) (xy 414.355155 -275.766208) (xy 414.38779 -275.729371)
			(xy 414.425911 -275.698246) (xy 414.468532 -275.673639) (xy 414.514548 -275.656187) (xy 414.562767 -275.646343)
			(xy 414.611942 -275.644362) (xy 414.660797 -275.650294) (xy 414.708068 -275.663986) (xy 414.75253 -275.685084)
			(xy 414.793033 -275.71304) (xy 414.828526 -275.747132) (xy 414.858091 -275.786476) (xy 414.880962 -275.830053)
			(xy 414.896546 -275.876734) (xy 414.904441 -275.925311) (xy 414.904931 -275.949664) (xy 416.193744 -275.949664)
			(xy 416.197704 -275.90061) (xy 416.209481 -275.852826) (xy 416.228772 -275.80755) (xy 416.255075 -275.765954)
			(xy 416.28771 -275.729117) (xy 416.325831 -275.697992) (xy 416.368452 -275.673385) (xy 416.414468 -275.655933)
			(xy 416.462687 -275.646089) (xy 416.511862 -275.644108) (xy 416.560717 -275.65004) (xy 416.607988 -275.663732)
			(xy 416.65245 -275.68483) (xy 416.692953 -275.712786) (xy 416.728446 -275.746878) (xy 416.758011 -275.786222)
			(xy 416.780882 -275.829799) (xy 416.796466 -275.87648) (xy 416.804361 -275.925057) (xy 416.804856 -275.949664)
			(xy 416.804851 -275.949918) (xy 418.093664 -275.949918) (xy 418.097624 -275.900864) (xy 418.109401 -275.85308)
			(xy 418.128692 -275.807804) (xy 418.154995 -275.766208) (xy 418.18763 -275.729371) (xy 418.225751 -275.698246)
			(xy 418.268372 -275.673639) (xy 418.314388 -275.656187) (xy 418.362607 -275.646343) (xy 418.411782 -275.644362)
			(xy 418.460637 -275.650294) (xy 418.507908 -275.663986) (xy 418.55237 -275.685084) (xy 418.592873 -275.71304)
			(xy 418.628366 -275.747132) (xy 418.657931 -275.786476) (xy 418.680802 -275.830053) (xy 418.696386 -275.876734)
			(xy 418.704281 -275.925311) (xy 418.704771 -275.949664) (xy 419.993838 -275.949664) (xy 419.997798 -275.90061)
			(xy 420.009575 -275.852826) (xy 420.028866 -275.80755) (xy 420.055169 -275.765954) (xy 420.087804 -275.729117)
			(xy 420.125925 -275.697992) (xy 420.168546 -275.673385) (xy 420.214562 -275.655933) (xy 420.262781 -275.646089)
			(xy 420.311956 -275.644108) (xy 420.360811 -275.65004) (xy 420.408082 -275.663732) (xy 420.452544 -275.68483)
			(xy 420.493047 -275.712786) (xy 420.52854 -275.746878) (xy 420.558105 -275.786222) (xy 420.580976 -275.829799)
			(xy 420.59656 -275.87648) (xy 420.604455 -275.925057) (xy 420.60495 -275.949664) (xy 420.604945 -275.949918)
			(xy 421.893758 -275.949918) (xy 421.897718 -275.900864) (xy 421.909495 -275.85308) (xy 421.928786 -275.807804)
			(xy 421.955089 -275.766208) (xy 421.987724 -275.729371) (xy 422.025845 -275.698246) (xy 422.068466 -275.673639)
			(xy 422.114482 -275.656187) (xy 422.162701 -275.646343) (xy 422.211876 -275.644362) (xy 422.260731 -275.650294)
			(xy 422.308002 -275.663986) (xy 422.352464 -275.685084) (xy 422.392967 -275.71304) (xy 422.42846 -275.747132)
			(xy 422.458025 -275.786476) (xy 422.480896 -275.830053) (xy 422.49648 -275.876734) (xy 422.504375 -275.925311)
			(xy 422.504865 -275.949664) (xy 423.793932 -275.949664) (xy 423.797892 -275.90061) (xy 423.809669 -275.852826)
			(xy 423.82896 -275.80755) (xy 423.855263 -275.765954) (xy 423.887898 -275.729117) (xy 423.926019 -275.697992)
			(xy 423.96864 -275.673385) (xy 424.014656 -275.655933) (xy 424.062875 -275.646089) (xy 424.11205 -275.644108)
			(xy 424.160905 -275.65004) (xy 424.208176 -275.663732) (xy 424.252638 -275.68483) (xy 424.293141 -275.712786)
			(xy 424.328634 -275.746878) (xy 424.358199 -275.786222) (xy 424.38107 -275.829799) (xy 424.396654 -275.87648)
			(xy 424.404549 -275.925057) (xy 424.405044 -275.949664) (xy 424.405039 -275.949918) (xy 425.693852 -275.949918)
			(xy 425.697812 -275.900864) (xy 425.709589 -275.85308) (xy 425.72888 -275.807804) (xy 425.755183 -275.766208)
			(xy 425.787818 -275.729371) (xy 425.825939 -275.698246) (xy 425.86856 -275.673639) (xy 425.914576 -275.656187)
			(xy 425.962795 -275.646343) (xy 426.01197 -275.644362) (xy 426.060825 -275.650294) (xy 426.108096 -275.663986)
			(xy 426.152558 -275.685084) (xy 426.193061 -275.71304) (xy 426.228554 -275.747132) (xy 426.258119 -275.786476)
			(xy 426.28099 -275.830053) (xy 426.296574 -275.876734) (xy 426.304469 -275.925311) (xy 426.304964 -275.949918)
			(xy 427.593772 -275.949918) (xy 427.597732 -275.900864) (xy 427.609509 -275.85308) (xy 427.6288 -275.807804)
			(xy 427.655103 -275.766208) (xy 427.687738 -275.729371) (xy 427.725859 -275.698246) (xy 427.76848 -275.673639)
			(xy 427.814496 -275.656187) (xy 427.862715 -275.646343) (xy 427.91189 -275.644362) (xy 427.960745 -275.650294)
			(xy 428.008016 -275.663986) (xy 428.052478 -275.685084) (xy 428.092981 -275.71304) (xy 428.128474 -275.747132)
			(xy 428.158039 -275.786476) (xy 428.18091 -275.830053) (xy 428.196494 -275.876734) (xy 428.204389 -275.925311)
			(xy 428.204884 -275.949918) (xy 428.204389 -275.974525) (xy 428.196494 -276.023102) (xy 428.18091 -276.069783)
			(xy 428.158039 -276.11336) (xy 428.128474 -276.152704) (xy 428.092981 -276.186796) (xy 428.052478 -276.214752)
			(xy 428.008016 -276.23585) (xy 427.960745 -276.249542) (xy 427.91189 -276.255474) (xy 427.862715 -276.253493)
			(xy 427.814496 -276.243649) (xy 427.76848 -276.226197) (xy 427.725859 -276.20159) (xy 427.687738 -276.170465)
			(xy 427.655103 -276.133628) (xy 427.6288 -276.092032) (xy 427.609509 -276.046756) (xy 427.597732 -275.998972)
			(xy 427.593772 -275.949918) (xy 426.304964 -275.949918) (xy 426.304469 -275.974525) (xy 426.296574 -276.023102)
			(xy 426.28099 -276.069783) (xy 426.258119 -276.11336) (xy 426.228554 -276.152704) (xy 426.193061 -276.186796)
			(xy 426.152558 -276.214752) (xy 426.108096 -276.23585) (xy 426.060825 -276.249542) (xy 426.01197 -276.255474)
			(xy 425.962795 -276.253493) (xy 425.914576 -276.243649) (xy 425.86856 -276.226197) (xy 425.825939 -276.20159)
			(xy 425.787818 -276.170465) (xy 425.755183 -276.133628) (xy 425.72888 -276.092032) (xy 425.709589 -276.046756)
			(xy 425.697812 -275.998972) (xy 425.693852 -275.949918) (xy 424.405039 -275.949918) (xy 424.404549 -275.974271)
			(xy 424.396654 -276.022848) (xy 424.38107 -276.069529) (xy 424.358199 -276.113106) (xy 424.328634 -276.15245)
			(xy 424.293141 -276.186542) (xy 424.252638 -276.214498) (xy 424.208176 -276.235596) (xy 424.160905 -276.249288)
			(xy 424.11205 -276.25522) (xy 424.062875 -276.253239) (xy 424.014656 -276.243395) (xy 423.96864 -276.225943)
			(xy 423.926019 -276.201336) (xy 423.887898 -276.170211) (xy 423.855263 -276.133374) (xy 423.82896 -276.091778)
			(xy 423.809669 -276.046502) (xy 423.797892 -275.998718) (xy 423.793932 -275.949664) (xy 422.504865 -275.949664)
			(xy 422.50487 -275.949918) (xy 422.504375 -275.974525) (xy 422.49648 -276.023102) (xy 422.480896 -276.069783)
			(xy 422.458025 -276.11336) (xy 422.42846 -276.152704) (xy 422.392967 -276.186796) (xy 422.352464 -276.214752)
			(xy 422.308002 -276.23585) (xy 422.260731 -276.249542) (xy 422.211876 -276.255474) (xy 422.162701 -276.253493)
			(xy 422.114482 -276.243649) (xy 422.068466 -276.226197) (xy 422.025845 -276.20159) (xy 421.987724 -276.170465)
			(xy 421.955089 -276.133628) (xy 421.928786 -276.092032) (xy 421.909495 -276.046756) (xy 421.897718 -275.998972)
			(xy 421.893758 -275.949918) (xy 420.604945 -275.949918) (xy 420.604455 -275.974271) (xy 420.59656 -276.022848)
			(xy 420.580976 -276.069529) (xy 420.558105 -276.113106) (xy 420.52854 -276.15245) (xy 420.493047 -276.186542)
			(xy 420.452544 -276.214498) (xy 420.408082 -276.235596) (xy 420.360811 -276.249288) (xy 420.311956 -276.25522)
			(xy 420.262781 -276.253239) (xy 420.214562 -276.243395) (xy 420.168546 -276.225943) (xy 420.125925 -276.201336)
			(xy 420.087804 -276.170211) (xy 420.055169 -276.133374) (xy 420.028866 -276.091778) (xy 420.009575 -276.046502)
			(xy 419.997798 -275.998718) (xy 419.993838 -275.949664) (xy 418.704771 -275.949664) (xy 418.704776 -275.949918)
			(xy 418.704281 -275.974525) (xy 418.696386 -276.023102) (xy 418.680802 -276.069783) (xy 418.657931 -276.11336)
			(xy 418.628366 -276.152704) (xy 418.592873 -276.186796) (xy 418.55237 -276.214752) (xy 418.507908 -276.23585)
			(xy 418.460637 -276.249542) (xy 418.411782 -276.255474) (xy 418.362607 -276.253493) (xy 418.314388 -276.243649)
			(xy 418.268372 -276.226197) (xy 418.225751 -276.20159) (xy 418.18763 -276.170465) (xy 418.154995 -276.133628)
			(xy 418.128692 -276.092032) (xy 418.109401 -276.046756) (xy 418.097624 -275.998972) (xy 418.093664 -275.949918)
			(xy 416.804851 -275.949918) (xy 416.804361 -275.974271) (xy 416.796466 -276.022848) (xy 416.780882 -276.069529)
			(xy 416.758011 -276.113106) (xy 416.728446 -276.15245) (xy 416.692953 -276.186542) (xy 416.65245 -276.214498)
			(xy 416.607988 -276.235596) (xy 416.560717 -276.249288) (xy 416.511862 -276.25522) (xy 416.462687 -276.253239)
			(xy 416.414468 -276.243395) (xy 416.368452 -276.225943) (xy 416.325831 -276.201336) (xy 416.28771 -276.170211)
			(xy 416.255075 -276.133374) (xy 416.228772 -276.091778) (xy 416.209481 -276.046502) (xy 416.197704 -275.998718)
			(xy 416.193744 -275.949664) (xy 414.904931 -275.949664) (xy 414.904936 -275.949918) (xy 414.904441 -275.974525)
			(xy 414.896546 -276.023102) (xy 414.880962 -276.069783) (xy 414.858091 -276.11336) (xy 414.828526 -276.152704)
			(xy 414.793033 -276.186796) (xy 414.75253 -276.214752) (xy 414.708068 -276.23585) (xy 414.660797 -276.249542)
			(xy 414.611942 -276.255474) (xy 414.562767 -276.253493) (xy 414.514548 -276.243649) (xy 414.468532 -276.226197)
			(xy 414.425911 -276.20159) (xy 414.38779 -276.170465) (xy 414.355155 -276.133628) (xy 414.328852 -276.092032)
			(xy 414.309561 -276.046756) (xy 414.297784 -275.998972) (xy 414.293824 -275.949918) (xy 413.005011 -275.949918)
			(xy 413.004521 -275.974271) (xy 412.996626 -276.022848) (xy 412.981042 -276.069529) (xy 412.958171 -276.113106)
			(xy 412.928606 -276.15245) (xy 412.893113 -276.186542) (xy 412.85261 -276.214498) (xy 412.808148 -276.235596)
			(xy 412.760877 -276.249288) (xy 412.712022 -276.25522) (xy 412.662847 -276.253239) (xy 412.614628 -276.243395)
			(xy 412.568612 -276.225943) (xy 412.525991 -276.201336) (xy 412.48787 -276.170211) (xy 412.455235 -276.133374)
			(xy 412.428932 -276.091778) (xy 412.409641 -276.046502) (xy 412.397864 -275.998718) (xy 412.393904 -275.949664)
			(xy 411.104837 -275.949664) (xy 411.104842 -275.949918) (xy 411.104347 -275.974525) (xy 411.096452 -276.023102)
			(xy 411.080868 -276.069783) (xy 411.057997 -276.11336) (xy 411.028432 -276.152704) (xy 410.992939 -276.186796)
			(xy 410.952436 -276.214752) (xy 410.907974 -276.23585) (xy 410.860703 -276.249542) (xy 410.811848 -276.255474)
			(xy 410.762673 -276.253493) (xy 410.714454 -276.243649) (xy 410.668438 -276.226197) (xy 410.625817 -276.20159)
			(xy 410.587696 -276.170465) (xy 410.555061 -276.133628) (xy 410.528758 -276.092032) (xy 410.509467 -276.046756)
			(xy 410.49769 -275.998972) (xy 410.49373 -275.949918) (xy 409.204917 -275.949918) (xy 409.204427 -275.974271)
			(xy 409.196532 -276.022848) (xy 409.180948 -276.069529) (xy 409.158077 -276.113106) (xy 409.128512 -276.15245)
			(xy 409.093019 -276.186542) (xy 409.052516 -276.214498) (xy 409.008054 -276.235596) (xy 408.960783 -276.249288)
			(xy 408.911928 -276.25522) (xy 408.862753 -276.253239) (xy 408.814534 -276.243395) (xy 408.768518 -276.225943)
			(xy 408.725897 -276.201336) (xy 408.687776 -276.170211) (xy 408.655141 -276.133374) (xy 408.628838 -276.091778)
			(xy 408.609547 -276.046502) (xy 408.59777 -275.998718) (xy 408.59381 -275.949664) (xy 407.305251 -275.949664)
			(xy 407.305256 -275.949918) (xy 407.304761 -275.974525) (xy 407.296866 -276.023102) (xy 407.281282 -276.069783)
			(xy 407.258411 -276.11336) (xy 407.228846 -276.152704) (xy 407.193353 -276.186796) (xy 407.15285 -276.214752)
			(xy 407.108388 -276.23585) (xy 407.061117 -276.249542) (xy 407.012262 -276.255474) (xy 406.963087 -276.253493)
			(xy 406.914868 -276.243649) (xy 406.868852 -276.226197) (xy 406.826231 -276.20159) (xy 406.78811 -276.170465)
			(xy 406.755475 -276.133628) (xy 406.729172 -276.092032) (xy 406.709881 -276.046756) (xy 406.698104 -275.998972)
			(xy 406.694144 -275.949918) (xy 405.405336 -275.949918) (xy 405.404841 -275.974525) (xy 405.396946 -276.023102)
			(xy 405.381362 -276.069783) (xy 405.358491 -276.11336) (xy 405.328926 -276.152704) (xy 405.293433 -276.186796)
			(xy 405.25293 -276.214752) (xy 405.208468 -276.23585) (xy 405.161197 -276.249542) (xy 405.112342 -276.255474)
			(xy 405.063167 -276.253493) (xy 405.014948 -276.243649) (xy 404.968932 -276.226197) (xy 404.926311 -276.20159)
			(xy 404.88819 -276.170465) (xy 404.855555 -276.133628) (xy 404.829252 -276.092032) (xy 404.809961 -276.046756)
			(xy 404.798184 -275.998972) (xy 404.794224 -275.949918) (xy 403.505162 -275.949918) (xy 403.504667 -275.974525)
			(xy 403.496772 -276.023102) (xy 403.481188 -276.069783) (xy 403.458317 -276.11336) (xy 403.428752 -276.152704)
			(xy 403.393259 -276.186796) (xy 403.352756 -276.214752) (xy 403.308294 -276.23585) (xy 403.261023 -276.249542)
			(xy 403.212168 -276.255474) (xy 403.162993 -276.253493) (xy 403.114774 -276.243649) (xy 403.068758 -276.226197)
			(xy 403.026137 -276.20159) (xy 402.988016 -276.170465) (xy 402.955381 -276.133628) (xy 402.929078 -276.092032)
			(xy 402.909787 -276.046756) (xy 402.89801 -275.998972) (xy 402.89405 -275.949918) (xy 401.605242 -275.949918)
			(xy 401.604747 -275.974525) (xy 401.596852 -276.023102) (xy 401.581268 -276.069783) (xy 401.558397 -276.11336)
			(xy 401.528832 -276.152704) (xy 401.493339 -276.186796) (xy 401.452836 -276.214752) (xy 401.408374 -276.23585)
			(xy 401.361103 -276.249542) (xy 401.312248 -276.255474) (xy 401.263073 -276.253493) (xy 401.214854 -276.243649)
			(xy 401.168838 -276.226197) (xy 401.126217 -276.20159) (xy 401.088096 -276.170465) (xy 401.055461 -276.133628)
			(xy 401.029158 -276.092032) (xy 401.009867 -276.046756) (xy 400.99809 -275.998972) (xy 400.99413 -275.949918)
			(xy 399.705322 -275.949918) (xy 399.704827 -275.974525) (xy 399.696932 -276.023102) (xy 399.681348 -276.069783)
			(xy 399.658477 -276.11336) (xy 399.628912 -276.152704) (xy 399.593419 -276.186796) (xy 399.552916 -276.214752)
			(xy 399.508454 -276.23585) (xy 399.461183 -276.249542) (xy 399.412328 -276.255474) (xy 399.363153 -276.253493)
			(xy 399.314934 -276.243649) (xy 399.268918 -276.226197) (xy 399.226297 -276.20159) (xy 399.188176 -276.170465)
			(xy 399.155541 -276.133628) (xy 399.129238 -276.092032) (xy 399.109947 -276.046756) (xy 399.09817 -275.998972)
			(xy 399.09421 -275.949918) (xy 397.805148 -275.949918) (xy 397.804653 -275.974525) (xy 397.796758 -276.023102)
			(xy 397.781174 -276.069783) (xy 397.758303 -276.11336) (xy 397.728738 -276.152704) (xy 397.693245 -276.186796)
			(xy 397.652742 -276.214752) (xy 397.60828 -276.23585) (xy 397.561009 -276.249542) (xy 397.512154 -276.255474)
			(xy 397.462979 -276.253493) (xy 397.41476 -276.243649) (xy 397.368744 -276.226197) (xy 397.326123 -276.20159)
			(xy 397.288002 -276.170465) (xy 397.255367 -276.133628) (xy 397.229064 -276.092032) (xy 397.209773 -276.046756)
			(xy 397.197996 -275.998972) (xy 397.194036 -275.949918) (xy 395.905228 -275.949918) (xy 395.904733 -275.974525)
			(xy 395.896838 -276.023102) (xy 395.881254 -276.069783) (xy 395.858383 -276.11336) (xy 395.828818 -276.152704)
			(xy 395.793325 -276.186796) (xy 395.752822 -276.214752) (xy 395.70836 -276.23585) (xy 395.661089 -276.249542)
			(xy 395.612234 -276.255474) (xy 395.563059 -276.253493) (xy 395.51484 -276.243649) (xy 395.468824 -276.226197)
			(xy 395.426203 -276.20159) (xy 395.388082 -276.170465) (xy 395.355447 -276.133628) (xy 395.329144 -276.092032)
			(xy 395.309853 -276.046756) (xy 395.298076 -275.998972) (xy 395.294116 -275.949918) (xy 394.005308 -275.949918)
			(xy 394.004813 -275.974525) (xy 393.996918 -276.023102) (xy 393.981334 -276.069783) (xy 393.958463 -276.11336)
			(xy 393.928898 -276.152704) (xy 393.893405 -276.186796) (xy 393.852902 -276.214752) (xy 393.80844 -276.23585)
			(xy 393.761169 -276.249542) (xy 393.712314 -276.255474) (xy 393.663139 -276.253493) (xy 393.61492 -276.243649)
			(xy 393.568904 -276.226197) (xy 393.526283 -276.20159) (xy 393.488162 -276.170465) (xy 393.455527 -276.133628)
			(xy 393.429224 -276.092032) (xy 393.409933 -276.046756) (xy 393.398156 -275.998972) (xy 393.394196 -275.949918)
			(xy 312.104786 -275.949918) (xy 312.104291 -275.974525) (xy 312.096396 -276.023102) (xy 312.080812 -276.069783)
			(xy 312.057941 -276.11336) (xy 312.028376 -276.152704) (xy 311.992883 -276.186796) (xy 311.95238 -276.214752)
			(xy 311.907918 -276.23585) (xy 311.860647 -276.249542) (xy 311.811792 -276.255474) (xy 311.762617 -276.253493)
			(xy 311.714398 -276.243649) (xy 311.668382 -276.226197) (xy 311.625761 -276.20159) (xy 311.58764 -276.170465)
			(xy 311.555005 -276.133628) (xy 311.528702 -276.092032) (xy 311.509411 -276.046756) (xy 311.497634 -275.998972)
			(xy 311.493674 -275.949918) (xy 310.204866 -275.949918) (xy 310.204371 -275.974525) (xy 310.196476 -276.023102)
			(xy 310.180892 -276.069783) (xy 310.158021 -276.11336) (xy 310.128456 -276.152704) (xy 310.092963 -276.186796)
			(xy 310.05246 -276.214752) (xy 310.007998 -276.23585) (xy 309.960727 -276.249542) (xy 309.911872 -276.255474)
			(xy 309.862697 -276.253493) (xy 309.814478 -276.243649) (xy 309.768462 -276.226197) (xy 309.725841 -276.20159)
			(xy 309.68772 -276.170465) (xy 309.655085 -276.133628) (xy 309.628782 -276.092032) (xy 309.609491 -276.046756)
			(xy 309.597714 -275.998972) (xy 309.593754 -275.949918) (xy 308.304941 -275.949918) (xy 308.304451 -275.974271)
			(xy 308.296556 -276.022848) (xy 308.280972 -276.069529) (xy 308.258101 -276.113106) (xy 308.228536 -276.15245)
			(xy 308.193043 -276.186542) (xy 308.15254 -276.214498) (xy 308.108078 -276.235596) (xy 308.060807 -276.249288)
			(xy 308.011952 -276.25522) (xy 307.962777 -276.253239) (xy 307.914558 -276.243395) (xy 307.868542 -276.225943)
			(xy 307.825921 -276.201336) (xy 307.7878 -276.170211) (xy 307.755165 -276.133374) (xy 307.728862 -276.091778)
			(xy 307.709571 -276.046502) (xy 307.697794 -275.998718) (xy 307.693834 -275.949664) (xy 306.404767 -275.949664)
			(xy 306.404772 -275.949918) (xy 306.404277 -275.974525) (xy 306.396382 -276.023102) (xy 306.380798 -276.069783)
			(xy 306.357927 -276.11336) (xy 306.328362 -276.152704) (xy 306.292869 -276.186796) (xy 306.252366 -276.214752)
			(xy 306.207904 -276.23585) (xy 306.160633 -276.249542) (xy 306.111778 -276.255474) (xy 306.062603 -276.253493)
			(xy 306.014384 -276.243649) (xy 305.968368 -276.226197) (xy 305.925747 -276.20159) (xy 305.887626 -276.170465)
			(xy 305.854991 -276.133628) (xy 305.828688 -276.092032) (xy 305.809397 -276.046756) (xy 305.79762 -275.998972)
			(xy 305.79366 -275.949918) (xy 304.504847 -275.949918) (xy 304.504357 -275.974271) (xy 304.496462 -276.022848)
			(xy 304.480878 -276.069529) (xy 304.458007 -276.113106) (xy 304.428442 -276.15245) (xy 304.392949 -276.186542)
			(xy 304.352446 -276.214498) (xy 304.307984 -276.235596) (xy 304.260713 -276.249288) (xy 304.211858 -276.25522)
			(xy 304.162683 -276.253239) (xy 304.114464 -276.243395) (xy 304.068448 -276.225943) (xy 304.025827 -276.201336)
			(xy 303.987706 -276.170211) (xy 303.955071 -276.133374) (xy 303.928768 -276.091778) (xy 303.909477 -276.046502)
			(xy 303.8977 -275.998718) (xy 303.89374 -275.949664) (xy 302.604673 -275.949664) (xy 302.604678 -275.949918)
			(xy 302.604183 -275.974525) (xy 302.596288 -276.023102) (xy 302.580704 -276.069783) (xy 302.557833 -276.11336)
			(xy 302.528268 -276.152704) (xy 302.492775 -276.186796) (xy 302.452272 -276.214752) (xy 302.40781 -276.23585)
			(xy 302.360539 -276.249542) (xy 302.311684 -276.255474) (xy 302.262509 -276.253493) (xy 302.21429 -276.243649)
			(xy 302.168274 -276.226197) (xy 302.125653 -276.20159) (xy 302.087532 -276.170465) (xy 302.054897 -276.133628)
			(xy 302.028594 -276.092032) (xy 302.009303 -276.046756) (xy 301.997526 -275.998972) (xy 301.993566 -275.949918)
			(xy 300.704753 -275.949918) (xy 300.704263 -275.974271) (xy 300.696368 -276.022848) (xy 300.680784 -276.069529)
			(xy 300.657913 -276.113106) (xy 300.628348 -276.15245) (xy 300.592855 -276.186542) (xy 300.552352 -276.214498)
			(xy 300.50789 -276.235596) (xy 300.460619 -276.249288) (xy 300.411764 -276.25522) (xy 300.362589 -276.253239)
			(xy 300.31437 -276.243395) (xy 300.268354 -276.225943) (xy 300.225733 -276.201336) (xy 300.187612 -276.170211)
			(xy 300.154977 -276.133374) (xy 300.128674 -276.091778) (xy 300.109383 -276.046502) (xy 300.097606 -275.998718)
			(xy 300.093646 -275.949664) (xy 298.804833 -275.949664) (xy 298.804838 -275.949918) (xy 298.804343 -275.974525)
			(xy 298.796448 -276.023102) (xy 298.780864 -276.069783) (xy 298.757993 -276.11336) (xy 298.728428 -276.152704)
			(xy 298.692935 -276.186796) (xy 298.652432 -276.214752) (xy 298.60797 -276.23585) (xy 298.560699 -276.249542)
			(xy 298.511844 -276.255474) (xy 298.462669 -276.253493) (xy 298.41445 -276.243649) (xy 298.368434 -276.226197)
			(xy 298.325813 -276.20159) (xy 298.287692 -276.170465) (xy 298.255057 -276.133628) (xy 298.228754 -276.092032)
			(xy 298.209463 -276.046756) (xy 298.197686 -275.998972) (xy 298.193726 -275.949918) (xy 296.904913 -275.949918)
			(xy 296.904423 -275.974271) (xy 296.896528 -276.022848) (xy 296.880944 -276.069529) (xy 296.858073 -276.113106)
			(xy 296.828508 -276.15245) (xy 296.793015 -276.186542) (xy 296.752512 -276.214498) (xy 296.70805 -276.235596)
			(xy 296.660779 -276.249288) (xy 296.611924 -276.25522) (xy 296.562749 -276.253239) (xy 296.51453 -276.243395)
			(xy 296.468514 -276.225943) (xy 296.425893 -276.201336) (xy 296.387772 -276.170211) (xy 296.355137 -276.133374)
			(xy 296.328834 -276.091778) (xy 296.309543 -276.046502) (xy 296.297766 -275.998718) (xy 296.293806 -275.949664)
			(xy 295.004739 -275.949664) (xy 295.004744 -275.949918) (xy 295.004249 -275.974525) (xy 294.996354 -276.023102)
			(xy 294.98077 -276.069783) (xy 294.957899 -276.11336) (xy 294.928334 -276.152704) (xy 294.892841 -276.186796)
			(xy 294.852338 -276.214752) (xy 294.807876 -276.23585) (xy 294.760605 -276.249542) (xy 294.71175 -276.255474)
			(xy 294.662575 -276.253493) (xy 294.614356 -276.243649) (xy 294.56834 -276.226197) (xy 294.525719 -276.20159)
			(xy 294.487598 -276.170465) (xy 294.454963 -276.133628) (xy 294.42866 -276.092032) (xy 294.409369 -276.046756)
			(xy 294.397592 -275.998972) (xy 294.393632 -275.949918) (xy 293.104819 -275.949918) (xy 293.104329 -275.974271)
			(xy 293.096434 -276.022848) (xy 293.08085 -276.069529) (xy 293.057979 -276.113106) (xy 293.028414 -276.15245)
			(xy 292.992921 -276.186542) (xy 292.952418 -276.214498) (xy 292.907956 -276.235596) (xy 292.860685 -276.249288)
			(xy 292.81183 -276.25522) (xy 292.762655 -276.253239) (xy 292.714436 -276.243395) (xy 292.66842 -276.225943)
			(xy 292.625799 -276.201336) (xy 292.587678 -276.170211) (xy 292.555043 -276.133374) (xy 292.52874 -276.091778)
			(xy 292.509449 -276.046502) (xy 292.497672 -275.998718) (xy 292.493712 -275.949664) (xy 291.205153 -275.949664)
			(xy 291.205158 -275.949918) (xy 291.204663 -275.974525) (xy 291.196768 -276.023102) (xy 291.181184 -276.069783)
			(xy 291.158313 -276.11336) (xy 291.128748 -276.152704) (xy 291.093255 -276.186796) (xy 291.052752 -276.214752)
			(xy 291.00829 -276.23585) (xy 290.961019 -276.249542) (xy 290.912164 -276.255474) (xy 290.862989 -276.253493)
			(xy 290.81477 -276.243649) (xy 290.768754 -276.226197) (xy 290.726133 -276.20159) (xy 290.688012 -276.170465)
			(xy 290.655377 -276.133628) (xy 290.629074 -276.092032) (xy 290.609783 -276.046756) (xy 290.598006 -275.998972)
			(xy 290.594046 -275.949918) (xy 289.305238 -275.949918) (xy 289.304743 -275.974525) (xy 289.296848 -276.023102)
			(xy 289.281264 -276.069783) (xy 289.258393 -276.11336) (xy 289.228828 -276.152704) (xy 289.193335 -276.186796)
			(xy 289.152832 -276.214752) (xy 289.10837 -276.23585) (xy 289.061099 -276.249542) (xy 289.012244 -276.255474)
			(xy 288.963069 -276.253493) (xy 288.91485 -276.243649) (xy 288.868834 -276.226197) (xy 288.826213 -276.20159)
			(xy 288.788092 -276.170465) (xy 288.755457 -276.133628) (xy 288.729154 -276.092032) (xy 288.709863 -276.046756)
			(xy 288.698086 -275.998972) (xy 288.694126 -275.949918) (xy 287.405064 -275.949918) (xy 287.404569 -275.974525)
			(xy 287.396674 -276.023102) (xy 287.38109 -276.069783) (xy 287.358219 -276.11336) (xy 287.328654 -276.152704)
			(xy 287.293161 -276.186796) (xy 287.252658 -276.214752) (xy 287.208196 -276.23585) (xy 287.160925 -276.249542)
			(xy 287.11207 -276.255474) (xy 287.062895 -276.253493) (xy 287.014676 -276.243649) (xy 286.96866 -276.226197)
			(xy 286.926039 -276.20159) (xy 286.887918 -276.170465) (xy 286.855283 -276.133628) (xy 286.82898 -276.092032)
			(xy 286.809689 -276.046756) (xy 286.797912 -275.998972) (xy 286.793952 -275.949918) (xy 285.505144 -275.949918)
			(xy 285.504649 -275.974525) (xy 285.496754 -276.023102) (xy 285.48117 -276.069783) (xy 285.458299 -276.11336)
			(xy 285.428734 -276.152704) (xy 285.393241 -276.186796) (xy 285.352738 -276.214752) (xy 285.308276 -276.23585)
			(xy 285.261005 -276.249542) (xy 285.21215 -276.255474) (xy 285.162975 -276.253493) (xy 285.114756 -276.243649)
			(xy 285.06874 -276.226197) (xy 285.026119 -276.20159) (xy 284.987998 -276.170465) (xy 284.955363 -276.133628)
			(xy 284.92906 -276.092032) (xy 284.909769 -276.046756) (xy 284.897992 -275.998972) (xy 284.894032 -275.949918)
			(xy 283.605224 -275.949918) (xy 283.604729 -275.974525) (xy 283.596834 -276.023102) (xy 283.58125 -276.069783)
			(xy 283.558379 -276.11336) (xy 283.528814 -276.152704) (xy 283.493321 -276.186796) (xy 283.452818 -276.214752)
			(xy 283.408356 -276.23585) (xy 283.361085 -276.249542) (xy 283.31223 -276.255474) (xy 283.263055 -276.253493)
			(xy 283.214836 -276.243649) (xy 283.16882 -276.226197) (xy 283.126199 -276.20159) (xy 283.088078 -276.170465)
			(xy 283.055443 -276.133628) (xy 283.02914 -276.092032) (xy 283.009849 -276.046756) (xy 282.998072 -275.998972)
			(xy 282.994112 -275.949918) (xy 281.70505 -275.949918) (xy 281.704555 -275.974525) (xy 281.69666 -276.023102)
			(xy 281.681076 -276.069783) (xy 281.658205 -276.11336) (xy 281.62864 -276.152704) (xy 281.593147 -276.186796)
			(xy 281.552644 -276.214752) (xy 281.508182 -276.23585) (xy 281.460911 -276.249542) (xy 281.412056 -276.255474)
			(xy 281.362881 -276.253493) (xy 281.314662 -276.243649) (xy 281.268646 -276.226197) (xy 281.226025 -276.20159)
			(xy 281.187904 -276.170465) (xy 281.155269 -276.133628) (xy 281.128966 -276.092032) (xy 281.109675 -276.046756)
			(xy 281.097898 -275.998972) (xy 281.093938 -275.949918) (xy 279.80513 -275.949918) (xy 279.804635 -275.974525)
			(xy 279.79674 -276.023102) (xy 279.781156 -276.069783) (xy 279.758285 -276.11336) (xy 279.72872 -276.152704)
			(xy 279.693227 -276.186796) (xy 279.652724 -276.214752) (xy 279.608262 -276.23585) (xy 279.560991 -276.249542)
			(xy 279.512136 -276.255474) (xy 279.462961 -276.253493) (xy 279.414742 -276.243649) (xy 279.368726 -276.226197)
			(xy 279.326105 -276.20159) (xy 279.287984 -276.170465) (xy 279.255349 -276.133628) (xy 279.229046 -276.092032)
			(xy 279.209755 -276.046756) (xy 279.197978 -275.998972) (xy 279.194018 -275.949918) (xy 277.90521 -275.949918)
			(xy 277.904715 -275.974525) (xy 277.89682 -276.023102) (xy 277.881236 -276.069783) (xy 277.858365 -276.11336)
			(xy 277.8288 -276.152704) (xy 277.793307 -276.186796) (xy 277.752804 -276.214752) (xy 277.708342 -276.23585)
			(xy 277.661071 -276.249542) (xy 277.612216 -276.255474) (xy 277.563041 -276.253493) (xy 277.514822 -276.243649)
			(xy 277.468806 -276.226197) (xy 277.426185 -276.20159) (xy 277.388064 -276.170465) (xy 277.355429 -276.133628)
			(xy 277.329126 -276.092032) (xy 277.309835 -276.046756) (xy 277.298058 -275.998972) (xy 277.294098 -275.949918)
			(xy 196.004942 -275.949918) (xy 196.004447 -275.974525) (xy 195.996552 -276.023102) (xy 195.980968 -276.069783)
			(xy 195.958097 -276.11336) (xy 195.928532 -276.152704) (xy 195.893039 -276.186796) (xy 195.852536 -276.214752)
			(xy 195.808074 -276.23585) (xy 195.760803 -276.249542) (xy 195.711948 -276.255474) (xy 195.662773 -276.253493)
			(xy 195.614554 -276.243649) (xy 195.568538 -276.226197) (xy 195.525917 -276.20159) (xy 195.487796 -276.170465)
			(xy 195.455161 -276.133628) (xy 195.428858 -276.092032) (xy 195.409567 -276.046756) (xy 195.39779 -275.998972)
			(xy 195.39383 -275.949918) (xy 194.105022 -275.949918) (xy 194.104527 -275.974525) (xy 194.096632 -276.023102)
			(xy 194.081048 -276.069783) (xy 194.058177 -276.11336) (xy 194.028612 -276.152704) (xy 193.993119 -276.186796)
			(xy 193.952616 -276.214752) (xy 193.908154 -276.23585) (xy 193.860883 -276.249542) (xy 193.812028 -276.255474)
			(xy 193.762853 -276.253493) (xy 193.714634 -276.243649) (xy 193.668618 -276.226197) (xy 193.625997 -276.20159)
			(xy 193.587876 -276.170465) (xy 193.555241 -276.133628) (xy 193.528938 -276.092032) (xy 193.509647 -276.046756)
			(xy 193.49787 -275.998972) (xy 193.49391 -275.949918) (xy 192.205097 -275.949918) (xy 192.204607 -275.974271)
			(xy 192.196712 -276.022848) (xy 192.181128 -276.069529) (xy 192.158257 -276.113106) (xy 192.128692 -276.15245)
			(xy 192.093199 -276.186542) (xy 192.052696 -276.214498) (xy 192.008234 -276.235596) (xy 191.960963 -276.249288)
			(xy 191.912108 -276.25522) (xy 191.862933 -276.253239) (xy 191.814714 -276.243395) (xy 191.768698 -276.225943)
			(xy 191.726077 -276.201336) (xy 191.687956 -276.170211) (xy 191.655321 -276.133374) (xy 191.629018 -276.091778)
			(xy 191.609727 -276.046502) (xy 191.59795 -275.998718) (xy 191.59399 -275.949664) (xy 190.304923 -275.949664)
			(xy 190.304928 -275.949918) (xy 190.304433 -275.974525) (xy 190.296538 -276.023102) (xy 190.280954 -276.069783)
			(xy 190.258083 -276.11336) (xy 190.228518 -276.152704) (xy 190.193025 -276.186796) (xy 190.152522 -276.214752)
			(xy 190.10806 -276.23585) (xy 190.060789 -276.249542) (xy 190.011934 -276.255474) (xy 189.962759 -276.253493)
			(xy 189.91454 -276.243649) (xy 189.868524 -276.226197) (xy 189.825903 -276.20159) (xy 189.787782 -276.170465)
			(xy 189.755147 -276.133628) (xy 189.728844 -276.092032) (xy 189.709553 -276.046756) (xy 189.697776 -275.998972)
			(xy 189.693816 -275.949918) (xy 188.405003 -275.949918) (xy 188.404513 -275.974271) (xy 188.396618 -276.022848)
			(xy 188.381034 -276.069529) (xy 188.358163 -276.113106) (xy 188.328598 -276.15245) (xy 188.293105 -276.186542)
			(xy 188.252602 -276.214498) (xy 188.20814 -276.235596) (xy 188.160869 -276.249288) (xy 188.112014 -276.25522)
			(xy 188.062839 -276.253239) (xy 188.01462 -276.243395) (xy 187.968604 -276.225943) (xy 187.925983 -276.201336)
			(xy 187.887862 -276.170211) (xy 187.855227 -276.133374) (xy 187.828924 -276.091778) (xy 187.809633 -276.046502)
			(xy 187.797856 -275.998718) (xy 187.793896 -275.949664) (xy 186.504829 -275.949664) (xy 186.504834 -275.949918)
			(xy 186.504339 -275.974525) (xy 186.496444 -276.023102) (xy 186.48086 -276.069783) (xy 186.457989 -276.11336)
			(xy 186.428424 -276.152704) (xy 186.392931 -276.186796) (xy 186.352428 -276.214752) (xy 186.307966 -276.23585)
			(xy 186.260695 -276.249542) (xy 186.21184 -276.255474) (xy 186.162665 -276.253493) (xy 186.114446 -276.243649)
			(xy 186.06843 -276.226197) (xy 186.025809 -276.20159) (xy 185.987688 -276.170465) (xy 185.955053 -276.133628)
			(xy 185.92875 -276.092032) (xy 185.909459 -276.046756) (xy 185.897682 -275.998972) (xy 185.893722 -275.949918)
			(xy 184.604909 -275.949918) (xy 184.604419 -275.974271) (xy 184.596524 -276.022848) (xy 184.58094 -276.069529)
			(xy 184.558069 -276.113106) (xy 184.528504 -276.15245) (xy 184.493011 -276.186542) (xy 184.452508 -276.214498)
			(xy 184.408046 -276.235596) (xy 184.360775 -276.249288) (xy 184.31192 -276.25522) (xy 184.262745 -276.253239)
			(xy 184.214526 -276.243395) (xy 184.16851 -276.225943) (xy 184.125889 -276.201336) (xy 184.087768 -276.170211)
			(xy 184.055133 -276.133374) (xy 184.02883 -276.091778) (xy 184.009539 -276.046502) (xy 183.997762 -275.998718)
			(xy 183.993802 -275.949664) (xy 182.704989 -275.949664) (xy 182.704994 -275.949918) (xy 182.704499 -275.974525)
			(xy 182.696604 -276.023102) (xy 182.68102 -276.069783) (xy 182.658149 -276.11336) (xy 182.628584 -276.152704)
			(xy 182.593091 -276.186796) (xy 182.552588 -276.214752) (xy 182.508126 -276.23585) (xy 182.460855 -276.249542)
			(xy 182.412 -276.255474) (xy 182.362825 -276.253493) (xy 182.314606 -276.243649) (xy 182.26859 -276.226197)
			(xy 182.225969 -276.20159) (xy 182.187848 -276.170465) (xy 182.155213 -276.133628) (xy 182.12891 -276.092032)
			(xy 182.109619 -276.046756) (xy 182.097842 -275.998972) (xy 182.093882 -275.949918) (xy 180.805069 -275.949918)
			(xy 180.804579 -275.974271) (xy 180.796684 -276.022848) (xy 180.7811 -276.069529) (xy 180.758229 -276.113106)
			(xy 180.728664 -276.15245) (xy 180.693171 -276.186542) (xy 180.652668 -276.214498) (xy 180.608206 -276.235596)
			(xy 180.560935 -276.249288) (xy 180.51208 -276.25522) (xy 180.462905 -276.253239) (xy 180.414686 -276.243395)
			(xy 180.36867 -276.225943) (xy 180.326049 -276.201336) (xy 180.287928 -276.170211) (xy 180.255293 -276.133374)
			(xy 180.22899 -276.091778) (xy 180.209699 -276.046502) (xy 180.197922 -275.998718) (xy 180.193962 -275.949664)
			(xy 178.904895 -275.949664) (xy 178.9049 -275.949918) (xy 178.904405 -275.974525) (xy 178.89651 -276.023102)
			(xy 178.880926 -276.069783) (xy 178.858055 -276.11336) (xy 178.82849 -276.152704) (xy 178.792997 -276.186796)
			(xy 178.752494 -276.214752) (xy 178.708032 -276.23585) (xy 178.660761 -276.249542) (xy 178.611906 -276.255474)
			(xy 178.562731 -276.253493) (xy 178.514512 -276.243649) (xy 178.468496 -276.226197) (xy 178.425875 -276.20159)
			(xy 178.387754 -276.170465) (xy 178.355119 -276.133628) (xy 178.328816 -276.092032) (xy 178.309525 -276.046756)
			(xy 178.297748 -275.998972) (xy 178.293788 -275.949918) (xy 177.004975 -275.949918) (xy 177.004485 -275.974271)
			(xy 176.99659 -276.022848) (xy 176.981006 -276.069529) (xy 176.958135 -276.113106) (xy 176.92857 -276.15245)
			(xy 176.893077 -276.186542) (xy 176.852574 -276.214498) (xy 176.808112 -276.235596) (xy 176.760841 -276.249288)
			(xy 176.711986 -276.25522) (xy 176.662811 -276.253239) (xy 176.614592 -276.243395) (xy 176.568576 -276.225943)
			(xy 176.525955 -276.201336) (xy 176.487834 -276.170211) (xy 176.455199 -276.133374) (xy 176.428896 -276.091778)
			(xy 176.409605 -276.046502) (xy 176.397828 -275.998718) (xy 176.393868 -275.949664) (xy 175.105309 -275.949664)
			(xy 175.105314 -275.949918) (xy 175.104819 -275.974525) (xy 175.096924 -276.023102) (xy 175.08134 -276.069783)
			(xy 175.058469 -276.11336) (xy 175.028904 -276.152704) (xy 174.993411 -276.186796) (xy 174.952908 -276.214752)
			(xy 174.908446 -276.23585) (xy 174.861175 -276.249542) (xy 174.81232 -276.255474) (xy 174.763145 -276.253493)
			(xy 174.714926 -276.243649) (xy 174.66891 -276.226197) (xy 174.626289 -276.20159) (xy 174.588168 -276.170465)
			(xy 174.555533 -276.133628) (xy 174.52923 -276.092032) (xy 174.509939 -276.046756) (xy 174.498162 -275.998972)
			(xy 174.494202 -275.949918) (xy 173.205394 -275.949918) (xy 173.204899 -275.974525) (xy 173.197004 -276.023102)
			(xy 173.18142 -276.069783) (xy 173.158549 -276.11336) (xy 173.128984 -276.152704) (xy 173.093491 -276.186796)
			(xy 173.052988 -276.214752) (xy 173.008526 -276.23585) (xy 172.961255 -276.249542) (xy 172.9124 -276.255474)
			(xy 172.863225 -276.253493) (xy 172.815006 -276.243649) (xy 172.76899 -276.226197) (xy 172.726369 -276.20159)
			(xy 172.688248 -276.170465) (xy 172.655613 -276.133628) (xy 172.62931 -276.092032) (xy 172.610019 -276.046756)
			(xy 172.598242 -275.998972) (xy 172.594282 -275.949918) (xy 171.30522 -275.949918) (xy 171.304725 -275.974525)
			(xy 171.29683 -276.023102) (xy 171.281246 -276.069783) (xy 171.258375 -276.11336) (xy 171.22881 -276.152704)
			(xy 171.193317 -276.186796) (xy 171.152814 -276.214752) (xy 171.108352 -276.23585) (xy 171.061081 -276.249542)
			(xy 171.012226 -276.255474) (xy 170.963051 -276.253493) (xy 170.914832 -276.243649) (xy 170.868816 -276.226197)
			(xy 170.826195 -276.20159) (xy 170.788074 -276.170465) (xy 170.755439 -276.133628) (xy 170.729136 -276.092032)
			(xy 170.709845 -276.046756) (xy 170.698068 -275.998972) (xy 170.694108 -275.949918) (xy 169.4053 -275.949918)
			(xy 169.404805 -275.974525) (xy 169.39691 -276.023102) (xy 169.381326 -276.069783) (xy 169.358455 -276.11336)
			(xy 169.32889 -276.152704) (xy 169.293397 -276.186796) (xy 169.252894 -276.214752) (xy 169.208432 -276.23585)
			(xy 169.161161 -276.249542) (xy 169.112306 -276.255474) (xy 169.063131 -276.253493) (xy 169.014912 -276.243649)
			(xy 168.968896 -276.226197) (xy 168.926275 -276.20159) (xy 168.888154 -276.170465) (xy 168.855519 -276.133628)
			(xy 168.829216 -276.092032) (xy 168.809925 -276.046756) (xy 168.798148 -275.998972) (xy 168.794188 -275.949918)
			(xy 167.50538 -275.949918) (xy 167.504885 -275.974525) (xy 167.49699 -276.023102) (xy 167.481406 -276.069783)
			(xy 167.458535 -276.11336) (xy 167.42897 -276.152704) (xy 167.393477 -276.186796) (xy 167.352974 -276.214752)
			(xy 167.308512 -276.23585) (xy 167.261241 -276.249542) (xy 167.212386 -276.255474) (xy 167.163211 -276.253493)
			(xy 167.114992 -276.243649) (xy 167.068976 -276.226197) (xy 167.026355 -276.20159) (xy 166.988234 -276.170465)
			(xy 166.955599 -276.133628) (xy 166.929296 -276.092032) (xy 166.910005 -276.046756) (xy 166.898228 -275.998972)
			(xy 166.894268 -275.949918) (xy 165.605206 -275.949918) (xy 165.604711 -275.974525) (xy 165.596816 -276.023102)
			(xy 165.581232 -276.069783) (xy 165.558361 -276.11336) (xy 165.528796 -276.152704) (xy 165.493303 -276.186796)
			(xy 165.4528 -276.214752) (xy 165.408338 -276.23585) (xy 165.361067 -276.249542) (xy 165.312212 -276.255474)
			(xy 165.263037 -276.253493) (xy 165.214818 -276.243649) (xy 165.168802 -276.226197) (xy 165.126181 -276.20159)
			(xy 165.08806 -276.170465) (xy 165.055425 -276.133628) (xy 165.029122 -276.092032) (xy 165.009831 -276.046756)
			(xy 164.998054 -275.998972) (xy 164.994094 -275.949918) (xy 163.705286 -275.949918) (xy 163.704791 -275.974525)
			(xy 163.696896 -276.023102) (xy 163.681312 -276.069783) (xy 163.658441 -276.11336) (xy 163.628876 -276.152704)
			(xy 163.593383 -276.186796) (xy 163.55288 -276.214752) (xy 163.508418 -276.23585) (xy 163.461147 -276.249542)
			(xy 163.412292 -276.255474) (xy 163.363117 -276.253493) (xy 163.314898 -276.243649) (xy 163.268882 -276.226197)
			(xy 163.226261 -276.20159) (xy 163.18814 -276.170465) (xy 163.155505 -276.133628) (xy 163.129202 -276.092032)
			(xy 163.109911 -276.046756) (xy 163.098134 -275.998972) (xy 163.094174 -275.949918) (xy 161.805366 -275.949918)
			(xy 161.804871 -275.974525) (xy 161.796976 -276.023102) (xy 161.781392 -276.069783) (xy 161.758521 -276.11336)
			(xy 161.728956 -276.152704) (xy 161.693463 -276.186796) (xy 161.65296 -276.214752) (xy 161.608498 -276.23585)
			(xy 161.561227 -276.249542) (xy 161.512372 -276.255474) (xy 161.463197 -276.253493) (xy 161.414978 -276.243649)
			(xy 161.368962 -276.226197) (xy 161.326341 -276.20159) (xy 161.28822 -276.170465) (xy 161.255585 -276.133628)
			(xy 161.229282 -276.092032) (xy 161.209991 -276.046756) (xy 161.198214 -275.998972) (xy 161.194254 -275.949918)
			(xy 79.904844 -275.949918) (xy 79.904349 -275.974525) (xy 79.896454 -276.023102) (xy 79.88087 -276.069783)
			(xy 79.857999 -276.11336) (xy 79.828434 -276.152704) (xy 79.792941 -276.186796) (xy 79.752438 -276.214752)
			(xy 79.707976 -276.23585) (xy 79.660705 -276.249542) (xy 79.61185 -276.255474) (xy 79.562675 -276.253493)
			(xy 79.514456 -276.243649) (xy 79.46844 -276.226197) (xy 79.425819 -276.20159) (xy 79.387698 -276.170465)
			(xy 79.355063 -276.133628) (xy 79.32876 -276.092032) (xy 79.309469 -276.046756) (xy 79.297692 -275.998972)
			(xy 79.293732 -275.949918) (xy 78.004924 -275.949918) (xy 78.004429 -275.974525) (xy 77.996534 -276.023102)
			(xy 77.98095 -276.069783) (xy 77.958079 -276.11336) (xy 77.928514 -276.152704) (xy 77.893021 -276.186796)
			(xy 77.852518 -276.214752) (xy 77.808056 -276.23585) (xy 77.760785 -276.249542) (xy 77.71193 -276.255474)
			(xy 77.662755 -276.253493) (xy 77.614536 -276.243649) (xy 77.56852 -276.226197) (xy 77.525899 -276.20159)
			(xy 77.487778 -276.170465) (xy 77.455143 -276.133628) (xy 77.42884 -276.092032) (xy 77.409549 -276.046756)
			(xy 77.397772 -275.998972) (xy 77.393812 -275.949918) (xy 76.104999 -275.949918) (xy 76.104509 -275.974271)
			(xy 76.096614 -276.022848) (xy 76.08103 -276.069529) (xy 76.058159 -276.113106) (xy 76.028594 -276.15245)
			(xy 75.993101 -276.186542) (xy 75.952598 -276.214498) (xy 75.908136 -276.235596) (xy 75.860865 -276.249288)
			(xy 75.81201 -276.25522) (xy 75.762835 -276.253239) (xy 75.714616 -276.243395) (xy 75.6686 -276.225943)
			(xy 75.625979 -276.201336) (xy 75.587858 -276.170211) (xy 75.555223 -276.133374) (xy 75.52892 -276.091778)
			(xy 75.509629 -276.046502) (xy 75.497852 -275.998718) (xy 75.493892 -275.949664) (xy 74.204825 -275.949664)
			(xy 74.20483 -275.949918) (xy 74.204335 -275.974525) (xy 74.19644 -276.023102) (xy 74.180856 -276.069783)
			(xy 74.157985 -276.11336) (xy 74.12842 -276.152704) (xy 74.092927 -276.186796) (xy 74.052424 -276.214752)
			(xy 74.007962 -276.23585) (xy 73.960691 -276.249542) (xy 73.911836 -276.255474) (xy 73.862661 -276.253493)
			(xy 73.814442 -276.243649) (xy 73.768426 -276.226197) (xy 73.725805 -276.20159) (xy 73.687684 -276.170465)
			(xy 73.655049 -276.133628) (xy 73.628746 -276.092032) (xy 73.609455 -276.046756) (xy 73.597678 -275.998972)
			(xy 73.593718 -275.949918) (xy 72.304905 -275.949918) (xy 72.304415 -275.974271) (xy 72.29652 -276.022848)
			(xy 72.280936 -276.069529) (xy 72.258065 -276.113106) (xy 72.2285 -276.15245) (xy 72.193007 -276.186542)
			(xy 72.152504 -276.214498) (xy 72.108042 -276.235596) (xy 72.060771 -276.249288) (xy 72.011916 -276.25522)
			(xy 71.962741 -276.253239) (xy 71.914522 -276.243395) (xy 71.868506 -276.225943) (xy 71.825885 -276.201336)
			(xy 71.787764 -276.170211) (xy 71.755129 -276.133374) (xy 71.728826 -276.091778) (xy 71.709535 -276.046502)
			(xy 71.697758 -275.998718) (xy 71.693798 -275.949664) (xy 70.404731 -275.949664) (xy 70.404736 -275.949918)
			(xy 70.404241 -275.974525) (xy 70.396346 -276.023102) (xy 70.380762 -276.069783) (xy 70.357891 -276.11336)
			(xy 70.328326 -276.152704) (xy 70.292833 -276.186796) (xy 70.25233 -276.214752) (xy 70.207868 -276.23585)
			(xy 70.160597 -276.249542) (xy 70.111742 -276.255474) (xy 70.062567 -276.253493) (xy 70.014348 -276.243649)
			(xy 69.968332 -276.226197) (xy 69.925711 -276.20159) (xy 69.88759 -276.170465) (xy 69.854955 -276.133628)
			(xy 69.828652 -276.092032) (xy 69.809361 -276.046756) (xy 69.797584 -275.998972) (xy 69.793624 -275.949918)
			(xy 68.504811 -275.949918) (xy 68.504321 -275.974271) (xy 68.496426 -276.022848) (xy 68.480842 -276.069529)
			(xy 68.457971 -276.113106) (xy 68.428406 -276.15245) (xy 68.392913 -276.186542) (xy 68.35241 -276.214498)
			(xy 68.307948 -276.235596) (xy 68.260677 -276.249288) (xy 68.211822 -276.25522) (xy 68.162647 -276.253239)
			(xy 68.114428 -276.243395) (xy 68.068412 -276.225943) (xy 68.025791 -276.201336) (xy 67.98767 -276.170211)
			(xy 67.955035 -276.133374) (xy 67.928732 -276.091778) (xy 67.909441 -276.046502) (xy 67.897664 -275.998718)
			(xy 67.893704 -275.949664) (xy 66.604891 -275.949664) (xy 66.604896 -275.949918) (xy 66.604401 -275.974525)
			(xy 66.596506 -276.023102) (xy 66.580922 -276.069783) (xy 66.558051 -276.11336) (xy 66.528486 -276.152704)
			(xy 66.492993 -276.186796) (xy 66.45249 -276.214752) (xy 66.408028 -276.23585) (xy 66.360757 -276.249542)
			(xy 66.311902 -276.255474) (xy 66.262727 -276.253493) (xy 66.214508 -276.243649) (xy 66.168492 -276.226197)
			(xy 66.125871 -276.20159) (xy 66.08775 -276.170465) (xy 66.055115 -276.133628) (xy 66.028812 -276.092032)
			(xy 66.009521 -276.046756) (xy 65.997744 -275.998972) (xy 65.993784 -275.949918) (xy 64.704971 -275.949918)
			(xy 64.704481 -275.974271) (xy 64.696586 -276.022848) (xy 64.681002 -276.069529) (xy 64.658131 -276.113106)
			(xy 64.628566 -276.15245) (xy 64.593073 -276.186542) (xy 64.55257 -276.214498) (xy 64.508108 -276.235596)
			(xy 64.460837 -276.249288) (xy 64.411982 -276.25522) (xy 64.362807 -276.253239) (xy 64.314588 -276.243395)
			(xy 64.268572 -276.225943) (xy 64.225951 -276.201336) (xy 64.18783 -276.170211) (xy 64.155195 -276.133374)
			(xy 64.128892 -276.091778) (xy 64.109601 -276.046502) (xy 64.097824 -275.998718) (xy 64.093864 -275.949664)
			(xy 62.804797 -275.949664) (xy 62.804802 -275.949918) (xy 62.804307 -275.974525) (xy 62.796412 -276.023102)
			(xy 62.780828 -276.069783) (xy 62.757957 -276.11336) (xy 62.728392 -276.152704) (xy 62.692899 -276.186796)
			(xy 62.652396 -276.214752) (xy 62.607934 -276.23585) (xy 62.560663 -276.249542) (xy 62.511808 -276.255474)
			(xy 62.462633 -276.253493) (xy 62.414414 -276.243649) (xy 62.368398 -276.226197) (xy 62.325777 -276.20159)
			(xy 62.287656 -276.170465) (xy 62.255021 -276.133628) (xy 62.228718 -276.092032) (xy 62.209427 -276.046756)
			(xy 62.19765 -275.998972) (xy 62.19369 -275.949918) (xy 60.904877 -275.949918) (xy 60.904387 -275.974271)
			(xy 60.896492 -276.022848) (xy 60.880908 -276.069529) (xy 60.858037 -276.113106) (xy 60.828472 -276.15245)
			(xy 60.792979 -276.186542) (xy 60.752476 -276.214498) (xy 60.708014 -276.235596) (xy 60.660743 -276.249288)
			(xy 60.611888 -276.25522) (xy 60.562713 -276.253239) (xy 60.514494 -276.243395) (xy 60.468478 -276.225943)
			(xy 60.425857 -276.201336) (xy 60.387736 -276.170211) (xy 60.355101 -276.133374) (xy 60.328798 -276.091778)
			(xy 60.309507 -276.046502) (xy 60.29773 -275.998718) (xy 60.29377 -275.949664) (xy 59.005211 -275.949664)
			(xy 59.005216 -275.949918) (xy 59.004721 -275.974525) (xy 58.996826 -276.023102) (xy 58.981242 -276.069783)
			(xy 58.958371 -276.11336) (xy 58.928806 -276.152704) (xy 58.893313 -276.186796) (xy 58.85281 -276.214752)
			(xy 58.808348 -276.23585) (xy 58.761077 -276.249542) (xy 58.712222 -276.255474) (xy 58.663047 -276.253493)
			(xy 58.614828 -276.243649) (xy 58.568812 -276.226197) (xy 58.526191 -276.20159) (xy 58.48807 -276.170465)
			(xy 58.455435 -276.133628) (xy 58.429132 -276.092032) (xy 58.409841 -276.046756) (xy 58.398064 -275.998972)
			(xy 58.394104 -275.949918) (xy 57.105296 -275.949918) (xy 57.104801 -275.974525) (xy 57.096906 -276.023102)
			(xy 57.081322 -276.069783) (xy 57.058451 -276.11336) (xy 57.028886 -276.152704) (xy 56.993393 -276.186796)
			(xy 56.95289 -276.214752) (xy 56.908428 -276.23585) (xy 56.861157 -276.249542) (xy 56.812302 -276.255474)
			(xy 56.763127 -276.253493) (xy 56.714908 -276.243649) (xy 56.668892 -276.226197) (xy 56.626271 -276.20159)
			(xy 56.58815 -276.170465) (xy 56.555515 -276.133628) (xy 56.529212 -276.092032) (xy 56.509921 -276.046756)
			(xy 56.498144 -275.998972) (xy 56.494184 -275.949918) (xy 55.205122 -275.949918) (xy 55.204627 -275.974525)
			(xy 55.196732 -276.023102) (xy 55.181148 -276.069783) (xy 55.158277 -276.11336) (xy 55.128712 -276.152704)
			(xy 55.093219 -276.186796) (xy 55.052716 -276.214752) (xy 55.008254 -276.23585) (xy 54.960983 -276.249542)
			(xy 54.912128 -276.255474) (xy 54.862953 -276.253493) (xy 54.814734 -276.243649) (xy 54.768718 -276.226197)
			(xy 54.726097 -276.20159) (xy 54.687976 -276.170465) (xy 54.655341 -276.133628) (xy 54.629038 -276.092032)
			(xy 54.609747 -276.046756) (xy 54.59797 -275.998972) (xy 54.59401 -275.949918) (xy 53.305202 -275.949918)
			(xy 53.304707 -275.974525) (xy 53.296812 -276.023102) (xy 53.281228 -276.069783) (xy 53.258357 -276.11336)
			(xy 53.228792 -276.152704) (xy 53.193299 -276.186796) (xy 53.152796 -276.214752) (xy 53.108334 -276.23585)
			(xy 53.061063 -276.249542) (xy 53.012208 -276.255474) (xy 52.963033 -276.253493) (xy 52.914814 -276.243649)
			(xy 52.868798 -276.226197) (xy 52.826177 -276.20159) (xy 52.788056 -276.170465) (xy 52.755421 -276.133628)
			(xy 52.729118 -276.092032) (xy 52.709827 -276.046756) (xy 52.69805 -275.998972) (xy 52.69409 -275.949918)
			(xy 51.405282 -275.949918) (xy 51.404787 -275.974525) (xy 51.396892 -276.023102) (xy 51.381308 -276.069783)
			(xy 51.358437 -276.11336) (xy 51.328872 -276.152704) (xy 51.293379 -276.186796) (xy 51.252876 -276.214752)
			(xy 51.208414 -276.23585) (xy 51.161143 -276.249542) (xy 51.112288 -276.255474) (xy 51.063113 -276.253493)
			(xy 51.014894 -276.243649) (xy 50.968878 -276.226197) (xy 50.926257 -276.20159) (xy 50.888136 -276.170465)
			(xy 50.855501 -276.133628) (xy 50.829198 -276.092032) (xy 50.809907 -276.046756) (xy 50.79813 -275.998972)
			(xy 50.79417 -275.949918) (xy 49.505108 -275.949918) (xy 49.504613 -275.974525) (xy 49.496718 -276.023102)
			(xy 49.481134 -276.069783) (xy 49.458263 -276.11336) (xy 49.428698 -276.152704) (xy 49.393205 -276.186796)
			(xy 49.352702 -276.214752) (xy 49.30824 -276.23585) (xy 49.260969 -276.249542) (xy 49.212114 -276.255474)
			(xy 49.162939 -276.253493) (xy 49.11472 -276.243649) (xy 49.068704 -276.226197) (xy 49.026083 -276.20159)
			(xy 48.987962 -276.170465) (xy 48.955327 -276.133628) (xy 48.929024 -276.092032) (xy 48.909733 -276.046756)
			(xy 48.897956 -275.998972) (xy 48.893996 -275.949918) (xy 47.605188 -275.949918) (xy 47.604693 -275.974525)
			(xy 47.596798 -276.023102) (xy 47.581214 -276.069783) (xy 47.558343 -276.11336) (xy 47.528778 -276.152704)
			(xy 47.493285 -276.186796) (xy 47.452782 -276.214752) (xy 47.40832 -276.23585) (xy 47.361049 -276.249542)
			(xy 47.312194 -276.255474) (xy 47.263019 -276.253493) (xy 47.2148 -276.243649) (xy 47.168784 -276.226197)
			(xy 47.126163 -276.20159) (xy 47.088042 -276.170465) (xy 47.055407 -276.133628) (xy 47.029104 -276.092032)
			(xy 47.009813 -276.046756) (xy 46.998036 -275.998972) (xy 46.994076 -275.949918) (xy 45.705268 -275.949918)
			(xy 45.704773 -275.974525) (xy 45.696878 -276.023102) (xy 45.681294 -276.069783) (xy 45.658423 -276.11336)
			(xy 45.628858 -276.152704) (xy 45.593365 -276.186796) (xy 45.552862 -276.214752) (xy 45.5084 -276.23585)
			(xy 45.461129 -276.249542) (xy 45.412274 -276.255474) (xy 45.363099 -276.253493) (xy 45.31488 -276.243649)
			(xy 45.268864 -276.226197) (xy 45.226243 -276.20159) (xy 45.188122 -276.170465) (xy 45.155487 -276.133628)
			(xy 45.129184 -276.092032) (xy 45.109893 -276.046756) (xy 45.098116 -275.998972) (xy 45.094156 -275.949918)
			(xy 0.508 -275.949918) (xy 0.508 -276.899878) (xy 81.19416 -276.899878) (xy 81.19812 -276.850824)
			(xy 81.209897 -276.80304) (xy 81.229188 -276.757764) (xy 81.255491 -276.716168) (xy 81.288126 -276.679331)
			(xy 81.326247 -276.648206) (xy 81.368868 -276.623599) (xy 81.414884 -276.606147) (xy 81.463103 -276.596303)
			(xy 81.512278 -276.594322) (xy 81.561133 -276.600254) (xy 81.608404 -276.613946) (xy 81.652866 -276.635044)
			(xy 81.693369 -276.663) (xy 81.728862 -276.697092) (xy 81.758427 -276.736436) (xy 81.781298 -276.780013)
			(xy 81.796882 -276.826694) (xy 81.804777 -276.875271) (xy 81.805272 -276.899878) (xy 82.14412 -276.899878)
			(xy 82.14808 -276.850824) (xy 82.159857 -276.80304) (xy 82.179148 -276.757764) (xy 82.205451 -276.716168)
			(xy 82.238086 -276.679331) (xy 82.276207 -276.648206) (xy 82.318828 -276.623599) (xy 82.364844 -276.606147)
			(xy 82.413063 -276.596303) (xy 82.462238 -276.594322) (xy 82.511093 -276.600254) (xy 82.558364 -276.613946)
			(xy 82.602826 -276.635044) (xy 82.643329 -276.663) (xy 82.678822 -276.697092) (xy 82.708387 -276.736436)
			(xy 82.731258 -276.780013) (xy 82.746842 -276.826694) (xy 82.754737 -276.875271) (xy 82.755232 -276.899878)
			(xy 197.294258 -276.899878) (xy 197.298218 -276.850824) (xy 197.309995 -276.80304) (xy 197.329286 -276.757764)
			(xy 197.355589 -276.716168) (xy 197.388224 -276.679331) (xy 197.426345 -276.648206) (xy 197.468966 -276.623599)
			(xy 197.514982 -276.606147) (xy 197.563201 -276.596303) (xy 197.612376 -276.594322) (xy 197.661231 -276.600254)
			(xy 197.708502 -276.613946) (xy 197.752964 -276.635044) (xy 197.793467 -276.663) (xy 197.82896 -276.697092)
			(xy 197.858525 -276.736436) (xy 197.881396 -276.780013) (xy 197.89698 -276.826694) (xy 197.904875 -276.875271)
			(xy 197.90537 -276.899878) (xy 198.244218 -276.899878) (xy 198.248178 -276.850824) (xy 198.259955 -276.80304)
			(xy 198.279246 -276.757764) (xy 198.305549 -276.716168) (xy 198.338184 -276.679331) (xy 198.376305 -276.648206)
			(xy 198.418926 -276.623599) (xy 198.464942 -276.606147) (xy 198.513161 -276.596303) (xy 198.562336 -276.594322)
			(xy 198.611191 -276.600254) (xy 198.658462 -276.613946) (xy 198.702924 -276.635044) (xy 198.743427 -276.663)
			(xy 198.77892 -276.697092) (xy 198.808485 -276.736436) (xy 198.831356 -276.780013) (xy 198.84694 -276.826694)
			(xy 198.854835 -276.875271) (xy 198.85533 -276.899878) (xy 313.394102 -276.899878) (xy 313.398062 -276.850824)
			(xy 313.409839 -276.80304) (xy 313.42913 -276.757764) (xy 313.455433 -276.716168) (xy 313.488068 -276.679331)
			(xy 313.526189 -276.648206) (xy 313.56881 -276.623599) (xy 313.614826 -276.606147) (xy 313.663045 -276.596303)
			(xy 313.71222 -276.594322) (xy 313.761075 -276.600254) (xy 313.808346 -276.613946) (xy 313.852808 -276.635044)
			(xy 313.893311 -276.663) (xy 313.928804 -276.697092) (xy 313.958369 -276.736436) (xy 313.98124 -276.780013)
			(xy 313.996824 -276.826694) (xy 314.004719 -276.875271) (xy 314.005214 -276.899878) (xy 314.344062 -276.899878)
			(xy 314.348022 -276.850824) (xy 314.359799 -276.80304) (xy 314.37909 -276.757764) (xy 314.405393 -276.716168)
			(xy 314.438028 -276.679331) (xy 314.476149 -276.648206) (xy 314.51877 -276.623599) (xy 314.564786 -276.606147)
			(xy 314.613005 -276.596303) (xy 314.66218 -276.594322) (xy 314.711035 -276.600254) (xy 314.758306 -276.613946)
			(xy 314.802768 -276.635044) (xy 314.843271 -276.663) (xy 314.878764 -276.697092) (xy 314.908329 -276.736436)
			(xy 314.9312 -276.780013) (xy 314.946784 -276.826694) (xy 314.954679 -276.875271) (xy 314.955174 -276.899878)
			(xy 429.4942 -276.899878) (xy 429.49816 -276.850824) (xy 429.509937 -276.80304) (xy 429.529228 -276.757764)
			(xy 429.555531 -276.716168) (xy 429.588166 -276.679331) (xy 429.626287 -276.648206) (xy 429.668908 -276.623599)
			(xy 429.714924 -276.606147) (xy 429.763143 -276.596303) (xy 429.812318 -276.594322) (xy 429.861173 -276.600254)
			(xy 429.908444 -276.613946) (xy 429.952906 -276.635044) (xy 429.993409 -276.663) (xy 430.028902 -276.697092)
			(xy 430.058467 -276.736436) (xy 430.081338 -276.780013) (xy 430.096922 -276.826694) (xy 430.104817 -276.875271)
			(xy 430.105312 -276.899878) (xy 430.44416 -276.899878) (xy 430.44812 -276.850824) (xy 430.459897 -276.80304)
			(xy 430.479188 -276.757764) (xy 430.505491 -276.716168) (xy 430.538126 -276.679331) (xy 430.576247 -276.648206)
			(xy 430.618868 -276.623599) (xy 430.664884 -276.606147) (xy 430.713103 -276.596303) (xy 430.762278 -276.594322)
			(xy 430.811133 -276.600254) (xy 430.858404 -276.613946) (xy 430.902866 -276.635044) (xy 430.943369 -276.663)
			(xy 430.978862 -276.697092) (xy 431.008427 -276.736436) (xy 431.031298 -276.780013) (xy 431.046882 -276.826694)
			(xy 431.054777 -276.875271) (xy 431.055272 -276.899878) (xy 431.054777 -276.924485) (xy 431.046882 -276.973062)
			(xy 431.031298 -277.019743) (xy 431.008427 -277.06332) (xy 430.978862 -277.102664) (xy 430.943369 -277.136756)
			(xy 430.902866 -277.164712) (xy 430.858404 -277.18581) (xy 430.811133 -277.199502) (xy 430.762278 -277.205434)
			(xy 430.713103 -277.203453) (xy 430.664884 -277.193609) (xy 430.618868 -277.176157) (xy 430.576247 -277.15155)
			(xy 430.538126 -277.120425) (xy 430.505491 -277.083588) (xy 430.479188 -277.041992) (xy 430.459897 -276.996716)
			(xy 430.44812 -276.948932) (xy 430.44416 -276.899878) (xy 430.105312 -276.899878) (xy 430.104817 -276.924485)
			(xy 430.096922 -276.973062) (xy 430.081338 -277.019743) (xy 430.058467 -277.06332) (xy 430.028902 -277.102664)
			(xy 429.993409 -277.136756) (xy 429.952906 -277.164712) (xy 429.908444 -277.18581) (xy 429.861173 -277.199502)
			(xy 429.812318 -277.205434) (xy 429.763143 -277.203453) (xy 429.714924 -277.193609) (xy 429.668908 -277.176157)
			(xy 429.626287 -277.15155) (xy 429.588166 -277.120425) (xy 429.555531 -277.083588) (xy 429.529228 -277.041992)
			(xy 429.509937 -276.996716) (xy 429.49816 -276.948932) (xy 429.4942 -276.899878) (xy 314.955174 -276.899878)
			(xy 314.954679 -276.924485) (xy 314.946784 -276.973062) (xy 314.9312 -277.019743) (xy 314.908329 -277.06332)
			(xy 314.878764 -277.102664) (xy 314.843271 -277.136756) (xy 314.802768 -277.164712) (xy 314.758306 -277.18581)
			(xy 314.711035 -277.199502) (xy 314.66218 -277.205434) (xy 314.613005 -277.203453) (xy 314.564786 -277.193609)
			(xy 314.51877 -277.176157) (xy 314.476149 -277.15155) (xy 314.438028 -277.120425) (xy 314.405393 -277.083588)
			(xy 314.37909 -277.041992) (xy 314.359799 -276.996716) (xy 314.348022 -276.948932) (xy 314.344062 -276.899878)
			(xy 314.005214 -276.899878) (xy 314.004719 -276.924485) (xy 313.996824 -276.973062) (xy 313.98124 -277.019743)
			(xy 313.958369 -277.06332) (xy 313.928804 -277.102664) (xy 313.893311 -277.136756) (xy 313.852808 -277.164712)
			(xy 313.808346 -277.18581) (xy 313.761075 -277.199502) (xy 313.71222 -277.205434) (xy 313.663045 -277.203453)
			(xy 313.614826 -277.193609) (xy 313.56881 -277.176157) (xy 313.526189 -277.15155) (xy 313.488068 -277.120425)
			(xy 313.455433 -277.083588) (xy 313.42913 -277.041992) (xy 313.409839 -276.996716) (xy 313.398062 -276.948932)
			(xy 313.394102 -276.899878) (xy 198.85533 -276.899878) (xy 198.854835 -276.924485) (xy 198.84694 -276.973062)
			(xy 198.831356 -277.019743) (xy 198.808485 -277.06332) (xy 198.77892 -277.102664) (xy 198.743427 -277.136756)
			(xy 198.702924 -277.164712) (xy 198.658462 -277.18581) (xy 198.611191 -277.199502) (xy 198.562336 -277.205434)
			(xy 198.513161 -277.203453) (xy 198.464942 -277.193609) (xy 198.418926 -277.176157) (xy 198.376305 -277.15155)
			(xy 198.338184 -277.120425) (xy 198.305549 -277.083588) (xy 198.279246 -277.041992) (xy 198.259955 -276.996716)
			(xy 198.248178 -276.948932) (xy 198.244218 -276.899878) (xy 197.90537 -276.899878) (xy 197.904875 -276.924485)
			(xy 197.89698 -276.973062) (xy 197.881396 -277.019743) (xy 197.858525 -277.06332) (xy 197.82896 -277.102664)
			(xy 197.793467 -277.136756) (xy 197.752964 -277.164712) (xy 197.708502 -277.18581) (xy 197.661231 -277.199502)
			(xy 197.612376 -277.205434) (xy 197.563201 -277.203453) (xy 197.514982 -277.193609) (xy 197.468966 -277.176157)
			(xy 197.426345 -277.15155) (xy 197.388224 -277.120425) (xy 197.355589 -277.083588) (xy 197.329286 -277.041992)
			(xy 197.309995 -276.996716) (xy 197.298218 -276.948932) (xy 197.294258 -276.899878) (xy 82.755232 -276.899878)
			(xy 82.754737 -276.924485) (xy 82.746842 -276.973062) (xy 82.731258 -277.019743) (xy 82.708387 -277.06332)
			(xy 82.678822 -277.102664) (xy 82.643329 -277.136756) (xy 82.602826 -277.164712) (xy 82.558364 -277.18581)
			(xy 82.511093 -277.199502) (xy 82.462238 -277.205434) (xy 82.413063 -277.203453) (xy 82.364844 -277.193609)
			(xy 82.318828 -277.176157) (xy 82.276207 -277.15155) (xy 82.238086 -277.120425) (xy 82.205451 -277.083588)
			(xy 82.179148 -277.041992) (xy 82.159857 -276.996716) (xy 82.14808 -276.948932) (xy 82.14412 -276.899878)
			(xy 81.805272 -276.899878) (xy 81.804777 -276.924485) (xy 81.796882 -276.973062) (xy 81.781298 -277.019743)
			(xy 81.758427 -277.06332) (xy 81.728862 -277.102664) (xy 81.693369 -277.136756) (xy 81.652866 -277.164712)
			(xy 81.608404 -277.18581) (xy 81.561133 -277.199502) (xy 81.512278 -277.205434) (xy 81.463103 -277.203453)
			(xy 81.414884 -277.193609) (xy 81.368868 -277.176157) (xy 81.326247 -277.15155) (xy 81.288126 -277.120425)
			(xy 81.255491 -277.083588) (xy 81.229188 -277.041992) (xy 81.209897 -276.996716) (xy 81.19812 -276.948932)
			(xy 81.19416 -276.899878) (xy 0.508 -276.899878) (xy 0.508 -277.849838) (xy 44.143942 -277.849838)
			(xy 44.147902 -277.800784) (xy 44.159679 -277.753) (xy 44.17897 -277.707724) (xy 44.205273 -277.666128)
			(xy 44.237908 -277.629291) (xy 44.276029 -277.598166) (xy 44.31865 -277.573559) (xy 44.364666 -277.556107)
			(xy 44.412885 -277.546263) (xy 44.46206 -277.544282) (xy 44.510915 -277.550214) (xy 44.558186 -277.563906)
			(xy 44.602648 -277.585004) (xy 44.643151 -277.61296) (xy 44.678644 -277.647052) (xy 44.708209 -277.686396)
			(xy 44.73108 -277.729973) (xy 44.746664 -277.776654) (xy 44.754559 -277.825231) (xy 44.755054 -277.849838)
			(xy 46.044116 -277.849838) (xy 46.048076 -277.800784) (xy 46.059853 -277.753) (xy 46.079144 -277.707724)
			(xy 46.105447 -277.666128) (xy 46.138082 -277.629291) (xy 46.176203 -277.598166) (xy 46.218824 -277.573559)
			(xy 46.26484 -277.556107) (xy 46.313059 -277.546263) (xy 46.362234 -277.544282) (xy 46.411089 -277.550214)
			(xy 46.45836 -277.563906) (xy 46.502822 -277.585004) (xy 46.543325 -277.61296) (xy 46.578818 -277.647052)
			(xy 46.608383 -277.686396) (xy 46.631254 -277.729973) (xy 46.646838 -277.776654) (xy 46.654733 -277.825231)
			(xy 46.655228 -277.849838) (xy 47.944036 -277.849838) (xy 47.947996 -277.800784) (xy 47.959773 -277.753)
			(xy 47.979064 -277.707724) (xy 48.005367 -277.666128) (xy 48.038002 -277.629291) (xy 48.076123 -277.598166)
			(xy 48.118744 -277.573559) (xy 48.16476 -277.556107) (xy 48.212979 -277.546263) (xy 48.262154 -277.544282)
			(xy 48.311009 -277.550214) (xy 48.35828 -277.563906) (xy 48.402742 -277.585004) (xy 48.443245 -277.61296)
			(xy 48.478738 -277.647052) (xy 48.508303 -277.686396) (xy 48.531174 -277.729973) (xy 48.546758 -277.776654)
			(xy 48.554653 -277.825231) (xy 48.555148 -277.849838) (xy 49.843956 -277.849838) (xy 49.847916 -277.800784)
			(xy 49.859693 -277.753) (xy 49.878984 -277.707724) (xy 49.905287 -277.666128) (xy 49.937922 -277.629291)
			(xy 49.976043 -277.598166) (xy 50.018664 -277.573559) (xy 50.06468 -277.556107) (xy 50.112899 -277.546263)
			(xy 50.162074 -277.544282) (xy 50.210929 -277.550214) (xy 50.2582 -277.563906) (xy 50.302662 -277.585004)
			(xy 50.343165 -277.61296) (xy 50.378658 -277.647052) (xy 50.408223 -277.686396) (xy 50.431094 -277.729973)
			(xy 50.446678 -277.776654) (xy 50.454573 -277.825231) (xy 50.455068 -277.849838) (xy 51.74413 -277.849838)
			(xy 51.74809 -277.800784) (xy 51.759867 -277.753) (xy 51.779158 -277.707724) (xy 51.805461 -277.666128)
			(xy 51.838096 -277.629291) (xy 51.876217 -277.598166) (xy 51.918838 -277.573559) (xy 51.964854 -277.556107)
			(xy 52.013073 -277.546263) (xy 52.062248 -277.544282) (xy 52.111103 -277.550214) (xy 52.158374 -277.563906)
			(xy 52.202836 -277.585004) (xy 52.243339 -277.61296) (xy 52.278832 -277.647052) (xy 52.308397 -277.686396)
			(xy 52.331268 -277.729973) (xy 52.346852 -277.776654) (xy 52.354747 -277.825231) (xy 52.355242 -277.849838)
			(xy 53.64405 -277.849838) (xy 53.64801 -277.800784) (xy 53.659787 -277.753) (xy 53.679078 -277.707724)
			(xy 53.705381 -277.666128) (xy 53.738016 -277.629291) (xy 53.776137 -277.598166) (xy 53.818758 -277.573559)
			(xy 53.864774 -277.556107) (xy 53.912993 -277.546263) (xy 53.962168 -277.544282) (xy 54.011023 -277.550214)
			(xy 54.058294 -277.563906) (xy 54.102756 -277.585004) (xy 54.143259 -277.61296) (xy 54.178752 -277.647052)
			(xy 54.208317 -277.686396) (xy 54.231188 -277.729973) (xy 54.246772 -277.776654) (xy 54.254667 -277.825231)
			(xy 54.255162 -277.849838) (xy 55.54397 -277.849838) (xy 55.54793 -277.800784) (xy 55.559707 -277.753)
			(xy 55.578998 -277.707724) (xy 55.605301 -277.666128) (xy 55.637936 -277.629291) (xy 55.676057 -277.598166)
			(xy 55.718678 -277.573559) (xy 55.764694 -277.556107) (xy 55.812913 -277.546263) (xy 55.862088 -277.544282)
			(xy 55.910943 -277.550214) (xy 55.958214 -277.563906) (xy 56.002676 -277.585004) (xy 56.043179 -277.61296)
			(xy 56.078672 -277.647052) (xy 56.108237 -277.686396) (xy 56.131108 -277.729973) (xy 56.146692 -277.776654)
			(xy 56.154587 -277.825231) (xy 56.155082 -277.849838) (xy 57.444144 -277.849838) (xy 57.448104 -277.800784)
			(xy 57.459881 -277.753) (xy 57.479172 -277.707724) (xy 57.505475 -277.666128) (xy 57.53811 -277.629291)
			(xy 57.576231 -277.598166) (xy 57.618852 -277.573559) (xy 57.664868 -277.556107) (xy 57.713087 -277.546263)
			(xy 57.762262 -277.544282) (xy 57.811117 -277.550214) (xy 57.858388 -277.563906) (xy 57.90285 -277.585004)
			(xy 57.943353 -277.61296) (xy 57.978846 -277.647052) (xy 58.008411 -277.686396) (xy 58.031282 -277.729973)
			(xy 58.046866 -277.776654) (xy 58.054761 -277.825231) (xy 58.055256 -277.849838) (xy 59.34381 -277.849838)
			(xy 59.34777 -277.800784) (xy 59.359547 -277.753) (xy 59.378838 -277.707724) (xy 59.405141 -277.666128)
			(xy 59.437776 -277.629291) (xy 59.475897 -277.598166) (xy 59.518518 -277.573559) (xy 59.564534 -277.556107)
			(xy 59.612753 -277.546263) (xy 59.661928 -277.544282) (xy 59.710783 -277.550214) (xy 59.758054 -277.563906)
			(xy 59.802516 -277.585004) (xy 59.843019 -277.61296) (xy 59.878512 -277.647052) (xy 59.908077 -277.686396)
			(xy 59.930948 -277.729973) (xy 59.946532 -277.776654) (xy 59.954427 -277.825231) (xy 59.954922 -277.849838)
			(xy 61.24373 -277.849838) (xy 61.24769 -277.800784) (xy 61.259467 -277.753) (xy 61.278758 -277.707724)
			(xy 61.305061 -277.666128) (xy 61.337696 -277.629291) (xy 61.375817 -277.598166) (xy 61.418438 -277.573559)
			(xy 61.464454 -277.556107) (xy 61.512673 -277.546263) (xy 61.561848 -277.544282) (xy 61.610703 -277.550214)
			(xy 61.657974 -277.563906) (xy 61.702436 -277.585004) (xy 61.742939 -277.61296) (xy 61.778432 -277.647052)
			(xy 61.807997 -277.686396) (xy 61.830868 -277.729973) (xy 61.846452 -277.776654) (xy 61.854347 -277.825231)
			(xy 61.854842 -277.849838) (xy 63.143904 -277.849838) (xy 63.147864 -277.800784) (xy 63.159641 -277.753)
			(xy 63.178932 -277.707724) (xy 63.205235 -277.666128) (xy 63.23787 -277.629291) (xy 63.275991 -277.598166)
			(xy 63.318612 -277.573559) (xy 63.364628 -277.556107) (xy 63.412847 -277.546263) (xy 63.462022 -277.544282)
			(xy 63.510877 -277.550214) (xy 63.558148 -277.563906) (xy 63.60261 -277.585004) (xy 63.643113 -277.61296)
			(xy 63.678606 -277.647052) (xy 63.708171 -277.686396) (xy 63.731042 -277.729973) (xy 63.746626 -277.776654)
			(xy 63.754521 -277.825231) (xy 63.755016 -277.849838) (xy 65.043824 -277.849838) (xy 65.047784 -277.800784)
			(xy 65.059561 -277.753) (xy 65.078852 -277.707724) (xy 65.105155 -277.666128) (xy 65.13779 -277.629291)
			(xy 65.175911 -277.598166) (xy 65.218532 -277.573559) (xy 65.264548 -277.556107) (xy 65.312767 -277.546263)
			(xy 65.361942 -277.544282) (xy 65.410797 -277.550214) (xy 65.458068 -277.563906) (xy 65.50253 -277.585004)
			(xy 65.543033 -277.61296) (xy 65.578526 -277.647052) (xy 65.608091 -277.686396) (xy 65.630962 -277.729973)
			(xy 65.646546 -277.776654) (xy 65.654441 -277.825231) (xy 65.654936 -277.849838) (xy 66.943744 -277.849838)
			(xy 66.947704 -277.800784) (xy 66.959481 -277.753) (xy 66.978772 -277.707724) (xy 67.005075 -277.666128)
			(xy 67.03771 -277.629291) (xy 67.075831 -277.598166) (xy 67.118452 -277.573559) (xy 67.164468 -277.556107)
			(xy 67.212687 -277.546263) (xy 67.261862 -277.544282) (xy 67.310717 -277.550214) (xy 67.357988 -277.563906)
			(xy 67.40245 -277.585004) (xy 67.442953 -277.61296) (xy 67.478446 -277.647052) (xy 67.508011 -277.686396)
			(xy 67.530882 -277.729973) (xy 67.546466 -277.776654) (xy 67.554361 -277.825231) (xy 67.554856 -277.849838)
			(xy 68.843918 -277.849838) (xy 68.847878 -277.800784) (xy 68.859655 -277.753) (xy 68.878946 -277.707724)
			(xy 68.905249 -277.666128) (xy 68.937884 -277.629291) (xy 68.976005 -277.598166) (xy 69.018626 -277.573559)
			(xy 69.064642 -277.556107) (xy 69.112861 -277.546263) (xy 69.162036 -277.544282) (xy 69.210891 -277.550214)
			(xy 69.258162 -277.563906) (xy 69.302624 -277.585004) (xy 69.343127 -277.61296) (xy 69.37862 -277.647052)
			(xy 69.408185 -277.686396) (xy 69.431056 -277.729973) (xy 69.44664 -277.776654) (xy 69.454535 -277.825231)
			(xy 69.45503 -277.849838) (xy 70.743838 -277.849838) (xy 70.747798 -277.800784) (xy 70.759575 -277.753)
			(xy 70.778866 -277.707724) (xy 70.805169 -277.666128) (xy 70.837804 -277.629291) (xy 70.875925 -277.598166)
			(xy 70.918546 -277.573559) (xy 70.964562 -277.556107) (xy 71.012781 -277.546263) (xy 71.061956 -277.544282)
			(xy 71.110811 -277.550214) (xy 71.158082 -277.563906) (xy 71.202544 -277.585004) (xy 71.243047 -277.61296)
			(xy 71.27854 -277.647052) (xy 71.308105 -277.686396) (xy 71.330976 -277.729973) (xy 71.34656 -277.776654)
			(xy 71.354455 -277.825231) (xy 71.35495 -277.849838) (xy 72.643758 -277.849838) (xy 72.647718 -277.800784)
			(xy 72.659495 -277.753) (xy 72.678786 -277.707724) (xy 72.705089 -277.666128) (xy 72.737724 -277.629291)
			(xy 72.775845 -277.598166) (xy 72.818466 -277.573559) (xy 72.864482 -277.556107) (xy 72.912701 -277.546263)
			(xy 72.961876 -277.544282) (xy 73.010731 -277.550214) (xy 73.058002 -277.563906) (xy 73.102464 -277.585004)
			(xy 73.142967 -277.61296) (xy 73.17846 -277.647052) (xy 73.208025 -277.686396) (xy 73.230896 -277.729973)
			(xy 73.24648 -277.776654) (xy 73.254375 -277.825231) (xy 73.25487 -277.849838) (xy 74.543932 -277.849838)
			(xy 74.547892 -277.800784) (xy 74.559669 -277.753) (xy 74.57896 -277.707724) (xy 74.605263 -277.666128)
			(xy 74.637898 -277.629291) (xy 74.676019 -277.598166) (xy 74.71864 -277.573559) (xy 74.764656 -277.556107)
			(xy 74.812875 -277.546263) (xy 74.86205 -277.544282) (xy 74.910905 -277.550214) (xy 74.958176 -277.563906)
			(xy 75.002638 -277.585004) (xy 75.043141 -277.61296) (xy 75.078634 -277.647052) (xy 75.108199 -277.686396)
			(xy 75.13107 -277.729973) (xy 75.146654 -277.776654) (xy 75.154549 -277.825231) (xy 75.155044 -277.849838)
			(xy 76.443852 -277.849838) (xy 76.447812 -277.800784) (xy 76.459589 -277.753) (xy 76.47888 -277.707724)
			(xy 76.505183 -277.666128) (xy 76.537818 -277.629291) (xy 76.575939 -277.598166) (xy 76.61856 -277.573559)
			(xy 76.664576 -277.556107) (xy 76.712795 -277.546263) (xy 76.76197 -277.544282) (xy 76.810825 -277.550214)
			(xy 76.858096 -277.563906) (xy 76.902558 -277.585004) (xy 76.943061 -277.61296) (xy 76.978554 -277.647052)
			(xy 77.008119 -277.686396) (xy 77.03099 -277.729973) (xy 77.046574 -277.776654) (xy 77.054469 -277.825231)
			(xy 77.054964 -277.849838) (xy 78.343772 -277.849838) (xy 78.347732 -277.800784) (xy 78.359509 -277.753)
			(xy 78.3788 -277.707724) (xy 78.405103 -277.666128) (xy 78.437738 -277.629291) (xy 78.475859 -277.598166)
			(xy 78.51848 -277.573559) (xy 78.564496 -277.556107) (xy 78.612715 -277.546263) (xy 78.66189 -277.544282)
			(xy 78.710745 -277.550214) (xy 78.758016 -277.563906) (xy 78.802478 -277.585004) (xy 78.842981 -277.61296)
			(xy 78.878474 -277.647052) (xy 78.908039 -277.686396) (xy 78.93091 -277.729973) (xy 78.946494 -277.776654)
			(xy 78.954389 -277.825231) (xy 78.954884 -277.849838) (xy 80.243946 -277.849838) (xy 80.247906 -277.800784)
			(xy 80.259683 -277.753) (xy 80.278974 -277.707724) (xy 80.305277 -277.666128) (xy 80.337912 -277.629291)
			(xy 80.376033 -277.598166) (xy 80.418654 -277.573559) (xy 80.46467 -277.556107) (xy 80.512889 -277.546263)
			(xy 80.562064 -277.544282) (xy 80.610919 -277.550214) (xy 80.65819 -277.563906) (xy 80.702652 -277.585004)
			(xy 80.743155 -277.61296) (xy 80.778648 -277.647052) (xy 80.808213 -277.686396) (xy 80.831084 -277.729973)
			(xy 80.846668 -277.776654) (xy 80.854563 -277.825231) (xy 80.855058 -277.849838) (xy 160.24404 -277.849838)
			(xy 160.248 -277.800784) (xy 160.259777 -277.753) (xy 160.279068 -277.707724) (xy 160.305371 -277.666128)
			(xy 160.338006 -277.629291) (xy 160.376127 -277.598166) (xy 160.418748 -277.573559) (xy 160.464764 -277.556107)
			(xy 160.512983 -277.546263) (xy 160.562158 -277.544282) (xy 160.611013 -277.550214) (xy 160.658284 -277.563906)
			(xy 160.702746 -277.585004) (xy 160.743249 -277.61296) (xy 160.778742 -277.647052) (xy 160.808307 -277.686396)
			(xy 160.831178 -277.729973) (xy 160.846762 -277.776654) (xy 160.854657 -277.825231) (xy 160.855152 -277.849838)
			(xy 162.144214 -277.849838) (xy 162.148174 -277.800784) (xy 162.159951 -277.753) (xy 162.179242 -277.707724)
			(xy 162.205545 -277.666128) (xy 162.23818 -277.629291) (xy 162.276301 -277.598166) (xy 162.318922 -277.573559)
			(xy 162.364938 -277.556107) (xy 162.413157 -277.546263) (xy 162.462332 -277.544282) (xy 162.511187 -277.550214)
			(xy 162.558458 -277.563906) (xy 162.60292 -277.585004) (xy 162.643423 -277.61296) (xy 162.678916 -277.647052)
			(xy 162.708481 -277.686396) (xy 162.731352 -277.729973) (xy 162.746936 -277.776654) (xy 162.754831 -277.825231)
			(xy 162.755326 -277.849838) (xy 164.044134 -277.849838) (xy 164.048094 -277.800784) (xy 164.059871 -277.753)
			(xy 164.079162 -277.707724) (xy 164.105465 -277.666128) (xy 164.1381 -277.629291) (xy 164.176221 -277.598166)
			(xy 164.218842 -277.573559) (xy 164.264858 -277.556107) (xy 164.313077 -277.546263) (xy 164.362252 -277.544282)
			(xy 164.411107 -277.550214) (xy 164.458378 -277.563906) (xy 164.50284 -277.585004) (xy 164.543343 -277.61296)
			(xy 164.578836 -277.647052) (xy 164.608401 -277.686396) (xy 164.631272 -277.729973) (xy 164.646856 -277.776654)
			(xy 164.654751 -277.825231) (xy 164.655246 -277.849838) (xy 165.944054 -277.849838) (xy 165.948014 -277.800784)
			(xy 165.959791 -277.753) (xy 165.979082 -277.707724) (xy 166.005385 -277.666128) (xy 166.03802 -277.629291)
			(xy 166.076141 -277.598166) (xy 166.118762 -277.573559) (xy 166.164778 -277.556107) (xy 166.212997 -277.546263)
			(xy 166.262172 -277.544282) (xy 166.311027 -277.550214) (xy 166.358298 -277.563906) (xy 166.40276 -277.585004)
			(xy 166.443263 -277.61296) (xy 166.478756 -277.647052) (xy 166.508321 -277.686396) (xy 166.531192 -277.729973)
			(xy 166.546776 -277.776654) (xy 166.554671 -277.825231) (xy 166.555166 -277.849838) (xy 167.844228 -277.849838)
			(xy 167.848188 -277.800784) (xy 167.859965 -277.753) (xy 167.879256 -277.707724) (xy 167.905559 -277.666128)
			(xy 167.938194 -277.629291) (xy 167.976315 -277.598166) (xy 168.018936 -277.573559) (xy 168.064952 -277.556107)
			(xy 168.113171 -277.546263) (xy 168.162346 -277.544282) (xy 168.211201 -277.550214) (xy 168.258472 -277.563906)
			(xy 168.302934 -277.585004) (xy 168.343437 -277.61296) (xy 168.37893 -277.647052) (xy 168.408495 -277.686396)
			(xy 168.431366 -277.729973) (xy 168.44695 -277.776654) (xy 168.454845 -277.825231) (xy 168.45534 -277.849838)
			(xy 169.744148 -277.849838) (xy 169.748108 -277.800784) (xy 169.759885 -277.753) (xy 169.779176 -277.707724)
			(xy 169.805479 -277.666128) (xy 169.838114 -277.629291) (xy 169.876235 -277.598166) (xy 169.918856 -277.573559)
			(xy 169.964872 -277.556107) (xy 170.013091 -277.546263) (xy 170.062266 -277.544282) (xy 170.111121 -277.550214)
			(xy 170.158392 -277.563906) (xy 170.202854 -277.585004) (xy 170.243357 -277.61296) (xy 170.27885 -277.647052)
			(xy 170.308415 -277.686396) (xy 170.331286 -277.729973) (xy 170.34687 -277.776654) (xy 170.354765 -277.825231)
			(xy 170.35526 -277.849838) (xy 171.644068 -277.849838) (xy 171.648028 -277.800784) (xy 171.659805 -277.753)
			(xy 171.679096 -277.707724) (xy 171.705399 -277.666128) (xy 171.738034 -277.629291) (xy 171.776155 -277.598166)
			(xy 171.818776 -277.573559) (xy 171.864792 -277.556107) (xy 171.913011 -277.546263) (xy 171.962186 -277.544282)
			(xy 172.011041 -277.550214) (xy 172.058312 -277.563906) (xy 172.102774 -277.585004) (xy 172.143277 -277.61296)
			(xy 172.17877 -277.647052) (xy 172.208335 -277.686396) (xy 172.231206 -277.729973) (xy 172.24679 -277.776654)
			(xy 172.254685 -277.825231) (xy 172.25518 -277.849838) (xy 173.544242 -277.849838) (xy 173.548202 -277.800784)
			(xy 173.559979 -277.753) (xy 173.57927 -277.707724) (xy 173.605573 -277.666128) (xy 173.638208 -277.629291)
			(xy 173.676329 -277.598166) (xy 173.71895 -277.573559) (xy 173.764966 -277.556107) (xy 173.813185 -277.546263)
			(xy 173.86236 -277.544282) (xy 173.911215 -277.550214) (xy 173.958486 -277.563906) (xy 174.002948 -277.585004)
			(xy 174.043451 -277.61296) (xy 174.078944 -277.647052) (xy 174.108509 -277.686396) (xy 174.13138 -277.729973)
			(xy 174.146964 -277.776654) (xy 174.154859 -277.825231) (xy 174.155354 -277.849838) (xy 175.443908 -277.849838)
			(xy 175.447868 -277.800784) (xy 175.459645 -277.753) (xy 175.478936 -277.707724) (xy 175.505239 -277.666128)
			(xy 175.537874 -277.629291) (xy 175.575995 -277.598166) (xy 175.618616 -277.573559) (xy 175.664632 -277.556107)
			(xy 175.712851 -277.546263) (xy 175.762026 -277.544282) (xy 175.810881 -277.550214) (xy 175.858152 -277.563906)
			(xy 175.902614 -277.585004) (xy 175.943117 -277.61296) (xy 175.97861 -277.647052) (xy 176.008175 -277.686396)
			(xy 176.031046 -277.729973) (xy 176.04663 -277.776654) (xy 176.054525 -277.825231) (xy 176.05502 -277.849838)
			(xy 177.343828 -277.849838) (xy 177.347788 -277.800784) (xy 177.359565 -277.753) (xy 177.378856 -277.707724)
			(xy 177.405159 -277.666128) (xy 177.437794 -277.629291) (xy 177.475915 -277.598166) (xy 177.518536 -277.573559)
			(xy 177.564552 -277.556107) (xy 177.612771 -277.546263) (xy 177.661946 -277.544282) (xy 177.710801 -277.550214)
			(xy 177.758072 -277.563906) (xy 177.802534 -277.585004) (xy 177.843037 -277.61296) (xy 177.87853 -277.647052)
			(xy 177.908095 -277.686396) (xy 177.930966 -277.729973) (xy 177.94655 -277.776654) (xy 177.954445 -277.825231)
			(xy 177.95494 -277.849838) (xy 179.244002 -277.849838) (xy 179.247962 -277.800784) (xy 179.259739 -277.753)
			(xy 179.27903 -277.707724) (xy 179.305333 -277.666128) (xy 179.337968 -277.629291) (xy 179.376089 -277.598166)
			(xy 179.41871 -277.573559) (xy 179.464726 -277.556107) (xy 179.512945 -277.546263) (xy 179.56212 -277.544282)
			(xy 179.610975 -277.550214) (xy 179.658246 -277.563906) (xy 179.702708 -277.585004) (xy 179.743211 -277.61296)
			(xy 179.778704 -277.647052) (xy 179.808269 -277.686396) (xy 179.83114 -277.729973) (xy 179.846724 -277.776654)
			(xy 179.854619 -277.825231) (xy 179.855114 -277.849838) (xy 181.143922 -277.849838) (xy 181.147882 -277.800784)
			(xy 181.159659 -277.753) (xy 181.17895 -277.707724) (xy 181.205253 -277.666128) (xy 181.237888 -277.629291)
			(xy 181.276009 -277.598166) (xy 181.31863 -277.573559) (xy 181.364646 -277.556107) (xy 181.412865 -277.546263)
			(xy 181.46204 -277.544282) (xy 181.510895 -277.550214) (xy 181.558166 -277.563906) (xy 181.602628 -277.585004)
			(xy 181.643131 -277.61296) (xy 181.678624 -277.647052) (xy 181.708189 -277.686396) (xy 181.73106 -277.729973)
			(xy 181.746644 -277.776654) (xy 181.754539 -277.825231) (xy 181.755034 -277.849838) (xy 183.043842 -277.849838)
			(xy 183.047802 -277.800784) (xy 183.059579 -277.753) (xy 183.07887 -277.707724) (xy 183.105173 -277.666128)
			(xy 183.137808 -277.629291) (xy 183.175929 -277.598166) (xy 183.21855 -277.573559) (xy 183.264566 -277.556107)
			(xy 183.312785 -277.546263) (xy 183.36196 -277.544282) (xy 183.410815 -277.550214) (xy 183.458086 -277.563906)
			(xy 183.502548 -277.585004) (xy 183.543051 -277.61296) (xy 183.578544 -277.647052) (xy 183.608109 -277.686396)
			(xy 183.63098 -277.729973) (xy 183.646564 -277.776654) (xy 183.654459 -277.825231) (xy 183.654954 -277.849838)
			(xy 184.944016 -277.849838) (xy 184.947976 -277.800784) (xy 184.959753 -277.753) (xy 184.979044 -277.707724)
			(xy 185.005347 -277.666128) (xy 185.037982 -277.629291) (xy 185.076103 -277.598166) (xy 185.118724 -277.573559)
			(xy 185.16474 -277.556107) (xy 185.212959 -277.546263) (xy 185.262134 -277.544282) (xy 185.310989 -277.550214)
			(xy 185.35826 -277.563906) (xy 185.402722 -277.585004) (xy 185.443225 -277.61296) (xy 185.478718 -277.647052)
			(xy 185.508283 -277.686396) (xy 185.531154 -277.729973) (xy 185.546738 -277.776654) (xy 185.554633 -277.825231)
			(xy 185.555128 -277.849838) (xy 186.843936 -277.849838) (xy 186.847896 -277.800784) (xy 186.859673 -277.753)
			(xy 186.878964 -277.707724) (xy 186.905267 -277.666128) (xy 186.937902 -277.629291) (xy 186.976023 -277.598166)
			(xy 187.018644 -277.573559) (xy 187.06466 -277.556107) (xy 187.112879 -277.546263) (xy 187.162054 -277.544282)
			(xy 187.210909 -277.550214) (xy 187.25818 -277.563906) (xy 187.302642 -277.585004) (xy 187.343145 -277.61296)
			(xy 187.378638 -277.647052) (xy 187.408203 -277.686396) (xy 187.431074 -277.729973) (xy 187.446658 -277.776654)
			(xy 187.454553 -277.825231) (xy 187.455048 -277.849838) (xy 188.743856 -277.849838) (xy 188.747816 -277.800784)
			(xy 188.759593 -277.753) (xy 188.778884 -277.707724) (xy 188.805187 -277.666128) (xy 188.837822 -277.629291)
			(xy 188.875943 -277.598166) (xy 188.918564 -277.573559) (xy 188.96458 -277.556107) (xy 189.012799 -277.546263)
			(xy 189.061974 -277.544282) (xy 189.110829 -277.550214) (xy 189.1581 -277.563906) (xy 189.202562 -277.585004)
			(xy 189.243065 -277.61296) (xy 189.278558 -277.647052) (xy 189.308123 -277.686396) (xy 189.330994 -277.729973)
			(xy 189.346578 -277.776654) (xy 189.354473 -277.825231) (xy 189.354968 -277.849838) (xy 190.64403 -277.849838)
			(xy 190.64799 -277.800784) (xy 190.659767 -277.753) (xy 190.679058 -277.707724) (xy 190.705361 -277.666128)
			(xy 190.737996 -277.629291) (xy 190.776117 -277.598166) (xy 190.818738 -277.573559) (xy 190.864754 -277.556107)
			(xy 190.912973 -277.546263) (xy 190.962148 -277.544282) (xy 191.011003 -277.550214) (xy 191.058274 -277.563906)
			(xy 191.102736 -277.585004) (xy 191.143239 -277.61296) (xy 191.178732 -277.647052) (xy 191.208297 -277.686396)
			(xy 191.231168 -277.729973) (xy 191.246752 -277.776654) (xy 191.254647 -277.825231) (xy 191.255142 -277.849838)
			(xy 192.54395 -277.849838) (xy 192.54791 -277.800784) (xy 192.559687 -277.753) (xy 192.578978 -277.707724)
			(xy 192.605281 -277.666128) (xy 192.637916 -277.629291) (xy 192.676037 -277.598166) (xy 192.718658 -277.573559)
			(xy 192.764674 -277.556107) (xy 192.812893 -277.546263) (xy 192.862068 -277.544282) (xy 192.910923 -277.550214)
			(xy 192.958194 -277.563906) (xy 193.002656 -277.585004) (xy 193.043159 -277.61296) (xy 193.078652 -277.647052)
			(xy 193.108217 -277.686396) (xy 193.131088 -277.729973) (xy 193.146672 -277.776654) (xy 193.154567 -277.825231)
			(xy 193.155062 -277.849838) (xy 194.44387 -277.849838) (xy 194.44783 -277.800784) (xy 194.459607 -277.753)
			(xy 194.478898 -277.707724) (xy 194.505201 -277.666128) (xy 194.537836 -277.629291) (xy 194.575957 -277.598166)
			(xy 194.618578 -277.573559) (xy 194.664594 -277.556107) (xy 194.712813 -277.546263) (xy 194.761988 -277.544282)
			(xy 194.810843 -277.550214) (xy 194.858114 -277.563906) (xy 194.902576 -277.585004) (xy 194.943079 -277.61296)
			(xy 194.978572 -277.647052) (xy 195.008137 -277.686396) (xy 195.031008 -277.729973) (xy 195.046592 -277.776654)
			(xy 195.054487 -277.825231) (xy 195.054982 -277.849838) (xy 196.344044 -277.849838) (xy 196.348004 -277.800784)
			(xy 196.359781 -277.753) (xy 196.379072 -277.707724) (xy 196.405375 -277.666128) (xy 196.43801 -277.629291)
			(xy 196.476131 -277.598166) (xy 196.518752 -277.573559) (xy 196.564768 -277.556107) (xy 196.612987 -277.546263)
			(xy 196.662162 -277.544282) (xy 196.711017 -277.550214) (xy 196.758288 -277.563906) (xy 196.80275 -277.585004)
			(xy 196.843253 -277.61296) (xy 196.878746 -277.647052) (xy 196.908311 -277.686396) (xy 196.931182 -277.729973)
			(xy 196.946766 -277.776654) (xy 196.954661 -277.825231) (xy 196.955156 -277.849838) (xy 276.343884 -277.849838)
			(xy 276.347844 -277.800784) (xy 276.359621 -277.753) (xy 276.378912 -277.707724) (xy 276.405215 -277.666128)
			(xy 276.43785 -277.629291) (xy 276.475971 -277.598166) (xy 276.518592 -277.573559) (xy 276.564608 -277.556107)
			(xy 276.612827 -277.546263) (xy 276.662002 -277.544282) (xy 276.710857 -277.550214) (xy 276.758128 -277.563906)
			(xy 276.80259 -277.585004) (xy 276.843093 -277.61296) (xy 276.878586 -277.647052) (xy 276.908151 -277.686396)
			(xy 276.931022 -277.729973) (xy 276.946606 -277.776654) (xy 276.954501 -277.825231) (xy 276.954996 -277.849838)
			(xy 278.244058 -277.849838) (xy 278.248018 -277.800784) (xy 278.259795 -277.753) (xy 278.279086 -277.707724)
			(xy 278.305389 -277.666128) (xy 278.338024 -277.629291) (xy 278.376145 -277.598166) (xy 278.418766 -277.573559)
			(xy 278.464782 -277.556107) (xy 278.513001 -277.546263) (xy 278.562176 -277.544282) (xy 278.611031 -277.550214)
			(xy 278.658302 -277.563906) (xy 278.702764 -277.585004) (xy 278.743267 -277.61296) (xy 278.77876 -277.647052)
			(xy 278.808325 -277.686396) (xy 278.831196 -277.729973) (xy 278.84678 -277.776654) (xy 278.854675 -277.825231)
			(xy 278.85517 -277.849838) (xy 280.143978 -277.849838) (xy 280.147938 -277.800784) (xy 280.159715 -277.753)
			(xy 280.179006 -277.707724) (xy 280.205309 -277.666128) (xy 280.237944 -277.629291) (xy 280.276065 -277.598166)
			(xy 280.318686 -277.573559) (xy 280.364702 -277.556107) (xy 280.412921 -277.546263) (xy 280.462096 -277.544282)
			(xy 280.510951 -277.550214) (xy 280.558222 -277.563906) (xy 280.602684 -277.585004) (xy 280.643187 -277.61296)
			(xy 280.67868 -277.647052) (xy 280.708245 -277.686396) (xy 280.731116 -277.729973) (xy 280.7467 -277.776654)
			(xy 280.754595 -277.825231) (xy 280.75509 -277.849838) (xy 282.043898 -277.849838) (xy 282.047858 -277.800784)
			(xy 282.059635 -277.753) (xy 282.078926 -277.707724) (xy 282.105229 -277.666128) (xy 282.137864 -277.629291)
			(xy 282.175985 -277.598166) (xy 282.218606 -277.573559) (xy 282.264622 -277.556107) (xy 282.312841 -277.546263)
			(xy 282.362016 -277.544282) (xy 282.410871 -277.550214) (xy 282.458142 -277.563906) (xy 282.502604 -277.585004)
			(xy 282.543107 -277.61296) (xy 282.5786 -277.647052) (xy 282.608165 -277.686396) (xy 282.631036 -277.729973)
			(xy 282.64662 -277.776654) (xy 282.654515 -277.825231) (xy 282.65501 -277.849838) (xy 283.944072 -277.849838)
			(xy 283.948032 -277.800784) (xy 283.959809 -277.753) (xy 283.9791 -277.707724) (xy 284.005403 -277.666128)
			(xy 284.038038 -277.629291) (xy 284.076159 -277.598166) (xy 284.11878 -277.573559) (xy 284.164796 -277.556107)
			(xy 284.213015 -277.546263) (xy 284.26219 -277.544282) (xy 284.311045 -277.550214) (xy 284.358316 -277.563906)
			(xy 284.402778 -277.585004) (xy 284.443281 -277.61296) (xy 284.478774 -277.647052) (xy 284.508339 -277.686396)
			(xy 284.53121 -277.729973) (xy 284.546794 -277.776654) (xy 284.554689 -277.825231) (xy 284.555184 -277.849838)
			(xy 285.843992 -277.849838) (xy 285.847952 -277.800784) (xy 285.859729 -277.753) (xy 285.87902 -277.707724)
			(xy 285.905323 -277.666128) (xy 285.937958 -277.629291) (xy 285.976079 -277.598166) (xy 286.0187 -277.573559)
			(xy 286.064716 -277.556107) (xy 286.112935 -277.546263) (xy 286.16211 -277.544282) (xy 286.210965 -277.550214)
			(xy 286.258236 -277.563906) (xy 286.302698 -277.585004) (xy 286.343201 -277.61296) (xy 286.378694 -277.647052)
			(xy 286.408259 -277.686396) (xy 286.43113 -277.729973) (xy 286.446714 -277.776654) (xy 286.454609 -277.825231)
			(xy 286.455104 -277.849838) (xy 287.743912 -277.849838) (xy 287.747872 -277.800784) (xy 287.759649 -277.753)
			(xy 287.77894 -277.707724) (xy 287.805243 -277.666128) (xy 287.837878 -277.629291) (xy 287.875999 -277.598166)
			(xy 287.91862 -277.573559) (xy 287.964636 -277.556107) (xy 288.012855 -277.546263) (xy 288.06203 -277.544282)
			(xy 288.110885 -277.550214) (xy 288.158156 -277.563906) (xy 288.202618 -277.585004) (xy 288.243121 -277.61296)
			(xy 288.278614 -277.647052) (xy 288.308179 -277.686396) (xy 288.33105 -277.729973) (xy 288.346634 -277.776654)
			(xy 288.354529 -277.825231) (xy 288.355024 -277.849838) (xy 289.644086 -277.849838) (xy 289.648046 -277.800784)
			(xy 289.659823 -277.753) (xy 289.679114 -277.707724) (xy 289.705417 -277.666128) (xy 289.738052 -277.629291)
			(xy 289.776173 -277.598166) (xy 289.818794 -277.573559) (xy 289.86481 -277.556107) (xy 289.913029 -277.546263)
			(xy 289.962204 -277.544282) (xy 290.011059 -277.550214) (xy 290.05833 -277.563906) (xy 290.102792 -277.585004)
			(xy 290.143295 -277.61296) (xy 290.178788 -277.647052) (xy 290.208353 -277.686396) (xy 290.231224 -277.729973)
			(xy 290.246808 -277.776654) (xy 290.254703 -277.825231) (xy 290.255198 -277.849838) (xy 291.543752 -277.849838)
			(xy 291.547712 -277.800784) (xy 291.559489 -277.753) (xy 291.57878 -277.707724) (xy 291.605083 -277.666128)
			(xy 291.637718 -277.629291) (xy 291.675839 -277.598166) (xy 291.71846 -277.573559) (xy 291.764476 -277.556107)
			(xy 291.812695 -277.546263) (xy 291.86187 -277.544282) (xy 291.910725 -277.550214) (xy 291.957996 -277.563906)
			(xy 292.002458 -277.585004) (xy 292.042961 -277.61296) (xy 292.078454 -277.647052) (xy 292.108019 -277.686396)
			(xy 292.13089 -277.729973) (xy 292.146474 -277.776654) (xy 292.154369 -277.825231) (xy 292.154864 -277.849838)
			(xy 293.443672 -277.849838) (xy 293.447632 -277.800784) (xy 293.459409 -277.753) (xy 293.4787 -277.707724)
			(xy 293.505003 -277.666128) (xy 293.537638 -277.629291) (xy 293.575759 -277.598166) (xy 293.61838 -277.573559)
			(xy 293.664396 -277.556107) (xy 293.712615 -277.546263) (xy 293.76179 -277.544282) (xy 293.810645 -277.550214)
			(xy 293.857916 -277.563906) (xy 293.902378 -277.585004) (xy 293.942881 -277.61296) (xy 293.978374 -277.647052)
			(xy 294.007939 -277.686396) (xy 294.03081 -277.729973) (xy 294.046394 -277.776654) (xy 294.054289 -277.825231)
			(xy 294.054784 -277.849838) (xy 295.343846 -277.849838) (xy 295.347806 -277.800784) (xy 295.359583 -277.753)
			(xy 295.378874 -277.707724) (xy 295.405177 -277.666128) (xy 295.437812 -277.629291) (xy 295.475933 -277.598166)
			(xy 295.518554 -277.573559) (xy 295.56457 -277.556107) (xy 295.612789 -277.546263) (xy 295.661964 -277.544282)
			(xy 295.710819 -277.550214) (xy 295.75809 -277.563906) (xy 295.802552 -277.585004) (xy 295.843055 -277.61296)
			(xy 295.878548 -277.647052) (xy 295.908113 -277.686396) (xy 295.930984 -277.729973) (xy 295.946568 -277.776654)
			(xy 295.954463 -277.825231) (xy 295.954958 -277.849838) (xy 297.243766 -277.849838) (xy 297.247726 -277.800784)
			(xy 297.259503 -277.753) (xy 297.278794 -277.707724) (xy 297.305097 -277.666128) (xy 297.337732 -277.629291)
			(xy 297.375853 -277.598166) (xy 297.418474 -277.573559) (xy 297.46449 -277.556107) (xy 297.512709 -277.546263)
			(xy 297.561884 -277.544282) (xy 297.610739 -277.550214) (xy 297.65801 -277.563906) (xy 297.702472 -277.585004)
			(xy 297.742975 -277.61296) (xy 297.778468 -277.647052) (xy 297.808033 -277.686396) (xy 297.830904 -277.729973)
			(xy 297.846488 -277.776654) (xy 297.854383 -277.825231) (xy 297.854878 -277.849838) (xy 299.143686 -277.849838)
			(xy 299.147646 -277.800784) (xy 299.159423 -277.753) (xy 299.178714 -277.707724) (xy 299.205017 -277.666128)
			(xy 299.237652 -277.629291) (xy 299.275773 -277.598166) (xy 299.318394 -277.573559) (xy 299.36441 -277.556107)
			(xy 299.412629 -277.546263) (xy 299.461804 -277.544282) (xy 299.510659 -277.550214) (xy 299.55793 -277.563906)
			(xy 299.602392 -277.585004) (xy 299.642895 -277.61296) (xy 299.678388 -277.647052) (xy 299.707953 -277.686396)
			(xy 299.730824 -277.729973) (xy 299.746408 -277.776654) (xy 299.754303 -277.825231) (xy 299.754798 -277.849838)
			(xy 301.04386 -277.849838) (xy 301.04782 -277.800784) (xy 301.059597 -277.753) (xy 301.078888 -277.707724)
			(xy 301.105191 -277.666128) (xy 301.137826 -277.629291) (xy 301.175947 -277.598166) (xy 301.218568 -277.573559)
			(xy 301.264584 -277.556107) (xy 301.312803 -277.546263) (xy 301.361978 -277.544282) (xy 301.410833 -277.550214)
			(xy 301.458104 -277.563906) (xy 301.502566 -277.585004) (xy 301.543069 -277.61296) (xy 301.578562 -277.647052)
			(xy 301.608127 -277.686396) (xy 301.630998 -277.729973) (xy 301.646582 -277.776654) (xy 301.654477 -277.825231)
			(xy 301.654972 -277.849838) (xy 302.94378 -277.849838) (xy 302.94774 -277.800784) (xy 302.959517 -277.753)
			(xy 302.978808 -277.707724) (xy 303.005111 -277.666128) (xy 303.037746 -277.629291) (xy 303.075867 -277.598166)
			(xy 303.118488 -277.573559) (xy 303.164504 -277.556107) (xy 303.212723 -277.546263) (xy 303.261898 -277.544282)
			(xy 303.310753 -277.550214) (xy 303.358024 -277.563906) (xy 303.402486 -277.585004) (xy 303.442989 -277.61296)
			(xy 303.478482 -277.647052) (xy 303.508047 -277.686396) (xy 303.530918 -277.729973) (xy 303.546502 -277.776654)
			(xy 303.554397 -277.825231) (xy 303.554892 -277.849838) (xy 304.8437 -277.849838) (xy 304.84766 -277.800784)
			(xy 304.859437 -277.753) (xy 304.878728 -277.707724) (xy 304.905031 -277.666128) (xy 304.937666 -277.629291)
			(xy 304.975787 -277.598166) (xy 305.018408 -277.573559) (xy 305.064424 -277.556107) (xy 305.112643 -277.546263)
			(xy 305.161818 -277.544282) (xy 305.210673 -277.550214) (xy 305.257944 -277.563906) (xy 305.302406 -277.585004)
			(xy 305.342909 -277.61296) (xy 305.378402 -277.647052) (xy 305.407967 -277.686396) (xy 305.430838 -277.729973)
			(xy 305.446422 -277.776654) (xy 305.454317 -277.825231) (xy 305.454812 -277.849838) (xy 306.743874 -277.849838)
			(xy 306.747834 -277.800784) (xy 306.759611 -277.753) (xy 306.778902 -277.707724) (xy 306.805205 -277.666128)
			(xy 306.83784 -277.629291) (xy 306.875961 -277.598166) (xy 306.918582 -277.573559) (xy 306.964598 -277.556107)
			(xy 307.012817 -277.546263) (xy 307.061992 -277.544282) (xy 307.110847 -277.550214) (xy 307.158118 -277.563906)
			(xy 307.20258 -277.585004) (xy 307.243083 -277.61296) (xy 307.278576 -277.647052) (xy 307.308141 -277.686396)
			(xy 307.331012 -277.729973) (xy 307.346596 -277.776654) (xy 307.354491 -277.825231) (xy 307.354986 -277.849838)
			(xy 308.643794 -277.849838) (xy 308.647754 -277.800784) (xy 308.659531 -277.753) (xy 308.678822 -277.707724)
			(xy 308.705125 -277.666128) (xy 308.73776 -277.629291) (xy 308.775881 -277.598166) (xy 308.818502 -277.573559)
			(xy 308.864518 -277.556107) (xy 308.912737 -277.546263) (xy 308.961912 -277.544282) (xy 309.010767 -277.550214)
			(xy 309.058038 -277.563906) (xy 309.1025 -277.585004) (xy 309.143003 -277.61296) (xy 309.178496 -277.647052)
			(xy 309.208061 -277.686396) (xy 309.230932 -277.729973) (xy 309.246516 -277.776654) (xy 309.254411 -277.825231)
			(xy 309.254906 -277.849838) (xy 310.543714 -277.849838) (xy 310.547674 -277.800784) (xy 310.559451 -277.753)
			(xy 310.578742 -277.707724) (xy 310.605045 -277.666128) (xy 310.63768 -277.629291) (xy 310.675801 -277.598166)
			(xy 310.718422 -277.573559) (xy 310.764438 -277.556107) (xy 310.812657 -277.546263) (xy 310.861832 -277.544282)
			(xy 310.910687 -277.550214) (xy 310.957958 -277.563906) (xy 311.00242 -277.585004) (xy 311.042923 -277.61296)
			(xy 311.078416 -277.647052) (xy 311.107981 -277.686396) (xy 311.130852 -277.729973) (xy 311.146436 -277.776654)
			(xy 311.154331 -277.825231) (xy 311.154826 -277.849838) (xy 312.443888 -277.849838) (xy 312.447848 -277.800784)
			(xy 312.459625 -277.753) (xy 312.478916 -277.707724) (xy 312.505219 -277.666128) (xy 312.537854 -277.629291)
			(xy 312.575975 -277.598166) (xy 312.618596 -277.573559) (xy 312.664612 -277.556107) (xy 312.712831 -277.546263)
			(xy 312.762006 -277.544282) (xy 312.810861 -277.550214) (xy 312.858132 -277.563906) (xy 312.902594 -277.585004)
			(xy 312.943097 -277.61296) (xy 312.97859 -277.647052) (xy 313.008155 -277.686396) (xy 313.031026 -277.729973)
			(xy 313.04661 -277.776654) (xy 313.054505 -277.825231) (xy 313.055 -277.849838) (xy 392.443982 -277.849838)
			(xy 392.447942 -277.800784) (xy 392.459719 -277.753) (xy 392.47901 -277.707724) (xy 392.505313 -277.666128)
			(xy 392.537948 -277.629291) (xy 392.576069 -277.598166) (xy 392.61869 -277.573559) (xy 392.664706 -277.556107)
			(xy 392.712925 -277.546263) (xy 392.7621 -277.544282) (xy 392.810955 -277.550214) (xy 392.858226 -277.563906)
			(xy 392.902688 -277.585004) (xy 392.943191 -277.61296) (xy 392.978684 -277.647052) (xy 393.008249 -277.686396)
			(xy 393.03112 -277.729973) (xy 393.046704 -277.776654) (xy 393.054599 -277.825231) (xy 393.055094 -277.849838)
			(xy 394.344156 -277.849838) (xy 394.348116 -277.800784) (xy 394.359893 -277.753) (xy 394.379184 -277.707724)
			(xy 394.405487 -277.666128) (xy 394.438122 -277.629291) (xy 394.476243 -277.598166) (xy 394.518864 -277.573559)
			(xy 394.56488 -277.556107) (xy 394.613099 -277.546263) (xy 394.662274 -277.544282) (xy 394.711129 -277.550214)
			(xy 394.7584 -277.563906) (xy 394.802862 -277.585004) (xy 394.843365 -277.61296) (xy 394.878858 -277.647052)
			(xy 394.908423 -277.686396) (xy 394.931294 -277.729973) (xy 394.946878 -277.776654) (xy 394.954773 -277.825231)
			(xy 394.955268 -277.849838) (xy 396.244076 -277.849838) (xy 396.248036 -277.800784) (xy 396.259813 -277.753)
			(xy 396.279104 -277.707724) (xy 396.305407 -277.666128) (xy 396.338042 -277.629291) (xy 396.376163 -277.598166)
			(xy 396.418784 -277.573559) (xy 396.4648 -277.556107) (xy 396.513019 -277.546263) (xy 396.562194 -277.544282)
			(xy 396.611049 -277.550214) (xy 396.65832 -277.563906) (xy 396.702782 -277.585004) (xy 396.743285 -277.61296)
			(xy 396.778778 -277.647052) (xy 396.808343 -277.686396) (xy 396.831214 -277.729973) (xy 396.846798 -277.776654)
			(xy 396.854693 -277.825231) (xy 396.855188 -277.849838) (xy 398.143996 -277.849838) (xy 398.147956 -277.800784)
			(xy 398.159733 -277.753) (xy 398.179024 -277.707724) (xy 398.205327 -277.666128) (xy 398.237962 -277.629291)
			(xy 398.276083 -277.598166) (xy 398.318704 -277.573559) (xy 398.36472 -277.556107) (xy 398.412939 -277.546263)
			(xy 398.462114 -277.544282) (xy 398.510969 -277.550214) (xy 398.55824 -277.563906) (xy 398.602702 -277.585004)
			(xy 398.643205 -277.61296) (xy 398.678698 -277.647052) (xy 398.708263 -277.686396) (xy 398.731134 -277.729973)
			(xy 398.746718 -277.776654) (xy 398.754613 -277.825231) (xy 398.755108 -277.849838) (xy 400.04417 -277.849838)
			(xy 400.04813 -277.800784) (xy 400.059907 -277.753) (xy 400.079198 -277.707724) (xy 400.105501 -277.666128)
			(xy 400.138136 -277.629291) (xy 400.176257 -277.598166) (xy 400.218878 -277.573559) (xy 400.264894 -277.556107)
			(xy 400.313113 -277.546263) (xy 400.362288 -277.544282) (xy 400.411143 -277.550214) (xy 400.458414 -277.563906)
			(xy 400.502876 -277.585004) (xy 400.543379 -277.61296) (xy 400.578872 -277.647052) (xy 400.608437 -277.686396)
			(xy 400.631308 -277.729973) (xy 400.646892 -277.776654) (xy 400.654787 -277.825231) (xy 400.655282 -277.849838)
			(xy 401.94409 -277.849838) (xy 401.94805 -277.800784) (xy 401.959827 -277.753) (xy 401.979118 -277.707724)
			(xy 402.005421 -277.666128) (xy 402.038056 -277.629291) (xy 402.076177 -277.598166) (xy 402.118798 -277.573559)
			(xy 402.164814 -277.556107) (xy 402.213033 -277.546263) (xy 402.262208 -277.544282) (xy 402.311063 -277.550214)
			(xy 402.358334 -277.563906) (xy 402.402796 -277.585004) (xy 402.443299 -277.61296) (xy 402.478792 -277.647052)
			(xy 402.508357 -277.686396) (xy 402.531228 -277.729973) (xy 402.546812 -277.776654) (xy 402.554707 -277.825231)
			(xy 402.555202 -277.849838) (xy 403.84401 -277.849838) (xy 403.84797 -277.800784) (xy 403.859747 -277.753)
			(xy 403.879038 -277.707724) (xy 403.905341 -277.666128) (xy 403.937976 -277.629291) (xy 403.976097 -277.598166)
			(xy 404.018718 -277.573559) (xy 404.064734 -277.556107) (xy 404.112953 -277.546263) (xy 404.162128 -277.544282)
			(xy 404.210983 -277.550214) (xy 404.258254 -277.563906) (xy 404.302716 -277.585004) (xy 404.343219 -277.61296)
			(xy 404.378712 -277.647052) (xy 404.408277 -277.686396) (xy 404.431148 -277.729973) (xy 404.446732 -277.776654)
			(xy 404.454627 -277.825231) (xy 404.455122 -277.849838) (xy 405.744184 -277.849838) (xy 405.748144 -277.800784)
			(xy 405.759921 -277.753) (xy 405.779212 -277.707724) (xy 405.805515 -277.666128) (xy 405.83815 -277.629291)
			(xy 405.876271 -277.598166) (xy 405.918892 -277.573559) (xy 405.964908 -277.556107) (xy 406.013127 -277.546263)
			(xy 406.062302 -277.544282) (xy 406.111157 -277.550214) (xy 406.158428 -277.563906) (xy 406.20289 -277.585004)
			(xy 406.243393 -277.61296) (xy 406.278886 -277.647052) (xy 406.308451 -277.686396) (xy 406.331322 -277.729973)
			(xy 406.346906 -277.776654) (xy 406.354801 -277.825231) (xy 406.355296 -277.849838) (xy 407.64385 -277.849838)
			(xy 407.64781 -277.800784) (xy 407.659587 -277.753) (xy 407.678878 -277.707724) (xy 407.705181 -277.666128)
			(xy 407.737816 -277.629291) (xy 407.775937 -277.598166) (xy 407.818558 -277.573559) (xy 407.864574 -277.556107)
			(xy 407.912793 -277.546263) (xy 407.961968 -277.544282) (xy 408.010823 -277.550214) (xy 408.058094 -277.563906)
			(xy 408.102556 -277.585004) (xy 408.143059 -277.61296) (xy 408.178552 -277.647052) (xy 408.208117 -277.686396)
			(xy 408.230988 -277.729973) (xy 408.246572 -277.776654) (xy 408.254467 -277.825231) (xy 408.254962 -277.849838)
			(xy 409.54377 -277.849838) (xy 409.54773 -277.800784) (xy 409.559507 -277.753) (xy 409.578798 -277.707724)
			(xy 409.605101 -277.666128) (xy 409.637736 -277.629291) (xy 409.675857 -277.598166) (xy 409.718478 -277.573559)
			(xy 409.764494 -277.556107) (xy 409.812713 -277.546263) (xy 409.861888 -277.544282) (xy 409.910743 -277.550214)
			(xy 409.958014 -277.563906) (xy 410.002476 -277.585004) (xy 410.042979 -277.61296) (xy 410.078472 -277.647052)
			(xy 410.108037 -277.686396) (xy 410.130908 -277.729973) (xy 410.146492 -277.776654) (xy 410.154387 -277.825231)
			(xy 410.154882 -277.849838) (xy 411.443944 -277.849838) (xy 411.447904 -277.800784) (xy 411.459681 -277.753)
			(xy 411.478972 -277.707724) (xy 411.505275 -277.666128) (xy 411.53791 -277.629291) (xy 411.576031 -277.598166)
			(xy 411.618652 -277.573559) (xy 411.664668 -277.556107) (xy 411.712887 -277.546263) (xy 411.762062 -277.544282)
			(xy 411.810917 -277.550214) (xy 411.858188 -277.563906) (xy 411.90265 -277.585004) (xy 411.943153 -277.61296)
			(xy 411.978646 -277.647052) (xy 412.008211 -277.686396) (xy 412.031082 -277.729973) (xy 412.046666 -277.776654)
			(xy 412.054561 -277.825231) (xy 412.055056 -277.849838) (xy 413.343864 -277.849838) (xy 413.347824 -277.800784)
			(xy 413.359601 -277.753) (xy 413.378892 -277.707724) (xy 413.405195 -277.666128) (xy 413.43783 -277.629291)
			(xy 413.475951 -277.598166) (xy 413.518572 -277.573559) (xy 413.564588 -277.556107) (xy 413.612807 -277.546263)
			(xy 413.661982 -277.544282) (xy 413.710837 -277.550214) (xy 413.758108 -277.563906) (xy 413.80257 -277.585004)
			(xy 413.843073 -277.61296) (xy 413.878566 -277.647052) (xy 413.908131 -277.686396) (xy 413.931002 -277.729973)
			(xy 413.946586 -277.776654) (xy 413.954481 -277.825231) (xy 413.954976 -277.849838) (xy 415.243784 -277.849838)
			(xy 415.247744 -277.800784) (xy 415.259521 -277.753) (xy 415.278812 -277.707724) (xy 415.305115 -277.666128)
			(xy 415.33775 -277.629291) (xy 415.375871 -277.598166) (xy 415.418492 -277.573559) (xy 415.464508 -277.556107)
			(xy 415.512727 -277.546263) (xy 415.561902 -277.544282) (xy 415.610757 -277.550214) (xy 415.658028 -277.563906)
			(xy 415.70249 -277.585004) (xy 415.742993 -277.61296) (xy 415.778486 -277.647052) (xy 415.808051 -277.686396)
			(xy 415.830922 -277.729973) (xy 415.846506 -277.776654) (xy 415.854401 -277.825231) (xy 415.854896 -277.849838)
			(xy 417.143958 -277.849838) (xy 417.147918 -277.800784) (xy 417.159695 -277.753) (xy 417.178986 -277.707724)
			(xy 417.205289 -277.666128) (xy 417.237924 -277.629291) (xy 417.276045 -277.598166) (xy 417.318666 -277.573559)
			(xy 417.364682 -277.556107) (xy 417.412901 -277.546263) (xy 417.462076 -277.544282) (xy 417.510931 -277.550214)
			(xy 417.558202 -277.563906) (xy 417.602664 -277.585004) (xy 417.643167 -277.61296) (xy 417.67866 -277.647052)
			(xy 417.708225 -277.686396) (xy 417.731096 -277.729973) (xy 417.74668 -277.776654) (xy 417.754575 -277.825231)
			(xy 417.75507 -277.849838) (xy 419.043878 -277.849838) (xy 419.047838 -277.800784) (xy 419.059615 -277.753)
			(xy 419.078906 -277.707724) (xy 419.105209 -277.666128) (xy 419.137844 -277.629291) (xy 419.175965 -277.598166)
			(xy 419.218586 -277.573559) (xy 419.264602 -277.556107) (xy 419.312821 -277.546263) (xy 419.361996 -277.544282)
			(xy 419.410851 -277.550214) (xy 419.458122 -277.563906) (xy 419.502584 -277.585004) (xy 419.543087 -277.61296)
			(xy 419.57858 -277.647052) (xy 419.608145 -277.686396) (xy 419.631016 -277.729973) (xy 419.6466 -277.776654)
			(xy 419.654495 -277.825231) (xy 419.65499 -277.849838) (xy 420.943798 -277.849838) (xy 420.947758 -277.800784)
			(xy 420.959535 -277.753) (xy 420.978826 -277.707724) (xy 421.005129 -277.666128) (xy 421.037764 -277.629291)
			(xy 421.075885 -277.598166) (xy 421.118506 -277.573559) (xy 421.164522 -277.556107) (xy 421.212741 -277.546263)
			(xy 421.261916 -277.544282) (xy 421.310771 -277.550214) (xy 421.358042 -277.563906) (xy 421.402504 -277.585004)
			(xy 421.443007 -277.61296) (xy 421.4785 -277.647052) (xy 421.508065 -277.686396) (xy 421.530936 -277.729973)
			(xy 421.54652 -277.776654) (xy 421.554415 -277.825231) (xy 421.55491 -277.849838) (xy 422.843972 -277.849838)
			(xy 422.847932 -277.800784) (xy 422.859709 -277.753) (xy 422.879 -277.707724) (xy 422.905303 -277.666128)
			(xy 422.937938 -277.629291) (xy 422.976059 -277.598166) (xy 423.01868 -277.573559) (xy 423.064696 -277.556107)
			(xy 423.112915 -277.546263) (xy 423.16209 -277.544282) (xy 423.210945 -277.550214) (xy 423.258216 -277.563906)
			(xy 423.302678 -277.585004) (xy 423.343181 -277.61296) (xy 423.378674 -277.647052) (xy 423.408239 -277.686396)
			(xy 423.43111 -277.729973) (xy 423.446694 -277.776654) (xy 423.454589 -277.825231) (xy 423.455084 -277.849838)
			(xy 424.743892 -277.849838) (xy 424.747852 -277.800784) (xy 424.759629 -277.753) (xy 424.77892 -277.707724)
			(xy 424.805223 -277.666128) (xy 424.837858 -277.629291) (xy 424.875979 -277.598166) (xy 424.9186 -277.573559)
			(xy 424.964616 -277.556107) (xy 425.012835 -277.546263) (xy 425.06201 -277.544282) (xy 425.110865 -277.550214)
			(xy 425.158136 -277.563906) (xy 425.202598 -277.585004) (xy 425.243101 -277.61296) (xy 425.278594 -277.647052)
			(xy 425.308159 -277.686396) (xy 425.33103 -277.729973) (xy 425.346614 -277.776654) (xy 425.354509 -277.825231)
			(xy 425.355004 -277.849838) (xy 426.643812 -277.849838) (xy 426.647772 -277.800784) (xy 426.659549 -277.753)
			(xy 426.67884 -277.707724) (xy 426.705143 -277.666128) (xy 426.737778 -277.629291) (xy 426.775899 -277.598166)
			(xy 426.81852 -277.573559) (xy 426.864536 -277.556107) (xy 426.912755 -277.546263) (xy 426.96193 -277.544282)
			(xy 427.010785 -277.550214) (xy 427.058056 -277.563906) (xy 427.102518 -277.585004) (xy 427.143021 -277.61296)
			(xy 427.178514 -277.647052) (xy 427.208079 -277.686396) (xy 427.23095 -277.729973) (xy 427.246534 -277.776654)
			(xy 427.254429 -277.825231) (xy 427.254924 -277.849838) (xy 428.543986 -277.849838) (xy 428.547946 -277.800784)
			(xy 428.559723 -277.753) (xy 428.579014 -277.707724) (xy 428.605317 -277.666128) (xy 428.637952 -277.629291)
			(xy 428.676073 -277.598166) (xy 428.718694 -277.573559) (xy 428.76471 -277.556107) (xy 428.812929 -277.546263)
			(xy 428.862104 -277.544282) (xy 428.910959 -277.550214) (xy 428.95823 -277.563906) (xy 429.002692 -277.585004)
			(xy 429.043195 -277.61296) (xy 429.078688 -277.647052) (xy 429.108253 -277.686396) (xy 429.131124 -277.729973)
			(xy 429.146708 -277.776654) (xy 429.154603 -277.825231) (xy 429.155098 -277.849838) (xy 429.154603 -277.874445)
			(xy 429.146708 -277.923022) (xy 429.131124 -277.969703) (xy 429.108253 -278.01328) (xy 429.078688 -278.052624)
			(xy 429.043195 -278.086716) (xy 429.002692 -278.114672) (xy 428.95823 -278.13577) (xy 428.910959 -278.149462)
			(xy 428.862104 -278.155394) (xy 428.812929 -278.153413) (xy 428.76471 -278.143569) (xy 428.718694 -278.126117)
			(xy 428.676073 -278.10151) (xy 428.637952 -278.070385) (xy 428.605317 -278.033548) (xy 428.579014 -277.991952)
			(xy 428.559723 -277.946676) (xy 428.547946 -277.898892) (xy 428.543986 -277.849838) (xy 427.254924 -277.849838)
			(xy 427.254429 -277.874445) (xy 427.246534 -277.923022) (xy 427.23095 -277.969703) (xy 427.208079 -278.01328)
			(xy 427.178514 -278.052624) (xy 427.143021 -278.086716) (xy 427.102518 -278.114672) (xy 427.058056 -278.13577)
			(xy 427.010785 -278.149462) (xy 426.96193 -278.155394) (xy 426.912755 -278.153413) (xy 426.864536 -278.143569)
			(xy 426.81852 -278.126117) (xy 426.775899 -278.10151) (xy 426.737778 -278.070385) (xy 426.705143 -278.033548)
			(xy 426.67884 -277.991952) (xy 426.659549 -277.946676) (xy 426.647772 -277.898892) (xy 426.643812 -277.849838)
			(xy 425.355004 -277.849838) (xy 425.354509 -277.874445) (xy 425.346614 -277.923022) (xy 425.33103 -277.969703)
			(xy 425.308159 -278.01328) (xy 425.278594 -278.052624) (xy 425.243101 -278.086716) (xy 425.202598 -278.114672)
			(xy 425.158136 -278.13577) (xy 425.110865 -278.149462) (xy 425.06201 -278.155394) (xy 425.012835 -278.153413)
			(xy 424.964616 -278.143569) (xy 424.9186 -278.126117) (xy 424.875979 -278.10151) (xy 424.837858 -278.070385)
			(xy 424.805223 -278.033548) (xy 424.77892 -277.991952) (xy 424.759629 -277.946676) (xy 424.747852 -277.898892)
			(xy 424.743892 -277.849838) (xy 423.455084 -277.849838) (xy 423.454589 -277.874445) (xy 423.446694 -277.923022)
			(xy 423.43111 -277.969703) (xy 423.408239 -278.01328) (xy 423.378674 -278.052624) (xy 423.343181 -278.086716)
			(xy 423.302678 -278.114672) (xy 423.258216 -278.13577) (xy 423.210945 -278.149462) (xy 423.16209 -278.155394)
			(xy 423.112915 -278.153413) (xy 423.064696 -278.143569) (xy 423.01868 -278.126117) (xy 422.976059 -278.10151)
			(xy 422.937938 -278.070385) (xy 422.905303 -278.033548) (xy 422.879 -277.991952) (xy 422.859709 -277.946676)
			(xy 422.847932 -277.898892) (xy 422.843972 -277.849838) (xy 421.55491 -277.849838) (xy 421.554415 -277.874445)
			(xy 421.54652 -277.923022) (xy 421.530936 -277.969703) (xy 421.508065 -278.01328) (xy 421.4785 -278.052624)
			(xy 421.443007 -278.086716) (xy 421.402504 -278.114672) (xy 421.358042 -278.13577) (xy 421.310771 -278.149462)
			(xy 421.261916 -278.155394) (xy 421.212741 -278.153413) (xy 421.164522 -278.143569) (xy 421.118506 -278.126117)
			(xy 421.075885 -278.10151) (xy 421.037764 -278.070385) (xy 421.005129 -278.033548) (xy 420.978826 -277.991952)
			(xy 420.959535 -277.946676) (xy 420.947758 -277.898892) (xy 420.943798 -277.849838) (xy 419.65499 -277.849838)
			(xy 419.654495 -277.874445) (xy 419.6466 -277.923022) (xy 419.631016 -277.969703) (xy 419.608145 -278.01328)
			(xy 419.57858 -278.052624) (xy 419.543087 -278.086716) (xy 419.502584 -278.114672) (xy 419.458122 -278.13577)
			(xy 419.410851 -278.149462) (xy 419.361996 -278.155394) (xy 419.312821 -278.153413) (xy 419.264602 -278.143569)
			(xy 419.218586 -278.126117) (xy 419.175965 -278.10151) (xy 419.137844 -278.070385) (xy 419.105209 -278.033548)
			(xy 419.078906 -277.991952) (xy 419.059615 -277.946676) (xy 419.047838 -277.898892) (xy 419.043878 -277.849838)
			(xy 417.75507 -277.849838) (xy 417.754575 -277.874445) (xy 417.74668 -277.923022) (xy 417.731096 -277.969703)
			(xy 417.708225 -278.01328) (xy 417.67866 -278.052624) (xy 417.643167 -278.086716) (xy 417.602664 -278.114672)
			(xy 417.558202 -278.13577) (xy 417.510931 -278.149462) (xy 417.462076 -278.155394) (xy 417.412901 -278.153413)
			(xy 417.364682 -278.143569) (xy 417.318666 -278.126117) (xy 417.276045 -278.10151) (xy 417.237924 -278.070385)
			(xy 417.205289 -278.033548) (xy 417.178986 -277.991952) (xy 417.159695 -277.946676) (xy 417.147918 -277.898892)
			(xy 417.143958 -277.849838) (xy 415.854896 -277.849838) (xy 415.854401 -277.874445) (xy 415.846506 -277.923022)
			(xy 415.830922 -277.969703) (xy 415.808051 -278.01328) (xy 415.778486 -278.052624) (xy 415.742993 -278.086716)
			(xy 415.70249 -278.114672) (xy 415.658028 -278.13577) (xy 415.610757 -278.149462) (xy 415.561902 -278.155394)
			(xy 415.512727 -278.153413) (xy 415.464508 -278.143569) (xy 415.418492 -278.126117) (xy 415.375871 -278.10151)
			(xy 415.33775 -278.070385) (xy 415.305115 -278.033548) (xy 415.278812 -277.991952) (xy 415.259521 -277.946676)
			(xy 415.247744 -277.898892) (xy 415.243784 -277.849838) (xy 413.954976 -277.849838) (xy 413.954481 -277.874445)
			(xy 413.946586 -277.923022) (xy 413.931002 -277.969703) (xy 413.908131 -278.01328) (xy 413.878566 -278.052624)
			(xy 413.843073 -278.086716) (xy 413.80257 -278.114672) (xy 413.758108 -278.13577) (xy 413.710837 -278.149462)
			(xy 413.661982 -278.155394) (xy 413.612807 -278.153413) (xy 413.564588 -278.143569) (xy 413.518572 -278.126117)
			(xy 413.475951 -278.10151) (xy 413.43783 -278.070385) (xy 413.405195 -278.033548) (xy 413.378892 -277.991952)
			(xy 413.359601 -277.946676) (xy 413.347824 -277.898892) (xy 413.343864 -277.849838) (xy 412.055056 -277.849838)
			(xy 412.054561 -277.874445) (xy 412.046666 -277.923022) (xy 412.031082 -277.969703) (xy 412.008211 -278.01328)
			(xy 411.978646 -278.052624) (xy 411.943153 -278.086716) (xy 411.90265 -278.114672) (xy 411.858188 -278.13577)
			(xy 411.810917 -278.149462) (xy 411.762062 -278.155394) (xy 411.712887 -278.153413) (xy 411.664668 -278.143569)
			(xy 411.618652 -278.126117) (xy 411.576031 -278.10151) (xy 411.53791 -278.070385) (xy 411.505275 -278.033548)
			(xy 411.478972 -277.991952) (xy 411.459681 -277.946676) (xy 411.447904 -277.898892) (xy 411.443944 -277.849838)
			(xy 410.154882 -277.849838) (xy 410.154387 -277.874445) (xy 410.146492 -277.923022) (xy 410.130908 -277.969703)
			(xy 410.108037 -278.01328) (xy 410.078472 -278.052624) (xy 410.042979 -278.086716) (xy 410.002476 -278.114672)
			(xy 409.958014 -278.13577) (xy 409.910743 -278.149462) (xy 409.861888 -278.155394) (xy 409.812713 -278.153413)
			(xy 409.764494 -278.143569) (xy 409.718478 -278.126117) (xy 409.675857 -278.10151) (xy 409.637736 -278.070385)
			(xy 409.605101 -278.033548) (xy 409.578798 -277.991952) (xy 409.559507 -277.946676) (xy 409.54773 -277.898892)
			(xy 409.54377 -277.849838) (xy 408.254962 -277.849838) (xy 408.254467 -277.874445) (xy 408.246572 -277.923022)
			(xy 408.230988 -277.969703) (xy 408.208117 -278.01328) (xy 408.178552 -278.052624) (xy 408.143059 -278.086716)
			(xy 408.102556 -278.114672) (xy 408.058094 -278.13577) (xy 408.010823 -278.149462) (xy 407.961968 -278.155394)
			(xy 407.912793 -278.153413) (xy 407.864574 -278.143569) (xy 407.818558 -278.126117) (xy 407.775937 -278.10151)
			(xy 407.737816 -278.070385) (xy 407.705181 -278.033548) (xy 407.678878 -277.991952) (xy 407.659587 -277.946676)
			(xy 407.64781 -277.898892) (xy 407.64385 -277.849838) (xy 406.355296 -277.849838) (xy 406.354801 -277.874445)
			(xy 406.346906 -277.923022) (xy 406.331322 -277.969703) (xy 406.308451 -278.01328) (xy 406.278886 -278.052624)
			(xy 406.243393 -278.086716) (xy 406.20289 -278.114672) (xy 406.158428 -278.13577) (xy 406.111157 -278.149462)
			(xy 406.062302 -278.155394) (xy 406.013127 -278.153413) (xy 405.964908 -278.143569) (xy 405.918892 -278.126117)
			(xy 405.876271 -278.10151) (xy 405.83815 -278.070385) (xy 405.805515 -278.033548) (xy 405.779212 -277.991952)
			(xy 405.759921 -277.946676) (xy 405.748144 -277.898892) (xy 405.744184 -277.849838) (xy 404.455122 -277.849838)
			(xy 404.454627 -277.874445) (xy 404.446732 -277.923022) (xy 404.431148 -277.969703) (xy 404.408277 -278.01328)
			(xy 404.378712 -278.052624) (xy 404.343219 -278.086716) (xy 404.302716 -278.114672) (xy 404.258254 -278.13577)
			(xy 404.210983 -278.149462) (xy 404.162128 -278.155394) (xy 404.112953 -278.153413) (xy 404.064734 -278.143569)
			(xy 404.018718 -278.126117) (xy 403.976097 -278.10151) (xy 403.937976 -278.070385) (xy 403.905341 -278.033548)
			(xy 403.879038 -277.991952) (xy 403.859747 -277.946676) (xy 403.84797 -277.898892) (xy 403.84401 -277.849838)
			(xy 402.555202 -277.849838) (xy 402.554707 -277.874445) (xy 402.546812 -277.923022) (xy 402.531228 -277.969703)
			(xy 402.508357 -278.01328) (xy 402.478792 -278.052624) (xy 402.443299 -278.086716) (xy 402.402796 -278.114672)
			(xy 402.358334 -278.13577) (xy 402.311063 -278.149462) (xy 402.262208 -278.155394) (xy 402.213033 -278.153413)
			(xy 402.164814 -278.143569) (xy 402.118798 -278.126117) (xy 402.076177 -278.10151) (xy 402.038056 -278.070385)
			(xy 402.005421 -278.033548) (xy 401.979118 -277.991952) (xy 401.959827 -277.946676) (xy 401.94805 -277.898892)
			(xy 401.94409 -277.849838) (xy 400.655282 -277.849838) (xy 400.654787 -277.874445) (xy 400.646892 -277.923022)
			(xy 400.631308 -277.969703) (xy 400.608437 -278.01328) (xy 400.578872 -278.052624) (xy 400.543379 -278.086716)
			(xy 400.502876 -278.114672) (xy 400.458414 -278.13577) (xy 400.411143 -278.149462) (xy 400.362288 -278.155394)
			(xy 400.313113 -278.153413) (xy 400.264894 -278.143569) (xy 400.218878 -278.126117) (xy 400.176257 -278.10151)
			(xy 400.138136 -278.070385) (xy 400.105501 -278.033548) (xy 400.079198 -277.991952) (xy 400.059907 -277.946676)
			(xy 400.04813 -277.898892) (xy 400.04417 -277.849838) (xy 398.755108 -277.849838) (xy 398.754613 -277.874445)
			(xy 398.746718 -277.923022) (xy 398.731134 -277.969703) (xy 398.708263 -278.01328) (xy 398.678698 -278.052624)
			(xy 398.643205 -278.086716) (xy 398.602702 -278.114672) (xy 398.55824 -278.13577) (xy 398.510969 -278.149462)
			(xy 398.462114 -278.155394) (xy 398.412939 -278.153413) (xy 398.36472 -278.143569) (xy 398.318704 -278.126117)
			(xy 398.276083 -278.10151) (xy 398.237962 -278.070385) (xy 398.205327 -278.033548) (xy 398.179024 -277.991952)
			(xy 398.159733 -277.946676) (xy 398.147956 -277.898892) (xy 398.143996 -277.849838) (xy 396.855188 -277.849838)
			(xy 396.854693 -277.874445) (xy 396.846798 -277.923022) (xy 396.831214 -277.969703) (xy 396.808343 -278.01328)
			(xy 396.778778 -278.052624) (xy 396.743285 -278.086716) (xy 396.702782 -278.114672) (xy 396.65832 -278.13577)
			(xy 396.611049 -278.149462) (xy 396.562194 -278.155394) (xy 396.513019 -278.153413) (xy 396.4648 -278.143569)
			(xy 396.418784 -278.126117) (xy 396.376163 -278.10151) (xy 396.338042 -278.070385) (xy 396.305407 -278.033548)
			(xy 396.279104 -277.991952) (xy 396.259813 -277.946676) (xy 396.248036 -277.898892) (xy 396.244076 -277.849838)
			(xy 394.955268 -277.849838) (xy 394.954773 -277.874445) (xy 394.946878 -277.923022) (xy 394.931294 -277.969703)
			(xy 394.908423 -278.01328) (xy 394.878858 -278.052624) (xy 394.843365 -278.086716) (xy 394.802862 -278.114672)
			(xy 394.7584 -278.13577) (xy 394.711129 -278.149462) (xy 394.662274 -278.155394) (xy 394.613099 -278.153413)
			(xy 394.56488 -278.143569) (xy 394.518864 -278.126117) (xy 394.476243 -278.10151) (xy 394.438122 -278.070385)
			(xy 394.405487 -278.033548) (xy 394.379184 -277.991952) (xy 394.359893 -277.946676) (xy 394.348116 -277.898892)
			(xy 394.344156 -277.849838) (xy 393.055094 -277.849838) (xy 393.054599 -277.874445) (xy 393.046704 -277.923022)
			(xy 393.03112 -277.969703) (xy 393.008249 -278.01328) (xy 392.978684 -278.052624) (xy 392.943191 -278.086716)
			(xy 392.902688 -278.114672) (xy 392.858226 -278.13577) (xy 392.810955 -278.149462) (xy 392.7621 -278.155394)
			(xy 392.712925 -278.153413) (xy 392.664706 -278.143569) (xy 392.61869 -278.126117) (xy 392.576069 -278.10151)
			(xy 392.537948 -278.070385) (xy 392.505313 -278.033548) (xy 392.47901 -277.991952) (xy 392.459719 -277.946676)
			(xy 392.447942 -277.898892) (xy 392.443982 -277.849838) (xy 313.055 -277.849838) (xy 313.054505 -277.874445)
			(xy 313.04661 -277.923022) (xy 313.031026 -277.969703) (xy 313.008155 -278.01328) (xy 312.97859 -278.052624)
			(xy 312.943097 -278.086716) (xy 312.902594 -278.114672) (xy 312.858132 -278.13577) (xy 312.810861 -278.149462)
			(xy 312.762006 -278.155394) (xy 312.712831 -278.153413) (xy 312.664612 -278.143569) (xy 312.618596 -278.126117)
			(xy 312.575975 -278.10151) (xy 312.537854 -278.070385) (xy 312.505219 -278.033548) (xy 312.478916 -277.991952)
			(xy 312.459625 -277.946676) (xy 312.447848 -277.898892) (xy 312.443888 -277.849838) (xy 311.154826 -277.849838)
			(xy 311.154331 -277.874445) (xy 311.146436 -277.923022) (xy 311.130852 -277.969703) (xy 311.107981 -278.01328)
			(xy 311.078416 -278.052624) (xy 311.042923 -278.086716) (xy 311.00242 -278.114672) (xy 310.957958 -278.13577)
			(xy 310.910687 -278.149462) (xy 310.861832 -278.155394) (xy 310.812657 -278.153413) (xy 310.764438 -278.143569)
			(xy 310.718422 -278.126117) (xy 310.675801 -278.10151) (xy 310.63768 -278.070385) (xy 310.605045 -278.033548)
			(xy 310.578742 -277.991952) (xy 310.559451 -277.946676) (xy 310.547674 -277.898892) (xy 310.543714 -277.849838)
			(xy 309.254906 -277.849838) (xy 309.254411 -277.874445) (xy 309.246516 -277.923022) (xy 309.230932 -277.969703)
			(xy 309.208061 -278.01328) (xy 309.178496 -278.052624) (xy 309.143003 -278.086716) (xy 309.1025 -278.114672)
			(xy 309.058038 -278.13577) (xy 309.010767 -278.149462) (xy 308.961912 -278.155394) (xy 308.912737 -278.153413)
			(xy 308.864518 -278.143569) (xy 308.818502 -278.126117) (xy 308.775881 -278.10151) (xy 308.73776 -278.070385)
			(xy 308.705125 -278.033548) (xy 308.678822 -277.991952) (xy 308.659531 -277.946676) (xy 308.647754 -277.898892)
			(xy 308.643794 -277.849838) (xy 307.354986 -277.849838) (xy 307.354491 -277.874445) (xy 307.346596 -277.923022)
			(xy 307.331012 -277.969703) (xy 307.308141 -278.01328) (xy 307.278576 -278.052624) (xy 307.243083 -278.086716)
			(xy 307.20258 -278.114672) (xy 307.158118 -278.13577) (xy 307.110847 -278.149462) (xy 307.061992 -278.155394)
			(xy 307.012817 -278.153413) (xy 306.964598 -278.143569) (xy 306.918582 -278.126117) (xy 306.875961 -278.10151)
			(xy 306.83784 -278.070385) (xy 306.805205 -278.033548) (xy 306.778902 -277.991952) (xy 306.759611 -277.946676)
			(xy 306.747834 -277.898892) (xy 306.743874 -277.849838) (xy 305.454812 -277.849838) (xy 305.454317 -277.874445)
			(xy 305.446422 -277.923022) (xy 305.430838 -277.969703) (xy 305.407967 -278.01328) (xy 305.378402 -278.052624)
			(xy 305.342909 -278.086716) (xy 305.302406 -278.114672) (xy 305.257944 -278.13577) (xy 305.210673 -278.149462)
			(xy 305.161818 -278.155394) (xy 305.112643 -278.153413) (xy 305.064424 -278.143569) (xy 305.018408 -278.126117)
			(xy 304.975787 -278.10151) (xy 304.937666 -278.070385) (xy 304.905031 -278.033548) (xy 304.878728 -277.991952)
			(xy 304.859437 -277.946676) (xy 304.84766 -277.898892) (xy 304.8437 -277.849838) (xy 303.554892 -277.849838)
			(xy 303.554397 -277.874445) (xy 303.546502 -277.923022) (xy 303.530918 -277.969703) (xy 303.508047 -278.01328)
			(xy 303.478482 -278.052624) (xy 303.442989 -278.086716) (xy 303.402486 -278.114672) (xy 303.358024 -278.13577)
			(xy 303.310753 -278.149462) (xy 303.261898 -278.155394) (xy 303.212723 -278.153413) (xy 303.164504 -278.143569)
			(xy 303.118488 -278.126117) (xy 303.075867 -278.10151) (xy 303.037746 -278.070385) (xy 303.005111 -278.033548)
			(xy 302.978808 -277.991952) (xy 302.959517 -277.946676) (xy 302.94774 -277.898892) (xy 302.94378 -277.849838)
			(xy 301.654972 -277.849838) (xy 301.654477 -277.874445) (xy 301.646582 -277.923022) (xy 301.630998 -277.969703)
			(xy 301.608127 -278.01328) (xy 301.578562 -278.052624) (xy 301.543069 -278.086716) (xy 301.502566 -278.114672)
			(xy 301.458104 -278.13577) (xy 301.410833 -278.149462) (xy 301.361978 -278.155394) (xy 301.312803 -278.153413)
			(xy 301.264584 -278.143569) (xy 301.218568 -278.126117) (xy 301.175947 -278.10151) (xy 301.137826 -278.070385)
			(xy 301.105191 -278.033548) (xy 301.078888 -277.991952) (xy 301.059597 -277.946676) (xy 301.04782 -277.898892)
			(xy 301.04386 -277.849838) (xy 299.754798 -277.849838) (xy 299.754303 -277.874445) (xy 299.746408 -277.923022)
			(xy 299.730824 -277.969703) (xy 299.707953 -278.01328) (xy 299.678388 -278.052624) (xy 299.642895 -278.086716)
			(xy 299.602392 -278.114672) (xy 299.55793 -278.13577) (xy 299.510659 -278.149462) (xy 299.461804 -278.155394)
			(xy 299.412629 -278.153413) (xy 299.36441 -278.143569) (xy 299.318394 -278.126117) (xy 299.275773 -278.10151)
			(xy 299.237652 -278.070385) (xy 299.205017 -278.033548) (xy 299.178714 -277.991952) (xy 299.159423 -277.946676)
			(xy 299.147646 -277.898892) (xy 299.143686 -277.849838) (xy 297.854878 -277.849838) (xy 297.854383 -277.874445)
			(xy 297.846488 -277.923022) (xy 297.830904 -277.969703) (xy 297.808033 -278.01328) (xy 297.778468 -278.052624)
			(xy 297.742975 -278.086716) (xy 297.702472 -278.114672) (xy 297.65801 -278.13577) (xy 297.610739 -278.149462)
			(xy 297.561884 -278.155394) (xy 297.512709 -278.153413) (xy 297.46449 -278.143569) (xy 297.418474 -278.126117)
			(xy 297.375853 -278.10151) (xy 297.337732 -278.070385) (xy 297.305097 -278.033548) (xy 297.278794 -277.991952)
			(xy 297.259503 -277.946676) (xy 297.247726 -277.898892) (xy 297.243766 -277.849838) (xy 295.954958 -277.849838)
			(xy 295.954463 -277.874445) (xy 295.946568 -277.923022) (xy 295.930984 -277.969703) (xy 295.908113 -278.01328)
			(xy 295.878548 -278.052624) (xy 295.843055 -278.086716) (xy 295.802552 -278.114672) (xy 295.75809 -278.13577)
			(xy 295.710819 -278.149462) (xy 295.661964 -278.155394) (xy 295.612789 -278.153413) (xy 295.56457 -278.143569)
			(xy 295.518554 -278.126117) (xy 295.475933 -278.10151) (xy 295.437812 -278.070385) (xy 295.405177 -278.033548)
			(xy 295.378874 -277.991952) (xy 295.359583 -277.946676) (xy 295.347806 -277.898892) (xy 295.343846 -277.849838)
			(xy 294.054784 -277.849838) (xy 294.054289 -277.874445) (xy 294.046394 -277.923022) (xy 294.03081 -277.969703)
			(xy 294.007939 -278.01328) (xy 293.978374 -278.052624) (xy 293.942881 -278.086716) (xy 293.902378 -278.114672)
			(xy 293.857916 -278.13577) (xy 293.810645 -278.149462) (xy 293.76179 -278.155394) (xy 293.712615 -278.153413)
			(xy 293.664396 -278.143569) (xy 293.61838 -278.126117) (xy 293.575759 -278.10151) (xy 293.537638 -278.070385)
			(xy 293.505003 -278.033548) (xy 293.4787 -277.991952) (xy 293.459409 -277.946676) (xy 293.447632 -277.898892)
			(xy 293.443672 -277.849838) (xy 292.154864 -277.849838) (xy 292.154369 -277.874445) (xy 292.146474 -277.923022)
			(xy 292.13089 -277.969703) (xy 292.108019 -278.01328) (xy 292.078454 -278.052624) (xy 292.042961 -278.086716)
			(xy 292.002458 -278.114672) (xy 291.957996 -278.13577) (xy 291.910725 -278.149462) (xy 291.86187 -278.155394)
			(xy 291.812695 -278.153413) (xy 291.764476 -278.143569) (xy 291.71846 -278.126117) (xy 291.675839 -278.10151)
			(xy 291.637718 -278.070385) (xy 291.605083 -278.033548) (xy 291.57878 -277.991952) (xy 291.559489 -277.946676)
			(xy 291.547712 -277.898892) (xy 291.543752 -277.849838) (xy 290.255198 -277.849838) (xy 290.254703 -277.874445)
			(xy 290.246808 -277.923022) (xy 290.231224 -277.969703) (xy 290.208353 -278.01328) (xy 290.178788 -278.052624)
			(xy 290.143295 -278.086716) (xy 290.102792 -278.114672) (xy 290.05833 -278.13577) (xy 290.011059 -278.149462)
			(xy 289.962204 -278.155394) (xy 289.913029 -278.153413) (xy 289.86481 -278.143569) (xy 289.818794 -278.126117)
			(xy 289.776173 -278.10151) (xy 289.738052 -278.070385) (xy 289.705417 -278.033548) (xy 289.679114 -277.991952)
			(xy 289.659823 -277.946676) (xy 289.648046 -277.898892) (xy 289.644086 -277.849838) (xy 288.355024 -277.849838)
			(xy 288.354529 -277.874445) (xy 288.346634 -277.923022) (xy 288.33105 -277.969703) (xy 288.308179 -278.01328)
			(xy 288.278614 -278.052624) (xy 288.243121 -278.086716) (xy 288.202618 -278.114672) (xy 288.158156 -278.13577)
			(xy 288.110885 -278.149462) (xy 288.06203 -278.155394) (xy 288.012855 -278.153413) (xy 287.964636 -278.143569)
			(xy 287.91862 -278.126117) (xy 287.875999 -278.10151) (xy 287.837878 -278.070385) (xy 287.805243 -278.033548)
			(xy 287.77894 -277.991952) (xy 287.759649 -277.946676) (xy 287.747872 -277.898892) (xy 287.743912 -277.849838)
			(xy 286.455104 -277.849838) (xy 286.454609 -277.874445) (xy 286.446714 -277.923022) (xy 286.43113 -277.969703)
			(xy 286.408259 -278.01328) (xy 286.378694 -278.052624) (xy 286.343201 -278.086716) (xy 286.302698 -278.114672)
			(xy 286.258236 -278.13577) (xy 286.210965 -278.149462) (xy 286.16211 -278.155394) (xy 286.112935 -278.153413)
			(xy 286.064716 -278.143569) (xy 286.0187 -278.126117) (xy 285.976079 -278.10151) (xy 285.937958 -278.070385)
			(xy 285.905323 -278.033548) (xy 285.87902 -277.991952) (xy 285.859729 -277.946676) (xy 285.847952 -277.898892)
			(xy 285.843992 -277.849838) (xy 284.555184 -277.849838) (xy 284.554689 -277.874445) (xy 284.546794 -277.923022)
			(xy 284.53121 -277.969703) (xy 284.508339 -278.01328) (xy 284.478774 -278.052624) (xy 284.443281 -278.086716)
			(xy 284.402778 -278.114672) (xy 284.358316 -278.13577) (xy 284.311045 -278.149462) (xy 284.26219 -278.155394)
			(xy 284.213015 -278.153413) (xy 284.164796 -278.143569) (xy 284.11878 -278.126117) (xy 284.076159 -278.10151)
			(xy 284.038038 -278.070385) (xy 284.005403 -278.033548) (xy 283.9791 -277.991952) (xy 283.959809 -277.946676)
			(xy 283.948032 -277.898892) (xy 283.944072 -277.849838) (xy 282.65501 -277.849838) (xy 282.654515 -277.874445)
			(xy 282.64662 -277.923022) (xy 282.631036 -277.969703) (xy 282.608165 -278.01328) (xy 282.5786 -278.052624)
			(xy 282.543107 -278.086716) (xy 282.502604 -278.114672) (xy 282.458142 -278.13577) (xy 282.410871 -278.149462)
			(xy 282.362016 -278.155394) (xy 282.312841 -278.153413) (xy 282.264622 -278.143569) (xy 282.218606 -278.126117)
			(xy 282.175985 -278.10151) (xy 282.137864 -278.070385) (xy 282.105229 -278.033548) (xy 282.078926 -277.991952)
			(xy 282.059635 -277.946676) (xy 282.047858 -277.898892) (xy 282.043898 -277.849838) (xy 280.75509 -277.849838)
			(xy 280.754595 -277.874445) (xy 280.7467 -277.923022) (xy 280.731116 -277.969703) (xy 280.708245 -278.01328)
			(xy 280.67868 -278.052624) (xy 280.643187 -278.086716) (xy 280.602684 -278.114672) (xy 280.558222 -278.13577)
			(xy 280.510951 -278.149462) (xy 280.462096 -278.155394) (xy 280.412921 -278.153413) (xy 280.364702 -278.143569)
			(xy 280.318686 -278.126117) (xy 280.276065 -278.10151) (xy 280.237944 -278.070385) (xy 280.205309 -278.033548)
			(xy 280.179006 -277.991952) (xy 280.159715 -277.946676) (xy 280.147938 -277.898892) (xy 280.143978 -277.849838)
			(xy 278.85517 -277.849838) (xy 278.854675 -277.874445) (xy 278.84678 -277.923022) (xy 278.831196 -277.969703)
			(xy 278.808325 -278.01328) (xy 278.77876 -278.052624) (xy 278.743267 -278.086716) (xy 278.702764 -278.114672)
			(xy 278.658302 -278.13577) (xy 278.611031 -278.149462) (xy 278.562176 -278.155394) (xy 278.513001 -278.153413)
			(xy 278.464782 -278.143569) (xy 278.418766 -278.126117) (xy 278.376145 -278.10151) (xy 278.338024 -278.070385)
			(xy 278.305389 -278.033548) (xy 278.279086 -277.991952) (xy 278.259795 -277.946676) (xy 278.248018 -277.898892)
			(xy 278.244058 -277.849838) (xy 276.954996 -277.849838) (xy 276.954501 -277.874445) (xy 276.946606 -277.923022)
			(xy 276.931022 -277.969703) (xy 276.908151 -278.01328) (xy 276.878586 -278.052624) (xy 276.843093 -278.086716)
			(xy 276.80259 -278.114672) (xy 276.758128 -278.13577) (xy 276.710857 -278.149462) (xy 276.662002 -278.155394)
			(xy 276.612827 -278.153413) (xy 276.564608 -278.143569) (xy 276.518592 -278.126117) (xy 276.475971 -278.10151)
			(xy 276.43785 -278.070385) (xy 276.405215 -278.033548) (xy 276.378912 -277.991952) (xy 276.359621 -277.946676)
			(xy 276.347844 -277.898892) (xy 276.343884 -277.849838) (xy 196.955156 -277.849838) (xy 196.954661 -277.874445)
			(xy 196.946766 -277.923022) (xy 196.931182 -277.969703) (xy 196.908311 -278.01328) (xy 196.878746 -278.052624)
			(xy 196.843253 -278.086716) (xy 196.80275 -278.114672) (xy 196.758288 -278.13577) (xy 196.711017 -278.149462)
			(xy 196.662162 -278.155394) (xy 196.612987 -278.153413) (xy 196.564768 -278.143569) (xy 196.518752 -278.126117)
			(xy 196.476131 -278.10151) (xy 196.43801 -278.070385) (xy 196.405375 -278.033548) (xy 196.379072 -277.991952)
			(xy 196.359781 -277.946676) (xy 196.348004 -277.898892) (xy 196.344044 -277.849838) (xy 195.054982 -277.849838)
			(xy 195.054487 -277.874445) (xy 195.046592 -277.923022) (xy 195.031008 -277.969703) (xy 195.008137 -278.01328)
			(xy 194.978572 -278.052624) (xy 194.943079 -278.086716) (xy 194.902576 -278.114672) (xy 194.858114 -278.13577)
			(xy 194.810843 -278.149462) (xy 194.761988 -278.155394) (xy 194.712813 -278.153413) (xy 194.664594 -278.143569)
			(xy 194.618578 -278.126117) (xy 194.575957 -278.10151) (xy 194.537836 -278.070385) (xy 194.505201 -278.033548)
			(xy 194.478898 -277.991952) (xy 194.459607 -277.946676) (xy 194.44783 -277.898892) (xy 194.44387 -277.849838)
			(xy 193.155062 -277.849838) (xy 193.154567 -277.874445) (xy 193.146672 -277.923022) (xy 193.131088 -277.969703)
			(xy 193.108217 -278.01328) (xy 193.078652 -278.052624) (xy 193.043159 -278.086716) (xy 193.002656 -278.114672)
			(xy 192.958194 -278.13577) (xy 192.910923 -278.149462) (xy 192.862068 -278.155394) (xy 192.812893 -278.153413)
			(xy 192.764674 -278.143569) (xy 192.718658 -278.126117) (xy 192.676037 -278.10151) (xy 192.637916 -278.070385)
			(xy 192.605281 -278.033548) (xy 192.578978 -277.991952) (xy 192.559687 -277.946676) (xy 192.54791 -277.898892)
			(xy 192.54395 -277.849838) (xy 191.255142 -277.849838) (xy 191.254647 -277.874445) (xy 191.246752 -277.923022)
			(xy 191.231168 -277.969703) (xy 191.208297 -278.01328) (xy 191.178732 -278.052624) (xy 191.143239 -278.086716)
			(xy 191.102736 -278.114672) (xy 191.058274 -278.13577) (xy 191.011003 -278.149462) (xy 190.962148 -278.155394)
			(xy 190.912973 -278.153413) (xy 190.864754 -278.143569) (xy 190.818738 -278.126117) (xy 190.776117 -278.10151)
			(xy 190.737996 -278.070385) (xy 190.705361 -278.033548) (xy 190.679058 -277.991952) (xy 190.659767 -277.946676)
			(xy 190.64799 -277.898892) (xy 190.64403 -277.849838) (xy 189.354968 -277.849838) (xy 189.354473 -277.874445)
			(xy 189.346578 -277.923022) (xy 189.330994 -277.969703) (xy 189.308123 -278.01328) (xy 189.278558 -278.052624)
			(xy 189.243065 -278.086716) (xy 189.202562 -278.114672) (xy 189.1581 -278.13577) (xy 189.110829 -278.149462)
			(xy 189.061974 -278.155394) (xy 189.012799 -278.153413) (xy 188.96458 -278.143569) (xy 188.918564 -278.126117)
			(xy 188.875943 -278.10151) (xy 188.837822 -278.070385) (xy 188.805187 -278.033548) (xy 188.778884 -277.991952)
			(xy 188.759593 -277.946676) (xy 188.747816 -277.898892) (xy 188.743856 -277.849838) (xy 187.455048 -277.849838)
			(xy 187.454553 -277.874445) (xy 187.446658 -277.923022) (xy 187.431074 -277.969703) (xy 187.408203 -278.01328)
			(xy 187.378638 -278.052624) (xy 187.343145 -278.086716) (xy 187.302642 -278.114672) (xy 187.25818 -278.13577)
			(xy 187.210909 -278.149462) (xy 187.162054 -278.155394) (xy 187.112879 -278.153413) (xy 187.06466 -278.143569)
			(xy 187.018644 -278.126117) (xy 186.976023 -278.10151) (xy 186.937902 -278.070385) (xy 186.905267 -278.033548)
			(xy 186.878964 -277.991952) (xy 186.859673 -277.946676) (xy 186.847896 -277.898892) (xy 186.843936 -277.849838)
			(xy 185.555128 -277.849838) (xy 185.554633 -277.874445) (xy 185.546738 -277.923022) (xy 185.531154 -277.969703)
			(xy 185.508283 -278.01328) (xy 185.478718 -278.052624) (xy 185.443225 -278.086716) (xy 185.402722 -278.114672)
			(xy 185.35826 -278.13577) (xy 185.310989 -278.149462) (xy 185.262134 -278.155394) (xy 185.212959 -278.153413)
			(xy 185.16474 -278.143569) (xy 185.118724 -278.126117) (xy 185.076103 -278.10151) (xy 185.037982 -278.070385)
			(xy 185.005347 -278.033548) (xy 184.979044 -277.991952) (xy 184.959753 -277.946676) (xy 184.947976 -277.898892)
			(xy 184.944016 -277.849838) (xy 183.654954 -277.849838) (xy 183.654459 -277.874445) (xy 183.646564 -277.923022)
			(xy 183.63098 -277.969703) (xy 183.608109 -278.01328) (xy 183.578544 -278.052624) (xy 183.543051 -278.086716)
			(xy 183.502548 -278.114672) (xy 183.458086 -278.13577) (xy 183.410815 -278.149462) (xy 183.36196 -278.155394)
			(xy 183.312785 -278.153413) (xy 183.264566 -278.143569) (xy 183.21855 -278.126117) (xy 183.175929 -278.10151)
			(xy 183.137808 -278.070385) (xy 183.105173 -278.033548) (xy 183.07887 -277.991952) (xy 183.059579 -277.946676)
			(xy 183.047802 -277.898892) (xy 183.043842 -277.849838) (xy 181.755034 -277.849838) (xy 181.754539 -277.874445)
			(xy 181.746644 -277.923022) (xy 181.73106 -277.969703) (xy 181.708189 -278.01328) (xy 181.678624 -278.052624)
			(xy 181.643131 -278.086716) (xy 181.602628 -278.114672) (xy 181.558166 -278.13577) (xy 181.510895 -278.149462)
			(xy 181.46204 -278.155394) (xy 181.412865 -278.153413) (xy 181.364646 -278.143569) (xy 181.31863 -278.126117)
			(xy 181.276009 -278.10151) (xy 181.237888 -278.070385) (xy 181.205253 -278.033548) (xy 181.17895 -277.991952)
			(xy 181.159659 -277.946676) (xy 181.147882 -277.898892) (xy 181.143922 -277.849838) (xy 179.855114 -277.849838)
			(xy 179.854619 -277.874445) (xy 179.846724 -277.923022) (xy 179.83114 -277.969703) (xy 179.808269 -278.01328)
			(xy 179.778704 -278.052624) (xy 179.743211 -278.086716) (xy 179.702708 -278.114672) (xy 179.658246 -278.13577)
			(xy 179.610975 -278.149462) (xy 179.56212 -278.155394) (xy 179.512945 -278.153413) (xy 179.464726 -278.143569)
			(xy 179.41871 -278.126117) (xy 179.376089 -278.10151) (xy 179.337968 -278.070385) (xy 179.305333 -278.033548)
			(xy 179.27903 -277.991952) (xy 179.259739 -277.946676) (xy 179.247962 -277.898892) (xy 179.244002 -277.849838)
			(xy 177.95494 -277.849838) (xy 177.954445 -277.874445) (xy 177.94655 -277.923022) (xy 177.930966 -277.969703)
			(xy 177.908095 -278.01328) (xy 177.87853 -278.052624) (xy 177.843037 -278.086716) (xy 177.802534 -278.114672)
			(xy 177.758072 -278.13577) (xy 177.710801 -278.149462) (xy 177.661946 -278.155394) (xy 177.612771 -278.153413)
			(xy 177.564552 -278.143569) (xy 177.518536 -278.126117) (xy 177.475915 -278.10151) (xy 177.437794 -278.070385)
			(xy 177.405159 -278.033548) (xy 177.378856 -277.991952) (xy 177.359565 -277.946676) (xy 177.347788 -277.898892)
			(xy 177.343828 -277.849838) (xy 176.05502 -277.849838) (xy 176.054525 -277.874445) (xy 176.04663 -277.923022)
			(xy 176.031046 -277.969703) (xy 176.008175 -278.01328) (xy 175.97861 -278.052624) (xy 175.943117 -278.086716)
			(xy 175.902614 -278.114672) (xy 175.858152 -278.13577) (xy 175.810881 -278.149462) (xy 175.762026 -278.155394)
			(xy 175.712851 -278.153413) (xy 175.664632 -278.143569) (xy 175.618616 -278.126117) (xy 175.575995 -278.10151)
			(xy 175.537874 -278.070385) (xy 175.505239 -278.033548) (xy 175.478936 -277.991952) (xy 175.459645 -277.946676)
			(xy 175.447868 -277.898892) (xy 175.443908 -277.849838) (xy 174.155354 -277.849838) (xy 174.154859 -277.874445)
			(xy 174.146964 -277.923022) (xy 174.13138 -277.969703) (xy 174.108509 -278.01328) (xy 174.078944 -278.052624)
			(xy 174.043451 -278.086716) (xy 174.002948 -278.114672) (xy 173.958486 -278.13577) (xy 173.911215 -278.149462)
			(xy 173.86236 -278.155394) (xy 173.813185 -278.153413) (xy 173.764966 -278.143569) (xy 173.71895 -278.126117)
			(xy 173.676329 -278.10151) (xy 173.638208 -278.070385) (xy 173.605573 -278.033548) (xy 173.57927 -277.991952)
			(xy 173.559979 -277.946676) (xy 173.548202 -277.898892) (xy 173.544242 -277.849838) (xy 172.25518 -277.849838)
			(xy 172.254685 -277.874445) (xy 172.24679 -277.923022) (xy 172.231206 -277.969703) (xy 172.208335 -278.01328)
			(xy 172.17877 -278.052624) (xy 172.143277 -278.086716) (xy 172.102774 -278.114672) (xy 172.058312 -278.13577)
			(xy 172.011041 -278.149462) (xy 171.962186 -278.155394) (xy 171.913011 -278.153413) (xy 171.864792 -278.143569)
			(xy 171.818776 -278.126117) (xy 171.776155 -278.10151) (xy 171.738034 -278.070385) (xy 171.705399 -278.033548)
			(xy 171.679096 -277.991952) (xy 171.659805 -277.946676) (xy 171.648028 -277.898892) (xy 171.644068 -277.849838)
			(xy 170.35526 -277.849838) (xy 170.354765 -277.874445) (xy 170.34687 -277.923022) (xy 170.331286 -277.969703)
			(xy 170.308415 -278.01328) (xy 170.27885 -278.052624) (xy 170.243357 -278.086716) (xy 170.202854 -278.114672)
			(xy 170.158392 -278.13577) (xy 170.111121 -278.149462) (xy 170.062266 -278.155394) (xy 170.013091 -278.153413)
			(xy 169.964872 -278.143569) (xy 169.918856 -278.126117) (xy 169.876235 -278.10151) (xy 169.838114 -278.070385)
			(xy 169.805479 -278.033548) (xy 169.779176 -277.991952) (xy 169.759885 -277.946676) (xy 169.748108 -277.898892)
			(xy 169.744148 -277.849838) (xy 168.45534 -277.849838) (xy 168.454845 -277.874445) (xy 168.44695 -277.923022)
			(xy 168.431366 -277.969703) (xy 168.408495 -278.01328) (xy 168.37893 -278.052624) (xy 168.343437 -278.086716)
			(xy 168.302934 -278.114672) (xy 168.258472 -278.13577) (xy 168.211201 -278.149462) (xy 168.162346 -278.155394)
			(xy 168.113171 -278.153413) (xy 168.064952 -278.143569) (xy 168.018936 -278.126117) (xy 167.976315 -278.10151)
			(xy 167.938194 -278.070385) (xy 167.905559 -278.033548) (xy 167.879256 -277.991952) (xy 167.859965 -277.946676)
			(xy 167.848188 -277.898892) (xy 167.844228 -277.849838) (xy 166.555166 -277.849838) (xy 166.554671 -277.874445)
			(xy 166.546776 -277.923022) (xy 166.531192 -277.969703) (xy 166.508321 -278.01328) (xy 166.478756 -278.052624)
			(xy 166.443263 -278.086716) (xy 166.40276 -278.114672) (xy 166.358298 -278.13577) (xy 166.311027 -278.149462)
			(xy 166.262172 -278.155394) (xy 166.212997 -278.153413) (xy 166.164778 -278.143569) (xy 166.118762 -278.126117)
			(xy 166.076141 -278.10151) (xy 166.03802 -278.070385) (xy 166.005385 -278.033548) (xy 165.979082 -277.991952)
			(xy 165.959791 -277.946676) (xy 165.948014 -277.898892) (xy 165.944054 -277.849838) (xy 164.655246 -277.849838)
			(xy 164.654751 -277.874445) (xy 164.646856 -277.923022) (xy 164.631272 -277.969703) (xy 164.608401 -278.01328)
			(xy 164.578836 -278.052624) (xy 164.543343 -278.086716) (xy 164.50284 -278.114672) (xy 164.458378 -278.13577)
			(xy 164.411107 -278.149462) (xy 164.362252 -278.155394) (xy 164.313077 -278.153413) (xy 164.264858 -278.143569)
			(xy 164.218842 -278.126117) (xy 164.176221 -278.10151) (xy 164.1381 -278.070385) (xy 164.105465 -278.033548)
			(xy 164.079162 -277.991952) (xy 164.059871 -277.946676) (xy 164.048094 -277.898892) (xy 164.044134 -277.849838)
			(xy 162.755326 -277.849838) (xy 162.754831 -277.874445) (xy 162.746936 -277.923022) (xy 162.731352 -277.969703)
			(xy 162.708481 -278.01328) (xy 162.678916 -278.052624) (xy 162.643423 -278.086716) (xy 162.60292 -278.114672)
			(xy 162.558458 -278.13577) (xy 162.511187 -278.149462) (xy 162.462332 -278.155394) (xy 162.413157 -278.153413)
			(xy 162.364938 -278.143569) (xy 162.318922 -278.126117) (xy 162.276301 -278.10151) (xy 162.23818 -278.070385)
			(xy 162.205545 -278.033548) (xy 162.179242 -277.991952) (xy 162.159951 -277.946676) (xy 162.148174 -277.898892)
			(xy 162.144214 -277.849838) (xy 160.855152 -277.849838) (xy 160.854657 -277.874445) (xy 160.846762 -277.923022)
			(xy 160.831178 -277.969703) (xy 160.808307 -278.01328) (xy 160.778742 -278.052624) (xy 160.743249 -278.086716)
			(xy 160.702746 -278.114672) (xy 160.658284 -278.13577) (xy 160.611013 -278.149462) (xy 160.562158 -278.155394)
			(xy 160.512983 -278.153413) (xy 160.464764 -278.143569) (xy 160.418748 -278.126117) (xy 160.376127 -278.10151)
			(xy 160.338006 -278.070385) (xy 160.305371 -278.033548) (xy 160.279068 -277.991952) (xy 160.259777 -277.946676)
			(xy 160.248 -277.898892) (xy 160.24404 -277.849838) (xy 80.855058 -277.849838) (xy 80.854563 -277.874445)
			(xy 80.846668 -277.923022) (xy 80.831084 -277.969703) (xy 80.808213 -278.01328) (xy 80.778648 -278.052624)
			(xy 80.743155 -278.086716) (xy 80.702652 -278.114672) (xy 80.65819 -278.13577) (xy 80.610919 -278.149462)
			(xy 80.562064 -278.155394) (xy 80.512889 -278.153413) (xy 80.46467 -278.143569) (xy 80.418654 -278.126117)
			(xy 80.376033 -278.10151) (xy 80.337912 -278.070385) (xy 80.305277 -278.033548) (xy 80.278974 -277.991952)
			(xy 80.259683 -277.946676) (xy 80.247906 -277.898892) (xy 80.243946 -277.849838) (xy 78.954884 -277.849838)
			(xy 78.954389 -277.874445) (xy 78.946494 -277.923022) (xy 78.93091 -277.969703) (xy 78.908039 -278.01328)
			(xy 78.878474 -278.052624) (xy 78.842981 -278.086716) (xy 78.802478 -278.114672) (xy 78.758016 -278.13577)
			(xy 78.710745 -278.149462) (xy 78.66189 -278.155394) (xy 78.612715 -278.153413) (xy 78.564496 -278.143569)
			(xy 78.51848 -278.126117) (xy 78.475859 -278.10151) (xy 78.437738 -278.070385) (xy 78.405103 -278.033548)
			(xy 78.3788 -277.991952) (xy 78.359509 -277.946676) (xy 78.347732 -277.898892) (xy 78.343772 -277.849838)
			(xy 77.054964 -277.849838) (xy 77.054469 -277.874445) (xy 77.046574 -277.923022) (xy 77.03099 -277.969703)
			(xy 77.008119 -278.01328) (xy 76.978554 -278.052624) (xy 76.943061 -278.086716) (xy 76.902558 -278.114672)
			(xy 76.858096 -278.13577) (xy 76.810825 -278.149462) (xy 76.76197 -278.155394) (xy 76.712795 -278.153413)
			(xy 76.664576 -278.143569) (xy 76.61856 -278.126117) (xy 76.575939 -278.10151) (xy 76.537818 -278.070385)
			(xy 76.505183 -278.033548) (xy 76.47888 -277.991952) (xy 76.459589 -277.946676) (xy 76.447812 -277.898892)
			(xy 76.443852 -277.849838) (xy 75.155044 -277.849838) (xy 75.154549 -277.874445) (xy 75.146654 -277.923022)
			(xy 75.13107 -277.969703) (xy 75.108199 -278.01328) (xy 75.078634 -278.052624) (xy 75.043141 -278.086716)
			(xy 75.002638 -278.114672) (xy 74.958176 -278.13577) (xy 74.910905 -278.149462) (xy 74.86205 -278.155394)
			(xy 74.812875 -278.153413) (xy 74.764656 -278.143569) (xy 74.71864 -278.126117) (xy 74.676019 -278.10151)
			(xy 74.637898 -278.070385) (xy 74.605263 -278.033548) (xy 74.57896 -277.991952) (xy 74.559669 -277.946676)
			(xy 74.547892 -277.898892) (xy 74.543932 -277.849838) (xy 73.25487 -277.849838) (xy 73.254375 -277.874445)
			(xy 73.24648 -277.923022) (xy 73.230896 -277.969703) (xy 73.208025 -278.01328) (xy 73.17846 -278.052624)
			(xy 73.142967 -278.086716) (xy 73.102464 -278.114672) (xy 73.058002 -278.13577) (xy 73.010731 -278.149462)
			(xy 72.961876 -278.155394) (xy 72.912701 -278.153413) (xy 72.864482 -278.143569) (xy 72.818466 -278.126117)
			(xy 72.775845 -278.10151) (xy 72.737724 -278.070385) (xy 72.705089 -278.033548) (xy 72.678786 -277.991952)
			(xy 72.659495 -277.946676) (xy 72.647718 -277.898892) (xy 72.643758 -277.849838) (xy 71.35495 -277.849838)
			(xy 71.354455 -277.874445) (xy 71.34656 -277.923022) (xy 71.330976 -277.969703) (xy 71.308105 -278.01328)
			(xy 71.27854 -278.052624) (xy 71.243047 -278.086716) (xy 71.202544 -278.114672) (xy 71.158082 -278.13577)
			(xy 71.110811 -278.149462) (xy 71.061956 -278.155394) (xy 71.012781 -278.153413) (xy 70.964562 -278.143569)
			(xy 70.918546 -278.126117) (xy 70.875925 -278.10151) (xy 70.837804 -278.070385) (xy 70.805169 -278.033548)
			(xy 70.778866 -277.991952) (xy 70.759575 -277.946676) (xy 70.747798 -277.898892) (xy 70.743838 -277.849838)
			(xy 69.45503 -277.849838) (xy 69.454535 -277.874445) (xy 69.44664 -277.923022) (xy 69.431056 -277.969703)
			(xy 69.408185 -278.01328) (xy 69.37862 -278.052624) (xy 69.343127 -278.086716) (xy 69.302624 -278.114672)
			(xy 69.258162 -278.13577) (xy 69.210891 -278.149462) (xy 69.162036 -278.155394) (xy 69.112861 -278.153413)
			(xy 69.064642 -278.143569) (xy 69.018626 -278.126117) (xy 68.976005 -278.10151) (xy 68.937884 -278.070385)
			(xy 68.905249 -278.033548) (xy 68.878946 -277.991952) (xy 68.859655 -277.946676) (xy 68.847878 -277.898892)
			(xy 68.843918 -277.849838) (xy 67.554856 -277.849838) (xy 67.554361 -277.874445) (xy 67.546466 -277.923022)
			(xy 67.530882 -277.969703) (xy 67.508011 -278.01328) (xy 67.478446 -278.052624) (xy 67.442953 -278.086716)
			(xy 67.40245 -278.114672) (xy 67.357988 -278.13577) (xy 67.310717 -278.149462) (xy 67.261862 -278.155394)
			(xy 67.212687 -278.153413) (xy 67.164468 -278.143569) (xy 67.118452 -278.126117) (xy 67.075831 -278.10151)
			(xy 67.03771 -278.070385) (xy 67.005075 -278.033548) (xy 66.978772 -277.991952) (xy 66.959481 -277.946676)
			(xy 66.947704 -277.898892) (xy 66.943744 -277.849838) (xy 65.654936 -277.849838) (xy 65.654441 -277.874445)
			(xy 65.646546 -277.923022) (xy 65.630962 -277.969703) (xy 65.608091 -278.01328) (xy 65.578526 -278.052624)
			(xy 65.543033 -278.086716) (xy 65.50253 -278.114672) (xy 65.458068 -278.13577) (xy 65.410797 -278.149462)
			(xy 65.361942 -278.155394) (xy 65.312767 -278.153413) (xy 65.264548 -278.143569) (xy 65.218532 -278.126117)
			(xy 65.175911 -278.10151) (xy 65.13779 -278.070385) (xy 65.105155 -278.033548) (xy 65.078852 -277.991952)
			(xy 65.059561 -277.946676) (xy 65.047784 -277.898892) (xy 65.043824 -277.849838) (xy 63.755016 -277.849838)
			(xy 63.754521 -277.874445) (xy 63.746626 -277.923022) (xy 63.731042 -277.969703) (xy 63.708171 -278.01328)
			(xy 63.678606 -278.052624) (xy 63.643113 -278.086716) (xy 63.60261 -278.114672) (xy 63.558148 -278.13577)
			(xy 63.510877 -278.149462) (xy 63.462022 -278.155394) (xy 63.412847 -278.153413) (xy 63.364628 -278.143569)
			(xy 63.318612 -278.126117) (xy 63.275991 -278.10151) (xy 63.23787 -278.070385) (xy 63.205235 -278.033548)
			(xy 63.178932 -277.991952) (xy 63.159641 -277.946676) (xy 63.147864 -277.898892) (xy 63.143904 -277.849838)
			(xy 61.854842 -277.849838) (xy 61.854347 -277.874445) (xy 61.846452 -277.923022) (xy 61.830868 -277.969703)
			(xy 61.807997 -278.01328) (xy 61.778432 -278.052624) (xy 61.742939 -278.086716) (xy 61.702436 -278.114672)
			(xy 61.657974 -278.13577) (xy 61.610703 -278.149462) (xy 61.561848 -278.155394) (xy 61.512673 -278.153413)
			(xy 61.464454 -278.143569) (xy 61.418438 -278.126117) (xy 61.375817 -278.10151) (xy 61.337696 -278.070385)
			(xy 61.305061 -278.033548) (xy 61.278758 -277.991952) (xy 61.259467 -277.946676) (xy 61.24769 -277.898892)
			(xy 61.24373 -277.849838) (xy 59.954922 -277.849838) (xy 59.954427 -277.874445) (xy 59.946532 -277.923022)
			(xy 59.930948 -277.969703) (xy 59.908077 -278.01328) (xy 59.878512 -278.052624) (xy 59.843019 -278.086716)
			(xy 59.802516 -278.114672) (xy 59.758054 -278.13577) (xy 59.710783 -278.149462) (xy 59.661928 -278.155394)
			(xy 59.612753 -278.153413) (xy 59.564534 -278.143569) (xy 59.518518 -278.126117) (xy 59.475897 -278.10151)
			(xy 59.437776 -278.070385) (xy 59.405141 -278.033548) (xy 59.378838 -277.991952) (xy 59.359547 -277.946676)
			(xy 59.34777 -277.898892) (xy 59.34381 -277.849838) (xy 58.055256 -277.849838) (xy 58.054761 -277.874445)
			(xy 58.046866 -277.923022) (xy 58.031282 -277.969703) (xy 58.008411 -278.01328) (xy 57.978846 -278.052624)
			(xy 57.943353 -278.086716) (xy 57.90285 -278.114672) (xy 57.858388 -278.13577) (xy 57.811117 -278.149462)
			(xy 57.762262 -278.155394) (xy 57.713087 -278.153413) (xy 57.664868 -278.143569) (xy 57.618852 -278.126117)
			(xy 57.576231 -278.10151) (xy 57.53811 -278.070385) (xy 57.505475 -278.033548) (xy 57.479172 -277.991952)
			(xy 57.459881 -277.946676) (xy 57.448104 -277.898892) (xy 57.444144 -277.849838) (xy 56.155082 -277.849838)
			(xy 56.154587 -277.874445) (xy 56.146692 -277.923022) (xy 56.131108 -277.969703) (xy 56.108237 -278.01328)
			(xy 56.078672 -278.052624) (xy 56.043179 -278.086716) (xy 56.002676 -278.114672) (xy 55.958214 -278.13577)
			(xy 55.910943 -278.149462) (xy 55.862088 -278.155394) (xy 55.812913 -278.153413) (xy 55.764694 -278.143569)
			(xy 55.718678 -278.126117) (xy 55.676057 -278.10151) (xy 55.637936 -278.070385) (xy 55.605301 -278.033548)
			(xy 55.578998 -277.991952) (xy 55.559707 -277.946676) (xy 55.54793 -277.898892) (xy 55.54397 -277.849838)
			(xy 54.255162 -277.849838) (xy 54.254667 -277.874445) (xy 54.246772 -277.923022) (xy 54.231188 -277.969703)
			(xy 54.208317 -278.01328) (xy 54.178752 -278.052624) (xy 54.143259 -278.086716) (xy 54.102756 -278.114672)
			(xy 54.058294 -278.13577) (xy 54.011023 -278.149462) (xy 53.962168 -278.155394) (xy 53.912993 -278.153413)
			(xy 53.864774 -278.143569) (xy 53.818758 -278.126117) (xy 53.776137 -278.10151) (xy 53.738016 -278.070385)
			(xy 53.705381 -278.033548) (xy 53.679078 -277.991952) (xy 53.659787 -277.946676) (xy 53.64801 -277.898892)
			(xy 53.64405 -277.849838) (xy 52.355242 -277.849838) (xy 52.354747 -277.874445) (xy 52.346852 -277.923022)
			(xy 52.331268 -277.969703) (xy 52.308397 -278.01328) (xy 52.278832 -278.052624) (xy 52.243339 -278.086716)
			(xy 52.202836 -278.114672) (xy 52.158374 -278.13577) (xy 52.111103 -278.149462) (xy 52.062248 -278.155394)
			(xy 52.013073 -278.153413) (xy 51.964854 -278.143569) (xy 51.918838 -278.126117) (xy 51.876217 -278.10151)
			(xy 51.838096 -278.070385) (xy 51.805461 -278.033548) (xy 51.779158 -277.991952) (xy 51.759867 -277.946676)
			(xy 51.74809 -277.898892) (xy 51.74413 -277.849838) (xy 50.455068 -277.849838) (xy 50.454573 -277.874445)
			(xy 50.446678 -277.923022) (xy 50.431094 -277.969703) (xy 50.408223 -278.01328) (xy 50.378658 -278.052624)
			(xy 50.343165 -278.086716) (xy 50.302662 -278.114672) (xy 50.2582 -278.13577) (xy 50.210929 -278.149462)
			(xy 50.162074 -278.155394) (xy 50.112899 -278.153413) (xy 50.06468 -278.143569) (xy 50.018664 -278.126117)
			(xy 49.976043 -278.10151) (xy 49.937922 -278.070385) (xy 49.905287 -278.033548) (xy 49.878984 -277.991952)
			(xy 49.859693 -277.946676) (xy 49.847916 -277.898892) (xy 49.843956 -277.849838) (xy 48.555148 -277.849838)
			(xy 48.554653 -277.874445) (xy 48.546758 -277.923022) (xy 48.531174 -277.969703) (xy 48.508303 -278.01328)
			(xy 48.478738 -278.052624) (xy 48.443245 -278.086716) (xy 48.402742 -278.114672) (xy 48.35828 -278.13577)
			(xy 48.311009 -278.149462) (xy 48.262154 -278.155394) (xy 48.212979 -278.153413) (xy 48.16476 -278.143569)
			(xy 48.118744 -278.126117) (xy 48.076123 -278.10151) (xy 48.038002 -278.070385) (xy 48.005367 -278.033548)
			(xy 47.979064 -277.991952) (xy 47.959773 -277.946676) (xy 47.947996 -277.898892) (xy 47.944036 -277.849838)
			(xy 46.655228 -277.849838) (xy 46.654733 -277.874445) (xy 46.646838 -277.923022) (xy 46.631254 -277.969703)
			(xy 46.608383 -278.01328) (xy 46.578818 -278.052624) (xy 46.543325 -278.086716) (xy 46.502822 -278.114672)
			(xy 46.45836 -278.13577) (xy 46.411089 -278.149462) (xy 46.362234 -278.155394) (xy 46.313059 -278.153413)
			(xy 46.26484 -278.143569) (xy 46.218824 -278.126117) (xy 46.176203 -278.10151) (xy 46.138082 -278.070385)
			(xy 46.105447 -278.033548) (xy 46.079144 -277.991952) (xy 46.059853 -277.946676) (xy 46.048076 -277.898892)
			(xy 46.044116 -277.849838) (xy 44.755054 -277.849838) (xy 44.754559 -277.874445) (xy 44.746664 -277.923022)
			(xy 44.73108 -277.969703) (xy 44.708209 -278.01328) (xy 44.678644 -278.052624) (xy 44.643151 -278.086716)
			(xy 44.602648 -278.114672) (xy 44.558186 -278.13577) (xy 44.510915 -278.149462) (xy 44.46206 -278.155394)
			(xy 44.412885 -278.153413) (xy 44.364666 -278.143569) (xy 44.31865 -278.126117) (xy 44.276029 -278.10151)
			(xy 44.237908 -278.070385) (xy 44.205273 -278.033548) (xy 44.17897 -277.991952) (xy 44.159679 -277.946676)
			(xy 44.147902 -277.898892) (xy 44.143942 -277.849838) (xy 0.508 -277.849838) (xy 0.508 -278.799798)
			(xy 44.143942 -278.799798) (xy 44.147902 -278.750744) (xy 44.159679 -278.70296) (xy 44.17897 -278.657684)
			(xy 44.205273 -278.616088) (xy 44.237908 -278.579251) (xy 44.276029 -278.548126) (xy 44.31865 -278.523519)
			(xy 44.364666 -278.506067) (xy 44.412885 -278.496223) (xy 44.46206 -278.494242) (xy 44.510915 -278.500174)
			(xy 44.558186 -278.513866) (xy 44.602648 -278.534964) (xy 44.643151 -278.56292) (xy 44.678644 -278.597012)
			(xy 44.708209 -278.636356) (xy 44.73108 -278.679933) (xy 44.746664 -278.726614) (xy 44.754559 -278.775191)
			(xy 44.755054 -278.799798) (xy 46.044116 -278.799798) (xy 46.048076 -278.750744) (xy 46.059853 -278.70296)
			(xy 46.079144 -278.657684) (xy 46.105447 -278.616088) (xy 46.138082 -278.579251) (xy 46.176203 -278.548126)
			(xy 46.218824 -278.523519) (xy 46.26484 -278.506067) (xy 46.313059 -278.496223) (xy 46.362234 -278.494242)
			(xy 46.411089 -278.500174) (xy 46.45836 -278.513866) (xy 46.502822 -278.534964) (xy 46.543325 -278.56292)
			(xy 46.578818 -278.597012) (xy 46.608383 -278.636356) (xy 46.631254 -278.679933) (xy 46.646838 -278.726614)
			(xy 46.654733 -278.775191) (xy 46.655228 -278.799798) (xy 47.944036 -278.799798) (xy 47.947996 -278.750744)
			(xy 47.959773 -278.70296) (xy 47.979064 -278.657684) (xy 48.005367 -278.616088) (xy 48.038002 -278.579251)
			(xy 48.076123 -278.548126) (xy 48.118744 -278.523519) (xy 48.16476 -278.506067) (xy 48.212979 -278.496223)
			(xy 48.262154 -278.494242) (xy 48.311009 -278.500174) (xy 48.35828 -278.513866) (xy 48.402742 -278.534964)
			(xy 48.443245 -278.56292) (xy 48.478738 -278.597012) (xy 48.508303 -278.636356) (xy 48.531174 -278.679933)
			(xy 48.546758 -278.726614) (xy 48.554653 -278.775191) (xy 48.555148 -278.799798) (xy 49.843956 -278.799798)
			(xy 49.847916 -278.750744) (xy 49.859693 -278.70296) (xy 49.878984 -278.657684) (xy 49.905287 -278.616088)
			(xy 49.937922 -278.579251) (xy 49.976043 -278.548126) (xy 50.018664 -278.523519) (xy 50.06468 -278.506067)
			(xy 50.112899 -278.496223) (xy 50.162074 -278.494242) (xy 50.210929 -278.500174) (xy 50.2582 -278.513866)
			(xy 50.302662 -278.534964) (xy 50.343165 -278.56292) (xy 50.378658 -278.597012) (xy 50.408223 -278.636356)
			(xy 50.431094 -278.679933) (xy 50.446678 -278.726614) (xy 50.454573 -278.775191) (xy 50.455068 -278.799798)
			(xy 51.74413 -278.799798) (xy 51.74809 -278.750744) (xy 51.759867 -278.70296) (xy 51.779158 -278.657684)
			(xy 51.805461 -278.616088) (xy 51.838096 -278.579251) (xy 51.876217 -278.548126) (xy 51.918838 -278.523519)
			(xy 51.964854 -278.506067) (xy 52.013073 -278.496223) (xy 52.062248 -278.494242) (xy 52.111103 -278.500174)
			(xy 52.158374 -278.513866) (xy 52.202836 -278.534964) (xy 52.243339 -278.56292) (xy 52.278832 -278.597012)
			(xy 52.308397 -278.636356) (xy 52.331268 -278.679933) (xy 52.346852 -278.726614) (xy 52.354747 -278.775191)
			(xy 52.355242 -278.799798) (xy 53.64405 -278.799798) (xy 53.64801 -278.750744) (xy 53.659787 -278.70296)
			(xy 53.679078 -278.657684) (xy 53.705381 -278.616088) (xy 53.738016 -278.579251) (xy 53.776137 -278.548126)
			(xy 53.818758 -278.523519) (xy 53.864774 -278.506067) (xy 53.912993 -278.496223) (xy 53.962168 -278.494242)
			(xy 54.011023 -278.500174) (xy 54.058294 -278.513866) (xy 54.102756 -278.534964) (xy 54.143259 -278.56292)
			(xy 54.178752 -278.597012) (xy 54.208317 -278.636356) (xy 54.231188 -278.679933) (xy 54.246772 -278.726614)
			(xy 54.254667 -278.775191) (xy 54.255162 -278.799798) (xy 55.54397 -278.799798) (xy 55.54793 -278.750744)
			(xy 55.559707 -278.70296) (xy 55.578998 -278.657684) (xy 55.605301 -278.616088) (xy 55.637936 -278.579251)
			(xy 55.676057 -278.548126) (xy 55.718678 -278.523519) (xy 55.764694 -278.506067) (xy 55.812913 -278.496223)
			(xy 55.862088 -278.494242) (xy 55.910943 -278.500174) (xy 55.958214 -278.513866) (xy 56.002676 -278.534964)
			(xy 56.043179 -278.56292) (xy 56.078672 -278.597012) (xy 56.108237 -278.636356) (xy 56.131108 -278.679933)
			(xy 56.146692 -278.726614) (xy 56.154587 -278.775191) (xy 56.155082 -278.799798) (xy 57.444144 -278.799798)
			(xy 57.448104 -278.750744) (xy 57.459881 -278.70296) (xy 57.479172 -278.657684) (xy 57.505475 -278.616088)
			(xy 57.53811 -278.579251) (xy 57.576231 -278.548126) (xy 57.618852 -278.523519) (xy 57.664868 -278.506067)
			(xy 57.713087 -278.496223) (xy 57.762262 -278.494242) (xy 57.811117 -278.500174) (xy 57.858388 -278.513866)
			(xy 57.90285 -278.534964) (xy 57.943353 -278.56292) (xy 57.978846 -278.597012) (xy 58.008411 -278.636356)
			(xy 58.031282 -278.679933) (xy 58.046866 -278.726614) (xy 58.054761 -278.775191) (xy 58.055256 -278.799798)
			(xy 59.34381 -278.799798) (xy 59.34777 -278.750744) (xy 59.359547 -278.70296) (xy 59.378838 -278.657684)
			(xy 59.405141 -278.616088) (xy 59.437776 -278.579251) (xy 59.475897 -278.548126) (xy 59.518518 -278.523519)
			(xy 59.564534 -278.506067) (xy 59.612753 -278.496223) (xy 59.661928 -278.494242) (xy 59.710783 -278.500174)
			(xy 59.758054 -278.513866) (xy 59.802516 -278.534964) (xy 59.843019 -278.56292) (xy 59.878512 -278.597012)
			(xy 59.908077 -278.636356) (xy 59.930948 -278.679933) (xy 59.946532 -278.726614) (xy 59.954427 -278.775191)
			(xy 59.954922 -278.799798) (xy 61.24373 -278.799798) (xy 61.24769 -278.750744) (xy 61.259467 -278.70296)
			(xy 61.278758 -278.657684) (xy 61.305061 -278.616088) (xy 61.337696 -278.579251) (xy 61.375817 -278.548126)
			(xy 61.418438 -278.523519) (xy 61.464454 -278.506067) (xy 61.512673 -278.496223) (xy 61.561848 -278.494242)
			(xy 61.610703 -278.500174) (xy 61.657974 -278.513866) (xy 61.702436 -278.534964) (xy 61.742939 -278.56292)
			(xy 61.778432 -278.597012) (xy 61.807997 -278.636356) (xy 61.830868 -278.679933) (xy 61.846452 -278.726614)
			(xy 61.854347 -278.775191) (xy 61.854842 -278.799798) (xy 63.143904 -278.799798) (xy 63.147864 -278.750744)
			(xy 63.159641 -278.70296) (xy 63.178932 -278.657684) (xy 63.205235 -278.616088) (xy 63.23787 -278.579251)
			(xy 63.275991 -278.548126) (xy 63.318612 -278.523519) (xy 63.364628 -278.506067) (xy 63.412847 -278.496223)
			(xy 63.462022 -278.494242) (xy 63.510877 -278.500174) (xy 63.558148 -278.513866) (xy 63.60261 -278.534964)
			(xy 63.643113 -278.56292) (xy 63.678606 -278.597012) (xy 63.708171 -278.636356) (xy 63.731042 -278.679933)
			(xy 63.746626 -278.726614) (xy 63.754521 -278.775191) (xy 63.755016 -278.799798) (xy 65.043824 -278.799798)
			(xy 65.047784 -278.750744) (xy 65.059561 -278.70296) (xy 65.078852 -278.657684) (xy 65.105155 -278.616088)
			(xy 65.13779 -278.579251) (xy 65.175911 -278.548126) (xy 65.218532 -278.523519) (xy 65.264548 -278.506067)
			(xy 65.312767 -278.496223) (xy 65.361942 -278.494242) (xy 65.410797 -278.500174) (xy 65.458068 -278.513866)
			(xy 65.50253 -278.534964) (xy 65.543033 -278.56292) (xy 65.578526 -278.597012) (xy 65.608091 -278.636356)
			(xy 65.630962 -278.679933) (xy 65.646546 -278.726614) (xy 65.654441 -278.775191) (xy 65.654936 -278.799798)
			(xy 66.943744 -278.799798) (xy 66.947704 -278.750744) (xy 66.959481 -278.70296) (xy 66.978772 -278.657684)
			(xy 67.005075 -278.616088) (xy 67.03771 -278.579251) (xy 67.075831 -278.548126) (xy 67.118452 -278.523519)
			(xy 67.164468 -278.506067) (xy 67.212687 -278.496223) (xy 67.261862 -278.494242) (xy 67.310717 -278.500174)
			(xy 67.357988 -278.513866) (xy 67.40245 -278.534964) (xy 67.442953 -278.56292) (xy 67.478446 -278.597012)
			(xy 67.508011 -278.636356) (xy 67.530882 -278.679933) (xy 67.546466 -278.726614) (xy 67.554361 -278.775191)
			(xy 67.554856 -278.799798) (xy 68.843918 -278.799798) (xy 68.847878 -278.750744) (xy 68.859655 -278.70296)
			(xy 68.878946 -278.657684) (xy 68.905249 -278.616088) (xy 68.937884 -278.579251) (xy 68.976005 -278.548126)
			(xy 69.018626 -278.523519) (xy 69.064642 -278.506067) (xy 69.112861 -278.496223) (xy 69.162036 -278.494242)
			(xy 69.210891 -278.500174) (xy 69.258162 -278.513866) (xy 69.302624 -278.534964) (xy 69.343127 -278.56292)
			(xy 69.37862 -278.597012) (xy 69.408185 -278.636356) (xy 69.431056 -278.679933) (xy 69.44664 -278.726614)
			(xy 69.454535 -278.775191) (xy 69.45503 -278.799798) (xy 70.743838 -278.799798) (xy 70.747798 -278.750744)
			(xy 70.759575 -278.70296) (xy 70.778866 -278.657684) (xy 70.805169 -278.616088) (xy 70.837804 -278.579251)
			(xy 70.875925 -278.548126) (xy 70.918546 -278.523519) (xy 70.964562 -278.506067) (xy 71.012781 -278.496223)
			(xy 71.061956 -278.494242) (xy 71.110811 -278.500174) (xy 71.158082 -278.513866) (xy 71.202544 -278.534964)
			(xy 71.243047 -278.56292) (xy 71.27854 -278.597012) (xy 71.308105 -278.636356) (xy 71.330976 -278.679933)
			(xy 71.34656 -278.726614) (xy 71.354455 -278.775191) (xy 71.35495 -278.799798) (xy 72.643758 -278.799798)
			(xy 72.647718 -278.750744) (xy 72.659495 -278.70296) (xy 72.678786 -278.657684) (xy 72.705089 -278.616088)
			(xy 72.737724 -278.579251) (xy 72.775845 -278.548126) (xy 72.818466 -278.523519) (xy 72.864482 -278.506067)
			(xy 72.912701 -278.496223) (xy 72.961876 -278.494242) (xy 73.010731 -278.500174) (xy 73.058002 -278.513866)
			(xy 73.102464 -278.534964) (xy 73.142967 -278.56292) (xy 73.17846 -278.597012) (xy 73.208025 -278.636356)
			(xy 73.230896 -278.679933) (xy 73.24648 -278.726614) (xy 73.254375 -278.775191) (xy 73.25487 -278.799798)
			(xy 74.543932 -278.799798) (xy 74.547892 -278.750744) (xy 74.559669 -278.70296) (xy 74.57896 -278.657684)
			(xy 74.605263 -278.616088) (xy 74.637898 -278.579251) (xy 74.676019 -278.548126) (xy 74.71864 -278.523519)
			(xy 74.764656 -278.506067) (xy 74.812875 -278.496223) (xy 74.86205 -278.494242) (xy 74.910905 -278.500174)
			(xy 74.958176 -278.513866) (xy 75.002638 -278.534964) (xy 75.043141 -278.56292) (xy 75.078634 -278.597012)
			(xy 75.108199 -278.636356) (xy 75.13107 -278.679933) (xy 75.146654 -278.726614) (xy 75.154549 -278.775191)
			(xy 75.155044 -278.799798) (xy 76.443852 -278.799798) (xy 76.447812 -278.750744) (xy 76.459589 -278.70296)
			(xy 76.47888 -278.657684) (xy 76.505183 -278.616088) (xy 76.537818 -278.579251) (xy 76.575939 -278.548126)
			(xy 76.61856 -278.523519) (xy 76.664576 -278.506067) (xy 76.712795 -278.496223) (xy 76.76197 -278.494242)
			(xy 76.810825 -278.500174) (xy 76.858096 -278.513866) (xy 76.902558 -278.534964) (xy 76.943061 -278.56292)
			(xy 76.978554 -278.597012) (xy 77.008119 -278.636356) (xy 77.03099 -278.679933) (xy 77.046574 -278.726614)
			(xy 77.054469 -278.775191) (xy 77.054964 -278.799798) (xy 78.343772 -278.799798) (xy 78.347732 -278.750744)
			(xy 78.359509 -278.70296) (xy 78.3788 -278.657684) (xy 78.405103 -278.616088) (xy 78.437738 -278.579251)
			(xy 78.475859 -278.548126) (xy 78.51848 -278.523519) (xy 78.564496 -278.506067) (xy 78.612715 -278.496223)
			(xy 78.66189 -278.494242) (xy 78.710745 -278.500174) (xy 78.758016 -278.513866) (xy 78.802478 -278.534964)
			(xy 78.842981 -278.56292) (xy 78.878474 -278.597012) (xy 78.908039 -278.636356) (xy 78.93091 -278.679933)
			(xy 78.946494 -278.726614) (xy 78.954389 -278.775191) (xy 78.954884 -278.799798) (xy 80.243946 -278.799798)
			(xy 80.247906 -278.750744) (xy 80.259683 -278.70296) (xy 80.278974 -278.657684) (xy 80.305277 -278.616088)
			(xy 80.337912 -278.579251) (xy 80.376033 -278.548126) (xy 80.418654 -278.523519) (xy 80.46467 -278.506067)
			(xy 80.512889 -278.496223) (xy 80.562064 -278.494242) (xy 80.610919 -278.500174) (xy 80.65819 -278.513866)
			(xy 80.702652 -278.534964) (xy 80.743155 -278.56292) (xy 80.778648 -278.597012) (xy 80.808213 -278.636356)
			(xy 80.831084 -278.679933) (xy 80.846668 -278.726614) (xy 80.854563 -278.775191) (xy 80.855058 -278.799798)
			(xy 160.24404 -278.799798) (xy 160.248 -278.750744) (xy 160.259777 -278.70296) (xy 160.279068 -278.657684)
			(xy 160.305371 -278.616088) (xy 160.338006 -278.579251) (xy 160.376127 -278.548126) (xy 160.418748 -278.523519)
			(xy 160.464764 -278.506067) (xy 160.512983 -278.496223) (xy 160.562158 -278.494242) (xy 160.611013 -278.500174)
			(xy 160.658284 -278.513866) (xy 160.702746 -278.534964) (xy 160.743249 -278.56292) (xy 160.778742 -278.597012)
			(xy 160.808307 -278.636356) (xy 160.831178 -278.679933) (xy 160.846762 -278.726614) (xy 160.854657 -278.775191)
			(xy 160.855152 -278.799798) (xy 162.144214 -278.799798) (xy 162.148174 -278.750744) (xy 162.159951 -278.70296)
			(xy 162.179242 -278.657684) (xy 162.205545 -278.616088) (xy 162.23818 -278.579251) (xy 162.276301 -278.548126)
			(xy 162.318922 -278.523519) (xy 162.364938 -278.506067) (xy 162.413157 -278.496223) (xy 162.462332 -278.494242)
			(xy 162.511187 -278.500174) (xy 162.558458 -278.513866) (xy 162.60292 -278.534964) (xy 162.643423 -278.56292)
			(xy 162.678916 -278.597012) (xy 162.708481 -278.636356) (xy 162.731352 -278.679933) (xy 162.746936 -278.726614)
			(xy 162.754831 -278.775191) (xy 162.755326 -278.799798) (xy 164.044134 -278.799798) (xy 164.048094 -278.750744)
			(xy 164.059871 -278.70296) (xy 164.079162 -278.657684) (xy 164.105465 -278.616088) (xy 164.1381 -278.579251)
			(xy 164.176221 -278.548126) (xy 164.218842 -278.523519) (xy 164.264858 -278.506067) (xy 164.313077 -278.496223)
			(xy 164.362252 -278.494242) (xy 164.411107 -278.500174) (xy 164.458378 -278.513866) (xy 164.50284 -278.534964)
			(xy 164.543343 -278.56292) (xy 164.578836 -278.597012) (xy 164.608401 -278.636356) (xy 164.631272 -278.679933)
			(xy 164.646856 -278.726614) (xy 164.654751 -278.775191) (xy 164.655246 -278.799798) (xy 165.944054 -278.799798)
			(xy 165.948014 -278.750744) (xy 165.959791 -278.70296) (xy 165.979082 -278.657684) (xy 166.005385 -278.616088)
			(xy 166.03802 -278.579251) (xy 166.076141 -278.548126) (xy 166.118762 -278.523519) (xy 166.164778 -278.506067)
			(xy 166.212997 -278.496223) (xy 166.262172 -278.494242) (xy 166.311027 -278.500174) (xy 166.358298 -278.513866)
			(xy 166.40276 -278.534964) (xy 166.443263 -278.56292) (xy 166.478756 -278.597012) (xy 166.508321 -278.636356)
			(xy 166.531192 -278.679933) (xy 166.546776 -278.726614) (xy 166.554671 -278.775191) (xy 166.555166 -278.799798)
			(xy 167.844228 -278.799798) (xy 167.848188 -278.750744) (xy 167.859965 -278.70296) (xy 167.879256 -278.657684)
			(xy 167.905559 -278.616088) (xy 167.938194 -278.579251) (xy 167.976315 -278.548126) (xy 168.018936 -278.523519)
			(xy 168.064952 -278.506067) (xy 168.113171 -278.496223) (xy 168.162346 -278.494242) (xy 168.211201 -278.500174)
			(xy 168.258472 -278.513866) (xy 168.302934 -278.534964) (xy 168.343437 -278.56292) (xy 168.37893 -278.597012)
			(xy 168.408495 -278.636356) (xy 168.431366 -278.679933) (xy 168.44695 -278.726614) (xy 168.454845 -278.775191)
			(xy 168.45534 -278.799798) (xy 169.744148 -278.799798) (xy 169.748108 -278.750744) (xy 169.759885 -278.70296)
			(xy 169.779176 -278.657684) (xy 169.805479 -278.616088) (xy 169.838114 -278.579251) (xy 169.876235 -278.548126)
			(xy 169.918856 -278.523519) (xy 169.964872 -278.506067) (xy 170.013091 -278.496223) (xy 170.062266 -278.494242)
			(xy 170.111121 -278.500174) (xy 170.158392 -278.513866) (xy 170.202854 -278.534964) (xy 170.243357 -278.56292)
			(xy 170.27885 -278.597012) (xy 170.308415 -278.636356) (xy 170.331286 -278.679933) (xy 170.34687 -278.726614)
			(xy 170.354765 -278.775191) (xy 170.35526 -278.799798) (xy 171.644068 -278.799798) (xy 171.648028 -278.750744)
			(xy 171.659805 -278.70296) (xy 171.679096 -278.657684) (xy 171.705399 -278.616088) (xy 171.738034 -278.579251)
			(xy 171.776155 -278.548126) (xy 171.818776 -278.523519) (xy 171.864792 -278.506067) (xy 171.913011 -278.496223)
			(xy 171.962186 -278.494242) (xy 172.011041 -278.500174) (xy 172.058312 -278.513866) (xy 172.102774 -278.534964)
			(xy 172.143277 -278.56292) (xy 172.17877 -278.597012) (xy 172.208335 -278.636356) (xy 172.231206 -278.679933)
			(xy 172.24679 -278.726614) (xy 172.254685 -278.775191) (xy 172.25518 -278.799798) (xy 173.544242 -278.799798)
			(xy 173.548202 -278.750744) (xy 173.559979 -278.70296) (xy 173.57927 -278.657684) (xy 173.605573 -278.616088)
			(xy 173.638208 -278.579251) (xy 173.676329 -278.548126) (xy 173.71895 -278.523519) (xy 173.764966 -278.506067)
			(xy 173.813185 -278.496223) (xy 173.86236 -278.494242) (xy 173.911215 -278.500174) (xy 173.958486 -278.513866)
			(xy 174.002948 -278.534964) (xy 174.043451 -278.56292) (xy 174.078944 -278.597012) (xy 174.108509 -278.636356)
			(xy 174.13138 -278.679933) (xy 174.146964 -278.726614) (xy 174.154859 -278.775191) (xy 174.155354 -278.799798)
			(xy 175.443908 -278.799798) (xy 175.447868 -278.750744) (xy 175.459645 -278.70296) (xy 175.478936 -278.657684)
			(xy 175.505239 -278.616088) (xy 175.537874 -278.579251) (xy 175.575995 -278.548126) (xy 175.618616 -278.523519)
			(xy 175.664632 -278.506067) (xy 175.712851 -278.496223) (xy 175.762026 -278.494242) (xy 175.810881 -278.500174)
			(xy 175.858152 -278.513866) (xy 175.902614 -278.534964) (xy 175.943117 -278.56292) (xy 175.97861 -278.597012)
			(xy 176.008175 -278.636356) (xy 176.031046 -278.679933) (xy 176.04663 -278.726614) (xy 176.054525 -278.775191)
			(xy 176.05502 -278.799798) (xy 177.343828 -278.799798) (xy 177.347788 -278.750744) (xy 177.359565 -278.70296)
			(xy 177.378856 -278.657684) (xy 177.405159 -278.616088) (xy 177.437794 -278.579251) (xy 177.475915 -278.548126)
			(xy 177.518536 -278.523519) (xy 177.564552 -278.506067) (xy 177.612771 -278.496223) (xy 177.661946 -278.494242)
			(xy 177.710801 -278.500174) (xy 177.758072 -278.513866) (xy 177.802534 -278.534964) (xy 177.843037 -278.56292)
			(xy 177.87853 -278.597012) (xy 177.908095 -278.636356) (xy 177.930966 -278.679933) (xy 177.94655 -278.726614)
			(xy 177.954445 -278.775191) (xy 177.95494 -278.799798) (xy 179.244002 -278.799798) (xy 179.247962 -278.750744)
			(xy 179.259739 -278.70296) (xy 179.27903 -278.657684) (xy 179.305333 -278.616088) (xy 179.337968 -278.579251)
			(xy 179.376089 -278.548126) (xy 179.41871 -278.523519) (xy 179.464726 -278.506067) (xy 179.512945 -278.496223)
			(xy 179.56212 -278.494242) (xy 179.610975 -278.500174) (xy 179.658246 -278.513866) (xy 179.702708 -278.534964)
			(xy 179.743211 -278.56292) (xy 179.778704 -278.597012) (xy 179.808269 -278.636356) (xy 179.83114 -278.679933)
			(xy 179.846724 -278.726614) (xy 179.854619 -278.775191) (xy 179.855114 -278.799798) (xy 181.143922 -278.799798)
			(xy 181.147882 -278.750744) (xy 181.159659 -278.70296) (xy 181.17895 -278.657684) (xy 181.205253 -278.616088)
			(xy 181.237888 -278.579251) (xy 181.276009 -278.548126) (xy 181.31863 -278.523519) (xy 181.364646 -278.506067)
			(xy 181.412865 -278.496223) (xy 181.46204 -278.494242) (xy 181.510895 -278.500174) (xy 181.558166 -278.513866)
			(xy 181.602628 -278.534964) (xy 181.643131 -278.56292) (xy 181.678624 -278.597012) (xy 181.708189 -278.636356)
			(xy 181.73106 -278.679933) (xy 181.746644 -278.726614) (xy 181.754539 -278.775191) (xy 181.755034 -278.799798)
			(xy 183.043842 -278.799798) (xy 183.047802 -278.750744) (xy 183.059579 -278.70296) (xy 183.07887 -278.657684)
			(xy 183.105173 -278.616088) (xy 183.137808 -278.579251) (xy 183.175929 -278.548126) (xy 183.21855 -278.523519)
			(xy 183.264566 -278.506067) (xy 183.312785 -278.496223) (xy 183.36196 -278.494242) (xy 183.410815 -278.500174)
			(xy 183.458086 -278.513866) (xy 183.502548 -278.534964) (xy 183.543051 -278.56292) (xy 183.578544 -278.597012)
			(xy 183.608109 -278.636356) (xy 183.63098 -278.679933) (xy 183.646564 -278.726614) (xy 183.654459 -278.775191)
			(xy 183.654954 -278.799798) (xy 184.944016 -278.799798) (xy 184.947976 -278.750744) (xy 184.959753 -278.70296)
			(xy 184.979044 -278.657684) (xy 185.005347 -278.616088) (xy 185.037982 -278.579251) (xy 185.076103 -278.548126)
			(xy 185.118724 -278.523519) (xy 185.16474 -278.506067) (xy 185.212959 -278.496223) (xy 185.262134 -278.494242)
			(xy 185.310989 -278.500174) (xy 185.35826 -278.513866) (xy 185.402722 -278.534964) (xy 185.443225 -278.56292)
			(xy 185.478718 -278.597012) (xy 185.508283 -278.636356) (xy 185.531154 -278.679933) (xy 185.546738 -278.726614)
			(xy 185.554633 -278.775191) (xy 185.555128 -278.799798) (xy 186.843936 -278.799798) (xy 186.847896 -278.750744)
			(xy 186.859673 -278.70296) (xy 186.878964 -278.657684) (xy 186.905267 -278.616088) (xy 186.937902 -278.579251)
			(xy 186.976023 -278.548126) (xy 187.018644 -278.523519) (xy 187.06466 -278.506067) (xy 187.112879 -278.496223)
			(xy 187.162054 -278.494242) (xy 187.210909 -278.500174) (xy 187.25818 -278.513866) (xy 187.302642 -278.534964)
			(xy 187.343145 -278.56292) (xy 187.378638 -278.597012) (xy 187.408203 -278.636356) (xy 187.431074 -278.679933)
			(xy 187.446658 -278.726614) (xy 187.454553 -278.775191) (xy 187.455048 -278.799798) (xy 188.743856 -278.799798)
			(xy 188.747816 -278.750744) (xy 188.759593 -278.70296) (xy 188.778884 -278.657684) (xy 188.805187 -278.616088)
			(xy 188.837822 -278.579251) (xy 188.875943 -278.548126) (xy 188.918564 -278.523519) (xy 188.96458 -278.506067)
			(xy 189.012799 -278.496223) (xy 189.061974 -278.494242) (xy 189.110829 -278.500174) (xy 189.1581 -278.513866)
			(xy 189.202562 -278.534964) (xy 189.243065 -278.56292) (xy 189.278558 -278.597012) (xy 189.308123 -278.636356)
			(xy 189.330994 -278.679933) (xy 189.346578 -278.726614) (xy 189.354473 -278.775191) (xy 189.354968 -278.799798)
			(xy 190.64403 -278.799798) (xy 190.64799 -278.750744) (xy 190.659767 -278.70296) (xy 190.679058 -278.657684)
			(xy 190.705361 -278.616088) (xy 190.737996 -278.579251) (xy 190.776117 -278.548126) (xy 190.818738 -278.523519)
			(xy 190.864754 -278.506067) (xy 190.912973 -278.496223) (xy 190.962148 -278.494242) (xy 191.011003 -278.500174)
			(xy 191.058274 -278.513866) (xy 191.102736 -278.534964) (xy 191.143239 -278.56292) (xy 191.178732 -278.597012)
			(xy 191.208297 -278.636356) (xy 191.231168 -278.679933) (xy 191.246752 -278.726614) (xy 191.254647 -278.775191)
			(xy 191.255142 -278.799798) (xy 192.54395 -278.799798) (xy 192.54791 -278.750744) (xy 192.559687 -278.70296)
			(xy 192.578978 -278.657684) (xy 192.605281 -278.616088) (xy 192.637916 -278.579251) (xy 192.676037 -278.548126)
			(xy 192.718658 -278.523519) (xy 192.764674 -278.506067) (xy 192.812893 -278.496223) (xy 192.862068 -278.494242)
			(xy 192.910923 -278.500174) (xy 192.958194 -278.513866) (xy 193.002656 -278.534964) (xy 193.043159 -278.56292)
			(xy 193.078652 -278.597012) (xy 193.108217 -278.636356) (xy 193.131088 -278.679933) (xy 193.146672 -278.726614)
			(xy 193.154567 -278.775191) (xy 193.155062 -278.799798) (xy 194.44387 -278.799798) (xy 194.44783 -278.750744)
			(xy 194.459607 -278.70296) (xy 194.478898 -278.657684) (xy 194.505201 -278.616088) (xy 194.537836 -278.579251)
			(xy 194.575957 -278.548126) (xy 194.618578 -278.523519) (xy 194.664594 -278.506067) (xy 194.712813 -278.496223)
			(xy 194.761988 -278.494242) (xy 194.810843 -278.500174) (xy 194.858114 -278.513866) (xy 194.902576 -278.534964)
			(xy 194.943079 -278.56292) (xy 194.978572 -278.597012) (xy 195.008137 -278.636356) (xy 195.031008 -278.679933)
			(xy 195.046592 -278.726614) (xy 195.054487 -278.775191) (xy 195.054982 -278.799798) (xy 196.344044 -278.799798)
			(xy 196.348004 -278.750744) (xy 196.359781 -278.70296) (xy 196.379072 -278.657684) (xy 196.405375 -278.616088)
			(xy 196.43801 -278.579251) (xy 196.476131 -278.548126) (xy 196.518752 -278.523519) (xy 196.564768 -278.506067)
			(xy 196.612987 -278.496223) (xy 196.662162 -278.494242) (xy 196.711017 -278.500174) (xy 196.758288 -278.513866)
			(xy 196.80275 -278.534964) (xy 196.843253 -278.56292) (xy 196.878746 -278.597012) (xy 196.908311 -278.636356)
			(xy 196.931182 -278.679933) (xy 196.946766 -278.726614) (xy 196.954661 -278.775191) (xy 196.955156 -278.799798)
			(xy 276.343884 -278.799798) (xy 276.347844 -278.750744) (xy 276.359621 -278.70296) (xy 276.378912 -278.657684)
			(xy 276.405215 -278.616088) (xy 276.43785 -278.579251) (xy 276.475971 -278.548126) (xy 276.518592 -278.523519)
			(xy 276.564608 -278.506067) (xy 276.612827 -278.496223) (xy 276.662002 -278.494242) (xy 276.710857 -278.500174)
			(xy 276.758128 -278.513866) (xy 276.80259 -278.534964) (xy 276.843093 -278.56292) (xy 276.878586 -278.597012)
			(xy 276.908151 -278.636356) (xy 276.931022 -278.679933) (xy 276.946606 -278.726614) (xy 276.954501 -278.775191)
			(xy 276.954996 -278.799798) (xy 278.244058 -278.799798) (xy 278.248018 -278.750744) (xy 278.259795 -278.70296)
			(xy 278.279086 -278.657684) (xy 278.305389 -278.616088) (xy 278.338024 -278.579251) (xy 278.376145 -278.548126)
			(xy 278.418766 -278.523519) (xy 278.464782 -278.506067) (xy 278.513001 -278.496223) (xy 278.562176 -278.494242)
			(xy 278.611031 -278.500174) (xy 278.658302 -278.513866) (xy 278.702764 -278.534964) (xy 278.743267 -278.56292)
			(xy 278.77876 -278.597012) (xy 278.808325 -278.636356) (xy 278.831196 -278.679933) (xy 278.84678 -278.726614)
			(xy 278.854675 -278.775191) (xy 278.85517 -278.799798) (xy 280.143978 -278.799798) (xy 280.147938 -278.750744)
			(xy 280.159715 -278.70296) (xy 280.179006 -278.657684) (xy 280.205309 -278.616088) (xy 280.237944 -278.579251)
			(xy 280.276065 -278.548126) (xy 280.318686 -278.523519) (xy 280.364702 -278.506067) (xy 280.412921 -278.496223)
			(xy 280.462096 -278.494242) (xy 280.510951 -278.500174) (xy 280.558222 -278.513866) (xy 280.602684 -278.534964)
			(xy 280.643187 -278.56292) (xy 280.67868 -278.597012) (xy 280.708245 -278.636356) (xy 280.731116 -278.679933)
			(xy 280.7467 -278.726614) (xy 280.754595 -278.775191) (xy 280.75509 -278.799798) (xy 282.043898 -278.799798)
			(xy 282.047858 -278.750744) (xy 282.059635 -278.70296) (xy 282.078926 -278.657684) (xy 282.105229 -278.616088)
			(xy 282.137864 -278.579251) (xy 282.175985 -278.548126) (xy 282.218606 -278.523519) (xy 282.264622 -278.506067)
			(xy 282.312841 -278.496223) (xy 282.362016 -278.494242) (xy 282.410871 -278.500174) (xy 282.458142 -278.513866)
			(xy 282.502604 -278.534964) (xy 282.543107 -278.56292) (xy 282.5786 -278.597012) (xy 282.608165 -278.636356)
			(xy 282.631036 -278.679933) (xy 282.64662 -278.726614) (xy 282.654515 -278.775191) (xy 282.65501 -278.799798)
			(xy 283.944072 -278.799798) (xy 283.948032 -278.750744) (xy 283.959809 -278.70296) (xy 283.9791 -278.657684)
			(xy 284.005403 -278.616088) (xy 284.038038 -278.579251) (xy 284.076159 -278.548126) (xy 284.11878 -278.523519)
			(xy 284.164796 -278.506067) (xy 284.213015 -278.496223) (xy 284.26219 -278.494242) (xy 284.311045 -278.500174)
			(xy 284.358316 -278.513866) (xy 284.402778 -278.534964) (xy 284.443281 -278.56292) (xy 284.478774 -278.597012)
			(xy 284.508339 -278.636356) (xy 284.53121 -278.679933) (xy 284.546794 -278.726614) (xy 284.554689 -278.775191)
			(xy 284.555184 -278.799798) (xy 285.843992 -278.799798) (xy 285.847952 -278.750744) (xy 285.859729 -278.70296)
			(xy 285.87902 -278.657684) (xy 285.905323 -278.616088) (xy 285.937958 -278.579251) (xy 285.976079 -278.548126)
			(xy 286.0187 -278.523519) (xy 286.064716 -278.506067) (xy 286.112935 -278.496223) (xy 286.16211 -278.494242)
			(xy 286.210965 -278.500174) (xy 286.258236 -278.513866) (xy 286.302698 -278.534964) (xy 286.343201 -278.56292)
			(xy 286.378694 -278.597012) (xy 286.408259 -278.636356) (xy 286.43113 -278.679933) (xy 286.446714 -278.726614)
			(xy 286.454609 -278.775191) (xy 286.455104 -278.799798) (xy 287.743912 -278.799798) (xy 287.747872 -278.750744)
			(xy 287.759649 -278.70296) (xy 287.77894 -278.657684) (xy 287.805243 -278.616088) (xy 287.837878 -278.579251)
			(xy 287.875999 -278.548126) (xy 287.91862 -278.523519) (xy 287.964636 -278.506067) (xy 288.012855 -278.496223)
			(xy 288.06203 -278.494242) (xy 288.110885 -278.500174) (xy 288.158156 -278.513866) (xy 288.202618 -278.534964)
			(xy 288.243121 -278.56292) (xy 288.278614 -278.597012) (xy 288.308179 -278.636356) (xy 288.33105 -278.679933)
			(xy 288.346634 -278.726614) (xy 288.354529 -278.775191) (xy 288.355024 -278.799798) (xy 289.644086 -278.799798)
			(xy 289.648046 -278.750744) (xy 289.659823 -278.70296) (xy 289.679114 -278.657684) (xy 289.705417 -278.616088)
			(xy 289.738052 -278.579251) (xy 289.776173 -278.548126) (xy 289.818794 -278.523519) (xy 289.86481 -278.506067)
			(xy 289.913029 -278.496223) (xy 289.962204 -278.494242) (xy 290.011059 -278.500174) (xy 290.05833 -278.513866)
			(xy 290.102792 -278.534964) (xy 290.143295 -278.56292) (xy 290.178788 -278.597012) (xy 290.208353 -278.636356)
			(xy 290.231224 -278.679933) (xy 290.246808 -278.726614) (xy 290.254703 -278.775191) (xy 290.255198 -278.799798)
			(xy 291.543752 -278.799798) (xy 291.547712 -278.750744) (xy 291.559489 -278.70296) (xy 291.57878 -278.657684)
			(xy 291.605083 -278.616088) (xy 291.637718 -278.579251) (xy 291.675839 -278.548126) (xy 291.71846 -278.523519)
			(xy 291.764476 -278.506067) (xy 291.812695 -278.496223) (xy 291.86187 -278.494242) (xy 291.910725 -278.500174)
			(xy 291.957996 -278.513866) (xy 292.002458 -278.534964) (xy 292.042961 -278.56292) (xy 292.078454 -278.597012)
			(xy 292.108019 -278.636356) (xy 292.13089 -278.679933) (xy 292.146474 -278.726614) (xy 292.154369 -278.775191)
			(xy 292.154864 -278.799798) (xy 293.443672 -278.799798) (xy 293.447632 -278.750744) (xy 293.459409 -278.70296)
			(xy 293.4787 -278.657684) (xy 293.505003 -278.616088) (xy 293.537638 -278.579251) (xy 293.575759 -278.548126)
			(xy 293.61838 -278.523519) (xy 293.664396 -278.506067) (xy 293.712615 -278.496223) (xy 293.76179 -278.494242)
			(xy 293.810645 -278.500174) (xy 293.857916 -278.513866) (xy 293.902378 -278.534964) (xy 293.942881 -278.56292)
			(xy 293.978374 -278.597012) (xy 294.007939 -278.636356) (xy 294.03081 -278.679933) (xy 294.046394 -278.726614)
			(xy 294.054289 -278.775191) (xy 294.054784 -278.799798) (xy 295.343846 -278.799798) (xy 295.347806 -278.750744)
			(xy 295.359583 -278.70296) (xy 295.378874 -278.657684) (xy 295.405177 -278.616088) (xy 295.437812 -278.579251)
			(xy 295.475933 -278.548126) (xy 295.518554 -278.523519) (xy 295.56457 -278.506067) (xy 295.612789 -278.496223)
			(xy 295.661964 -278.494242) (xy 295.710819 -278.500174) (xy 295.75809 -278.513866) (xy 295.802552 -278.534964)
			(xy 295.843055 -278.56292) (xy 295.878548 -278.597012) (xy 295.908113 -278.636356) (xy 295.930984 -278.679933)
			(xy 295.946568 -278.726614) (xy 295.954463 -278.775191) (xy 295.954958 -278.799798) (xy 297.243766 -278.799798)
			(xy 297.247726 -278.750744) (xy 297.259503 -278.70296) (xy 297.278794 -278.657684) (xy 297.305097 -278.616088)
			(xy 297.337732 -278.579251) (xy 297.375853 -278.548126) (xy 297.418474 -278.523519) (xy 297.46449 -278.506067)
			(xy 297.512709 -278.496223) (xy 297.561884 -278.494242) (xy 297.610739 -278.500174) (xy 297.65801 -278.513866)
			(xy 297.702472 -278.534964) (xy 297.742975 -278.56292) (xy 297.778468 -278.597012) (xy 297.808033 -278.636356)
			(xy 297.830904 -278.679933) (xy 297.846488 -278.726614) (xy 297.854383 -278.775191) (xy 297.854878 -278.799798)
			(xy 299.143686 -278.799798) (xy 299.147646 -278.750744) (xy 299.159423 -278.70296) (xy 299.178714 -278.657684)
			(xy 299.205017 -278.616088) (xy 299.237652 -278.579251) (xy 299.275773 -278.548126) (xy 299.318394 -278.523519)
			(xy 299.36441 -278.506067) (xy 299.412629 -278.496223) (xy 299.461804 -278.494242) (xy 299.510659 -278.500174)
			(xy 299.55793 -278.513866) (xy 299.602392 -278.534964) (xy 299.642895 -278.56292) (xy 299.678388 -278.597012)
			(xy 299.707953 -278.636356) (xy 299.730824 -278.679933) (xy 299.746408 -278.726614) (xy 299.754303 -278.775191)
			(xy 299.754798 -278.799798) (xy 301.04386 -278.799798) (xy 301.04782 -278.750744) (xy 301.059597 -278.70296)
			(xy 301.078888 -278.657684) (xy 301.105191 -278.616088) (xy 301.137826 -278.579251) (xy 301.175947 -278.548126)
			(xy 301.218568 -278.523519) (xy 301.264584 -278.506067) (xy 301.312803 -278.496223) (xy 301.361978 -278.494242)
			(xy 301.410833 -278.500174) (xy 301.458104 -278.513866) (xy 301.502566 -278.534964) (xy 301.543069 -278.56292)
			(xy 301.578562 -278.597012) (xy 301.608127 -278.636356) (xy 301.630998 -278.679933) (xy 301.646582 -278.726614)
			(xy 301.654477 -278.775191) (xy 301.654972 -278.799798) (xy 302.94378 -278.799798) (xy 302.94774 -278.750744)
			(xy 302.959517 -278.70296) (xy 302.978808 -278.657684) (xy 303.005111 -278.616088) (xy 303.037746 -278.579251)
			(xy 303.075867 -278.548126) (xy 303.118488 -278.523519) (xy 303.164504 -278.506067) (xy 303.212723 -278.496223)
			(xy 303.261898 -278.494242) (xy 303.310753 -278.500174) (xy 303.358024 -278.513866) (xy 303.402486 -278.534964)
			(xy 303.442989 -278.56292) (xy 303.478482 -278.597012) (xy 303.508047 -278.636356) (xy 303.530918 -278.679933)
			(xy 303.546502 -278.726614) (xy 303.554397 -278.775191) (xy 303.554892 -278.799798) (xy 304.8437 -278.799798)
			(xy 304.84766 -278.750744) (xy 304.859437 -278.70296) (xy 304.878728 -278.657684) (xy 304.905031 -278.616088)
			(xy 304.937666 -278.579251) (xy 304.975787 -278.548126) (xy 305.018408 -278.523519) (xy 305.064424 -278.506067)
			(xy 305.112643 -278.496223) (xy 305.161818 -278.494242) (xy 305.210673 -278.500174) (xy 305.257944 -278.513866)
			(xy 305.302406 -278.534964) (xy 305.342909 -278.56292) (xy 305.378402 -278.597012) (xy 305.407967 -278.636356)
			(xy 305.430838 -278.679933) (xy 305.446422 -278.726614) (xy 305.454317 -278.775191) (xy 305.454812 -278.799798)
			(xy 306.743874 -278.799798) (xy 306.747834 -278.750744) (xy 306.759611 -278.70296) (xy 306.778902 -278.657684)
			(xy 306.805205 -278.616088) (xy 306.83784 -278.579251) (xy 306.875961 -278.548126) (xy 306.918582 -278.523519)
			(xy 306.964598 -278.506067) (xy 307.012817 -278.496223) (xy 307.061992 -278.494242) (xy 307.110847 -278.500174)
			(xy 307.158118 -278.513866) (xy 307.20258 -278.534964) (xy 307.243083 -278.56292) (xy 307.278576 -278.597012)
			(xy 307.308141 -278.636356) (xy 307.331012 -278.679933) (xy 307.346596 -278.726614) (xy 307.354491 -278.775191)
			(xy 307.354986 -278.799798) (xy 308.643794 -278.799798) (xy 308.647754 -278.750744) (xy 308.659531 -278.70296)
			(xy 308.678822 -278.657684) (xy 308.705125 -278.616088) (xy 308.73776 -278.579251) (xy 308.775881 -278.548126)
			(xy 308.818502 -278.523519) (xy 308.864518 -278.506067) (xy 308.912737 -278.496223) (xy 308.961912 -278.494242)
			(xy 309.010767 -278.500174) (xy 309.058038 -278.513866) (xy 309.1025 -278.534964) (xy 309.143003 -278.56292)
			(xy 309.178496 -278.597012) (xy 309.208061 -278.636356) (xy 309.230932 -278.679933) (xy 309.246516 -278.726614)
			(xy 309.254411 -278.775191) (xy 309.254906 -278.799798) (xy 310.543714 -278.799798) (xy 310.547674 -278.750744)
			(xy 310.559451 -278.70296) (xy 310.578742 -278.657684) (xy 310.605045 -278.616088) (xy 310.63768 -278.579251)
			(xy 310.675801 -278.548126) (xy 310.718422 -278.523519) (xy 310.764438 -278.506067) (xy 310.812657 -278.496223)
			(xy 310.861832 -278.494242) (xy 310.910687 -278.500174) (xy 310.957958 -278.513866) (xy 311.00242 -278.534964)
			(xy 311.042923 -278.56292) (xy 311.078416 -278.597012) (xy 311.107981 -278.636356) (xy 311.130852 -278.679933)
			(xy 311.146436 -278.726614) (xy 311.154331 -278.775191) (xy 311.154826 -278.799798) (xy 312.443888 -278.799798)
			(xy 312.447848 -278.750744) (xy 312.459625 -278.70296) (xy 312.478916 -278.657684) (xy 312.505219 -278.616088)
			(xy 312.537854 -278.579251) (xy 312.575975 -278.548126) (xy 312.618596 -278.523519) (xy 312.664612 -278.506067)
			(xy 312.712831 -278.496223) (xy 312.762006 -278.494242) (xy 312.810861 -278.500174) (xy 312.858132 -278.513866)
			(xy 312.902594 -278.534964) (xy 312.943097 -278.56292) (xy 312.97859 -278.597012) (xy 313.008155 -278.636356)
			(xy 313.031026 -278.679933) (xy 313.04661 -278.726614) (xy 313.054505 -278.775191) (xy 313.055 -278.799798)
			(xy 392.443982 -278.799798) (xy 392.447942 -278.750744) (xy 392.459719 -278.70296) (xy 392.47901 -278.657684)
			(xy 392.505313 -278.616088) (xy 392.537948 -278.579251) (xy 392.576069 -278.548126) (xy 392.61869 -278.523519)
			(xy 392.664706 -278.506067) (xy 392.712925 -278.496223) (xy 392.7621 -278.494242) (xy 392.810955 -278.500174)
			(xy 392.858226 -278.513866) (xy 392.902688 -278.534964) (xy 392.943191 -278.56292) (xy 392.978684 -278.597012)
			(xy 393.008249 -278.636356) (xy 393.03112 -278.679933) (xy 393.046704 -278.726614) (xy 393.054599 -278.775191)
			(xy 393.055094 -278.799798) (xy 394.344156 -278.799798) (xy 394.348116 -278.750744) (xy 394.359893 -278.70296)
			(xy 394.379184 -278.657684) (xy 394.405487 -278.616088) (xy 394.438122 -278.579251) (xy 394.476243 -278.548126)
			(xy 394.518864 -278.523519) (xy 394.56488 -278.506067) (xy 394.613099 -278.496223) (xy 394.662274 -278.494242)
			(xy 394.711129 -278.500174) (xy 394.7584 -278.513866) (xy 394.802862 -278.534964) (xy 394.843365 -278.56292)
			(xy 394.878858 -278.597012) (xy 394.908423 -278.636356) (xy 394.931294 -278.679933) (xy 394.946878 -278.726614)
			(xy 394.954773 -278.775191) (xy 394.955268 -278.799798) (xy 396.244076 -278.799798) (xy 396.248036 -278.750744)
			(xy 396.259813 -278.70296) (xy 396.279104 -278.657684) (xy 396.305407 -278.616088) (xy 396.338042 -278.579251)
			(xy 396.376163 -278.548126) (xy 396.418784 -278.523519) (xy 396.4648 -278.506067) (xy 396.513019 -278.496223)
			(xy 396.562194 -278.494242) (xy 396.611049 -278.500174) (xy 396.65832 -278.513866) (xy 396.702782 -278.534964)
			(xy 396.743285 -278.56292) (xy 396.778778 -278.597012) (xy 396.808343 -278.636356) (xy 396.831214 -278.679933)
			(xy 396.846798 -278.726614) (xy 396.854693 -278.775191) (xy 396.855188 -278.799798) (xy 398.143996 -278.799798)
			(xy 398.147956 -278.750744) (xy 398.159733 -278.70296) (xy 398.179024 -278.657684) (xy 398.205327 -278.616088)
			(xy 398.237962 -278.579251) (xy 398.276083 -278.548126) (xy 398.318704 -278.523519) (xy 398.36472 -278.506067)
			(xy 398.412939 -278.496223) (xy 398.462114 -278.494242) (xy 398.510969 -278.500174) (xy 398.55824 -278.513866)
			(xy 398.602702 -278.534964) (xy 398.643205 -278.56292) (xy 398.678698 -278.597012) (xy 398.708263 -278.636356)
			(xy 398.731134 -278.679933) (xy 398.746718 -278.726614) (xy 398.754613 -278.775191) (xy 398.755108 -278.799798)
			(xy 400.04417 -278.799798) (xy 400.04813 -278.750744) (xy 400.059907 -278.70296) (xy 400.079198 -278.657684)
			(xy 400.105501 -278.616088) (xy 400.138136 -278.579251) (xy 400.176257 -278.548126) (xy 400.218878 -278.523519)
			(xy 400.264894 -278.506067) (xy 400.313113 -278.496223) (xy 400.362288 -278.494242) (xy 400.411143 -278.500174)
			(xy 400.458414 -278.513866) (xy 400.502876 -278.534964) (xy 400.543379 -278.56292) (xy 400.578872 -278.597012)
			(xy 400.608437 -278.636356) (xy 400.631308 -278.679933) (xy 400.646892 -278.726614) (xy 400.654787 -278.775191)
			(xy 400.655282 -278.799798) (xy 401.94409 -278.799798) (xy 401.94805 -278.750744) (xy 401.959827 -278.70296)
			(xy 401.979118 -278.657684) (xy 402.005421 -278.616088) (xy 402.038056 -278.579251) (xy 402.076177 -278.548126)
			(xy 402.118798 -278.523519) (xy 402.164814 -278.506067) (xy 402.213033 -278.496223) (xy 402.262208 -278.494242)
			(xy 402.311063 -278.500174) (xy 402.358334 -278.513866) (xy 402.402796 -278.534964) (xy 402.443299 -278.56292)
			(xy 402.478792 -278.597012) (xy 402.508357 -278.636356) (xy 402.531228 -278.679933) (xy 402.546812 -278.726614)
			(xy 402.554707 -278.775191) (xy 402.555202 -278.799798) (xy 403.84401 -278.799798) (xy 403.84797 -278.750744)
			(xy 403.859747 -278.70296) (xy 403.879038 -278.657684) (xy 403.905341 -278.616088) (xy 403.937976 -278.579251)
			(xy 403.976097 -278.548126) (xy 404.018718 -278.523519) (xy 404.064734 -278.506067) (xy 404.112953 -278.496223)
			(xy 404.162128 -278.494242) (xy 404.210983 -278.500174) (xy 404.258254 -278.513866) (xy 404.302716 -278.534964)
			(xy 404.343219 -278.56292) (xy 404.378712 -278.597012) (xy 404.408277 -278.636356) (xy 404.431148 -278.679933)
			(xy 404.446732 -278.726614) (xy 404.454627 -278.775191) (xy 404.455122 -278.799798) (xy 405.744184 -278.799798)
			(xy 405.748144 -278.750744) (xy 405.759921 -278.70296) (xy 405.779212 -278.657684) (xy 405.805515 -278.616088)
			(xy 405.83815 -278.579251) (xy 405.876271 -278.548126) (xy 405.918892 -278.523519) (xy 405.964908 -278.506067)
			(xy 406.013127 -278.496223) (xy 406.062302 -278.494242) (xy 406.111157 -278.500174) (xy 406.158428 -278.513866)
			(xy 406.20289 -278.534964) (xy 406.243393 -278.56292) (xy 406.278886 -278.597012) (xy 406.308451 -278.636356)
			(xy 406.331322 -278.679933) (xy 406.346906 -278.726614) (xy 406.354801 -278.775191) (xy 406.355296 -278.799798)
			(xy 407.64385 -278.799798) (xy 407.64781 -278.750744) (xy 407.659587 -278.70296) (xy 407.678878 -278.657684)
			(xy 407.705181 -278.616088) (xy 407.737816 -278.579251) (xy 407.775937 -278.548126) (xy 407.818558 -278.523519)
			(xy 407.864574 -278.506067) (xy 407.912793 -278.496223) (xy 407.961968 -278.494242) (xy 408.010823 -278.500174)
			(xy 408.058094 -278.513866) (xy 408.102556 -278.534964) (xy 408.143059 -278.56292) (xy 408.178552 -278.597012)
			(xy 408.208117 -278.636356) (xy 408.230988 -278.679933) (xy 408.246572 -278.726614) (xy 408.254467 -278.775191)
			(xy 408.254962 -278.799798) (xy 409.54377 -278.799798) (xy 409.54773 -278.750744) (xy 409.559507 -278.70296)
			(xy 409.578798 -278.657684) (xy 409.605101 -278.616088) (xy 409.637736 -278.579251) (xy 409.675857 -278.548126)
			(xy 409.718478 -278.523519) (xy 409.764494 -278.506067) (xy 409.812713 -278.496223) (xy 409.861888 -278.494242)
			(xy 409.910743 -278.500174) (xy 409.958014 -278.513866) (xy 410.002476 -278.534964) (xy 410.042979 -278.56292)
			(xy 410.078472 -278.597012) (xy 410.108037 -278.636356) (xy 410.130908 -278.679933) (xy 410.146492 -278.726614)
			(xy 410.154387 -278.775191) (xy 410.154882 -278.799798) (xy 411.443944 -278.799798) (xy 411.447904 -278.750744)
			(xy 411.459681 -278.70296) (xy 411.478972 -278.657684) (xy 411.505275 -278.616088) (xy 411.53791 -278.579251)
			(xy 411.576031 -278.548126) (xy 411.618652 -278.523519) (xy 411.664668 -278.506067) (xy 411.712887 -278.496223)
			(xy 411.762062 -278.494242) (xy 411.810917 -278.500174) (xy 411.858188 -278.513866) (xy 411.90265 -278.534964)
			(xy 411.943153 -278.56292) (xy 411.978646 -278.597012) (xy 412.008211 -278.636356) (xy 412.031082 -278.679933)
			(xy 412.046666 -278.726614) (xy 412.054561 -278.775191) (xy 412.055056 -278.799798) (xy 413.343864 -278.799798)
			(xy 413.347824 -278.750744) (xy 413.359601 -278.70296) (xy 413.378892 -278.657684) (xy 413.405195 -278.616088)
			(xy 413.43783 -278.579251) (xy 413.475951 -278.548126) (xy 413.518572 -278.523519) (xy 413.564588 -278.506067)
			(xy 413.612807 -278.496223) (xy 413.661982 -278.494242) (xy 413.710837 -278.500174) (xy 413.758108 -278.513866)
			(xy 413.80257 -278.534964) (xy 413.843073 -278.56292) (xy 413.878566 -278.597012) (xy 413.908131 -278.636356)
			(xy 413.931002 -278.679933) (xy 413.946586 -278.726614) (xy 413.954481 -278.775191) (xy 413.954976 -278.799798)
			(xy 415.243784 -278.799798) (xy 415.247744 -278.750744) (xy 415.259521 -278.70296) (xy 415.278812 -278.657684)
			(xy 415.305115 -278.616088) (xy 415.33775 -278.579251) (xy 415.375871 -278.548126) (xy 415.418492 -278.523519)
			(xy 415.464508 -278.506067) (xy 415.512727 -278.496223) (xy 415.561902 -278.494242) (xy 415.610757 -278.500174)
			(xy 415.658028 -278.513866) (xy 415.70249 -278.534964) (xy 415.742993 -278.56292) (xy 415.778486 -278.597012)
			(xy 415.808051 -278.636356) (xy 415.830922 -278.679933) (xy 415.846506 -278.726614) (xy 415.854401 -278.775191)
			(xy 415.854896 -278.799798) (xy 417.143958 -278.799798) (xy 417.147918 -278.750744) (xy 417.159695 -278.70296)
			(xy 417.178986 -278.657684) (xy 417.205289 -278.616088) (xy 417.237924 -278.579251) (xy 417.276045 -278.548126)
			(xy 417.318666 -278.523519) (xy 417.364682 -278.506067) (xy 417.412901 -278.496223) (xy 417.462076 -278.494242)
			(xy 417.510931 -278.500174) (xy 417.558202 -278.513866) (xy 417.602664 -278.534964) (xy 417.643167 -278.56292)
			(xy 417.67866 -278.597012) (xy 417.708225 -278.636356) (xy 417.731096 -278.679933) (xy 417.74668 -278.726614)
			(xy 417.754575 -278.775191) (xy 417.75507 -278.799798) (xy 419.043878 -278.799798) (xy 419.047838 -278.750744)
			(xy 419.059615 -278.70296) (xy 419.078906 -278.657684) (xy 419.105209 -278.616088) (xy 419.137844 -278.579251)
			(xy 419.175965 -278.548126) (xy 419.218586 -278.523519) (xy 419.264602 -278.506067) (xy 419.312821 -278.496223)
			(xy 419.361996 -278.494242) (xy 419.410851 -278.500174) (xy 419.458122 -278.513866) (xy 419.502584 -278.534964)
			(xy 419.543087 -278.56292) (xy 419.57858 -278.597012) (xy 419.608145 -278.636356) (xy 419.631016 -278.679933)
			(xy 419.6466 -278.726614) (xy 419.654495 -278.775191) (xy 419.65499 -278.799798) (xy 420.943798 -278.799798)
			(xy 420.947758 -278.750744) (xy 420.959535 -278.70296) (xy 420.978826 -278.657684) (xy 421.005129 -278.616088)
			(xy 421.037764 -278.579251) (xy 421.075885 -278.548126) (xy 421.118506 -278.523519) (xy 421.164522 -278.506067)
			(xy 421.212741 -278.496223) (xy 421.261916 -278.494242) (xy 421.310771 -278.500174) (xy 421.358042 -278.513866)
			(xy 421.402504 -278.534964) (xy 421.443007 -278.56292) (xy 421.4785 -278.597012) (xy 421.508065 -278.636356)
			(xy 421.530936 -278.679933) (xy 421.54652 -278.726614) (xy 421.554415 -278.775191) (xy 421.55491 -278.799798)
			(xy 422.843972 -278.799798) (xy 422.847932 -278.750744) (xy 422.859709 -278.70296) (xy 422.879 -278.657684)
			(xy 422.905303 -278.616088) (xy 422.937938 -278.579251) (xy 422.976059 -278.548126) (xy 423.01868 -278.523519)
			(xy 423.064696 -278.506067) (xy 423.112915 -278.496223) (xy 423.16209 -278.494242) (xy 423.210945 -278.500174)
			(xy 423.258216 -278.513866) (xy 423.302678 -278.534964) (xy 423.343181 -278.56292) (xy 423.378674 -278.597012)
			(xy 423.408239 -278.636356) (xy 423.43111 -278.679933) (xy 423.446694 -278.726614) (xy 423.454589 -278.775191)
			(xy 423.455084 -278.799798) (xy 424.743892 -278.799798) (xy 424.747852 -278.750744) (xy 424.759629 -278.70296)
			(xy 424.77892 -278.657684) (xy 424.805223 -278.616088) (xy 424.837858 -278.579251) (xy 424.875979 -278.548126)
			(xy 424.9186 -278.523519) (xy 424.964616 -278.506067) (xy 425.012835 -278.496223) (xy 425.06201 -278.494242)
			(xy 425.110865 -278.500174) (xy 425.158136 -278.513866) (xy 425.202598 -278.534964) (xy 425.243101 -278.56292)
			(xy 425.278594 -278.597012) (xy 425.308159 -278.636356) (xy 425.33103 -278.679933) (xy 425.346614 -278.726614)
			(xy 425.354509 -278.775191) (xy 425.355004 -278.799798) (xy 426.643812 -278.799798) (xy 426.647772 -278.750744)
			(xy 426.659549 -278.70296) (xy 426.67884 -278.657684) (xy 426.705143 -278.616088) (xy 426.737778 -278.579251)
			(xy 426.775899 -278.548126) (xy 426.81852 -278.523519) (xy 426.864536 -278.506067) (xy 426.912755 -278.496223)
			(xy 426.96193 -278.494242) (xy 427.010785 -278.500174) (xy 427.058056 -278.513866) (xy 427.102518 -278.534964)
			(xy 427.143021 -278.56292) (xy 427.178514 -278.597012) (xy 427.208079 -278.636356) (xy 427.23095 -278.679933)
			(xy 427.246534 -278.726614) (xy 427.254429 -278.775191) (xy 427.254924 -278.799798) (xy 428.543986 -278.799798)
			(xy 428.547946 -278.750744) (xy 428.559723 -278.70296) (xy 428.579014 -278.657684) (xy 428.605317 -278.616088)
			(xy 428.637952 -278.579251) (xy 428.676073 -278.548126) (xy 428.718694 -278.523519) (xy 428.76471 -278.506067)
			(xy 428.812929 -278.496223) (xy 428.862104 -278.494242) (xy 428.910959 -278.500174) (xy 428.95823 -278.513866)
			(xy 429.002692 -278.534964) (xy 429.043195 -278.56292) (xy 429.078688 -278.597012) (xy 429.108253 -278.636356)
			(xy 429.131124 -278.679933) (xy 429.146708 -278.726614) (xy 429.154603 -278.775191) (xy 429.155098 -278.799798)
			(xy 429.154603 -278.824405) (xy 429.146708 -278.872982) (xy 429.131124 -278.919663) (xy 429.108253 -278.96324)
			(xy 429.078688 -279.002584) (xy 429.043195 -279.036676) (xy 429.002692 -279.064632) (xy 428.95823 -279.08573)
			(xy 428.910959 -279.099422) (xy 428.862104 -279.105354) (xy 428.812929 -279.103373) (xy 428.76471 -279.093529)
			(xy 428.718694 -279.076077) (xy 428.676073 -279.05147) (xy 428.637952 -279.020345) (xy 428.605317 -278.983508)
			(xy 428.579014 -278.941912) (xy 428.559723 -278.896636) (xy 428.547946 -278.848852) (xy 428.543986 -278.799798)
			(xy 427.254924 -278.799798) (xy 427.254429 -278.824405) (xy 427.246534 -278.872982) (xy 427.23095 -278.919663)
			(xy 427.208079 -278.96324) (xy 427.178514 -279.002584) (xy 427.143021 -279.036676) (xy 427.102518 -279.064632)
			(xy 427.058056 -279.08573) (xy 427.010785 -279.099422) (xy 426.96193 -279.105354) (xy 426.912755 -279.103373)
			(xy 426.864536 -279.093529) (xy 426.81852 -279.076077) (xy 426.775899 -279.05147) (xy 426.737778 -279.020345)
			(xy 426.705143 -278.983508) (xy 426.67884 -278.941912) (xy 426.659549 -278.896636) (xy 426.647772 -278.848852)
			(xy 426.643812 -278.799798) (xy 425.355004 -278.799798) (xy 425.354509 -278.824405) (xy 425.346614 -278.872982)
			(xy 425.33103 -278.919663) (xy 425.308159 -278.96324) (xy 425.278594 -279.002584) (xy 425.243101 -279.036676)
			(xy 425.202598 -279.064632) (xy 425.158136 -279.08573) (xy 425.110865 -279.099422) (xy 425.06201 -279.105354)
			(xy 425.012835 -279.103373) (xy 424.964616 -279.093529) (xy 424.9186 -279.076077) (xy 424.875979 -279.05147)
			(xy 424.837858 -279.020345) (xy 424.805223 -278.983508) (xy 424.77892 -278.941912) (xy 424.759629 -278.896636)
			(xy 424.747852 -278.848852) (xy 424.743892 -278.799798) (xy 423.455084 -278.799798) (xy 423.454589 -278.824405)
			(xy 423.446694 -278.872982) (xy 423.43111 -278.919663) (xy 423.408239 -278.96324) (xy 423.378674 -279.002584)
			(xy 423.343181 -279.036676) (xy 423.302678 -279.064632) (xy 423.258216 -279.08573) (xy 423.210945 -279.099422)
			(xy 423.16209 -279.105354) (xy 423.112915 -279.103373) (xy 423.064696 -279.093529) (xy 423.01868 -279.076077)
			(xy 422.976059 -279.05147) (xy 422.937938 -279.020345) (xy 422.905303 -278.983508) (xy 422.879 -278.941912)
			(xy 422.859709 -278.896636) (xy 422.847932 -278.848852) (xy 422.843972 -278.799798) (xy 421.55491 -278.799798)
			(xy 421.554415 -278.824405) (xy 421.54652 -278.872982) (xy 421.530936 -278.919663) (xy 421.508065 -278.96324)
			(xy 421.4785 -279.002584) (xy 421.443007 -279.036676) (xy 421.402504 -279.064632) (xy 421.358042 -279.08573)
			(xy 421.310771 -279.099422) (xy 421.261916 -279.105354) (xy 421.212741 -279.103373) (xy 421.164522 -279.093529)
			(xy 421.118506 -279.076077) (xy 421.075885 -279.05147) (xy 421.037764 -279.020345) (xy 421.005129 -278.983508)
			(xy 420.978826 -278.941912) (xy 420.959535 -278.896636) (xy 420.947758 -278.848852) (xy 420.943798 -278.799798)
			(xy 419.65499 -278.799798) (xy 419.654495 -278.824405) (xy 419.6466 -278.872982) (xy 419.631016 -278.919663)
			(xy 419.608145 -278.96324) (xy 419.57858 -279.002584) (xy 419.543087 -279.036676) (xy 419.502584 -279.064632)
			(xy 419.458122 -279.08573) (xy 419.410851 -279.099422) (xy 419.361996 -279.105354) (xy 419.312821 -279.103373)
			(xy 419.264602 -279.093529) (xy 419.218586 -279.076077) (xy 419.175965 -279.05147) (xy 419.137844 -279.020345)
			(xy 419.105209 -278.983508) (xy 419.078906 -278.941912) (xy 419.059615 -278.896636) (xy 419.047838 -278.848852)
			(xy 419.043878 -278.799798) (xy 417.75507 -278.799798) (xy 417.754575 -278.824405) (xy 417.74668 -278.872982)
			(xy 417.731096 -278.919663) (xy 417.708225 -278.96324) (xy 417.67866 -279.002584) (xy 417.643167 -279.036676)
			(xy 417.602664 -279.064632) (xy 417.558202 -279.08573) (xy 417.510931 -279.099422) (xy 417.462076 -279.105354)
			(xy 417.412901 -279.103373) (xy 417.364682 -279.093529) (xy 417.318666 -279.076077) (xy 417.276045 -279.05147)
			(xy 417.237924 -279.020345) (xy 417.205289 -278.983508) (xy 417.178986 -278.941912) (xy 417.159695 -278.896636)
			(xy 417.147918 -278.848852) (xy 417.143958 -278.799798) (xy 415.854896 -278.799798) (xy 415.854401 -278.824405)
			(xy 415.846506 -278.872982) (xy 415.830922 -278.919663) (xy 415.808051 -278.96324) (xy 415.778486 -279.002584)
			(xy 415.742993 -279.036676) (xy 415.70249 -279.064632) (xy 415.658028 -279.08573) (xy 415.610757 -279.099422)
			(xy 415.561902 -279.105354) (xy 415.512727 -279.103373) (xy 415.464508 -279.093529) (xy 415.418492 -279.076077)
			(xy 415.375871 -279.05147) (xy 415.33775 -279.020345) (xy 415.305115 -278.983508) (xy 415.278812 -278.941912)
			(xy 415.259521 -278.896636) (xy 415.247744 -278.848852) (xy 415.243784 -278.799798) (xy 413.954976 -278.799798)
			(xy 413.954481 -278.824405) (xy 413.946586 -278.872982) (xy 413.931002 -278.919663) (xy 413.908131 -278.96324)
			(xy 413.878566 -279.002584) (xy 413.843073 -279.036676) (xy 413.80257 -279.064632) (xy 413.758108 -279.08573)
			(xy 413.710837 -279.099422) (xy 413.661982 -279.105354) (xy 413.612807 -279.103373) (xy 413.564588 -279.093529)
			(xy 413.518572 -279.076077) (xy 413.475951 -279.05147) (xy 413.43783 -279.020345) (xy 413.405195 -278.983508)
			(xy 413.378892 -278.941912) (xy 413.359601 -278.896636) (xy 413.347824 -278.848852) (xy 413.343864 -278.799798)
			(xy 412.055056 -278.799798) (xy 412.054561 -278.824405) (xy 412.046666 -278.872982) (xy 412.031082 -278.919663)
			(xy 412.008211 -278.96324) (xy 411.978646 -279.002584) (xy 411.943153 -279.036676) (xy 411.90265 -279.064632)
			(xy 411.858188 -279.08573) (xy 411.810917 -279.099422) (xy 411.762062 -279.105354) (xy 411.712887 -279.103373)
			(xy 411.664668 -279.093529) (xy 411.618652 -279.076077) (xy 411.576031 -279.05147) (xy 411.53791 -279.020345)
			(xy 411.505275 -278.983508) (xy 411.478972 -278.941912) (xy 411.459681 -278.896636) (xy 411.447904 -278.848852)
			(xy 411.443944 -278.799798) (xy 410.154882 -278.799798) (xy 410.154387 -278.824405) (xy 410.146492 -278.872982)
			(xy 410.130908 -278.919663) (xy 410.108037 -278.96324) (xy 410.078472 -279.002584) (xy 410.042979 -279.036676)
			(xy 410.002476 -279.064632) (xy 409.958014 -279.08573) (xy 409.910743 -279.099422) (xy 409.861888 -279.105354)
			(xy 409.812713 -279.103373) (xy 409.764494 -279.093529) (xy 409.718478 -279.076077) (xy 409.675857 -279.05147)
			(xy 409.637736 -279.020345) (xy 409.605101 -278.983508) (xy 409.578798 -278.941912) (xy 409.559507 -278.896636)
			(xy 409.54773 -278.848852) (xy 409.54377 -278.799798) (xy 408.254962 -278.799798) (xy 408.254467 -278.824405)
			(xy 408.246572 -278.872982) (xy 408.230988 -278.919663) (xy 408.208117 -278.96324) (xy 408.178552 -279.002584)
			(xy 408.143059 -279.036676) (xy 408.102556 -279.064632) (xy 408.058094 -279.08573) (xy 408.010823 -279.099422)
			(xy 407.961968 -279.105354) (xy 407.912793 -279.103373) (xy 407.864574 -279.093529) (xy 407.818558 -279.076077)
			(xy 407.775937 -279.05147) (xy 407.737816 -279.020345) (xy 407.705181 -278.983508) (xy 407.678878 -278.941912)
			(xy 407.659587 -278.896636) (xy 407.64781 -278.848852) (xy 407.64385 -278.799798) (xy 406.355296 -278.799798)
			(xy 406.354801 -278.824405) (xy 406.346906 -278.872982) (xy 406.331322 -278.919663) (xy 406.308451 -278.96324)
			(xy 406.278886 -279.002584) (xy 406.243393 -279.036676) (xy 406.20289 -279.064632) (xy 406.158428 -279.08573)
			(xy 406.111157 -279.099422) (xy 406.062302 -279.105354) (xy 406.013127 -279.103373) (xy 405.964908 -279.093529)
			(xy 405.918892 -279.076077) (xy 405.876271 -279.05147) (xy 405.83815 -279.020345) (xy 405.805515 -278.983508)
			(xy 405.779212 -278.941912) (xy 405.759921 -278.896636) (xy 405.748144 -278.848852) (xy 405.744184 -278.799798)
			(xy 404.455122 -278.799798) (xy 404.454627 -278.824405) (xy 404.446732 -278.872982) (xy 404.431148 -278.919663)
			(xy 404.408277 -278.96324) (xy 404.378712 -279.002584) (xy 404.343219 -279.036676) (xy 404.302716 -279.064632)
			(xy 404.258254 -279.08573) (xy 404.210983 -279.099422) (xy 404.162128 -279.105354) (xy 404.112953 -279.103373)
			(xy 404.064734 -279.093529) (xy 404.018718 -279.076077) (xy 403.976097 -279.05147) (xy 403.937976 -279.020345)
			(xy 403.905341 -278.983508) (xy 403.879038 -278.941912) (xy 403.859747 -278.896636) (xy 403.84797 -278.848852)
			(xy 403.84401 -278.799798) (xy 402.555202 -278.799798) (xy 402.554707 -278.824405) (xy 402.546812 -278.872982)
			(xy 402.531228 -278.919663) (xy 402.508357 -278.96324) (xy 402.478792 -279.002584) (xy 402.443299 -279.036676)
			(xy 402.402796 -279.064632) (xy 402.358334 -279.08573) (xy 402.311063 -279.099422) (xy 402.262208 -279.105354)
			(xy 402.213033 -279.103373) (xy 402.164814 -279.093529) (xy 402.118798 -279.076077) (xy 402.076177 -279.05147)
			(xy 402.038056 -279.020345) (xy 402.005421 -278.983508) (xy 401.979118 -278.941912) (xy 401.959827 -278.896636)
			(xy 401.94805 -278.848852) (xy 401.94409 -278.799798) (xy 400.655282 -278.799798) (xy 400.654787 -278.824405)
			(xy 400.646892 -278.872982) (xy 400.631308 -278.919663) (xy 400.608437 -278.96324) (xy 400.578872 -279.002584)
			(xy 400.543379 -279.036676) (xy 400.502876 -279.064632) (xy 400.458414 -279.08573) (xy 400.411143 -279.099422)
			(xy 400.362288 -279.105354) (xy 400.313113 -279.103373) (xy 400.264894 -279.093529) (xy 400.218878 -279.076077)
			(xy 400.176257 -279.05147) (xy 400.138136 -279.020345) (xy 400.105501 -278.983508) (xy 400.079198 -278.941912)
			(xy 400.059907 -278.896636) (xy 400.04813 -278.848852) (xy 400.04417 -278.799798) (xy 398.755108 -278.799798)
			(xy 398.754613 -278.824405) (xy 398.746718 -278.872982) (xy 398.731134 -278.919663) (xy 398.708263 -278.96324)
			(xy 398.678698 -279.002584) (xy 398.643205 -279.036676) (xy 398.602702 -279.064632) (xy 398.55824 -279.08573)
			(xy 398.510969 -279.099422) (xy 398.462114 -279.105354) (xy 398.412939 -279.103373) (xy 398.36472 -279.093529)
			(xy 398.318704 -279.076077) (xy 398.276083 -279.05147) (xy 398.237962 -279.020345) (xy 398.205327 -278.983508)
			(xy 398.179024 -278.941912) (xy 398.159733 -278.896636) (xy 398.147956 -278.848852) (xy 398.143996 -278.799798)
			(xy 396.855188 -278.799798) (xy 396.854693 -278.824405) (xy 396.846798 -278.872982) (xy 396.831214 -278.919663)
			(xy 396.808343 -278.96324) (xy 396.778778 -279.002584) (xy 396.743285 -279.036676) (xy 396.702782 -279.064632)
			(xy 396.65832 -279.08573) (xy 396.611049 -279.099422) (xy 396.562194 -279.105354) (xy 396.513019 -279.103373)
			(xy 396.4648 -279.093529) (xy 396.418784 -279.076077) (xy 396.376163 -279.05147) (xy 396.338042 -279.020345)
			(xy 396.305407 -278.983508) (xy 396.279104 -278.941912) (xy 396.259813 -278.896636) (xy 396.248036 -278.848852)
			(xy 396.244076 -278.799798) (xy 394.955268 -278.799798) (xy 394.954773 -278.824405) (xy 394.946878 -278.872982)
			(xy 394.931294 -278.919663) (xy 394.908423 -278.96324) (xy 394.878858 -279.002584) (xy 394.843365 -279.036676)
			(xy 394.802862 -279.064632) (xy 394.7584 -279.08573) (xy 394.711129 -279.099422) (xy 394.662274 -279.105354)
			(xy 394.613099 -279.103373) (xy 394.56488 -279.093529) (xy 394.518864 -279.076077) (xy 394.476243 -279.05147)
			(xy 394.438122 -279.020345) (xy 394.405487 -278.983508) (xy 394.379184 -278.941912) (xy 394.359893 -278.896636)
			(xy 394.348116 -278.848852) (xy 394.344156 -278.799798) (xy 393.055094 -278.799798) (xy 393.054599 -278.824405)
			(xy 393.046704 -278.872982) (xy 393.03112 -278.919663) (xy 393.008249 -278.96324) (xy 392.978684 -279.002584)
			(xy 392.943191 -279.036676) (xy 392.902688 -279.064632) (xy 392.858226 -279.08573) (xy 392.810955 -279.099422)
			(xy 392.7621 -279.105354) (xy 392.712925 -279.103373) (xy 392.664706 -279.093529) (xy 392.61869 -279.076077)
			(xy 392.576069 -279.05147) (xy 392.537948 -279.020345) (xy 392.505313 -278.983508) (xy 392.47901 -278.941912)
			(xy 392.459719 -278.896636) (xy 392.447942 -278.848852) (xy 392.443982 -278.799798) (xy 313.055 -278.799798)
			(xy 313.054505 -278.824405) (xy 313.04661 -278.872982) (xy 313.031026 -278.919663) (xy 313.008155 -278.96324)
			(xy 312.97859 -279.002584) (xy 312.943097 -279.036676) (xy 312.902594 -279.064632) (xy 312.858132 -279.08573)
			(xy 312.810861 -279.099422) (xy 312.762006 -279.105354) (xy 312.712831 -279.103373) (xy 312.664612 -279.093529)
			(xy 312.618596 -279.076077) (xy 312.575975 -279.05147) (xy 312.537854 -279.020345) (xy 312.505219 -278.983508)
			(xy 312.478916 -278.941912) (xy 312.459625 -278.896636) (xy 312.447848 -278.848852) (xy 312.443888 -278.799798)
			(xy 311.154826 -278.799798) (xy 311.154331 -278.824405) (xy 311.146436 -278.872982) (xy 311.130852 -278.919663)
			(xy 311.107981 -278.96324) (xy 311.078416 -279.002584) (xy 311.042923 -279.036676) (xy 311.00242 -279.064632)
			(xy 310.957958 -279.08573) (xy 310.910687 -279.099422) (xy 310.861832 -279.105354) (xy 310.812657 -279.103373)
			(xy 310.764438 -279.093529) (xy 310.718422 -279.076077) (xy 310.675801 -279.05147) (xy 310.63768 -279.020345)
			(xy 310.605045 -278.983508) (xy 310.578742 -278.941912) (xy 310.559451 -278.896636) (xy 310.547674 -278.848852)
			(xy 310.543714 -278.799798) (xy 309.254906 -278.799798) (xy 309.254411 -278.824405) (xy 309.246516 -278.872982)
			(xy 309.230932 -278.919663) (xy 309.208061 -278.96324) (xy 309.178496 -279.002584) (xy 309.143003 -279.036676)
			(xy 309.1025 -279.064632) (xy 309.058038 -279.08573) (xy 309.010767 -279.099422) (xy 308.961912 -279.105354)
			(xy 308.912737 -279.103373) (xy 308.864518 -279.093529) (xy 308.818502 -279.076077) (xy 308.775881 -279.05147)
			(xy 308.73776 -279.020345) (xy 308.705125 -278.983508) (xy 308.678822 -278.941912) (xy 308.659531 -278.896636)
			(xy 308.647754 -278.848852) (xy 308.643794 -278.799798) (xy 307.354986 -278.799798) (xy 307.354491 -278.824405)
			(xy 307.346596 -278.872982) (xy 307.331012 -278.919663) (xy 307.308141 -278.96324) (xy 307.278576 -279.002584)
			(xy 307.243083 -279.036676) (xy 307.20258 -279.064632) (xy 307.158118 -279.08573) (xy 307.110847 -279.099422)
			(xy 307.061992 -279.105354) (xy 307.012817 -279.103373) (xy 306.964598 -279.093529) (xy 306.918582 -279.076077)
			(xy 306.875961 -279.05147) (xy 306.83784 -279.020345) (xy 306.805205 -278.983508) (xy 306.778902 -278.941912)
			(xy 306.759611 -278.896636) (xy 306.747834 -278.848852) (xy 306.743874 -278.799798) (xy 305.454812 -278.799798)
			(xy 305.454317 -278.824405) (xy 305.446422 -278.872982) (xy 305.430838 -278.919663) (xy 305.407967 -278.96324)
			(xy 305.378402 -279.002584) (xy 305.342909 -279.036676) (xy 305.302406 -279.064632) (xy 305.257944 -279.08573)
			(xy 305.210673 -279.099422) (xy 305.161818 -279.105354) (xy 305.112643 -279.103373) (xy 305.064424 -279.093529)
			(xy 305.018408 -279.076077) (xy 304.975787 -279.05147) (xy 304.937666 -279.020345) (xy 304.905031 -278.983508)
			(xy 304.878728 -278.941912) (xy 304.859437 -278.896636) (xy 304.84766 -278.848852) (xy 304.8437 -278.799798)
			(xy 303.554892 -278.799798) (xy 303.554397 -278.824405) (xy 303.546502 -278.872982) (xy 303.530918 -278.919663)
			(xy 303.508047 -278.96324) (xy 303.478482 -279.002584) (xy 303.442989 -279.036676) (xy 303.402486 -279.064632)
			(xy 303.358024 -279.08573) (xy 303.310753 -279.099422) (xy 303.261898 -279.105354) (xy 303.212723 -279.103373)
			(xy 303.164504 -279.093529) (xy 303.118488 -279.076077) (xy 303.075867 -279.05147) (xy 303.037746 -279.020345)
			(xy 303.005111 -278.983508) (xy 302.978808 -278.941912) (xy 302.959517 -278.896636) (xy 302.94774 -278.848852)
			(xy 302.94378 -278.799798) (xy 301.654972 -278.799798) (xy 301.654477 -278.824405) (xy 301.646582 -278.872982)
			(xy 301.630998 -278.919663) (xy 301.608127 -278.96324) (xy 301.578562 -279.002584) (xy 301.543069 -279.036676)
			(xy 301.502566 -279.064632) (xy 301.458104 -279.08573) (xy 301.410833 -279.099422) (xy 301.361978 -279.105354)
			(xy 301.312803 -279.103373) (xy 301.264584 -279.093529) (xy 301.218568 -279.076077) (xy 301.175947 -279.05147)
			(xy 301.137826 -279.020345) (xy 301.105191 -278.983508) (xy 301.078888 -278.941912) (xy 301.059597 -278.896636)
			(xy 301.04782 -278.848852) (xy 301.04386 -278.799798) (xy 299.754798 -278.799798) (xy 299.754303 -278.824405)
			(xy 299.746408 -278.872982) (xy 299.730824 -278.919663) (xy 299.707953 -278.96324) (xy 299.678388 -279.002584)
			(xy 299.642895 -279.036676) (xy 299.602392 -279.064632) (xy 299.55793 -279.08573) (xy 299.510659 -279.099422)
			(xy 299.461804 -279.105354) (xy 299.412629 -279.103373) (xy 299.36441 -279.093529) (xy 299.318394 -279.076077)
			(xy 299.275773 -279.05147) (xy 299.237652 -279.020345) (xy 299.205017 -278.983508) (xy 299.178714 -278.941912)
			(xy 299.159423 -278.896636) (xy 299.147646 -278.848852) (xy 299.143686 -278.799798) (xy 297.854878 -278.799798)
			(xy 297.854383 -278.824405) (xy 297.846488 -278.872982) (xy 297.830904 -278.919663) (xy 297.808033 -278.96324)
			(xy 297.778468 -279.002584) (xy 297.742975 -279.036676) (xy 297.702472 -279.064632) (xy 297.65801 -279.08573)
			(xy 297.610739 -279.099422) (xy 297.561884 -279.105354) (xy 297.512709 -279.103373) (xy 297.46449 -279.093529)
			(xy 297.418474 -279.076077) (xy 297.375853 -279.05147) (xy 297.337732 -279.020345) (xy 297.305097 -278.983508)
			(xy 297.278794 -278.941912) (xy 297.259503 -278.896636) (xy 297.247726 -278.848852) (xy 297.243766 -278.799798)
			(xy 295.954958 -278.799798) (xy 295.954463 -278.824405) (xy 295.946568 -278.872982) (xy 295.930984 -278.919663)
			(xy 295.908113 -278.96324) (xy 295.878548 -279.002584) (xy 295.843055 -279.036676) (xy 295.802552 -279.064632)
			(xy 295.75809 -279.08573) (xy 295.710819 -279.099422) (xy 295.661964 -279.105354) (xy 295.612789 -279.103373)
			(xy 295.56457 -279.093529) (xy 295.518554 -279.076077) (xy 295.475933 -279.05147) (xy 295.437812 -279.020345)
			(xy 295.405177 -278.983508) (xy 295.378874 -278.941912) (xy 295.359583 -278.896636) (xy 295.347806 -278.848852)
			(xy 295.343846 -278.799798) (xy 294.054784 -278.799798) (xy 294.054289 -278.824405) (xy 294.046394 -278.872982)
			(xy 294.03081 -278.919663) (xy 294.007939 -278.96324) (xy 293.978374 -279.002584) (xy 293.942881 -279.036676)
			(xy 293.902378 -279.064632) (xy 293.857916 -279.08573) (xy 293.810645 -279.099422) (xy 293.76179 -279.105354)
			(xy 293.712615 -279.103373) (xy 293.664396 -279.093529) (xy 293.61838 -279.076077) (xy 293.575759 -279.05147)
			(xy 293.537638 -279.020345) (xy 293.505003 -278.983508) (xy 293.4787 -278.941912) (xy 293.459409 -278.896636)
			(xy 293.447632 -278.848852) (xy 293.443672 -278.799798) (xy 292.154864 -278.799798) (xy 292.154369 -278.824405)
			(xy 292.146474 -278.872982) (xy 292.13089 -278.919663) (xy 292.108019 -278.96324) (xy 292.078454 -279.002584)
			(xy 292.042961 -279.036676) (xy 292.002458 -279.064632) (xy 291.957996 -279.08573) (xy 291.910725 -279.099422)
			(xy 291.86187 -279.105354) (xy 291.812695 -279.103373) (xy 291.764476 -279.093529) (xy 291.71846 -279.076077)
			(xy 291.675839 -279.05147) (xy 291.637718 -279.020345) (xy 291.605083 -278.983508) (xy 291.57878 -278.941912)
			(xy 291.559489 -278.896636) (xy 291.547712 -278.848852) (xy 291.543752 -278.799798) (xy 290.255198 -278.799798)
			(xy 290.254703 -278.824405) (xy 290.246808 -278.872982) (xy 290.231224 -278.919663) (xy 290.208353 -278.96324)
			(xy 290.178788 -279.002584) (xy 290.143295 -279.036676) (xy 290.102792 -279.064632) (xy 290.05833 -279.08573)
			(xy 290.011059 -279.099422) (xy 289.962204 -279.105354) (xy 289.913029 -279.103373) (xy 289.86481 -279.093529)
			(xy 289.818794 -279.076077) (xy 289.776173 -279.05147) (xy 289.738052 -279.020345) (xy 289.705417 -278.983508)
			(xy 289.679114 -278.941912) (xy 289.659823 -278.896636) (xy 289.648046 -278.848852) (xy 289.644086 -278.799798)
			(xy 288.355024 -278.799798) (xy 288.354529 -278.824405) (xy 288.346634 -278.872982) (xy 288.33105 -278.919663)
			(xy 288.308179 -278.96324) (xy 288.278614 -279.002584) (xy 288.243121 -279.036676) (xy 288.202618 -279.064632)
			(xy 288.158156 -279.08573) (xy 288.110885 -279.099422) (xy 288.06203 -279.105354) (xy 288.012855 -279.103373)
			(xy 287.964636 -279.093529) (xy 287.91862 -279.076077) (xy 287.875999 -279.05147) (xy 287.837878 -279.020345)
			(xy 287.805243 -278.983508) (xy 287.77894 -278.941912) (xy 287.759649 -278.896636) (xy 287.747872 -278.848852)
			(xy 287.743912 -278.799798) (xy 286.455104 -278.799798) (xy 286.454609 -278.824405) (xy 286.446714 -278.872982)
			(xy 286.43113 -278.919663) (xy 286.408259 -278.96324) (xy 286.378694 -279.002584) (xy 286.343201 -279.036676)
			(xy 286.302698 -279.064632) (xy 286.258236 -279.08573) (xy 286.210965 -279.099422) (xy 286.16211 -279.105354)
			(xy 286.112935 -279.103373) (xy 286.064716 -279.093529) (xy 286.0187 -279.076077) (xy 285.976079 -279.05147)
			(xy 285.937958 -279.020345) (xy 285.905323 -278.983508) (xy 285.87902 -278.941912) (xy 285.859729 -278.896636)
			(xy 285.847952 -278.848852) (xy 285.843992 -278.799798) (xy 284.555184 -278.799798) (xy 284.554689 -278.824405)
			(xy 284.546794 -278.872982) (xy 284.53121 -278.919663) (xy 284.508339 -278.96324) (xy 284.478774 -279.002584)
			(xy 284.443281 -279.036676) (xy 284.402778 -279.064632) (xy 284.358316 -279.08573) (xy 284.311045 -279.099422)
			(xy 284.26219 -279.105354) (xy 284.213015 -279.103373) (xy 284.164796 -279.093529) (xy 284.11878 -279.076077)
			(xy 284.076159 -279.05147) (xy 284.038038 -279.020345) (xy 284.005403 -278.983508) (xy 283.9791 -278.941912)
			(xy 283.959809 -278.896636) (xy 283.948032 -278.848852) (xy 283.944072 -278.799798) (xy 282.65501 -278.799798)
			(xy 282.654515 -278.824405) (xy 282.64662 -278.872982) (xy 282.631036 -278.919663) (xy 282.608165 -278.96324)
			(xy 282.5786 -279.002584) (xy 282.543107 -279.036676) (xy 282.502604 -279.064632) (xy 282.458142 -279.08573)
			(xy 282.410871 -279.099422) (xy 282.362016 -279.105354) (xy 282.312841 -279.103373) (xy 282.264622 -279.093529)
			(xy 282.218606 -279.076077) (xy 282.175985 -279.05147) (xy 282.137864 -279.020345) (xy 282.105229 -278.983508)
			(xy 282.078926 -278.941912) (xy 282.059635 -278.896636) (xy 282.047858 -278.848852) (xy 282.043898 -278.799798)
			(xy 280.75509 -278.799798) (xy 280.754595 -278.824405) (xy 280.7467 -278.872982) (xy 280.731116 -278.919663)
			(xy 280.708245 -278.96324) (xy 280.67868 -279.002584) (xy 280.643187 -279.036676) (xy 280.602684 -279.064632)
			(xy 280.558222 -279.08573) (xy 280.510951 -279.099422) (xy 280.462096 -279.105354) (xy 280.412921 -279.103373)
			(xy 280.364702 -279.093529) (xy 280.318686 -279.076077) (xy 280.276065 -279.05147) (xy 280.237944 -279.020345)
			(xy 280.205309 -278.983508) (xy 280.179006 -278.941912) (xy 280.159715 -278.896636) (xy 280.147938 -278.848852)
			(xy 280.143978 -278.799798) (xy 278.85517 -278.799798) (xy 278.854675 -278.824405) (xy 278.84678 -278.872982)
			(xy 278.831196 -278.919663) (xy 278.808325 -278.96324) (xy 278.77876 -279.002584) (xy 278.743267 -279.036676)
			(xy 278.702764 -279.064632) (xy 278.658302 -279.08573) (xy 278.611031 -279.099422) (xy 278.562176 -279.105354)
			(xy 278.513001 -279.103373) (xy 278.464782 -279.093529) (xy 278.418766 -279.076077) (xy 278.376145 -279.05147)
			(xy 278.338024 -279.020345) (xy 278.305389 -278.983508) (xy 278.279086 -278.941912) (xy 278.259795 -278.896636)
			(xy 278.248018 -278.848852) (xy 278.244058 -278.799798) (xy 276.954996 -278.799798) (xy 276.954501 -278.824405)
			(xy 276.946606 -278.872982) (xy 276.931022 -278.919663) (xy 276.908151 -278.96324) (xy 276.878586 -279.002584)
			(xy 276.843093 -279.036676) (xy 276.80259 -279.064632) (xy 276.758128 -279.08573) (xy 276.710857 -279.099422)
			(xy 276.662002 -279.105354) (xy 276.612827 -279.103373) (xy 276.564608 -279.093529) (xy 276.518592 -279.076077)
			(xy 276.475971 -279.05147) (xy 276.43785 -279.020345) (xy 276.405215 -278.983508) (xy 276.378912 -278.941912)
			(xy 276.359621 -278.896636) (xy 276.347844 -278.848852) (xy 276.343884 -278.799798) (xy 196.955156 -278.799798)
			(xy 196.954661 -278.824405) (xy 196.946766 -278.872982) (xy 196.931182 -278.919663) (xy 196.908311 -278.96324)
			(xy 196.878746 -279.002584) (xy 196.843253 -279.036676) (xy 196.80275 -279.064632) (xy 196.758288 -279.08573)
			(xy 196.711017 -279.099422) (xy 196.662162 -279.105354) (xy 196.612987 -279.103373) (xy 196.564768 -279.093529)
			(xy 196.518752 -279.076077) (xy 196.476131 -279.05147) (xy 196.43801 -279.020345) (xy 196.405375 -278.983508)
			(xy 196.379072 -278.941912) (xy 196.359781 -278.896636) (xy 196.348004 -278.848852) (xy 196.344044 -278.799798)
			(xy 195.054982 -278.799798) (xy 195.054487 -278.824405) (xy 195.046592 -278.872982) (xy 195.031008 -278.919663)
			(xy 195.008137 -278.96324) (xy 194.978572 -279.002584) (xy 194.943079 -279.036676) (xy 194.902576 -279.064632)
			(xy 194.858114 -279.08573) (xy 194.810843 -279.099422) (xy 194.761988 -279.105354) (xy 194.712813 -279.103373)
			(xy 194.664594 -279.093529) (xy 194.618578 -279.076077) (xy 194.575957 -279.05147) (xy 194.537836 -279.020345)
			(xy 194.505201 -278.983508) (xy 194.478898 -278.941912) (xy 194.459607 -278.896636) (xy 194.44783 -278.848852)
			(xy 194.44387 -278.799798) (xy 193.155062 -278.799798) (xy 193.154567 -278.824405) (xy 193.146672 -278.872982)
			(xy 193.131088 -278.919663) (xy 193.108217 -278.96324) (xy 193.078652 -279.002584) (xy 193.043159 -279.036676)
			(xy 193.002656 -279.064632) (xy 192.958194 -279.08573) (xy 192.910923 -279.099422) (xy 192.862068 -279.105354)
			(xy 192.812893 -279.103373) (xy 192.764674 -279.093529) (xy 192.718658 -279.076077) (xy 192.676037 -279.05147)
			(xy 192.637916 -279.020345) (xy 192.605281 -278.983508) (xy 192.578978 -278.941912) (xy 192.559687 -278.896636)
			(xy 192.54791 -278.848852) (xy 192.54395 -278.799798) (xy 191.255142 -278.799798) (xy 191.254647 -278.824405)
			(xy 191.246752 -278.872982) (xy 191.231168 -278.919663) (xy 191.208297 -278.96324) (xy 191.178732 -279.002584)
			(xy 191.143239 -279.036676) (xy 191.102736 -279.064632) (xy 191.058274 -279.08573) (xy 191.011003 -279.099422)
			(xy 190.962148 -279.105354) (xy 190.912973 -279.103373) (xy 190.864754 -279.093529) (xy 190.818738 -279.076077)
			(xy 190.776117 -279.05147) (xy 190.737996 -279.020345) (xy 190.705361 -278.983508) (xy 190.679058 -278.941912)
			(xy 190.659767 -278.896636) (xy 190.64799 -278.848852) (xy 190.64403 -278.799798) (xy 189.354968 -278.799798)
			(xy 189.354473 -278.824405) (xy 189.346578 -278.872982) (xy 189.330994 -278.919663) (xy 189.308123 -278.96324)
			(xy 189.278558 -279.002584) (xy 189.243065 -279.036676) (xy 189.202562 -279.064632) (xy 189.1581 -279.08573)
			(xy 189.110829 -279.099422) (xy 189.061974 -279.105354) (xy 189.012799 -279.103373) (xy 188.96458 -279.093529)
			(xy 188.918564 -279.076077) (xy 188.875943 -279.05147) (xy 188.837822 -279.020345) (xy 188.805187 -278.983508)
			(xy 188.778884 -278.941912) (xy 188.759593 -278.896636) (xy 188.747816 -278.848852) (xy 188.743856 -278.799798)
			(xy 187.455048 -278.799798) (xy 187.454553 -278.824405) (xy 187.446658 -278.872982) (xy 187.431074 -278.919663)
			(xy 187.408203 -278.96324) (xy 187.378638 -279.002584) (xy 187.343145 -279.036676) (xy 187.302642 -279.064632)
			(xy 187.25818 -279.08573) (xy 187.210909 -279.099422) (xy 187.162054 -279.105354) (xy 187.112879 -279.103373)
			(xy 187.06466 -279.093529) (xy 187.018644 -279.076077) (xy 186.976023 -279.05147) (xy 186.937902 -279.020345)
			(xy 186.905267 -278.983508) (xy 186.878964 -278.941912) (xy 186.859673 -278.896636) (xy 186.847896 -278.848852)
			(xy 186.843936 -278.799798) (xy 185.555128 -278.799798) (xy 185.554633 -278.824405) (xy 185.546738 -278.872982)
			(xy 185.531154 -278.919663) (xy 185.508283 -278.96324) (xy 185.478718 -279.002584) (xy 185.443225 -279.036676)
			(xy 185.402722 -279.064632) (xy 185.35826 -279.08573) (xy 185.310989 -279.099422) (xy 185.262134 -279.105354)
			(xy 185.212959 -279.103373) (xy 185.16474 -279.093529) (xy 185.118724 -279.076077) (xy 185.076103 -279.05147)
			(xy 185.037982 -279.020345) (xy 185.005347 -278.983508) (xy 184.979044 -278.941912) (xy 184.959753 -278.896636)
			(xy 184.947976 -278.848852) (xy 184.944016 -278.799798) (xy 183.654954 -278.799798) (xy 183.654459 -278.824405)
			(xy 183.646564 -278.872982) (xy 183.63098 -278.919663) (xy 183.608109 -278.96324) (xy 183.578544 -279.002584)
			(xy 183.543051 -279.036676) (xy 183.502548 -279.064632) (xy 183.458086 -279.08573) (xy 183.410815 -279.099422)
			(xy 183.36196 -279.105354) (xy 183.312785 -279.103373) (xy 183.264566 -279.093529) (xy 183.21855 -279.076077)
			(xy 183.175929 -279.05147) (xy 183.137808 -279.020345) (xy 183.105173 -278.983508) (xy 183.07887 -278.941912)
			(xy 183.059579 -278.896636) (xy 183.047802 -278.848852) (xy 183.043842 -278.799798) (xy 181.755034 -278.799798)
			(xy 181.754539 -278.824405) (xy 181.746644 -278.872982) (xy 181.73106 -278.919663) (xy 181.708189 -278.96324)
			(xy 181.678624 -279.002584) (xy 181.643131 -279.036676) (xy 181.602628 -279.064632) (xy 181.558166 -279.08573)
			(xy 181.510895 -279.099422) (xy 181.46204 -279.105354) (xy 181.412865 -279.103373) (xy 181.364646 -279.093529)
			(xy 181.31863 -279.076077) (xy 181.276009 -279.05147) (xy 181.237888 -279.020345) (xy 181.205253 -278.983508)
			(xy 181.17895 -278.941912) (xy 181.159659 -278.896636) (xy 181.147882 -278.848852) (xy 181.143922 -278.799798)
			(xy 179.855114 -278.799798) (xy 179.854619 -278.824405) (xy 179.846724 -278.872982) (xy 179.83114 -278.919663)
			(xy 179.808269 -278.96324) (xy 179.778704 -279.002584) (xy 179.743211 -279.036676) (xy 179.702708 -279.064632)
			(xy 179.658246 -279.08573) (xy 179.610975 -279.099422) (xy 179.56212 -279.105354) (xy 179.512945 -279.103373)
			(xy 179.464726 -279.093529) (xy 179.41871 -279.076077) (xy 179.376089 -279.05147) (xy 179.337968 -279.020345)
			(xy 179.305333 -278.983508) (xy 179.27903 -278.941912) (xy 179.259739 -278.896636) (xy 179.247962 -278.848852)
			(xy 179.244002 -278.799798) (xy 177.95494 -278.799798) (xy 177.954445 -278.824405) (xy 177.94655 -278.872982)
			(xy 177.930966 -278.919663) (xy 177.908095 -278.96324) (xy 177.87853 -279.002584) (xy 177.843037 -279.036676)
			(xy 177.802534 -279.064632) (xy 177.758072 -279.08573) (xy 177.710801 -279.099422) (xy 177.661946 -279.105354)
			(xy 177.612771 -279.103373) (xy 177.564552 -279.093529) (xy 177.518536 -279.076077) (xy 177.475915 -279.05147)
			(xy 177.437794 -279.020345) (xy 177.405159 -278.983508) (xy 177.378856 -278.941912) (xy 177.359565 -278.896636)
			(xy 177.347788 -278.848852) (xy 177.343828 -278.799798) (xy 176.05502 -278.799798) (xy 176.054525 -278.824405)
			(xy 176.04663 -278.872982) (xy 176.031046 -278.919663) (xy 176.008175 -278.96324) (xy 175.97861 -279.002584)
			(xy 175.943117 -279.036676) (xy 175.902614 -279.064632) (xy 175.858152 -279.08573) (xy 175.810881 -279.099422)
			(xy 175.762026 -279.105354) (xy 175.712851 -279.103373) (xy 175.664632 -279.093529) (xy 175.618616 -279.076077)
			(xy 175.575995 -279.05147) (xy 175.537874 -279.020345) (xy 175.505239 -278.983508) (xy 175.478936 -278.941912)
			(xy 175.459645 -278.896636) (xy 175.447868 -278.848852) (xy 175.443908 -278.799798) (xy 174.155354 -278.799798)
			(xy 174.154859 -278.824405) (xy 174.146964 -278.872982) (xy 174.13138 -278.919663) (xy 174.108509 -278.96324)
			(xy 174.078944 -279.002584) (xy 174.043451 -279.036676) (xy 174.002948 -279.064632) (xy 173.958486 -279.08573)
			(xy 173.911215 -279.099422) (xy 173.86236 -279.105354) (xy 173.813185 -279.103373) (xy 173.764966 -279.093529)
			(xy 173.71895 -279.076077) (xy 173.676329 -279.05147) (xy 173.638208 -279.020345) (xy 173.605573 -278.983508)
			(xy 173.57927 -278.941912) (xy 173.559979 -278.896636) (xy 173.548202 -278.848852) (xy 173.544242 -278.799798)
			(xy 172.25518 -278.799798) (xy 172.254685 -278.824405) (xy 172.24679 -278.872982) (xy 172.231206 -278.919663)
			(xy 172.208335 -278.96324) (xy 172.17877 -279.002584) (xy 172.143277 -279.036676) (xy 172.102774 -279.064632)
			(xy 172.058312 -279.08573) (xy 172.011041 -279.099422) (xy 171.962186 -279.105354) (xy 171.913011 -279.103373)
			(xy 171.864792 -279.093529) (xy 171.818776 -279.076077) (xy 171.776155 -279.05147) (xy 171.738034 -279.020345)
			(xy 171.705399 -278.983508) (xy 171.679096 -278.941912) (xy 171.659805 -278.896636) (xy 171.648028 -278.848852)
			(xy 171.644068 -278.799798) (xy 170.35526 -278.799798) (xy 170.354765 -278.824405) (xy 170.34687 -278.872982)
			(xy 170.331286 -278.919663) (xy 170.308415 -278.96324) (xy 170.27885 -279.002584) (xy 170.243357 -279.036676)
			(xy 170.202854 -279.064632) (xy 170.158392 -279.08573) (xy 170.111121 -279.099422) (xy 170.062266 -279.105354)
			(xy 170.013091 -279.103373) (xy 169.964872 -279.093529) (xy 169.918856 -279.076077) (xy 169.876235 -279.05147)
			(xy 169.838114 -279.020345) (xy 169.805479 -278.983508) (xy 169.779176 -278.941912) (xy 169.759885 -278.896636)
			(xy 169.748108 -278.848852) (xy 169.744148 -278.799798) (xy 168.45534 -278.799798) (xy 168.454845 -278.824405)
			(xy 168.44695 -278.872982) (xy 168.431366 -278.919663) (xy 168.408495 -278.96324) (xy 168.37893 -279.002584)
			(xy 168.343437 -279.036676) (xy 168.302934 -279.064632) (xy 168.258472 -279.08573) (xy 168.211201 -279.099422)
			(xy 168.162346 -279.105354) (xy 168.113171 -279.103373) (xy 168.064952 -279.093529) (xy 168.018936 -279.076077)
			(xy 167.976315 -279.05147) (xy 167.938194 -279.020345) (xy 167.905559 -278.983508) (xy 167.879256 -278.941912)
			(xy 167.859965 -278.896636) (xy 167.848188 -278.848852) (xy 167.844228 -278.799798) (xy 166.555166 -278.799798)
			(xy 166.554671 -278.824405) (xy 166.546776 -278.872982) (xy 166.531192 -278.919663) (xy 166.508321 -278.96324)
			(xy 166.478756 -279.002584) (xy 166.443263 -279.036676) (xy 166.40276 -279.064632) (xy 166.358298 -279.08573)
			(xy 166.311027 -279.099422) (xy 166.262172 -279.105354) (xy 166.212997 -279.103373) (xy 166.164778 -279.093529)
			(xy 166.118762 -279.076077) (xy 166.076141 -279.05147) (xy 166.03802 -279.020345) (xy 166.005385 -278.983508)
			(xy 165.979082 -278.941912) (xy 165.959791 -278.896636) (xy 165.948014 -278.848852) (xy 165.944054 -278.799798)
			(xy 164.655246 -278.799798) (xy 164.654751 -278.824405) (xy 164.646856 -278.872982) (xy 164.631272 -278.919663)
			(xy 164.608401 -278.96324) (xy 164.578836 -279.002584) (xy 164.543343 -279.036676) (xy 164.50284 -279.064632)
			(xy 164.458378 -279.08573) (xy 164.411107 -279.099422) (xy 164.362252 -279.105354) (xy 164.313077 -279.103373)
			(xy 164.264858 -279.093529) (xy 164.218842 -279.076077) (xy 164.176221 -279.05147) (xy 164.1381 -279.020345)
			(xy 164.105465 -278.983508) (xy 164.079162 -278.941912) (xy 164.059871 -278.896636) (xy 164.048094 -278.848852)
			(xy 164.044134 -278.799798) (xy 162.755326 -278.799798) (xy 162.754831 -278.824405) (xy 162.746936 -278.872982)
			(xy 162.731352 -278.919663) (xy 162.708481 -278.96324) (xy 162.678916 -279.002584) (xy 162.643423 -279.036676)
			(xy 162.60292 -279.064632) (xy 162.558458 -279.08573) (xy 162.511187 -279.099422) (xy 162.462332 -279.105354)
			(xy 162.413157 -279.103373) (xy 162.364938 -279.093529) (xy 162.318922 -279.076077) (xy 162.276301 -279.05147)
			(xy 162.23818 -279.020345) (xy 162.205545 -278.983508) (xy 162.179242 -278.941912) (xy 162.159951 -278.896636)
			(xy 162.148174 -278.848852) (xy 162.144214 -278.799798) (xy 160.855152 -278.799798) (xy 160.854657 -278.824405)
			(xy 160.846762 -278.872982) (xy 160.831178 -278.919663) (xy 160.808307 -278.96324) (xy 160.778742 -279.002584)
			(xy 160.743249 -279.036676) (xy 160.702746 -279.064632) (xy 160.658284 -279.08573) (xy 160.611013 -279.099422)
			(xy 160.562158 -279.105354) (xy 160.512983 -279.103373) (xy 160.464764 -279.093529) (xy 160.418748 -279.076077)
			(xy 160.376127 -279.05147) (xy 160.338006 -279.020345) (xy 160.305371 -278.983508) (xy 160.279068 -278.941912)
			(xy 160.259777 -278.896636) (xy 160.248 -278.848852) (xy 160.24404 -278.799798) (xy 80.855058 -278.799798)
			(xy 80.854563 -278.824405) (xy 80.846668 -278.872982) (xy 80.831084 -278.919663) (xy 80.808213 -278.96324)
			(xy 80.778648 -279.002584) (xy 80.743155 -279.036676) (xy 80.702652 -279.064632) (xy 80.65819 -279.08573)
			(xy 80.610919 -279.099422) (xy 80.562064 -279.105354) (xy 80.512889 -279.103373) (xy 80.46467 -279.093529)
			(xy 80.418654 -279.076077) (xy 80.376033 -279.05147) (xy 80.337912 -279.020345) (xy 80.305277 -278.983508)
			(xy 80.278974 -278.941912) (xy 80.259683 -278.896636) (xy 80.247906 -278.848852) (xy 80.243946 -278.799798)
			(xy 78.954884 -278.799798) (xy 78.954389 -278.824405) (xy 78.946494 -278.872982) (xy 78.93091 -278.919663)
			(xy 78.908039 -278.96324) (xy 78.878474 -279.002584) (xy 78.842981 -279.036676) (xy 78.802478 -279.064632)
			(xy 78.758016 -279.08573) (xy 78.710745 -279.099422) (xy 78.66189 -279.105354) (xy 78.612715 -279.103373)
			(xy 78.564496 -279.093529) (xy 78.51848 -279.076077) (xy 78.475859 -279.05147) (xy 78.437738 -279.020345)
			(xy 78.405103 -278.983508) (xy 78.3788 -278.941912) (xy 78.359509 -278.896636) (xy 78.347732 -278.848852)
			(xy 78.343772 -278.799798) (xy 77.054964 -278.799798) (xy 77.054469 -278.824405) (xy 77.046574 -278.872982)
			(xy 77.03099 -278.919663) (xy 77.008119 -278.96324) (xy 76.978554 -279.002584) (xy 76.943061 -279.036676)
			(xy 76.902558 -279.064632) (xy 76.858096 -279.08573) (xy 76.810825 -279.099422) (xy 76.76197 -279.105354)
			(xy 76.712795 -279.103373) (xy 76.664576 -279.093529) (xy 76.61856 -279.076077) (xy 76.575939 -279.05147)
			(xy 76.537818 -279.020345) (xy 76.505183 -278.983508) (xy 76.47888 -278.941912) (xy 76.459589 -278.896636)
			(xy 76.447812 -278.848852) (xy 76.443852 -278.799798) (xy 75.155044 -278.799798) (xy 75.154549 -278.824405)
			(xy 75.146654 -278.872982) (xy 75.13107 -278.919663) (xy 75.108199 -278.96324) (xy 75.078634 -279.002584)
			(xy 75.043141 -279.036676) (xy 75.002638 -279.064632) (xy 74.958176 -279.08573) (xy 74.910905 -279.099422)
			(xy 74.86205 -279.105354) (xy 74.812875 -279.103373) (xy 74.764656 -279.093529) (xy 74.71864 -279.076077)
			(xy 74.676019 -279.05147) (xy 74.637898 -279.020345) (xy 74.605263 -278.983508) (xy 74.57896 -278.941912)
			(xy 74.559669 -278.896636) (xy 74.547892 -278.848852) (xy 74.543932 -278.799798) (xy 73.25487 -278.799798)
			(xy 73.254375 -278.824405) (xy 73.24648 -278.872982) (xy 73.230896 -278.919663) (xy 73.208025 -278.96324)
			(xy 73.17846 -279.002584) (xy 73.142967 -279.036676) (xy 73.102464 -279.064632) (xy 73.058002 -279.08573)
			(xy 73.010731 -279.099422) (xy 72.961876 -279.105354) (xy 72.912701 -279.103373) (xy 72.864482 -279.093529)
			(xy 72.818466 -279.076077) (xy 72.775845 -279.05147) (xy 72.737724 -279.020345) (xy 72.705089 -278.983508)
			(xy 72.678786 -278.941912) (xy 72.659495 -278.896636) (xy 72.647718 -278.848852) (xy 72.643758 -278.799798)
			(xy 71.35495 -278.799798) (xy 71.354455 -278.824405) (xy 71.34656 -278.872982) (xy 71.330976 -278.919663)
			(xy 71.308105 -278.96324) (xy 71.27854 -279.002584) (xy 71.243047 -279.036676) (xy 71.202544 -279.064632)
			(xy 71.158082 -279.08573) (xy 71.110811 -279.099422) (xy 71.061956 -279.105354) (xy 71.012781 -279.103373)
			(xy 70.964562 -279.093529) (xy 70.918546 -279.076077) (xy 70.875925 -279.05147) (xy 70.837804 -279.020345)
			(xy 70.805169 -278.983508) (xy 70.778866 -278.941912) (xy 70.759575 -278.896636) (xy 70.747798 -278.848852)
			(xy 70.743838 -278.799798) (xy 69.45503 -278.799798) (xy 69.454535 -278.824405) (xy 69.44664 -278.872982)
			(xy 69.431056 -278.919663) (xy 69.408185 -278.96324) (xy 69.37862 -279.002584) (xy 69.343127 -279.036676)
			(xy 69.302624 -279.064632) (xy 69.258162 -279.08573) (xy 69.210891 -279.099422) (xy 69.162036 -279.105354)
			(xy 69.112861 -279.103373) (xy 69.064642 -279.093529) (xy 69.018626 -279.076077) (xy 68.976005 -279.05147)
			(xy 68.937884 -279.020345) (xy 68.905249 -278.983508) (xy 68.878946 -278.941912) (xy 68.859655 -278.896636)
			(xy 68.847878 -278.848852) (xy 68.843918 -278.799798) (xy 67.554856 -278.799798) (xy 67.554361 -278.824405)
			(xy 67.546466 -278.872982) (xy 67.530882 -278.919663) (xy 67.508011 -278.96324) (xy 67.478446 -279.002584)
			(xy 67.442953 -279.036676) (xy 67.40245 -279.064632) (xy 67.357988 -279.08573) (xy 67.310717 -279.099422)
			(xy 67.261862 -279.105354) (xy 67.212687 -279.103373) (xy 67.164468 -279.093529) (xy 67.118452 -279.076077)
			(xy 67.075831 -279.05147) (xy 67.03771 -279.020345) (xy 67.005075 -278.983508) (xy 66.978772 -278.941912)
			(xy 66.959481 -278.896636) (xy 66.947704 -278.848852) (xy 66.943744 -278.799798) (xy 65.654936 -278.799798)
			(xy 65.654441 -278.824405) (xy 65.646546 -278.872982) (xy 65.630962 -278.919663) (xy 65.608091 -278.96324)
			(xy 65.578526 -279.002584) (xy 65.543033 -279.036676) (xy 65.50253 -279.064632) (xy 65.458068 -279.08573)
			(xy 65.410797 -279.099422) (xy 65.361942 -279.105354) (xy 65.312767 -279.103373) (xy 65.264548 -279.093529)
			(xy 65.218532 -279.076077) (xy 65.175911 -279.05147) (xy 65.13779 -279.020345) (xy 65.105155 -278.983508)
			(xy 65.078852 -278.941912) (xy 65.059561 -278.896636) (xy 65.047784 -278.848852) (xy 65.043824 -278.799798)
			(xy 63.755016 -278.799798) (xy 63.754521 -278.824405) (xy 63.746626 -278.872982) (xy 63.731042 -278.919663)
			(xy 63.708171 -278.96324) (xy 63.678606 -279.002584) (xy 63.643113 -279.036676) (xy 63.60261 -279.064632)
			(xy 63.558148 -279.08573) (xy 63.510877 -279.099422) (xy 63.462022 -279.105354) (xy 63.412847 -279.103373)
			(xy 63.364628 -279.093529) (xy 63.318612 -279.076077) (xy 63.275991 -279.05147) (xy 63.23787 -279.020345)
			(xy 63.205235 -278.983508) (xy 63.178932 -278.941912) (xy 63.159641 -278.896636) (xy 63.147864 -278.848852)
			(xy 63.143904 -278.799798) (xy 61.854842 -278.799798) (xy 61.854347 -278.824405) (xy 61.846452 -278.872982)
			(xy 61.830868 -278.919663) (xy 61.807997 -278.96324) (xy 61.778432 -279.002584) (xy 61.742939 -279.036676)
			(xy 61.702436 -279.064632) (xy 61.657974 -279.08573) (xy 61.610703 -279.099422) (xy 61.561848 -279.105354)
			(xy 61.512673 -279.103373) (xy 61.464454 -279.093529) (xy 61.418438 -279.076077) (xy 61.375817 -279.05147)
			(xy 61.337696 -279.020345) (xy 61.305061 -278.983508) (xy 61.278758 -278.941912) (xy 61.259467 -278.896636)
			(xy 61.24769 -278.848852) (xy 61.24373 -278.799798) (xy 59.954922 -278.799798) (xy 59.954427 -278.824405)
			(xy 59.946532 -278.872982) (xy 59.930948 -278.919663) (xy 59.908077 -278.96324) (xy 59.878512 -279.002584)
			(xy 59.843019 -279.036676) (xy 59.802516 -279.064632) (xy 59.758054 -279.08573) (xy 59.710783 -279.099422)
			(xy 59.661928 -279.105354) (xy 59.612753 -279.103373) (xy 59.564534 -279.093529) (xy 59.518518 -279.076077)
			(xy 59.475897 -279.05147) (xy 59.437776 -279.020345) (xy 59.405141 -278.983508) (xy 59.378838 -278.941912)
			(xy 59.359547 -278.896636) (xy 59.34777 -278.848852) (xy 59.34381 -278.799798) (xy 58.055256 -278.799798)
			(xy 58.054761 -278.824405) (xy 58.046866 -278.872982) (xy 58.031282 -278.919663) (xy 58.008411 -278.96324)
			(xy 57.978846 -279.002584) (xy 57.943353 -279.036676) (xy 57.90285 -279.064632) (xy 57.858388 -279.08573)
			(xy 57.811117 -279.099422) (xy 57.762262 -279.105354) (xy 57.713087 -279.103373) (xy 57.664868 -279.093529)
			(xy 57.618852 -279.076077) (xy 57.576231 -279.05147) (xy 57.53811 -279.020345) (xy 57.505475 -278.983508)
			(xy 57.479172 -278.941912) (xy 57.459881 -278.896636) (xy 57.448104 -278.848852) (xy 57.444144 -278.799798)
			(xy 56.155082 -278.799798) (xy 56.154587 -278.824405) (xy 56.146692 -278.872982) (xy 56.131108 -278.919663)
			(xy 56.108237 -278.96324) (xy 56.078672 -279.002584) (xy 56.043179 -279.036676) (xy 56.002676 -279.064632)
			(xy 55.958214 -279.08573) (xy 55.910943 -279.099422) (xy 55.862088 -279.105354) (xy 55.812913 -279.103373)
			(xy 55.764694 -279.093529) (xy 55.718678 -279.076077) (xy 55.676057 -279.05147) (xy 55.637936 -279.020345)
			(xy 55.605301 -278.983508) (xy 55.578998 -278.941912) (xy 55.559707 -278.896636) (xy 55.54793 -278.848852)
			(xy 55.54397 -278.799798) (xy 54.255162 -278.799798) (xy 54.254667 -278.824405) (xy 54.246772 -278.872982)
			(xy 54.231188 -278.919663) (xy 54.208317 -278.96324) (xy 54.178752 -279.002584) (xy 54.143259 -279.036676)
			(xy 54.102756 -279.064632) (xy 54.058294 -279.08573) (xy 54.011023 -279.099422) (xy 53.962168 -279.105354)
			(xy 53.912993 -279.103373) (xy 53.864774 -279.093529) (xy 53.818758 -279.076077) (xy 53.776137 -279.05147)
			(xy 53.738016 -279.020345) (xy 53.705381 -278.983508) (xy 53.679078 -278.941912) (xy 53.659787 -278.896636)
			(xy 53.64801 -278.848852) (xy 53.64405 -278.799798) (xy 52.355242 -278.799798) (xy 52.354747 -278.824405)
			(xy 52.346852 -278.872982) (xy 52.331268 -278.919663) (xy 52.308397 -278.96324) (xy 52.278832 -279.002584)
			(xy 52.243339 -279.036676) (xy 52.202836 -279.064632) (xy 52.158374 -279.08573) (xy 52.111103 -279.099422)
			(xy 52.062248 -279.105354) (xy 52.013073 -279.103373) (xy 51.964854 -279.093529) (xy 51.918838 -279.076077)
			(xy 51.876217 -279.05147) (xy 51.838096 -279.020345) (xy 51.805461 -278.983508) (xy 51.779158 -278.941912)
			(xy 51.759867 -278.896636) (xy 51.74809 -278.848852) (xy 51.74413 -278.799798) (xy 50.455068 -278.799798)
			(xy 50.454573 -278.824405) (xy 50.446678 -278.872982) (xy 50.431094 -278.919663) (xy 50.408223 -278.96324)
			(xy 50.378658 -279.002584) (xy 50.343165 -279.036676) (xy 50.302662 -279.064632) (xy 50.2582 -279.08573)
			(xy 50.210929 -279.099422) (xy 50.162074 -279.105354) (xy 50.112899 -279.103373) (xy 50.06468 -279.093529)
			(xy 50.018664 -279.076077) (xy 49.976043 -279.05147) (xy 49.937922 -279.020345) (xy 49.905287 -278.983508)
			(xy 49.878984 -278.941912) (xy 49.859693 -278.896636) (xy 49.847916 -278.848852) (xy 49.843956 -278.799798)
			(xy 48.555148 -278.799798) (xy 48.554653 -278.824405) (xy 48.546758 -278.872982) (xy 48.531174 -278.919663)
			(xy 48.508303 -278.96324) (xy 48.478738 -279.002584) (xy 48.443245 -279.036676) (xy 48.402742 -279.064632)
			(xy 48.35828 -279.08573) (xy 48.311009 -279.099422) (xy 48.262154 -279.105354) (xy 48.212979 -279.103373)
			(xy 48.16476 -279.093529) (xy 48.118744 -279.076077) (xy 48.076123 -279.05147) (xy 48.038002 -279.020345)
			(xy 48.005367 -278.983508) (xy 47.979064 -278.941912) (xy 47.959773 -278.896636) (xy 47.947996 -278.848852)
			(xy 47.944036 -278.799798) (xy 46.655228 -278.799798) (xy 46.654733 -278.824405) (xy 46.646838 -278.872982)
			(xy 46.631254 -278.919663) (xy 46.608383 -278.96324) (xy 46.578818 -279.002584) (xy 46.543325 -279.036676)
			(xy 46.502822 -279.064632) (xy 46.45836 -279.08573) (xy 46.411089 -279.099422) (xy 46.362234 -279.105354)
			(xy 46.313059 -279.103373) (xy 46.26484 -279.093529) (xy 46.218824 -279.076077) (xy 46.176203 -279.05147)
			(xy 46.138082 -279.020345) (xy 46.105447 -278.983508) (xy 46.079144 -278.941912) (xy 46.059853 -278.896636)
			(xy 46.048076 -278.848852) (xy 46.044116 -278.799798) (xy 44.755054 -278.799798) (xy 44.754559 -278.824405)
			(xy 44.746664 -278.872982) (xy 44.73108 -278.919663) (xy 44.708209 -278.96324) (xy 44.678644 -279.002584)
			(xy 44.643151 -279.036676) (xy 44.602648 -279.064632) (xy 44.558186 -279.08573) (xy 44.510915 -279.099422)
			(xy 44.46206 -279.105354) (xy 44.412885 -279.103373) (xy 44.364666 -279.093529) (xy 44.31865 -279.076077)
			(xy 44.276029 -279.05147) (xy 44.237908 -279.020345) (xy 44.205273 -278.983508) (xy 44.17897 -278.941912)
			(xy 44.159679 -278.896636) (xy 44.147902 -278.848852) (xy 44.143942 -278.799798) (xy 0.508 -278.799798)
			(xy 0.508 -279.749504) (xy 45.094156 -279.749504) (xy 45.098116 -279.70045) (xy 45.109893 -279.652666)
			(xy 45.129184 -279.60739) (xy 45.155487 -279.565794) (xy 45.188122 -279.528957) (xy 45.226243 -279.497832)
			(xy 45.268864 -279.473225) (xy 45.31488 -279.455773) (xy 45.363099 -279.445929) (xy 45.412274 -279.443948)
			(xy 45.461129 -279.44988) (xy 45.5084 -279.463572) (xy 45.552862 -279.48467) (xy 45.593365 -279.512626)
			(xy 45.628858 -279.546718) (xy 45.658423 -279.586062) (xy 45.681294 -279.629639) (xy 45.696878 -279.67632)
			(xy 45.704773 -279.724897) (xy 45.705268 -279.749504) (xy 46.994076 -279.749504) (xy 46.998036 -279.70045)
			(xy 47.009813 -279.652666) (xy 47.029104 -279.60739) (xy 47.055407 -279.565794) (xy 47.088042 -279.528957)
			(xy 47.126163 -279.497832) (xy 47.168784 -279.473225) (xy 47.2148 -279.455773) (xy 47.263019 -279.445929)
			(xy 47.312194 -279.443948) (xy 47.361049 -279.44988) (xy 47.40832 -279.463572) (xy 47.452782 -279.48467)
			(xy 47.493285 -279.512626) (xy 47.528778 -279.546718) (xy 47.558343 -279.586062) (xy 47.581214 -279.629639)
			(xy 47.596798 -279.67632) (xy 47.604693 -279.724897) (xy 47.605188 -279.749504) (xy 48.893996 -279.749504)
			(xy 48.897956 -279.70045) (xy 48.909733 -279.652666) (xy 48.929024 -279.60739) (xy 48.955327 -279.565794)
			(xy 48.987962 -279.528957) (xy 49.026083 -279.497832) (xy 49.068704 -279.473225) (xy 49.11472 -279.455773)
			(xy 49.162939 -279.445929) (xy 49.212114 -279.443948) (xy 49.260969 -279.44988) (xy 49.30824 -279.463572)
			(xy 49.352702 -279.48467) (xy 49.393205 -279.512626) (xy 49.428698 -279.546718) (xy 49.458263 -279.586062)
			(xy 49.481134 -279.629639) (xy 49.496718 -279.67632) (xy 49.504613 -279.724897) (xy 49.505108 -279.749504)
			(xy 50.79417 -279.749504) (xy 50.79813 -279.70045) (xy 50.809907 -279.652666) (xy 50.829198 -279.60739)
			(xy 50.855501 -279.565794) (xy 50.888136 -279.528957) (xy 50.926257 -279.497832) (xy 50.968878 -279.473225)
			(xy 51.014894 -279.455773) (xy 51.063113 -279.445929) (xy 51.112288 -279.443948) (xy 51.161143 -279.44988)
			(xy 51.208414 -279.463572) (xy 51.252876 -279.48467) (xy 51.293379 -279.512626) (xy 51.328872 -279.546718)
			(xy 51.358437 -279.586062) (xy 51.381308 -279.629639) (xy 51.396892 -279.67632) (xy 51.404787 -279.724897)
			(xy 51.405282 -279.749504) (xy 52.69409 -279.749504) (xy 52.69805 -279.70045) (xy 52.709827 -279.652666)
			(xy 52.729118 -279.60739) (xy 52.755421 -279.565794) (xy 52.788056 -279.528957) (xy 52.826177 -279.497832)
			(xy 52.868798 -279.473225) (xy 52.914814 -279.455773) (xy 52.963033 -279.445929) (xy 53.012208 -279.443948)
			(xy 53.061063 -279.44988) (xy 53.108334 -279.463572) (xy 53.152796 -279.48467) (xy 53.193299 -279.512626)
			(xy 53.228792 -279.546718) (xy 53.258357 -279.586062) (xy 53.281228 -279.629639) (xy 53.296812 -279.67632)
			(xy 53.304707 -279.724897) (xy 53.305202 -279.749504) (xy 54.59401 -279.749504) (xy 54.59797 -279.70045)
			(xy 54.609747 -279.652666) (xy 54.629038 -279.60739) (xy 54.655341 -279.565794) (xy 54.687976 -279.528957)
			(xy 54.726097 -279.497832) (xy 54.768718 -279.473225) (xy 54.814734 -279.455773) (xy 54.862953 -279.445929)
			(xy 54.912128 -279.443948) (xy 54.960983 -279.44988) (xy 55.008254 -279.463572) (xy 55.052716 -279.48467)
			(xy 55.093219 -279.512626) (xy 55.128712 -279.546718) (xy 55.158277 -279.586062) (xy 55.181148 -279.629639)
			(xy 55.196732 -279.67632) (xy 55.204627 -279.724897) (xy 55.205122 -279.749504) (xy 56.49393 -279.749504)
			(xy 56.49789 -279.70045) (xy 56.509667 -279.652666) (xy 56.528958 -279.60739) (xy 56.555261 -279.565794)
			(xy 56.587896 -279.528957) (xy 56.626017 -279.497832) (xy 56.668638 -279.473225) (xy 56.714654 -279.455773)
			(xy 56.762873 -279.445929) (xy 56.812048 -279.443948) (xy 56.860903 -279.44988) (xy 56.908174 -279.463572)
			(xy 56.952636 -279.48467) (xy 56.993139 -279.512626) (xy 57.028632 -279.546718) (xy 57.058197 -279.586062)
			(xy 57.081068 -279.629639) (xy 57.096652 -279.67632) (xy 57.104547 -279.724897) (xy 57.105042 -279.749504)
			(xy 58.394104 -279.749504) (xy 58.398064 -279.70045) (xy 58.409841 -279.652666) (xy 58.429132 -279.60739)
			(xy 58.455435 -279.565794) (xy 58.48807 -279.528957) (xy 58.526191 -279.497832) (xy 58.568812 -279.473225)
			(xy 58.614828 -279.455773) (xy 58.663047 -279.445929) (xy 58.712222 -279.443948) (xy 58.761077 -279.44988)
			(xy 58.808348 -279.463572) (xy 58.85281 -279.48467) (xy 58.893313 -279.512626) (xy 58.928806 -279.546718)
			(xy 58.958371 -279.586062) (xy 58.981242 -279.629639) (xy 58.996826 -279.67632) (xy 59.004721 -279.724897)
			(xy 59.005216 -279.749504) (xy 60.294024 -279.749504) (xy 60.297984 -279.70045) (xy 60.309761 -279.652666)
			(xy 60.329052 -279.60739) (xy 60.355355 -279.565794) (xy 60.38799 -279.528957) (xy 60.426111 -279.497832)
			(xy 60.468732 -279.473225) (xy 60.514748 -279.455773) (xy 60.562967 -279.445929) (xy 60.612142 -279.443948)
			(xy 60.660997 -279.44988) (xy 60.708268 -279.463572) (xy 60.75273 -279.48467) (xy 60.793233 -279.512626)
			(xy 60.828726 -279.546718) (xy 60.858291 -279.586062) (xy 60.881162 -279.629639) (xy 60.896746 -279.67632)
			(xy 60.904641 -279.724897) (xy 60.905136 -279.749504) (xy 62.193944 -279.749504) (xy 62.197904 -279.70045)
			(xy 62.209681 -279.652666) (xy 62.228972 -279.60739) (xy 62.255275 -279.565794) (xy 62.28791 -279.528957)
			(xy 62.326031 -279.497832) (xy 62.368652 -279.473225) (xy 62.414668 -279.455773) (xy 62.462887 -279.445929)
			(xy 62.512062 -279.443948) (xy 62.560917 -279.44988) (xy 62.608188 -279.463572) (xy 62.65265 -279.48467)
			(xy 62.693153 -279.512626) (xy 62.728646 -279.546718) (xy 62.758211 -279.586062) (xy 62.781082 -279.629639)
			(xy 62.796666 -279.67632) (xy 62.804561 -279.724897) (xy 62.805056 -279.749504) (xy 64.094118 -279.749504)
			(xy 64.098078 -279.70045) (xy 64.109855 -279.652666) (xy 64.129146 -279.60739) (xy 64.155449 -279.565794)
			(xy 64.188084 -279.528957) (xy 64.226205 -279.497832) (xy 64.268826 -279.473225) (xy 64.314842 -279.455773)
			(xy 64.363061 -279.445929) (xy 64.412236 -279.443948) (xy 64.461091 -279.44988) (xy 64.508362 -279.463572)
			(xy 64.552824 -279.48467) (xy 64.593327 -279.512626) (xy 64.62882 -279.546718) (xy 64.658385 -279.586062)
			(xy 64.681256 -279.629639) (xy 64.69684 -279.67632) (xy 64.704735 -279.724897) (xy 64.70523 -279.749504)
			(xy 65.994038 -279.749504) (xy 65.997998 -279.70045) (xy 66.009775 -279.652666) (xy 66.029066 -279.60739)
			(xy 66.055369 -279.565794) (xy 66.088004 -279.528957) (xy 66.126125 -279.497832) (xy 66.168746 -279.473225)
			(xy 66.214762 -279.455773) (xy 66.262981 -279.445929) (xy 66.312156 -279.443948) (xy 66.361011 -279.44988)
			(xy 66.408282 -279.463572) (xy 66.452744 -279.48467) (xy 66.493247 -279.512626) (xy 66.52874 -279.546718)
			(xy 66.558305 -279.586062) (xy 66.581176 -279.629639) (xy 66.59676 -279.67632) (xy 66.604655 -279.724897)
			(xy 66.60515 -279.749504) (xy 67.893958 -279.749504) (xy 67.897918 -279.70045) (xy 67.909695 -279.652666)
			(xy 67.928986 -279.60739) (xy 67.955289 -279.565794) (xy 67.987924 -279.528957) (xy 68.026045 -279.497832)
			(xy 68.068666 -279.473225) (xy 68.114682 -279.455773) (xy 68.162901 -279.445929) (xy 68.212076 -279.443948)
			(xy 68.260931 -279.44988) (xy 68.308202 -279.463572) (xy 68.352664 -279.48467) (xy 68.393167 -279.512626)
			(xy 68.42866 -279.546718) (xy 68.458225 -279.586062) (xy 68.481096 -279.629639) (xy 68.49668 -279.67632)
			(xy 68.504575 -279.724897) (xy 68.50507 -279.749504) (xy 69.794132 -279.749504) (xy 69.798092 -279.70045)
			(xy 69.809869 -279.652666) (xy 69.82916 -279.60739) (xy 69.855463 -279.565794) (xy 69.888098 -279.528957)
			(xy 69.926219 -279.497832) (xy 69.96884 -279.473225) (xy 70.014856 -279.455773) (xy 70.063075 -279.445929)
			(xy 70.11225 -279.443948) (xy 70.161105 -279.44988) (xy 70.208376 -279.463572) (xy 70.252838 -279.48467)
			(xy 70.293341 -279.512626) (xy 70.328834 -279.546718) (xy 70.358399 -279.586062) (xy 70.38127 -279.629639)
			(xy 70.396854 -279.67632) (xy 70.404749 -279.724897) (xy 70.405244 -279.749504) (xy 71.694052 -279.749504)
			(xy 71.698012 -279.70045) (xy 71.709789 -279.652666) (xy 71.72908 -279.60739) (xy 71.755383 -279.565794)
			(xy 71.788018 -279.528957) (xy 71.826139 -279.497832) (xy 71.86876 -279.473225) (xy 71.914776 -279.455773)
			(xy 71.962995 -279.445929) (xy 72.01217 -279.443948) (xy 72.061025 -279.44988) (xy 72.108296 -279.463572)
			(xy 72.152758 -279.48467) (xy 72.193261 -279.512626) (xy 72.228754 -279.546718) (xy 72.258319 -279.586062)
			(xy 72.28119 -279.629639) (xy 72.296774 -279.67632) (xy 72.304669 -279.724897) (xy 72.305164 -279.749504)
			(xy 73.593972 -279.749504) (xy 73.597932 -279.70045) (xy 73.609709 -279.652666) (xy 73.629 -279.60739)
			(xy 73.655303 -279.565794) (xy 73.687938 -279.528957) (xy 73.726059 -279.497832) (xy 73.76868 -279.473225)
			(xy 73.814696 -279.455773) (xy 73.862915 -279.445929) (xy 73.91209 -279.443948) (xy 73.960945 -279.44988)
			(xy 74.008216 -279.463572) (xy 74.052678 -279.48467) (xy 74.093181 -279.512626) (xy 74.128674 -279.546718)
			(xy 74.158239 -279.586062) (xy 74.18111 -279.629639) (xy 74.196694 -279.67632) (xy 74.204589 -279.724897)
			(xy 74.205084 -279.749504) (xy 75.494146 -279.749504) (xy 75.498106 -279.70045) (xy 75.509883 -279.652666)
			(xy 75.529174 -279.60739) (xy 75.555477 -279.565794) (xy 75.588112 -279.528957) (xy 75.626233 -279.497832)
			(xy 75.668854 -279.473225) (xy 75.71487 -279.455773) (xy 75.763089 -279.445929) (xy 75.812264 -279.443948)
			(xy 75.861119 -279.44988) (xy 75.90839 -279.463572) (xy 75.952852 -279.48467) (xy 75.993355 -279.512626)
			(xy 76.028848 -279.546718) (xy 76.058413 -279.586062) (xy 76.081284 -279.629639) (xy 76.096868 -279.67632)
			(xy 76.104763 -279.724897) (xy 76.105258 -279.749504) (xy 77.394066 -279.749504) (xy 77.398026 -279.70045)
			(xy 77.409803 -279.652666) (xy 77.429094 -279.60739) (xy 77.455397 -279.565794) (xy 77.488032 -279.528957)
			(xy 77.526153 -279.497832) (xy 77.568774 -279.473225) (xy 77.61479 -279.455773) (xy 77.663009 -279.445929)
			(xy 77.712184 -279.443948) (xy 77.761039 -279.44988) (xy 77.80831 -279.463572) (xy 77.852772 -279.48467)
			(xy 77.893275 -279.512626) (xy 77.928768 -279.546718) (xy 77.958333 -279.586062) (xy 77.981204 -279.629639)
			(xy 77.996788 -279.67632) (xy 78.004683 -279.724897) (xy 78.005178 -279.749504) (xy 78.005173 -279.749758)
			(xy 79.293986 -279.749758) (xy 79.297946 -279.700704) (xy 79.309723 -279.65292) (xy 79.329014 -279.607644)
			(xy 79.355317 -279.566048) (xy 79.387952 -279.529211) (xy 79.426073 -279.498086) (xy 79.468694 -279.473479)
			(xy 79.51471 -279.456027) (xy 79.562929 -279.446183) (xy 79.612104 -279.444202) (xy 79.660959 -279.450134)
			(xy 79.70823 -279.463826) (xy 79.752692 -279.484924) (xy 79.793195 -279.51288) (xy 79.828688 -279.546972)
			(xy 79.858253 -279.586316) (xy 79.881124 -279.629893) (xy 79.896708 -279.676574) (xy 79.904603 -279.725151)
			(xy 79.905098 -279.749758) (xy 81.19416 -279.749758) (xy 81.19812 -279.700704) (xy 81.209897 -279.65292)
			(xy 81.229188 -279.607644) (xy 81.255491 -279.566048) (xy 81.288126 -279.529211) (xy 81.326247 -279.498086)
			(xy 81.368868 -279.473479) (xy 81.414884 -279.456027) (xy 81.463103 -279.446183) (xy 81.512278 -279.444202)
			(xy 81.561133 -279.450134) (xy 81.608404 -279.463826) (xy 81.652866 -279.484924) (xy 81.693369 -279.51288)
			(xy 81.728862 -279.546972) (xy 81.758427 -279.586316) (xy 81.781298 -279.629893) (xy 81.796882 -279.676574)
			(xy 81.804777 -279.725151) (xy 81.805272 -279.749758) (xy 82.14412 -279.749758) (xy 82.14808 -279.700704)
			(xy 82.159857 -279.65292) (xy 82.179148 -279.607644) (xy 82.205451 -279.566048) (xy 82.238086 -279.529211)
			(xy 82.276207 -279.498086) (xy 82.318828 -279.473479) (xy 82.364844 -279.456027) (xy 82.413063 -279.446183)
			(xy 82.462238 -279.444202) (xy 82.511093 -279.450134) (xy 82.558364 -279.463826) (xy 82.602826 -279.484924)
			(xy 82.643329 -279.51288) (xy 82.678822 -279.546972) (xy 82.708387 -279.586316) (xy 82.731258 -279.629893)
			(xy 82.746842 -279.676574) (xy 82.754737 -279.725151) (xy 82.755227 -279.749504) (xy 161.194254 -279.749504)
			(xy 161.198214 -279.70045) (xy 161.209991 -279.652666) (xy 161.229282 -279.60739) (xy 161.255585 -279.565794)
			(xy 161.28822 -279.528957) (xy 161.326341 -279.497832) (xy 161.368962 -279.473225) (xy 161.414978 -279.455773)
			(xy 161.463197 -279.445929) (xy 161.512372 -279.443948) (xy 161.561227 -279.44988) (xy 161.608498 -279.463572)
			(xy 161.65296 -279.48467) (xy 161.693463 -279.512626) (xy 161.728956 -279.546718) (xy 161.758521 -279.586062)
			(xy 161.781392 -279.629639) (xy 161.796976 -279.67632) (xy 161.804871 -279.724897) (xy 161.805366 -279.749504)
			(xy 163.094174 -279.749504) (xy 163.098134 -279.70045) (xy 163.109911 -279.652666) (xy 163.129202 -279.60739)
			(xy 163.155505 -279.565794) (xy 163.18814 -279.528957) (xy 163.226261 -279.497832) (xy 163.268882 -279.473225)
			(xy 163.314898 -279.455773) (xy 163.363117 -279.445929) (xy 163.412292 -279.443948) (xy 163.461147 -279.44988)
			(xy 163.508418 -279.463572) (xy 163.55288 -279.48467) (xy 163.593383 -279.512626) (xy 163.628876 -279.546718)
			(xy 163.658441 -279.586062) (xy 163.681312 -279.629639) (xy 163.696896 -279.67632) (xy 163.704791 -279.724897)
			(xy 163.705286 -279.749504) (xy 164.994094 -279.749504) (xy 164.998054 -279.70045) (xy 165.009831 -279.652666)
			(xy 165.029122 -279.60739) (xy 165.055425 -279.565794) (xy 165.08806 -279.528957) (xy 165.126181 -279.497832)
			(xy 165.168802 -279.473225) (xy 165.214818 -279.455773) (xy 165.263037 -279.445929) (xy 165.312212 -279.443948)
			(xy 165.361067 -279.44988) (xy 165.408338 -279.463572) (xy 165.4528 -279.48467) (xy 165.493303 -279.512626)
			(xy 165.528796 -279.546718) (xy 165.558361 -279.586062) (xy 165.581232 -279.629639) (xy 165.596816 -279.67632)
			(xy 165.604711 -279.724897) (xy 165.605206 -279.749504) (xy 166.894268 -279.749504) (xy 166.898228 -279.70045)
			(xy 166.910005 -279.652666) (xy 166.929296 -279.60739) (xy 166.955599 -279.565794) (xy 166.988234 -279.528957)
			(xy 167.026355 -279.497832) (xy 167.068976 -279.473225) (xy 167.114992 -279.455773) (xy 167.163211 -279.445929)
			(xy 167.212386 -279.443948) (xy 167.261241 -279.44988) (xy 167.308512 -279.463572) (xy 167.352974 -279.48467)
			(xy 167.393477 -279.512626) (xy 167.42897 -279.546718) (xy 167.458535 -279.586062) (xy 167.481406 -279.629639)
			(xy 167.49699 -279.67632) (xy 167.504885 -279.724897) (xy 167.50538 -279.749504) (xy 168.794188 -279.749504)
			(xy 168.798148 -279.70045) (xy 168.809925 -279.652666) (xy 168.829216 -279.60739) (xy 168.855519 -279.565794)
			(xy 168.888154 -279.528957) (xy 168.926275 -279.497832) (xy 168.968896 -279.473225) (xy 169.014912 -279.455773)
			(xy 169.063131 -279.445929) (xy 169.112306 -279.443948) (xy 169.161161 -279.44988) (xy 169.208432 -279.463572)
			(xy 169.252894 -279.48467) (xy 169.293397 -279.512626) (xy 169.32889 -279.546718) (xy 169.358455 -279.586062)
			(xy 169.381326 -279.629639) (xy 169.39691 -279.67632) (xy 169.404805 -279.724897) (xy 169.4053 -279.749504)
			(xy 170.694108 -279.749504) (xy 170.698068 -279.70045) (xy 170.709845 -279.652666) (xy 170.729136 -279.60739)
			(xy 170.755439 -279.565794) (xy 170.788074 -279.528957) (xy 170.826195 -279.497832) (xy 170.868816 -279.473225)
			(xy 170.914832 -279.455773) (xy 170.963051 -279.445929) (xy 171.012226 -279.443948) (xy 171.061081 -279.44988)
			(xy 171.108352 -279.463572) (xy 171.152814 -279.48467) (xy 171.193317 -279.512626) (xy 171.22881 -279.546718)
			(xy 171.258375 -279.586062) (xy 171.281246 -279.629639) (xy 171.29683 -279.67632) (xy 171.304725 -279.724897)
			(xy 171.30522 -279.749504) (xy 172.594028 -279.749504) (xy 172.597988 -279.70045) (xy 172.609765 -279.652666)
			(xy 172.629056 -279.60739) (xy 172.655359 -279.565794) (xy 172.687994 -279.528957) (xy 172.726115 -279.497832)
			(xy 172.768736 -279.473225) (xy 172.814752 -279.455773) (xy 172.862971 -279.445929) (xy 172.912146 -279.443948)
			(xy 172.961001 -279.44988) (xy 173.008272 -279.463572) (xy 173.052734 -279.48467) (xy 173.093237 -279.512626)
			(xy 173.12873 -279.546718) (xy 173.158295 -279.586062) (xy 173.181166 -279.629639) (xy 173.19675 -279.67632)
			(xy 173.204645 -279.724897) (xy 173.20514 -279.749504) (xy 174.494202 -279.749504) (xy 174.498162 -279.70045)
			(xy 174.509939 -279.652666) (xy 174.52923 -279.60739) (xy 174.555533 -279.565794) (xy 174.588168 -279.528957)
			(xy 174.626289 -279.497832) (xy 174.66891 -279.473225) (xy 174.714926 -279.455773) (xy 174.763145 -279.445929)
			(xy 174.81232 -279.443948) (xy 174.861175 -279.44988) (xy 174.908446 -279.463572) (xy 174.952908 -279.48467)
			(xy 174.993411 -279.512626) (xy 175.028904 -279.546718) (xy 175.058469 -279.586062) (xy 175.08134 -279.629639)
			(xy 175.096924 -279.67632) (xy 175.104819 -279.724897) (xy 175.105314 -279.749504) (xy 176.394122 -279.749504)
			(xy 176.398082 -279.70045) (xy 176.409859 -279.652666) (xy 176.42915 -279.60739) (xy 176.455453 -279.565794)
			(xy 176.488088 -279.528957) (xy 176.526209 -279.497832) (xy 176.56883 -279.473225) (xy 176.614846 -279.455773)
			(xy 176.663065 -279.445929) (xy 176.71224 -279.443948) (xy 176.761095 -279.44988) (xy 176.808366 -279.463572)
			(xy 176.852828 -279.48467) (xy 176.893331 -279.512626) (xy 176.928824 -279.546718) (xy 176.958389 -279.586062)
			(xy 176.98126 -279.629639) (xy 176.996844 -279.67632) (xy 177.004739 -279.724897) (xy 177.005234 -279.749504)
			(xy 178.294042 -279.749504) (xy 178.298002 -279.70045) (xy 178.309779 -279.652666) (xy 178.32907 -279.60739)
			(xy 178.355373 -279.565794) (xy 178.388008 -279.528957) (xy 178.426129 -279.497832) (xy 178.46875 -279.473225)
			(xy 178.514766 -279.455773) (xy 178.562985 -279.445929) (xy 178.61216 -279.443948) (xy 178.661015 -279.44988)
			(xy 178.708286 -279.463572) (xy 178.752748 -279.48467) (xy 178.793251 -279.512626) (xy 178.828744 -279.546718)
			(xy 178.858309 -279.586062) (xy 178.88118 -279.629639) (xy 178.896764 -279.67632) (xy 178.904659 -279.724897)
			(xy 178.905154 -279.749504) (xy 180.194216 -279.749504) (xy 180.198176 -279.70045) (xy 180.209953 -279.652666)
			(xy 180.229244 -279.60739) (xy 180.255547 -279.565794) (xy 180.288182 -279.528957) (xy 180.326303 -279.497832)
			(xy 180.368924 -279.473225) (xy 180.41494 -279.455773) (xy 180.463159 -279.445929) (xy 180.512334 -279.443948)
			(xy 180.561189 -279.44988) (xy 180.60846 -279.463572) (xy 180.652922 -279.48467) (xy 180.693425 -279.512626)
			(xy 180.728918 -279.546718) (xy 180.758483 -279.586062) (xy 180.781354 -279.629639) (xy 180.796938 -279.67632)
			(xy 180.804833 -279.724897) (xy 180.805328 -279.749504) (xy 182.094136 -279.749504) (xy 182.098096 -279.70045)
			(xy 182.109873 -279.652666) (xy 182.129164 -279.60739) (xy 182.155467 -279.565794) (xy 182.188102 -279.528957)
			(xy 182.226223 -279.497832) (xy 182.268844 -279.473225) (xy 182.31486 -279.455773) (xy 182.363079 -279.445929)
			(xy 182.412254 -279.443948) (xy 182.461109 -279.44988) (xy 182.50838 -279.463572) (xy 182.552842 -279.48467)
			(xy 182.593345 -279.512626) (xy 182.628838 -279.546718) (xy 182.658403 -279.586062) (xy 182.681274 -279.629639)
			(xy 182.696858 -279.67632) (xy 182.704753 -279.724897) (xy 182.705248 -279.749504) (xy 183.994056 -279.749504)
			(xy 183.998016 -279.70045) (xy 184.009793 -279.652666) (xy 184.029084 -279.60739) (xy 184.055387 -279.565794)
			(xy 184.088022 -279.528957) (xy 184.126143 -279.497832) (xy 184.168764 -279.473225) (xy 184.21478 -279.455773)
			(xy 184.262999 -279.445929) (xy 184.312174 -279.443948) (xy 184.361029 -279.44988) (xy 184.4083 -279.463572)
			(xy 184.452762 -279.48467) (xy 184.493265 -279.512626) (xy 184.528758 -279.546718) (xy 184.558323 -279.586062)
			(xy 184.581194 -279.629639) (xy 184.596778 -279.67632) (xy 184.604673 -279.724897) (xy 184.605168 -279.749504)
			(xy 185.89423 -279.749504) (xy 185.89819 -279.70045) (xy 185.909967 -279.652666) (xy 185.929258 -279.60739)
			(xy 185.955561 -279.565794) (xy 185.988196 -279.528957) (xy 186.026317 -279.497832) (xy 186.068938 -279.473225)
			(xy 186.114954 -279.455773) (xy 186.163173 -279.445929) (xy 186.212348 -279.443948) (xy 186.261203 -279.44988)
			(xy 186.308474 -279.463572) (xy 186.352936 -279.48467) (xy 186.393439 -279.512626) (xy 186.428932 -279.546718)
			(xy 186.458497 -279.586062) (xy 186.481368 -279.629639) (xy 186.496952 -279.67632) (xy 186.504847 -279.724897)
			(xy 186.505342 -279.749504) (xy 187.79415 -279.749504) (xy 187.79811 -279.70045) (xy 187.809887 -279.652666)
			(xy 187.829178 -279.60739) (xy 187.855481 -279.565794) (xy 187.888116 -279.528957) (xy 187.926237 -279.497832)
			(xy 187.968858 -279.473225) (xy 188.014874 -279.455773) (xy 188.063093 -279.445929) (xy 188.112268 -279.443948)
			(xy 188.161123 -279.44988) (xy 188.208394 -279.463572) (xy 188.252856 -279.48467) (xy 188.293359 -279.512626)
			(xy 188.328852 -279.546718) (xy 188.358417 -279.586062) (xy 188.381288 -279.629639) (xy 188.396872 -279.67632)
			(xy 188.404767 -279.724897) (xy 188.405262 -279.749504) (xy 189.69407 -279.749504) (xy 189.69803 -279.70045)
			(xy 189.709807 -279.652666) (xy 189.729098 -279.60739) (xy 189.755401 -279.565794) (xy 189.788036 -279.528957)
			(xy 189.826157 -279.497832) (xy 189.868778 -279.473225) (xy 189.914794 -279.455773) (xy 189.963013 -279.445929)
			(xy 190.012188 -279.443948) (xy 190.061043 -279.44988) (xy 190.108314 -279.463572) (xy 190.152776 -279.48467)
			(xy 190.193279 -279.512626) (xy 190.228772 -279.546718) (xy 190.258337 -279.586062) (xy 190.281208 -279.629639)
			(xy 190.296792 -279.67632) (xy 190.304687 -279.724897) (xy 190.305182 -279.749504) (xy 191.594244 -279.749504)
			(xy 191.598204 -279.70045) (xy 191.609981 -279.652666) (xy 191.629272 -279.60739) (xy 191.655575 -279.565794)
			(xy 191.68821 -279.528957) (xy 191.726331 -279.497832) (xy 191.768952 -279.473225) (xy 191.814968 -279.455773)
			(xy 191.863187 -279.445929) (xy 191.912362 -279.443948) (xy 191.961217 -279.44988) (xy 192.008488 -279.463572)
			(xy 192.05295 -279.48467) (xy 192.093453 -279.512626) (xy 192.128946 -279.546718) (xy 192.158511 -279.586062)
			(xy 192.181382 -279.629639) (xy 192.196966 -279.67632) (xy 192.204861 -279.724897) (xy 192.205356 -279.749504)
			(xy 193.494164 -279.749504) (xy 193.498124 -279.70045) (xy 193.509901 -279.652666) (xy 193.529192 -279.60739)
			(xy 193.555495 -279.565794) (xy 193.58813 -279.528957) (xy 193.626251 -279.497832) (xy 193.668872 -279.473225)
			(xy 193.714888 -279.455773) (xy 193.763107 -279.445929) (xy 193.812282 -279.443948) (xy 193.861137 -279.44988)
			(xy 193.908408 -279.463572) (xy 193.95287 -279.48467) (xy 193.993373 -279.512626) (xy 194.028866 -279.546718)
			(xy 194.058431 -279.586062) (xy 194.081302 -279.629639) (xy 194.096886 -279.67632) (xy 194.104781 -279.724897)
			(xy 194.105276 -279.749504) (xy 194.105271 -279.749758) (xy 195.394084 -279.749758) (xy 195.398044 -279.700704)
			(xy 195.409821 -279.65292) (xy 195.429112 -279.607644) (xy 195.455415 -279.566048) (xy 195.48805 -279.529211)
			(xy 195.526171 -279.498086) (xy 195.568792 -279.473479) (xy 195.614808 -279.456027) (xy 195.663027 -279.446183)
			(xy 195.712202 -279.444202) (xy 195.761057 -279.450134) (xy 195.808328 -279.463826) (xy 195.85279 -279.484924)
			(xy 195.893293 -279.51288) (xy 195.928786 -279.546972) (xy 195.958351 -279.586316) (xy 195.981222 -279.629893)
			(xy 195.996806 -279.676574) (xy 196.004701 -279.725151) (xy 196.005196 -279.749758) (xy 197.294258 -279.749758)
			(xy 197.298218 -279.700704) (xy 197.309995 -279.65292) (xy 197.329286 -279.607644) (xy 197.355589 -279.566048)
			(xy 197.388224 -279.529211) (xy 197.426345 -279.498086) (xy 197.468966 -279.473479) (xy 197.514982 -279.456027)
			(xy 197.563201 -279.446183) (xy 197.612376 -279.444202) (xy 197.661231 -279.450134) (xy 197.708502 -279.463826)
			(xy 197.752964 -279.484924) (xy 197.793467 -279.51288) (xy 197.82896 -279.546972) (xy 197.858525 -279.586316)
			(xy 197.881396 -279.629893) (xy 197.89698 -279.676574) (xy 197.904875 -279.725151) (xy 197.90537 -279.749758)
			(xy 198.244218 -279.749758) (xy 198.248178 -279.700704) (xy 198.259955 -279.65292) (xy 198.279246 -279.607644)
			(xy 198.305549 -279.566048) (xy 198.338184 -279.529211) (xy 198.376305 -279.498086) (xy 198.418926 -279.473479)
			(xy 198.464942 -279.456027) (xy 198.513161 -279.446183) (xy 198.562336 -279.444202) (xy 198.611191 -279.450134)
			(xy 198.658462 -279.463826) (xy 198.702924 -279.484924) (xy 198.743427 -279.51288) (xy 198.77892 -279.546972)
			(xy 198.808485 -279.586316) (xy 198.831356 -279.629893) (xy 198.84694 -279.676574) (xy 198.854835 -279.725151)
			(xy 198.855325 -279.749504) (xy 277.294098 -279.749504) (xy 277.298058 -279.70045) (xy 277.309835 -279.652666)
			(xy 277.329126 -279.60739) (xy 277.355429 -279.565794) (xy 277.388064 -279.528957) (xy 277.426185 -279.497832)
			(xy 277.468806 -279.473225) (xy 277.514822 -279.455773) (xy 277.563041 -279.445929) (xy 277.612216 -279.443948)
			(xy 277.661071 -279.44988) (xy 277.708342 -279.463572) (xy 277.752804 -279.48467) (xy 277.793307 -279.512626)
			(xy 277.8288 -279.546718) (xy 277.858365 -279.586062) (xy 277.881236 -279.629639) (xy 277.89682 -279.67632)
			(xy 277.904715 -279.724897) (xy 277.90521 -279.749504) (xy 279.194018 -279.749504) (xy 279.197978 -279.70045)
			(xy 279.209755 -279.652666) (xy 279.229046 -279.60739) (xy 279.255349 -279.565794) (xy 279.287984 -279.528957)
			(xy 279.326105 -279.497832) (xy 279.368726 -279.473225) (xy 279.414742 -279.455773) (xy 279.462961 -279.445929)
			(xy 279.512136 -279.443948) (xy 279.560991 -279.44988) (xy 279.608262 -279.463572) (xy 279.652724 -279.48467)
			(xy 279.693227 -279.512626) (xy 279.72872 -279.546718) (xy 279.758285 -279.586062) (xy 279.781156 -279.629639)
			(xy 279.79674 -279.67632) (xy 279.804635 -279.724897) (xy 279.80513 -279.749504) (xy 281.093938 -279.749504)
			(xy 281.097898 -279.70045) (xy 281.109675 -279.652666) (xy 281.128966 -279.60739) (xy 281.155269 -279.565794)
			(xy 281.187904 -279.528957) (xy 281.226025 -279.497832) (xy 281.268646 -279.473225) (xy 281.314662 -279.455773)
			(xy 281.362881 -279.445929) (xy 281.412056 -279.443948) (xy 281.460911 -279.44988) (xy 281.508182 -279.463572)
			(xy 281.552644 -279.48467) (xy 281.593147 -279.512626) (xy 281.62864 -279.546718) (xy 281.658205 -279.586062)
			(xy 281.681076 -279.629639) (xy 281.69666 -279.67632) (xy 281.704555 -279.724897) (xy 281.70505 -279.749504)
			(xy 282.994112 -279.749504) (xy 282.998072 -279.70045) (xy 283.009849 -279.652666) (xy 283.02914 -279.60739)
			(xy 283.055443 -279.565794) (xy 283.088078 -279.528957) (xy 283.126199 -279.497832) (xy 283.16882 -279.473225)
			(xy 283.214836 -279.455773) (xy 283.263055 -279.445929) (xy 283.31223 -279.443948) (xy 283.361085 -279.44988)
			(xy 283.408356 -279.463572) (xy 283.452818 -279.48467) (xy 283.493321 -279.512626) (xy 283.528814 -279.546718)
			(xy 283.558379 -279.586062) (xy 283.58125 -279.629639) (xy 283.596834 -279.67632) (xy 283.604729 -279.724897)
			(xy 283.605224 -279.749504) (xy 284.894032 -279.749504) (xy 284.897992 -279.70045) (xy 284.909769 -279.652666)
			(xy 284.92906 -279.60739) (xy 284.955363 -279.565794) (xy 284.987998 -279.528957) (xy 285.026119 -279.497832)
			(xy 285.06874 -279.473225) (xy 285.114756 -279.455773) (xy 285.162975 -279.445929) (xy 285.21215 -279.443948)
			(xy 285.261005 -279.44988) (xy 285.308276 -279.463572) (xy 285.352738 -279.48467) (xy 285.393241 -279.512626)
			(xy 285.428734 -279.546718) (xy 285.458299 -279.586062) (xy 285.48117 -279.629639) (xy 285.496754 -279.67632)
			(xy 285.504649 -279.724897) (xy 285.505144 -279.749504) (xy 286.793952 -279.749504) (xy 286.797912 -279.70045)
			(xy 286.809689 -279.652666) (xy 286.82898 -279.60739) (xy 286.855283 -279.565794) (xy 286.887918 -279.528957)
			(xy 286.926039 -279.497832) (xy 286.96866 -279.473225) (xy 287.014676 -279.455773) (xy 287.062895 -279.445929)
			(xy 287.11207 -279.443948) (xy 287.160925 -279.44988) (xy 287.208196 -279.463572) (xy 287.252658 -279.48467)
			(xy 287.293161 -279.512626) (xy 287.328654 -279.546718) (xy 287.358219 -279.586062) (xy 287.38109 -279.629639)
			(xy 287.396674 -279.67632) (xy 287.404569 -279.724897) (xy 287.405064 -279.749504) (xy 288.693872 -279.749504)
			(xy 288.697832 -279.70045) (xy 288.709609 -279.652666) (xy 288.7289 -279.60739) (xy 288.755203 -279.565794)
			(xy 288.787838 -279.528957) (xy 288.825959 -279.497832) (xy 288.86858 -279.473225) (xy 288.914596 -279.455773)
			(xy 288.962815 -279.445929) (xy 289.01199 -279.443948) (xy 289.060845 -279.44988) (xy 289.108116 -279.463572)
			(xy 289.152578 -279.48467) (xy 289.193081 -279.512626) (xy 289.228574 -279.546718) (xy 289.258139 -279.586062)
			(xy 289.28101 -279.629639) (xy 289.296594 -279.67632) (xy 289.304489 -279.724897) (xy 289.304984 -279.749504)
			(xy 290.594046 -279.749504) (xy 290.598006 -279.70045) (xy 290.609783 -279.652666) (xy 290.629074 -279.60739)
			(xy 290.655377 -279.565794) (xy 290.688012 -279.528957) (xy 290.726133 -279.497832) (xy 290.768754 -279.473225)
			(xy 290.81477 -279.455773) (xy 290.862989 -279.445929) (xy 290.912164 -279.443948) (xy 290.961019 -279.44988)
			(xy 291.00829 -279.463572) (xy 291.052752 -279.48467) (xy 291.093255 -279.512626) (xy 291.128748 -279.546718)
			(xy 291.158313 -279.586062) (xy 291.181184 -279.629639) (xy 291.196768 -279.67632) (xy 291.204663 -279.724897)
			(xy 291.205158 -279.749504) (xy 292.493966 -279.749504) (xy 292.497926 -279.70045) (xy 292.509703 -279.652666)
			(xy 292.528994 -279.60739) (xy 292.555297 -279.565794) (xy 292.587932 -279.528957) (xy 292.626053 -279.497832)
			(xy 292.668674 -279.473225) (xy 292.71469 -279.455773) (xy 292.762909 -279.445929) (xy 292.812084 -279.443948)
			(xy 292.860939 -279.44988) (xy 292.90821 -279.463572) (xy 292.952672 -279.48467) (xy 292.993175 -279.512626)
			(xy 293.028668 -279.546718) (xy 293.058233 -279.586062) (xy 293.081104 -279.629639) (xy 293.096688 -279.67632)
			(xy 293.104583 -279.724897) (xy 293.105078 -279.749504) (xy 294.393886 -279.749504) (xy 294.397846 -279.70045)
			(xy 294.409623 -279.652666) (xy 294.428914 -279.60739) (xy 294.455217 -279.565794) (xy 294.487852 -279.528957)
			(xy 294.525973 -279.497832) (xy 294.568594 -279.473225) (xy 294.61461 -279.455773) (xy 294.662829 -279.445929)
			(xy 294.712004 -279.443948) (xy 294.760859 -279.44988) (xy 294.80813 -279.463572) (xy 294.852592 -279.48467)
			(xy 294.893095 -279.512626) (xy 294.928588 -279.546718) (xy 294.958153 -279.586062) (xy 294.981024 -279.629639)
			(xy 294.996608 -279.67632) (xy 295.004503 -279.724897) (xy 295.004998 -279.749504) (xy 296.29406 -279.749504)
			(xy 296.29802 -279.70045) (xy 296.309797 -279.652666) (xy 296.329088 -279.60739) (xy 296.355391 -279.565794)
			(xy 296.388026 -279.528957) (xy 296.426147 -279.497832) (xy 296.468768 -279.473225) (xy 296.514784 -279.455773)
			(xy 296.563003 -279.445929) (xy 296.612178 -279.443948) (xy 296.661033 -279.44988) (xy 296.708304 -279.463572)
			(xy 296.752766 -279.48467) (xy 296.793269 -279.512626) (xy 296.828762 -279.546718) (xy 296.858327 -279.586062)
			(xy 296.881198 -279.629639) (xy 296.896782 -279.67632) (xy 296.904677 -279.724897) (xy 296.905172 -279.749504)
			(xy 298.19398 -279.749504) (xy 298.19794 -279.70045) (xy 298.209717 -279.652666) (xy 298.229008 -279.60739)
			(xy 298.255311 -279.565794) (xy 298.287946 -279.528957) (xy 298.326067 -279.497832) (xy 298.368688 -279.473225)
			(xy 298.414704 -279.455773) (xy 298.462923 -279.445929) (xy 298.512098 -279.443948) (xy 298.560953 -279.44988)
			(xy 298.608224 -279.463572) (xy 298.652686 -279.48467) (xy 298.693189 -279.512626) (xy 298.728682 -279.546718)
			(xy 298.758247 -279.586062) (xy 298.781118 -279.629639) (xy 298.796702 -279.67632) (xy 298.804597 -279.724897)
			(xy 298.805092 -279.749504) (xy 300.0939 -279.749504) (xy 300.09786 -279.70045) (xy 300.109637 -279.652666)
			(xy 300.128928 -279.60739) (xy 300.155231 -279.565794) (xy 300.187866 -279.528957) (xy 300.225987 -279.497832)
			(xy 300.268608 -279.473225) (xy 300.314624 -279.455773) (xy 300.362843 -279.445929) (xy 300.412018 -279.443948)
			(xy 300.460873 -279.44988) (xy 300.508144 -279.463572) (xy 300.552606 -279.48467) (xy 300.593109 -279.512626)
			(xy 300.628602 -279.546718) (xy 300.658167 -279.586062) (xy 300.681038 -279.629639) (xy 300.696622 -279.67632)
			(xy 300.704517 -279.724897) (xy 300.705012 -279.749504) (xy 301.994074 -279.749504) (xy 301.998034 -279.70045)
			(xy 302.009811 -279.652666) (xy 302.029102 -279.60739) (xy 302.055405 -279.565794) (xy 302.08804 -279.528957)
			(xy 302.126161 -279.497832) (xy 302.168782 -279.473225) (xy 302.214798 -279.455773) (xy 302.263017 -279.445929)
			(xy 302.312192 -279.443948) (xy 302.361047 -279.44988) (xy 302.408318 -279.463572) (xy 302.45278 -279.48467)
			(xy 302.493283 -279.512626) (xy 302.528776 -279.546718) (xy 302.558341 -279.586062) (xy 302.581212 -279.629639)
			(xy 302.596796 -279.67632) (xy 302.604691 -279.724897) (xy 302.605186 -279.749504) (xy 303.893994 -279.749504)
			(xy 303.897954 -279.70045) (xy 303.909731 -279.652666) (xy 303.929022 -279.60739) (xy 303.955325 -279.565794)
			(xy 303.98796 -279.528957) (xy 304.026081 -279.497832) (xy 304.068702 -279.473225) (xy 304.114718 -279.455773)
			(xy 304.162937 -279.445929) (xy 304.212112 -279.443948) (xy 304.260967 -279.44988) (xy 304.308238 -279.463572)
			(xy 304.3527 -279.48467) (xy 304.393203 -279.512626) (xy 304.428696 -279.546718) (xy 304.458261 -279.586062)
			(xy 304.481132 -279.629639) (xy 304.496716 -279.67632) (xy 304.504611 -279.724897) (xy 304.505106 -279.749504)
			(xy 305.793914 -279.749504) (xy 305.797874 -279.70045) (xy 305.809651 -279.652666) (xy 305.828942 -279.60739)
			(xy 305.855245 -279.565794) (xy 305.88788 -279.528957) (xy 305.926001 -279.497832) (xy 305.968622 -279.473225)
			(xy 306.014638 -279.455773) (xy 306.062857 -279.445929) (xy 306.112032 -279.443948) (xy 306.160887 -279.44988)
			(xy 306.208158 -279.463572) (xy 306.25262 -279.48467) (xy 306.293123 -279.512626) (xy 306.328616 -279.546718)
			(xy 306.358181 -279.586062) (xy 306.381052 -279.629639) (xy 306.396636 -279.67632) (xy 306.404531 -279.724897)
			(xy 306.405026 -279.749504) (xy 307.694088 -279.749504) (xy 307.698048 -279.70045) (xy 307.709825 -279.652666)
			(xy 307.729116 -279.60739) (xy 307.755419 -279.565794) (xy 307.788054 -279.528957) (xy 307.826175 -279.497832)
			(xy 307.868796 -279.473225) (xy 307.914812 -279.455773) (xy 307.963031 -279.445929) (xy 308.012206 -279.443948)
			(xy 308.061061 -279.44988) (xy 308.108332 -279.463572) (xy 308.152794 -279.48467) (xy 308.193297 -279.512626)
			(xy 308.22879 -279.546718) (xy 308.258355 -279.586062) (xy 308.281226 -279.629639) (xy 308.29681 -279.67632)
			(xy 308.304705 -279.724897) (xy 308.3052 -279.749504) (xy 309.594008 -279.749504) (xy 309.597968 -279.70045)
			(xy 309.609745 -279.652666) (xy 309.629036 -279.60739) (xy 309.655339 -279.565794) (xy 309.687974 -279.528957)
			(xy 309.726095 -279.497832) (xy 309.768716 -279.473225) (xy 309.814732 -279.455773) (xy 309.862951 -279.445929)
			(xy 309.912126 -279.443948) (xy 309.960981 -279.44988) (xy 310.008252 -279.463572) (xy 310.052714 -279.48467)
			(xy 310.093217 -279.512626) (xy 310.12871 -279.546718) (xy 310.158275 -279.586062) (xy 310.181146 -279.629639)
			(xy 310.19673 -279.67632) (xy 310.204625 -279.724897) (xy 310.20512 -279.749504) (xy 310.205115 -279.749758)
			(xy 311.493928 -279.749758) (xy 311.497888 -279.700704) (xy 311.509665 -279.65292) (xy 311.528956 -279.607644)
			(xy 311.555259 -279.566048) (xy 311.587894 -279.529211) (xy 311.626015 -279.498086) (xy 311.668636 -279.473479)
			(xy 311.714652 -279.456027) (xy 311.762871 -279.446183) (xy 311.812046 -279.444202) (xy 311.860901 -279.450134)
			(xy 311.908172 -279.463826) (xy 311.952634 -279.484924) (xy 311.993137 -279.51288) (xy 312.02863 -279.546972)
			(xy 312.058195 -279.586316) (xy 312.081066 -279.629893) (xy 312.09665 -279.676574) (xy 312.104545 -279.725151)
			(xy 312.10504 -279.749758) (xy 313.394102 -279.749758) (xy 313.398062 -279.700704) (xy 313.409839 -279.65292)
			(xy 313.42913 -279.607644) (xy 313.455433 -279.566048) (xy 313.488068 -279.529211) (xy 313.526189 -279.498086)
			(xy 313.56881 -279.473479) (xy 313.614826 -279.456027) (xy 313.663045 -279.446183) (xy 313.71222 -279.444202)
			(xy 313.761075 -279.450134) (xy 313.808346 -279.463826) (xy 313.852808 -279.484924) (xy 313.893311 -279.51288)
			(xy 313.928804 -279.546972) (xy 313.958369 -279.586316) (xy 313.98124 -279.629893) (xy 313.996824 -279.676574)
			(xy 314.004719 -279.725151) (xy 314.005214 -279.749758) (xy 314.344062 -279.749758) (xy 314.348022 -279.700704)
			(xy 314.359799 -279.65292) (xy 314.37909 -279.607644) (xy 314.405393 -279.566048) (xy 314.438028 -279.529211)
			(xy 314.476149 -279.498086) (xy 314.51877 -279.473479) (xy 314.564786 -279.456027) (xy 314.613005 -279.446183)
			(xy 314.66218 -279.444202) (xy 314.711035 -279.450134) (xy 314.758306 -279.463826) (xy 314.802768 -279.484924)
			(xy 314.843271 -279.51288) (xy 314.878764 -279.546972) (xy 314.908329 -279.586316) (xy 314.9312 -279.629893)
			(xy 314.946784 -279.676574) (xy 314.954679 -279.725151) (xy 314.955169 -279.749504) (xy 393.394196 -279.749504)
			(xy 393.398156 -279.70045) (xy 393.409933 -279.652666) (xy 393.429224 -279.60739) (xy 393.455527 -279.565794)
			(xy 393.488162 -279.528957) (xy 393.526283 -279.497832) (xy 393.568904 -279.473225) (xy 393.61492 -279.455773)
			(xy 393.663139 -279.445929) (xy 393.712314 -279.443948) (xy 393.761169 -279.44988) (xy 393.80844 -279.463572)
			(xy 393.852902 -279.48467) (xy 393.893405 -279.512626) (xy 393.928898 -279.546718) (xy 393.958463 -279.586062)
			(xy 393.981334 -279.629639) (xy 393.996918 -279.67632) (xy 394.004813 -279.724897) (xy 394.005308 -279.749504)
			(xy 395.294116 -279.749504) (xy 395.298076 -279.70045) (xy 395.309853 -279.652666) (xy 395.329144 -279.60739)
			(xy 395.355447 -279.565794) (xy 395.388082 -279.528957) (xy 395.426203 -279.497832) (xy 395.468824 -279.473225)
			(xy 395.51484 -279.455773) (xy 395.563059 -279.445929) (xy 395.612234 -279.443948) (xy 395.661089 -279.44988)
			(xy 395.70836 -279.463572) (xy 395.752822 -279.48467) (xy 395.793325 -279.512626) (xy 395.828818 -279.546718)
			(xy 395.858383 -279.586062) (xy 395.881254 -279.629639) (xy 395.896838 -279.67632) (xy 395.904733 -279.724897)
			(xy 395.905228 -279.749504) (xy 397.194036 -279.749504) (xy 397.197996 -279.70045) (xy 397.209773 -279.652666)
			(xy 397.229064 -279.60739) (xy 397.255367 -279.565794) (xy 397.288002 -279.528957) (xy 397.326123 -279.497832)
			(xy 397.368744 -279.473225) (xy 397.41476 -279.455773) (xy 397.462979 -279.445929) (xy 397.512154 -279.443948)
			(xy 397.561009 -279.44988) (xy 397.60828 -279.463572) (xy 397.652742 -279.48467) (xy 397.693245 -279.512626)
			(xy 397.728738 -279.546718) (xy 397.758303 -279.586062) (xy 397.781174 -279.629639) (xy 397.796758 -279.67632)
			(xy 397.804653 -279.724897) (xy 397.805148 -279.749504) (xy 399.09421 -279.749504) (xy 399.09817 -279.70045)
			(xy 399.109947 -279.652666) (xy 399.129238 -279.60739) (xy 399.155541 -279.565794) (xy 399.188176 -279.528957)
			(xy 399.226297 -279.497832) (xy 399.268918 -279.473225) (xy 399.314934 -279.455773) (xy 399.363153 -279.445929)
			(xy 399.412328 -279.443948) (xy 399.461183 -279.44988) (xy 399.508454 -279.463572) (xy 399.552916 -279.48467)
			(xy 399.593419 -279.512626) (xy 399.628912 -279.546718) (xy 399.658477 -279.586062) (xy 399.681348 -279.629639)
			(xy 399.696932 -279.67632) (xy 399.704827 -279.724897) (xy 399.705322 -279.749504) (xy 400.99413 -279.749504)
			(xy 400.99809 -279.70045) (xy 401.009867 -279.652666) (xy 401.029158 -279.60739) (xy 401.055461 -279.565794)
			(xy 401.088096 -279.528957) (xy 401.126217 -279.497832) (xy 401.168838 -279.473225) (xy 401.214854 -279.455773)
			(xy 401.263073 -279.445929) (xy 401.312248 -279.443948) (xy 401.361103 -279.44988) (xy 401.408374 -279.463572)
			(xy 401.452836 -279.48467) (xy 401.493339 -279.512626) (xy 401.528832 -279.546718) (xy 401.558397 -279.586062)
			(xy 401.581268 -279.629639) (xy 401.596852 -279.67632) (xy 401.604747 -279.724897) (xy 401.605242 -279.749504)
			(xy 402.89405 -279.749504) (xy 402.89801 -279.70045) (xy 402.909787 -279.652666) (xy 402.929078 -279.60739)
			(xy 402.955381 -279.565794) (xy 402.988016 -279.528957) (xy 403.026137 -279.497832) (xy 403.068758 -279.473225)
			(xy 403.114774 -279.455773) (xy 403.162993 -279.445929) (xy 403.212168 -279.443948) (xy 403.261023 -279.44988)
			(xy 403.308294 -279.463572) (xy 403.352756 -279.48467) (xy 403.393259 -279.512626) (xy 403.428752 -279.546718)
			(xy 403.458317 -279.586062) (xy 403.481188 -279.629639) (xy 403.496772 -279.67632) (xy 403.504667 -279.724897)
			(xy 403.505162 -279.749504) (xy 404.79397 -279.749504) (xy 404.79793 -279.70045) (xy 404.809707 -279.652666)
			(xy 404.828998 -279.60739) (xy 404.855301 -279.565794) (xy 404.887936 -279.528957) (xy 404.926057 -279.497832)
			(xy 404.968678 -279.473225) (xy 405.014694 -279.455773) (xy 405.062913 -279.445929) (xy 405.112088 -279.443948)
			(xy 405.160943 -279.44988) (xy 405.208214 -279.463572) (xy 405.252676 -279.48467) (xy 405.293179 -279.512626)
			(xy 405.328672 -279.546718) (xy 405.358237 -279.586062) (xy 405.381108 -279.629639) (xy 405.396692 -279.67632)
			(xy 405.404587 -279.724897) (xy 405.405082 -279.749504) (xy 406.694144 -279.749504) (xy 406.698104 -279.70045)
			(xy 406.709881 -279.652666) (xy 406.729172 -279.60739) (xy 406.755475 -279.565794) (xy 406.78811 -279.528957)
			(xy 406.826231 -279.497832) (xy 406.868852 -279.473225) (xy 406.914868 -279.455773) (xy 406.963087 -279.445929)
			(xy 407.012262 -279.443948) (xy 407.061117 -279.44988) (xy 407.108388 -279.463572) (xy 407.15285 -279.48467)
			(xy 407.193353 -279.512626) (xy 407.228846 -279.546718) (xy 407.258411 -279.586062) (xy 407.281282 -279.629639)
			(xy 407.296866 -279.67632) (xy 407.304761 -279.724897) (xy 407.305256 -279.749504) (xy 408.594064 -279.749504)
			(xy 408.598024 -279.70045) (xy 408.609801 -279.652666) (xy 408.629092 -279.60739) (xy 408.655395 -279.565794)
			(xy 408.68803 -279.528957) (xy 408.726151 -279.497832) (xy 408.768772 -279.473225) (xy 408.814788 -279.455773)
			(xy 408.863007 -279.445929) (xy 408.912182 -279.443948) (xy 408.961037 -279.44988) (xy 409.008308 -279.463572)
			(xy 409.05277 -279.48467) (xy 409.093273 -279.512626) (xy 409.128766 -279.546718) (xy 409.158331 -279.586062)
			(xy 409.181202 -279.629639) (xy 409.196786 -279.67632) (xy 409.204681 -279.724897) (xy 409.205176 -279.749504)
			(xy 410.493984 -279.749504) (xy 410.497944 -279.70045) (xy 410.509721 -279.652666) (xy 410.529012 -279.60739)
			(xy 410.555315 -279.565794) (xy 410.58795 -279.528957) (xy 410.626071 -279.497832) (xy 410.668692 -279.473225)
			(xy 410.714708 -279.455773) (xy 410.762927 -279.445929) (xy 410.812102 -279.443948) (xy 410.860957 -279.44988)
			(xy 410.908228 -279.463572) (xy 410.95269 -279.48467) (xy 410.993193 -279.512626) (xy 411.028686 -279.546718)
			(xy 411.058251 -279.586062) (xy 411.081122 -279.629639) (xy 411.096706 -279.67632) (xy 411.104601 -279.724897)
			(xy 411.105096 -279.749504) (xy 412.394158 -279.749504) (xy 412.398118 -279.70045) (xy 412.409895 -279.652666)
			(xy 412.429186 -279.60739) (xy 412.455489 -279.565794) (xy 412.488124 -279.528957) (xy 412.526245 -279.497832)
			(xy 412.568866 -279.473225) (xy 412.614882 -279.455773) (xy 412.663101 -279.445929) (xy 412.712276 -279.443948)
			(xy 412.761131 -279.44988) (xy 412.808402 -279.463572) (xy 412.852864 -279.48467) (xy 412.893367 -279.512626)
			(xy 412.92886 -279.546718) (xy 412.958425 -279.586062) (xy 412.981296 -279.629639) (xy 412.99688 -279.67632)
			(xy 413.004775 -279.724897) (xy 413.00527 -279.749504) (xy 414.294078 -279.749504) (xy 414.298038 -279.70045)
			(xy 414.309815 -279.652666) (xy 414.329106 -279.60739) (xy 414.355409 -279.565794) (xy 414.388044 -279.528957)
			(xy 414.426165 -279.497832) (xy 414.468786 -279.473225) (xy 414.514802 -279.455773) (xy 414.563021 -279.445929)
			(xy 414.612196 -279.443948) (xy 414.661051 -279.44988) (xy 414.708322 -279.463572) (xy 414.752784 -279.48467)
			(xy 414.793287 -279.512626) (xy 414.82878 -279.546718) (xy 414.858345 -279.586062) (xy 414.881216 -279.629639)
			(xy 414.8968 -279.67632) (xy 414.904695 -279.724897) (xy 414.90519 -279.749504) (xy 416.193998 -279.749504)
			(xy 416.197958 -279.70045) (xy 416.209735 -279.652666) (xy 416.229026 -279.60739) (xy 416.255329 -279.565794)
			(xy 416.287964 -279.528957) (xy 416.326085 -279.497832) (xy 416.368706 -279.473225) (xy 416.414722 -279.455773)
			(xy 416.462941 -279.445929) (xy 416.512116 -279.443948) (xy 416.560971 -279.44988) (xy 416.608242 -279.463572)
			(xy 416.652704 -279.48467) (xy 416.693207 -279.512626) (xy 416.7287 -279.546718) (xy 416.758265 -279.586062)
			(xy 416.781136 -279.629639) (xy 416.79672 -279.67632) (xy 416.804615 -279.724897) (xy 416.80511 -279.749504)
			(xy 418.094172 -279.749504) (xy 418.098132 -279.70045) (xy 418.109909 -279.652666) (xy 418.1292 -279.60739)
			(xy 418.155503 -279.565794) (xy 418.188138 -279.528957) (xy 418.226259 -279.497832) (xy 418.26888 -279.473225)
			(xy 418.314896 -279.455773) (xy 418.363115 -279.445929) (xy 418.41229 -279.443948) (xy 418.461145 -279.44988)
			(xy 418.508416 -279.463572) (xy 418.552878 -279.48467) (xy 418.593381 -279.512626) (xy 418.628874 -279.546718)
			(xy 418.658439 -279.586062) (xy 418.68131 -279.629639) (xy 418.696894 -279.67632) (xy 418.704789 -279.724897)
			(xy 418.705284 -279.749504) (xy 419.994092 -279.749504) (xy 419.998052 -279.70045) (xy 420.009829 -279.652666)
			(xy 420.02912 -279.60739) (xy 420.055423 -279.565794) (xy 420.088058 -279.528957) (xy 420.126179 -279.497832)
			(xy 420.1688 -279.473225) (xy 420.214816 -279.455773) (xy 420.263035 -279.445929) (xy 420.31221 -279.443948)
			(xy 420.361065 -279.44988) (xy 420.408336 -279.463572) (xy 420.452798 -279.48467) (xy 420.493301 -279.512626)
			(xy 420.528794 -279.546718) (xy 420.558359 -279.586062) (xy 420.58123 -279.629639) (xy 420.596814 -279.67632)
			(xy 420.604709 -279.724897) (xy 420.605204 -279.749504) (xy 421.894012 -279.749504) (xy 421.897972 -279.70045)
			(xy 421.909749 -279.652666) (xy 421.92904 -279.60739) (xy 421.955343 -279.565794) (xy 421.987978 -279.528957)
			(xy 422.026099 -279.497832) (xy 422.06872 -279.473225) (xy 422.114736 -279.455773) (xy 422.162955 -279.445929)
			(xy 422.21213 -279.443948) (xy 422.260985 -279.44988) (xy 422.308256 -279.463572) (xy 422.352718 -279.48467)
			(xy 422.393221 -279.512626) (xy 422.428714 -279.546718) (xy 422.458279 -279.586062) (xy 422.48115 -279.629639)
			(xy 422.496734 -279.67632) (xy 422.504629 -279.724897) (xy 422.505124 -279.749504) (xy 423.794186 -279.749504)
			(xy 423.798146 -279.70045) (xy 423.809923 -279.652666) (xy 423.829214 -279.60739) (xy 423.855517 -279.565794)
			(xy 423.888152 -279.528957) (xy 423.926273 -279.497832) (xy 423.968894 -279.473225) (xy 424.01491 -279.455773)
			(xy 424.063129 -279.445929) (xy 424.112304 -279.443948) (xy 424.161159 -279.44988) (xy 424.20843 -279.463572)
			(xy 424.252892 -279.48467) (xy 424.293395 -279.512626) (xy 424.328888 -279.546718) (xy 424.358453 -279.586062)
			(xy 424.381324 -279.629639) (xy 424.396908 -279.67632) (xy 424.404803 -279.724897) (xy 424.405298 -279.749504)
			(xy 425.694106 -279.749504) (xy 425.698066 -279.70045) (xy 425.709843 -279.652666) (xy 425.729134 -279.60739)
			(xy 425.755437 -279.565794) (xy 425.788072 -279.528957) (xy 425.826193 -279.497832) (xy 425.868814 -279.473225)
			(xy 425.91483 -279.455773) (xy 425.963049 -279.445929) (xy 426.012224 -279.443948) (xy 426.061079 -279.44988)
			(xy 426.10835 -279.463572) (xy 426.152812 -279.48467) (xy 426.193315 -279.512626) (xy 426.228808 -279.546718)
			(xy 426.258373 -279.586062) (xy 426.281244 -279.629639) (xy 426.296828 -279.67632) (xy 426.304723 -279.724897)
			(xy 426.305218 -279.749504) (xy 426.305213 -279.749758) (xy 427.594026 -279.749758) (xy 427.597986 -279.700704)
			(xy 427.609763 -279.65292) (xy 427.629054 -279.607644) (xy 427.655357 -279.566048) (xy 427.687992 -279.529211)
			(xy 427.726113 -279.498086) (xy 427.768734 -279.473479) (xy 427.81475 -279.456027) (xy 427.862969 -279.446183)
			(xy 427.912144 -279.444202) (xy 427.960999 -279.450134) (xy 428.00827 -279.463826) (xy 428.052732 -279.484924)
			(xy 428.093235 -279.51288) (xy 428.128728 -279.546972) (xy 428.158293 -279.586316) (xy 428.181164 -279.629893)
			(xy 428.196748 -279.676574) (xy 428.204643 -279.725151) (xy 428.205138 -279.749758) (xy 429.4942 -279.749758)
			(xy 429.49816 -279.700704) (xy 429.509937 -279.65292) (xy 429.529228 -279.607644) (xy 429.555531 -279.566048)
			(xy 429.588166 -279.529211) (xy 429.626287 -279.498086) (xy 429.668908 -279.473479) (xy 429.714924 -279.456027)
			(xy 429.763143 -279.446183) (xy 429.812318 -279.444202) (xy 429.861173 -279.450134) (xy 429.908444 -279.463826)
			(xy 429.952906 -279.484924) (xy 429.993409 -279.51288) (xy 430.028902 -279.546972) (xy 430.058467 -279.586316)
			(xy 430.081338 -279.629893) (xy 430.096922 -279.676574) (xy 430.104817 -279.725151) (xy 430.105312 -279.749758)
			(xy 430.44416 -279.749758) (xy 430.44812 -279.700704) (xy 430.459897 -279.65292) (xy 430.479188 -279.607644)
			(xy 430.505491 -279.566048) (xy 430.538126 -279.529211) (xy 430.576247 -279.498086) (xy 430.618868 -279.473479)
			(xy 430.664884 -279.456027) (xy 430.713103 -279.446183) (xy 430.762278 -279.444202) (xy 430.811133 -279.450134)
			(xy 430.858404 -279.463826) (xy 430.902866 -279.484924) (xy 430.943369 -279.51288) (xy 430.978862 -279.546972)
			(xy 431.008427 -279.586316) (xy 431.031298 -279.629893) (xy 431.046882 -279.676574) (xy 431.054777 -279.725151)
			(xy 431.055272 -279.749758) (xy 431.054777 -279.774365) (xy 431.046882 -279.822942) (xy 431.031298 -279.869623)
			(xy 431.008427 -279.9132) (xy 430.978862 -279.952544) (xy 430.943369 -279.986636) (xy 430.902866 -280.014592)
			(xy 430.858404 -280.03569) (xy 430.811133 -280.049382) (xy 430.762278 -280.055314) (xy 430.713103 -280.053333)
			(xy 430.664884 -280.043489) (xy 430.618868 -280.026037) (xy 430.576247 -280.00143) (xy 430.538126 -279.970305)
			(xy 430.505491 -279.933468) (xy 430.479188 -279.891872) (xy 430.459897 -279.846596) (xy 430.44812 -279.798812)
			(xy 430.44416 -279.749758) (xy 430.105312 -279.749758) (xy 430.104817 -279.774365) (xy 430.096922 -279.822942)
			(xy 430.081338 -279.869623) (xy 430.058467 -279.9132) (xy 430.028902 -279.952544) (xy 429.993409 -279.986636)
			(xy 429.952906 -280.014592) (xy 429.908444 -280.03569) (xy 429.861173 -280.049382) (xy 429.812318 -280.055314)
			(xy 429.763143 -280.053333) (xy 429.714924 -280.043489) (xy 429.668908 -280.026037) (xy 429.626287 -280.00143)
			(xy 429.588166 -279.970305) (xy 429.555531 -279.933468) (xy 429.529228 -279.891872) (xy 429.509937 -279.846596)
			(xy 429.49816 -279.798812) (xy 429.4942 -279.749758) (xy 428.205138 -279.749758) (xy 428.204643 -279.774365)
			(xy 428.196748 -279.822942) (xy 428.181164 -279.869623) (xy 428.158293 -279.9132) (xy 428.128728 -279.952544)
			(xy 428.093235 -279.986636) (xy 428.052732 -280.014592) (xy 428.00827 -280.03569) (xy 427.960999 -280.049382)
			(xy 427.912144 -280.055314) (xy 427.862969 -280.053333) (xy 427.81475 -280.043489) (xy 427.768734 -280.026037)
			(xy 427.726113 -280.00143) (xy 427.687992 -279.970305) (xy 427.655357 -279.933468) (xy 427.629054 -279.891872)
			(xy 427.609763 -279.846596) (xy 427.597986 -279.798812) (xy 427.594026 -279.749758) (xy 426.305213 -279.749758)
			(xy 426.304723 -279.774111) (xy 426.296828 -279.822688) (xy 426.281244 -279.869369) (xy 426.258373 -279.912946)
			(xy 426.228808 -279.95229) (xy 426.193315 -279.986382) (xy 426.152812 -280.014338) (xy 426.10835 -280.035436)
			(xy 426.061079 -280.049128) (xy 426.012224 -280.05506) (xy 425.963049 -280.053079) (xy 425.91483 -280.043235)
			(xy 425.868814 -280.025783) (xy 425.826193 -280.001176) (xy 425.788072 -279.970051) (xy 425.755437 -279.933214)
			(xy 425.729134 -279.891618) (xy 425.709843 -279.846342) (xy 425.698066 -279.798558) (xy 425.694106 -279.749504)
			(xy 424.405298 -279.749504) (xy 424.404803 -279.774111) (xy 424.396908 -279.822688) (xy 424.381324 -279.869369)
			(xy 424.358453 -279.912946) (xy 424.328888 -279.95229) (xy 424.293395 -279.986382) (xy 424.252892 -280.014338)
			(xy 424.20843 -280.035436) (xy 424.161159 -280.049128) (xy 424.112304 -280.05506) (xy 424.063129 -280.053079)
			(xy 424.01491 -280.043235) (xy 423.968894 -280.025783) (xy 423.926273 -280.001176) (xy 423.888152 -279.970051)
			(xy 423.855517 -279.933214) (xy 423.829214 -279.891618) (xy 423.809923 -279.846342) (xy 423.798146 -279.798558)
			(xy 423.794186 -279.749504) (xy 422.505124 -279.749504) (xy 422.504629 -279.774111) (xy 422.496734 -279.822688)
			(xy 422.48115 -279.869369) (xy 422.458279 -279.912946) (xy 422.428714 -279.95229) (xy 422.393221 -279.986382)
			(xy 422.352718 -280.014338) (xy 422.308256 -280.035436) (xy 422.260985 -280.049128) (xy 422.21213 -280.05506)
			(xy 422.162955 -280.053079) (xy 422.114736 -280.043235) (xy 422.06872 -280.025783) (xy 422.026099 -280.001176)
			(xy 421.987978 -279.970051) (xy 421.955343 -279.933214) (xy 421.92904 -279.891618) (xy 421.909749 -279.846342)
			(xy 421.897972 -279.798558) (xy 421.894012 -279.749504) (xy 420.605204 -279.749504) (xy 420.604709 -279.774111)
			(xy 420.596814 -279.822688) (xy 420.58123 -279.869369) (xy 420.558359 -279.912946) (xy 420.528794 -279.95229)
			(xy 420.493301 -279.986382) (xy 420.452798 -280.014338) (xy 420.408336 -280.035436) (xy 420.361065 -280.049128)
			(xy 420.31221 -280.05506) (xy 420.263035 -280.053079) (xy 420.214816 -280.043235) (xy 420.1688 -280.025783)
			(xy 420.126179 -280.001176) (xy 420.088058 -279.970051) (xy 420.055423 -279.933214) (xy 420.02912 -279.891618)
			(xy 420.009829 -279.846342) (xy 419.998052 -279.798558) (xy 419.994092 -279.749504) (xy 418.705284 -279.749504)
			(xy 418.704789 -279.774111) (xy 418.696894 -279.822688) (xy 418.68131 -279.869369) (xy 418.658439 -279.912946)
			(xy 418.628874 -279.95229) (xy 418.593381 -279.986382) (xy 418.552878 -280.014338) (xy 418.508416 -280.035436)
			(xy 418.461145 -280.049128) (xy 418.41229 -280.05506) (xy 418.363115 -280.053079) (xy 418.314896 -280.043235)
			(xy 418.26888 -280.025783) (xy 418.226259 -280.001176) (xy 418.188138 -279.970051) (xy 418.155503 -279.933214)
			(xy 418.1292 -279.891618) (xy 418.109909 -279.846342) (xy 418.098132 -279.798558) (xy 418.094172 -279.749504)
			(xy 416.80511 -279.749504) (xy 416.804615 -279.774111) (xy 416.79672 -279.822688) (xy 416.781136 -279.869369)
			(xy 416.758265 -279.912946) (xy 416.7287 -279.95229) (xy 416.693207 -279.986382) (xy 416.652704 -280.014338)
			(xy 416.608242 -280.035436) (xy 416.560971 -280.049128) (xy 416.512116 -280.05506) (xy 416.462941 -280.053079)
			(xy 416.414722 -280.043235) (xy 416.368706 -280.025783) (xy 416.326085 -280.001176) (xy 416.287964 -279.970051)
			(xy 416.255329 -279.933214) (xy 416.229026 -279.891618) (xy 416.209735 -279.846342) (xy 416.197958 -279.798558)
			(xy 416.193998 -279.749504) (xy 414.90519 -279.749504) (xy 414.904695 -279.774111) (xy 414.8968 -279.822688)
			(xy 414.881216 -279.869369) (xy 414.858345 -279.912946) (xy 414.82878 -279.95229) (xy 414.793287 -279.986382)
			(xy 414.752784 -280.014338) (xy 414.708322 -280.035436) (xy 414.661051 -280.049128) (xy 414.612196 -280.05506)
			(xy 414.563021 -280.053079) (xy 414.514802 -280.043235) (xy 414.468786 -280.025783) (xy 414.426165 -280.001176)
			(xy 414.388044 -279.970051) (xy 414.355409 -279.933214) (xy 414.329106 -279.891618) (xy 414.309815 -279.846342)
			(xy 414.298038 -279.798558) (xy 414.294078 -279.749504) (xy 413.00527 -279.749504) (xy 413.004775 -279.774111)
			(xy 412.99688 -279.822688) (xy 412.981296 -279.869369) (xy 412.958425 -279.912946) (xy 412.92886 -279.95229)
			(xy 412.893367 -279.986382) (xy 412.852864 -280.014338) (xy 412.808402 -280.035436) (xy 412.761131 -280.049128)
			(xy 412.712276 -280.05506) (xy 412.663101 -280.053079) (xy 412.614882 -280.043235) (xy 412.568866 -280.025783)
			(xy 412.526245 -280.001176) (xy 412.488124 -279.970051) (xy 412.455489 -279.933214) (xy 412.429186 -279.891618)
			(xy 412.409895 -279.846342) (xy 412.398118 -279.798558) (xy 412.394158 -279.749504) (xy 411.105096 -279.749504)
			(xy 411.104601 -279.774111) (xy 411.096706 -279.822688) (xy 411.081122 -279.869369) (xy 411.058251 -279.912946)
			(xy 411.028686 -279.95229) (xy 410.993193 -279.986382) (xy 410.95269 -280.014338) (xy 410.908228 -280.035436)
			(xy 410.860957 -280.049128) (xy 410.812102 -280.05506) (xy 410.762927 -280.053079) (xy 410.714708 -280.043235)
			(xy 410.668692 -280.025783) (xy 410.626071 -280.001176) (xy 410.58795 -279.970051) (xy 410.555315 -279.933214)
			(xy 410.529012 -279.891618) (xy 410.509721 -279.846342) (xy 410.497944 -279.798558) (xy 410.493984 -279.749504)
			(xy 409.205176 -279.749504) (xy 409.204681 -279.774111) (xy 409.196786 -279.822688) (xy 409.181202 -279.869369)
			(xy 409.158331 -279.912946) (xy 409.128766 -279.95229) (xy 409.093273 -279.986382) (xy 409.05277 -280.014338)
			(xy 409.008308 -280.035436) (xy 408.961037 -280.049128) (xy 408.912182 -280.05506) (xy 408.863007 -280.053079)
			(xy 408.814788 -280.043235) (xy 408.768772 -280.025783) (xy 408.726151 -280.001176) (xy 408.68803 -279.970051)
			(xy 408.655395 -279.933214) (xy 408.629092 -279.891618) (xy 408.609801 -279.846342) (xy 408.598024 -279.798558)
			(xy 408.594064 -279.749504) (xy 407.305256 -279.749504) (xy 407.304761 -279.774111) (xy 407.296866 -279.822688)
			(xy 407.281282 -279.869369) (xy 407.258411 -279.912946) (xy 407.228846 -279.95229) (xy 407.193353 -279.986382)
			(xy 407.15285 -280.014338) (xy 407.108388 -280.035436) (xy 407.061117 -280.049128) (xy 407.012262 -280.05506)
			(xy 406.963087 -280.053079) (xy 406.914868 -280.043235) (xy 406.868852 -280.025783) (xy 406.826231 -280.001176)
			(xy 406.78811 -279.970051) (xy 406.755475 -279.933214) (xy 406.729172 -279.891618) (xy 406.709881 -279.846342)
			(xy 406.698104 -279.798558) (xy 406.694144 -279.749504) (xy 405.405082 -279.749504) (xy 405.404587 -279.774111)
			(xy 405.396692 -279.822688) (xy 405.381108 -279.869369) (xy 405.358237 -279.912946) (xy 405.328672 -279.95229)
			(xy 405.293179 -279.986382) (xy 405.252676 -280.014338) (xy 405.208214 -280.035436) (xy 405.160943 -280.049128)
			(xy 405.112088 -280.05506) (xy 405.062913 -280.053079) (xy 405.014694 -280.043235) (xy 404.968678 -280.025783)
			(xy 404.926057 -280.001176) (xy 404.887936 -279.970051) (xy 404.855301 -279.933214) (xy 404.828998 -279.891618)
			(xy 404.809707 -279.846342) (xy 404.79793 -279.798558) (xy 404.79397 -279.749504) (xy 403.505162 -279.749504)
			(xy 403.504667 -279.774111) (xy 403.496772 -279.822688) (xy 403.481188 -279.869369) (xy 403.458317 -279.912946)
			(xy 403.428752 -279.95229) (xy 403.393259 -279.986382) (xy 403.352756 -280.014338) (xy 403.308294 -280.035436)
			(xy 403.261023 -280.049128) (xy 403.212168 -280.05506) (xy 403.162993 -280.053079) (xy 403.114774 -280.043235)
			(xy 403.068758 -280.025783) (xy 403.026137 -280.001176) (xy 402.988016 -279.970051) (xy 402.955381 -279.933214)
			(xy 402.929078 -279.891618) (xy 402.909787 -279.846342) (xy 402.89801 -279.798558) (xy 402.89405 -279.749504)
			(xy 401.605242 -279.749504) (xy 401.604747 -279.774111) (xy 401.596852 -279.822688) (xy 401.581268 -279.869369)
			(xy 401.558397 -279.912946) (xy 401.528832 -279.95229) (xy 401.493339 -279.986382) (xy 401.452836 -280.014338)
			(xy 401.408374 -280.035436) (xy 401.361103 -280.049128) (xy 401.312248 -280.05506) (xy 401.263073 -280.053079)
			(xy 401.214854 -280.043235) (xy 401.168838 -280.025783) (xy 401.126217 -280.001176) (xy 401.088096 -279.970051)
			(xy 401.055461 -279.933214) (xy 401.029158 -279.891618) (xy 401.009867 -279.846342) (xy 400.99809 -279.798558)
			(xy 400.99413 -279.749504) (xy 399.705322 -279.749504) (xy 399.704827 -279.774111) (xy 399.696932 -279.822688)
			(xy 399.681348 -279.869369) (xy 399.658477 -279.912946) (xy 399.628912 -279.95229) (xy 399.593419 -279.986382)
			(xy 399.552916 -280.014338) (xy 399.508454 -280.035436) (xy 399.461183 -280.049128) (xy 399.412328 -280.05506)
			(xy 399.363153 -280.053079) (xy 399.314934 -280.043235) (xy 399.268918 -280.025783) (xy 399.226297 -280.001176)
			(xy 399.188176 -279.970051) (xy 399.155541 -279.933214) (xy 399.129238 -279.891618) (xy 399.109947 -279.846342)
			(xy 399.09817 -279.798558) (xy 399.09421 -279.749504) (xy 397.805148 -279.749504) (xy 397.804653 -279.774111)
			(xy 397.796758 -279.822688) (xy 397.781174 -279.869369) (xy 397.758303 -279.912946) (xy 397.728738 -279.95229)
			(xy 397.693245 -279.986382) (xy 397.652742 -280.014338) (xy 397.60828 -280.035436) (xy 397.561009 -280.049128)
			(xy 397.512154 -280.05506) (xy 397.462979 -280.053079) (xy 397.41476 -280.043235) (xy 397.368744 -280.025783)
			(xy 397.326123 -280.001176) (xy 397.288002 -279.970051) (xy 397.255367 -279.933214) (xy 397.229064 -279.891618)
			(xy 397.209773 -279.846342) (xy 397.197996 -279.798558) (xy 397.194036 -279.749504) (xy 395.905228 -279.749504)
			(xy 395.904733 -279.774111) (xy 395.896838 -279.822688) (xy 395.881254 -279.869369) (xy 395.858383 -279.912946)
			(xy 395.828818 -279.95229) (xy 395.793325 -279.986382) (xy 395.752822 -280.014338) (xy 395.70836 -280.035436)
			(xy 395.661089 -280.049128) (xy 395.612234 -280.05506) (xy 395.563059 -280.053079) (xy 395.51484 -280.043235)
			(xy 395.468824 -280.025783) (xy 395.426203 -280.001176) (xy 395.388082 -279.970051) (xy 395.355447 -279.933214)
			(xy 395.329144 -279.891618) (xy 395.309853 -279.846342) (xy 395.298076 -279.798558) (xy 395.294116 -279.749504)
			(xy 394.005308 -279.749504) (xy 394.004813 -279.774111) (xy 393.996918 -279.822688) (xy 393.981334 -279.869369)
			(xy 393.958463 -279.912946) (xy 393.928898 -279.95229) (xy 393.893405 -279.986382) (xy 393.852902 -280.014338)
			(xy 393.80844 -280.035436) (xy 393.761169 -280.049128) (xy 393.712314 -280.05506) (xy 393.663139 -280.053079)
			(xy 393.61492 -280.043235) (xy 393.568904 -280.025783) (xy 393.526283 -280.001176) (xy 393.488162 -279.970051)
			(xy 393.455527 -279.933214) (xy 393.429224 -279.891618) (xy 393.409933 -279.846342) (xy 393.398156 -279.798558)
			(xy 393.394196 -279.749504) (xy 314.955169 -279.749504) (xy 314.955174 -279.749758) (xy 314.954679 -279.774365)
			(xy 314.946784 -279.822942) (xy 314.9312 -279.869623) (xy 314.908329 -279.9132) (xy 314.878764 -279.952544)
			(xy 314.843271 -279.986636) (xy 314.802768 -280.014592) (xy 314.758306 -280.03569) (xy 314.711035 -280.049382)
			(xy 314.66218 -280.055314) (xy 314.613005 -280.053333) (xy 314.564786 -280.043489) (xy 314.51877 -280.026037)
			(xy 314.476149 -280.00143) (xy 314.438028 -279.970305) (xy 314.405393 -279.933468) (xy 314.37909 -279.891872)
			(xy 314.359799 -279.846596) (xy 314.348022 -279.798812) (xy 314.344062 -279.749758) (xy 314.005214 -279.749758)
			(xy 314.004719 -279.774365) (xy 313.996824 -279.822942) (xy 313.98124 -279.869623) (xy 313.958369 -279.9132)
			(xy 313.928804 -279.952544) (xy 313.893311 -279.986636) (xy 313.852808 -280.014592) (xy 313.808346 -280.03569)
			(xy 313.761075 -280.049382) (xy 313.71222 -280.055314) (xy 313.663045 -280.053333) (xy 313.614826 -280.043489)
			(xy 313.56881 -280.026037) (xy 313.526189 -280.00143) (xy 313.488068 -279.970305) (xy 313.455433 -279.933468)
			(xy 313.42913 -279.891872) (xy 313.409839 -279.846596) (xy 313.398062 -279.798812) (xy 313.394102 -279.749758)
			(xy 312.10504 -279.749758) (xy 312.104545 -279.774365) (xy 312.09665 -279.822942) (xy 312.081066 -279.869623)
			(xy 312.058195 -279.9132) (xy 312.02863 -279.952544) (xy 311.993137 -279.986636) (xy 311.952634 -280.014592)
			(xy 311.908172 -280.03569) (xy 311.860901 -280.049382) (xy 311.812046 -280.055314) (xy 311.762871 -280.053333)
			(xy 311.714652 -280.043489) (xy 311.668636 -280.026037) (xy 311.626015 -280.00143) (xy 311.587894 -279.970305)
			(xy 311.555259 -279.933468) (xy 311.528956 -279.891872) (xy 311.509665 -279.846596) (xy 311.497888 -279.798812)
			(xy 311.493928 -279.749758) (xy 310.205115 -279.749758) (xy 310.204625 -279.774111) (xy 310.19673 -279.822688)
			(xy 310.181146 -279.869369) (xy 310.158275 -279.912946) (xy 310.12871 -279.95229) (xy 310.093217 -279.986382)
			(xy 310.052714 -280.014338) (xy 310.008252 -280.035436) (xy 309.960981 -280.049128) (xy 309.912126 -280.05506)
			(xy 309.862951 -280.053079) (xy 309.814732 -280.043235) (xy 309.768716 -280.025783) (xy 309.726095 -280.001176)
			(xy 309.687974 -279.970051) (xy 309.655339 -279.933214) (xy 309.629036 -279.891618) (xy 309.609745 -279.846342)
			(xy 309.597968 -279.798558) (xy 309.594008 -279.749504) (xy 308.3052 -279.749504) (xy 308.304705 -279.774111)
			(xy 308.29681 -279.822688) (xy 308.281226 -279.869369) (xy 308.258355 -279.912946) (xy 308.22879 -279.95229)
			(xy 308.193297 -279.986382) (xy 308.152794 -280.014338) (xy 308.108332 -280.035436) (xy 308.061061 -280.049128)
			(xy 308.012206 -280.05506) (xy 307.963031 -280.053079) (xy 307.914812 -280.043235) (xy 307.868796 -280.025783)
			(xy 307.826175 -280.001176) (xy 307.788054 -279.970051) (xy 307.755419 -279.933214) (xy 307.729116 -279.891618)
			(xy 307.709825 -279.846342) (xy 307.698048 -279.798558) (xy 307.694088 -279.749504) (xy 306.405026 -279.749504)
			(xy 306.404531 -279.774111) (xy 306.396636 -279.822688) (xy 306.381052 -279.869369) (xy 306.358181 -279.912946)
			(xy 306.328616 -279.95229) (xy 306.293123 -279.986382) (xy 306.25262 -280.014338) (xy 306.208158 -280.035436)
			(xy 306.160887 -280.049128) (xy 306.112032 -280.05506) (xy 306.062857 -280.053079) (xy 306.014638 -280.043235)
			(xy 305.968622 -280.025783) (xy 305.926001 -280.001176) (xy 305.88788 -279.970051) (xy 305.855245 -279.933214)
			(xy 305.828942 -279.891618) (xy 305.809651 -279.846342) (xy 305.797874 -279.798558) (xy 305.793914 -279.749504)
			(xy 304.505106 -279.749504) (xy 304.504611 -279.774111) (xy 304.496716 -279.822688) (xy 304.481132 -279.869369)
			(xy 304.458261 -279.912946) (xy 304.428696 -279.95229) (xy 304.393203 -279.986382) (xy 304.3527 -280.014338)
			(xy 304.308238 -280.035436) (xy 304.260967 -280.049128) (xy 304.212112 -280.05506) (xy 304.162937 -280.053079)
			(xy 304.114718 -280.043235) (xy 304.068702 -280.025783) (xy 304.026081 -280.001176) (xy 303.98796 -279.970051)
			(xy 303.955325 -279.933214) (xy 303.929022 -279.891618) (xy 303.909731 -279.846342) (xy 303.897954 -279.798558)
			(xy 303.893994 -279.749504) (xy 302.605186 -279.749504) (xy 302.604691 -279.774111) (xy 302.596796 -279.822688)
			(xy 302.581212 -279.869369) (xy 302.558341 -279.912946) (xy 302.528776 -279.95229) (xy 302.493283 -279.986382)
			(xy 302.45278 -280.014338) (xy 302.408318 -280.035436) (xy 302.361047 -280.049128) (xy 302.312192 -280.05506)
			(xy 302.263017 -280.053079) (xy 302.214798 -280.043235) (xy 302.168782 -280.025783) (xy 302.126161 -280.001176)
			(xy 302.08804 -279.970051) (xy 302.055405 -279.933214) (xy 302.029102 -279.891618) (xy 302.009811 -279.846342)
			(xy 301.998034 -279.798558) (xy 301.994074 -279.749504) (xy 300.705012 -279.749504) (xy 300.704517 -279.774111)
			(xy 300.696622 -279.822688) (xy 300.681038 -279.869369) (xy 300.658167 -279.912946) (xy 300.628602 -279.95229)
			(xy 300.593109 -279.986382) (xy 300.552606 -280.014338) (xy 300.508144 -280.035436) (xy 300.460873 -280.049128)
			(xy 300.412018 -280.05506) (xy 300.362843 -280.053079) (xy 300.314624 -280.043235) (xy 300.268608 -280.025783)
			(xy 300.225987 -280.001176) (xy 300.187866 -279.970051) (xy 300.155231 -279.933214) (xy 300.128928 -279.891618)
			(xy 300.109637 -279.846342) (xy 300.09786 -279.798558) (xy 300.0939 -279.749504) (xy 298.805092 -279.749504)
			(xy 298.804597 -279.774111) (xy 298.796702 -279.822688) (xy 298.781118 -279.869369) (xy 298.758247 -279.912946)
			(xy 298.728682 -279.95229) (xy 298.693189 -279.986382) (xy 298.652686 -280.014338) (xy 298.608224 -280.035436)
			(xy 298.560953 -280.049128) (xy 298.512098 -280.05506) (xy 298.462923 -280.053079) (xy 298.414704 -280.043235)
			(xy 298.368688 -280.025783) (xy 298.326067 -280.001176) (xy 298.287946 -279.970051) (xy 298.255311 -279.933214)
			(xy 298.229008 -279.891618) (xy 298.209717 -279.846342) (xy 298.19794 -279.798558) (xy 298.19398 -279.749504)
			(xy 296.905172 -279.749504) (xy 296.904677 -279.774111) (xy 296.896782 -279.822688) (xy 296.881198 -279.869369)
			(xy 296.858327 -279.912946) (xy 296.828762 -279.95229) (xy 296.793269 -279.986382) (xy 296.752766 -280.014338)
			(xy 296.708304 -280.035436) (xy 296.661033 -280.049128) (xy 296.612178 -280.05506) (xy 296.563003 -280.053079)
			(xy 296.514784 -280.043235) (xy 296.468768 -280.025783) (xy 296.426147 -280.001176) (xy 296.388026 -279.970051)
			(xy 296.355391 -279.933214) (xy 296.329088 -279.891618) (xy 296.309797 -279.846342) (xy 296.29802 -279.798558)
			(xy 296.29406 -279.749504) (xy 295.004998 -279.749504) (xy 295.004503 -279.774111) (xy 294.996608 -279.822688)
			(xy 294.981024 -279.869369) (xy 294.958153 -279.912946) (xy 294.928588 -279.95229) (xy 294.893095 -279.986382)
			(xy 294.852592 -280.014338) (xy 294.80813 -280.035436) (xy 294.760859 -280.049128) (xy 294.712004 -280.05506)
			(xy 294.662829 -280.053079) (xy 294.61461 -280.043235) (xy 294.568594 -280.025783) (xy 294.525973 -280.001176)
			(xy 294.487852 -279.970051) (xy 294.455217 -279.933214) (xy 294.428914 -279.891618) (xy 294.409623 -279.846342)
			(xy 294.397846 -279.798558) (xy 294.393886 -279.749504) (xy 293.105078 -279.749504) (xy 293.104583 -279.774111)
			(xy 293.096688 -279.822688) (xy 293.081104 -279.869369) (xy 293.058233 -279.912946) (xy 293.028668 -279.95229)
			(xy 292.993175 -279.986382) (xy 292.952672 -280.014338) (xy 292.90821 -280.035436) (xy 292.860939 -280.049128)
			(xy 292.812084 -280.05506) (xy 292.762909 -280.053079) (xy 292.71469 -280.043235) (xy 292.668674 -280.025783)
			(xy 292.626053 -280.001176) (xy 292.587932 -279.970051) (xy 292.555297 -279.933214) (xy 292.528994 -279.891618)
			(xy 292.509703 -279.846342) (xy 292.497926 -279.798558) (xy 292.493966 -279.749504) (xy 291.205158 -279.749504)
			(xy 291.204663 -279.774111) (xy 291.196768 -279.822688) (xy 291.181184 -279.869369) (xy 291.158313 -279.912946)
			(xy 291.128748 -279.95229) (xy 291.093255 -279.986382) (xy 291.052752 -280.014338) (xy 291.00829 -280.035436)
			(xy 290.961019 -280.049128) (xy 290.912164 -280.05506) (xy 290.862989 -280.053079) (xy 290.81477 -280.043235)
			(xy 290.768754 -280.025783) (xy 290.726133 -280.001176) (xy 290.688012 -279.970051) (xy 290.655377 -279.933214)
			(xy 290.629074 -279.891618) (xy 290.609783 -279.846342) (xy 290.598006 -279.798558) (xy 290.594046 -279.749504)
			(xy 289.304984 -279.749504) (xy 289.304489 -279.774111) (xy 289.296594 -279.822688) (xy 289.28101 -279.869369)
			(xy 289.258139 -279.912946) (xy 289.228574 -279.95229) (xy 289.193081 -279.986382) (xy 289.152578 -280.014338)
			(xy 289.108116 -280.035436) (xy 289.060845 -280.049128) (xy 289.01199 -280.05506) (xy 288.962815 -280.053079)
			(xy 288.914596 -280.043235) (xy 288.86858 -280.025783) (xy 288.825959 -280.001176) (xy 288.787838 -279.970051)
			(xy 288.755203 -279.933214) (xy 288.7289 -279.891618) (xy 288.709609 -279.846342) (xy 288.697832 -279.798558)
			(xy 288.693872 -279.749504) (xy 287.405064 -279.749504) (xy 287.404569 -279.774111) (xy 287.396674 -279.822688)
			(xy 287.38109 -279.869369) (xy 287.358219 -279.912946) (xy 287.328654 -279.95229) (xy 287.293161 -279.986382)
			(xy 287.252658 -280.014338) (xy 287.208196 -280.035436) (xy 287.160925 -280.049128) (xy 287.11207 -280.05506)
			(xy 287.062895 -280.053079) (xy 287.014676 -280.043235) (xy 286.96866 -280.025783) (xy 286.926039 -280.001176)
			(xy 286.887918 -279.970051) (xy 286.855283 -279.933214) (xy 286.82898 -279.891618) (xy 286.809689 -279.846342)
			(xy 286.797912 -279.798558) (xy 286.793952 -279.749504) (xy 285.505144 -279.749504) (xy 285.504649 -279.774111)
			(xy 285.496754 -279.822688) (xy 285.48117 -279.869369) (xy 285.458299 -279.912946) (xy 285.428734 -279.95229)
			(xy 285.393241 -279.986382) (xy 285.352738 -280.014338) (xy 285.308276 -280.035436) (xy 285.261005 -280.049128)
			(xy 285.21215 -280.05506) (xy 285.162975 -280.053079) (xy 285.114756 -280.043235) (xy 285.06874 -280.025783)
			(xy 285.026119 -280.001176) (xy 284.987998 -279.970051) (xy 284.955363 -279.933214) (xy 284.92906 -279.891618)
			(xy 284.909769 -279.846342) (xy 284.897992 -279.798558) (xy 284.894032 -279.749504) (xy 283.605224 -279.749504)
			(xy 283.604729 -279.774111) (xy 283.596834 -279.822688) (xy 283.58125 -279.869369) (xy 283.558379 -279.912946)
			(xy 283.528814 -279.95229) (xy 283.493321 -279.986382) (xy 283.452818 -280.014338) (xy 283.408356 -280.035436)
			(xy 283.361085 -280.049128) (xy 283.31223 -280.05506) (xy 283.263055 -280.053079) (xy 283.214836 -280.043235)
			(xy 283.16882 -280.025783) (xy 283.126199 -280.001176) (xy 283.088078 -279.970051) (xy 283.055443 -279.933214)
			(xy 283.02914 -279.891618) (xy 283.009849 -279.846342) (xy 282.998072 -279.798558) (xy 282.994112 -279.749504)
			(xy 281.70505 -279.749504) (xy 281.704555 -279.774111) (xy 281.69666 -279.822688) (xy 281.681076 -279.869369)
			(xy 281.658205 -279.912946) (xy 281.62864 -279.95229) (xy 281.593147 -279.986382) (xy 281.552644 -280.014338)
			(xy 281.508182 -280.035436) (xy 281.460911 -280.049128) (xy 281.412056 -280.05506) (xy 281.362881 -280.053079)
			(xy 281.314662 -280.043235) (xy 281.268646 -280.025783) (xy 281.226025 -280.001176) (xy 281.187904 -279.970051)
			(xy 281.155269 -279.933214) (xy 281.128966 -279.891618) (xy 281.109675 -279.846342) (xy 281.097898 -279.798558)
			(xy 281.093938 -279.749504) (xy 279.80513 -279.749504) (xy 279.804635 -279.774111) (xy 279.79674 -279.822688)
			(xy 279.781156 -279.869369) (xy 279.758285 -279.912946) (xy 279.72872 -279.95229) (xy 279.693227 -279.986382)
			(xy 279.652724 -280.014338) (xy 279.608262 -280.035436) (xy 279.560991 -280.049128) (xy 279.512136 -280.05506)
			(xy 279.462961 -280.053079) (xy 279.414742 -280.043235) (xy 279.368726 -280.025783) (xy 279.326105 -280.001176)
			(xy 279.287984 -279.970051) (xy 279.255349 -279.933214) (xy 279.229046 -279.891618) (xy 279.209755 -279.846342)
			(xy 279.197978 -279.798558) (xy 279.194018 -279.749504) (xy 277.90521 -279.749504) (xy 277.904715 -279.774111)
			(xy 277.89682 -279.822688) (xy 277.881236 -279.869369) (xy 277.858365 -279.912946) (xy 277.8288 -279.95229)
			(xy 277.793307 -279.986382) (xy 277.752804 -280.014338) (xy 277.708342 -280.035436) (xy 277.661071 -280.049128)
			(xy 277.612216 -280.05506) (xy 277.563041 -280.053079) (xy 277.514822 -280.043235) (xy 277.468806 -280.025783)
			(xy 277.426185 -280.001176) (xy 277.388064 -279.970051) (xy 277.355429 -279.933214) (xy 277.329126 -279.891618)
			(xy 277.309835 -279.846342) (xy 277.298058 -279.798558) (xy 277.294098 -279.749504) (xy 198.855325 -279.749504)
			(xy 198.85533 -279.749758) (xy 198.854835 -279.774365) (xy 198.84694 -279.822942) (xy 198.831356 -279.869623)
			(xy 198.808485 -279.9132) (xy 198.77892 -279.952544) (xy 198.743427 -279.986636) (xy 198.702924 -280.014592)
			(xy 198.658462 -280.03569) (xy 198.611191 -280.049382) (xy 198.562336 -280.055314) (xy 198.513161 -280.053333)
			(xy 198.464942 -280.043489) (xy 198.418926 -280.026037) (xy 198.376305 -280.00143) (xy 198.338184 -279.970305)
			(xy 198.305549 -279.933468) (xy 198.279246 -279.891872) (xy 198.259955 -279.846596) (xy 198.248178 -279.798812)
			(xy 198.244218 -279.749758) (xy 197.90537 -279.749758) (xy 197.904875 -279.774365) (xy 197.89698 -279.822942)
			(xy 197.881396 -279.869623) (xy 197.858525 -279.9132) (xy 197.82896 -279.952544) (xy 197.793467 -279.986636)
			(xy 197.752964 -280.014592) (xy 197.708502 -280.03569) (xy 197.661231 -280.049382) (xy 197.612376 -280.055314)
			(xy 197.563201 -280.053333) (xy 197.514982 -280.043489) (xy 197.468966 -280.026037) (xy 197.426345 -280.00143)
			(xy 197.388224 -279.970305) (xy 197.355589 -279.933468) (xy 197.329286 -279.891872) (xy 197.309995 -279.846596)
			(xy 197.298218 -279.798812) (xy 197.294258 -279.749758) (xy 196.005196 -279.749758) (xy 196.004701 -279.774365)
			(xy 195.996806 -279.822942) (xy 195.981222 -279.869623) (xy 195.958351 -279.9132) (xy 195.928786 -279.952544)
			(xy 195.893293 -279.986636) (xy 195.85279 -280.014592) (xy 195.808328 -280.03569) (xy 195.761057 -280.049382)
			(xy 195.712202 -280.055314) (xy 195.663027 -280.053333) (xy 195.614808 -280.043489) (xy 195.568792 -280.026037)
			(xy 195.526171 -280.00143) (xy 195.48805 -279.970305) (xy 195.455415 -279.933468) (xy 195.429112 -279.891872)
			(xy 195.409821 -279.846596) (xy 195.398044 -279.798812) (xy 195.394084 -279.749758) (xy 194.105271 -279.749758)
			(xy 194.104781 -279.774111) (xy 194.096886 -279.822688) (xy 194.081302 -279.869369) (xy 194.058431 -279.912946)
			(xy 194.028866 -279.95229) (xy 193.993373 -279.986382) (xy 193.95287 -280.014338) (xy 193.908408 -280.035436)
			(xy 193.861137 -280.049128) (xy 193.812282 -280.05506) (xy 193.763107 -280.053079) (xy 193.714888 -280.043235)
			(xy 193.668872 -280.025783) (xy 193.626251 -280.001176) (xy 193.58813 -279.970051) (xy 193.555495 -279.933214)
			(xy 193.529192 -279.891618) (xy 193.509901 -279.846342) (xy 193.498124 -279.798558) (xy 193.494164 -279.749504)
			(xy 192.205356 -279.749504) (xy 192.204861 -279.774111) (xy 192.196966 -279.822688) (xy 192.181382 -279.869369)
			(xy 192.158511 -279.912946) (xy 192.128946 -279.95229) (xy 192.093453 -279.986382) (xy 192.05295 -280.014338)
			(xy 192.008488 -280.035436) (xy 191.961217 -280.049128) (xy 191.912362 -280.05506) (xy 191.863187 -280.053079)
			(xy 191.814968 -280.043235) (xy 191.768952 -280.025783) (xy 191.726331 -280.001176) (xy 191.68821 -279.970051)
			(xy 191.655575 -279.933214) (xy 191.629272 -279.891618) (xy 191.609981 -279.846342) (xy 191.598204 -279.798558)
			(xy 191.594244 -279.749504) (xy 190.305182 -279.749504) (xy 190.304687 -279.774111) (xy 190.296792 -279.822688)
			(xy 190.281208 -279.869369) (xy 190.258337 -279.912946) (xy 190.228772 -279.95229) (xy 190.193279 -279.986382)
			(xy 190.152776 -280.014338) (xy 190.108314 -280.035436) (xy 190.061043 -280.049128) (xy 190.012188 -280.05506)
			(xy 189.963013 -280.053079) (xy 189.914794 -280.043235) (xy 189.868778 -280.025783) (xy 189.826157 -280.001176)
			(xy 189.788036 -279.970051) (xy 189.755401 -279.933214) (xy 189.729098 -279.891618) (xy 189.709807 -279.846342)
			(xy 189.69803 -279.798558) (xy 189.69407 -279.749504) (xy 188.405262 -279.749504) (xy 188.404767 -279.774111)
			(xy 188.396872 -279.822688) (xy 188.381288 -279.869369) (xy 188.358417 -279.912946) (xy 188.328852 -279.95229)
			(xy 188.293359 -279.986382) (xy 188.252856 -280.014338) (xy 188.208394 -280.035436) (xy 188.161123 -280.049128)
			(xy 188.112268 -280.05506) (xy 188.063093 -280.053079) (xy 188.014874 -280.043235) (xy 187.968858 -280.025783)
			(xy 187.926237 -280.001176) (xy 187.888116 -279.970051) (xy 187.855481 -279.933214) (xy 187.829178 -279.891618)
			(xy 187.809887 -279.846342) (xy 187.79811 -279.798558) (xy 187.79415 -279.749504) (xy 186.505342 -279.749504)
			(xy 186.504847 -279.774111) (xy 186.496952 -279.822688) (xy 186.481368 -279.869369) (xy 186.458497 -279.912946)
			(xy 186.428932 -279.95229) (xy 186.393439 -279.986382) (xy 186.352936 -280.014338) (xy 186.308474 -280.035436)
			(xy 186.261203 -280.049128) (xy 186.212348 -280.05506) (xy 186.163173 -280.053079) (xy 186.114954 -280.043235)
			(xy 186.068938 -280.025783) (xy 186.026317 -280.001176) (xy 185.988196 -279.970051) (xy 185.955561 -279.933214)
			(xy 185.929258 -279.891618) (xy 185.909967 -279.846342) (xy 185.89819 -279.798558) (xy 185.89423 -279.749504)
			(xy 184.605168 -279.749504) (xy 184.604673 -279.774111) (xy 184.596778 -279.822688) (xy 184.581194 -279.869369)
			(xy 184.558323 -279.912946) (xy 184.528758 -279.95229) (xy 184.493265 -279.986382) (xy 184.452762 -280.014338)
			(xy 184.4083 -280.035436) (xy 184.361029 -280.049128) (xy 184.312174 -280.05506) (xy 184.262999 -280.053079)
			(xy 184.21478 -280.043235) (xy 184.168764 -280.025783) (xy 184.126143 -280.001176) (xy 184.088022 -279.970051)
			(xy 184.055387 -279.933214) (xy 184.029084 -279.891618) (xy 184.009793 -279.846342) (xy 183.998016 -279.798558)
			(xy 183.994056 -279.749504) (xy 182.705248 -279.749504) (xy 182.704753 -279.774111) (xy 182.696858 -279.822688)
			(xy 182.681274 -279.869369) (xy 182.658403 -279.912946) (xy 182.628838 -279.95229) (xy 182.593345 -279.986382)
			(xy 182.552842 -280.014338) (xy 182.50838 -280.035436) (xy 182.461109 -280.049128) (xy 182.412254 -280.05506)
			(xy 182.363079 -280.053079) (xy 182.31486 -280.043235) (xy 182.268844 -280.025783) (xy 182.226223 -280.001176)
			(xy 182.188102 -279.970051) (xy 182.155467 -279.933214) (xy 182.129164 -279.891618) (xy 182.109873 -279.846342)
			(xy 182.098096 -279.798558) (xy 182.094136 -279.749504) (xy 180.805328 -279.749504) (xy 180.804833 -279.774111)
			(xy 180.796938 -279.822688) (xy 180.781354 -279.869369) (xy 180.758483 -279.912946) (xy 180.728918 -279.95229)
			(xy 180.693425 -279.986382) (xy 180.652922 -280.014338) (xy 180.60846 -280.035436) (xy 180.561189 -280.049128)
			(xy 180.512334 -280.05506) (xy 180.463159 -280.053079) (xy 180.41494 -280.043235) (xy 180.368924 -280.025783)
			(xy 180.326303 -280.001176) (xy 180.288182 -279.970051) (xy 180.255547 -279.933214) (xy 180.229244 -279.891618)
			(xy 180.209953 -279.846342) (xy 180.198176 -279.798558) (xy 180.194216 -279.749504) (xy 178.905154 -279.749504)
			(xy 178.904659 -279.774111) (xy 178.896764 -279.822688) (xy 178.88118 -279.869369) (xy 178.858309 -279.912946)
			(xy 178.828744 -279.95229) (xy 178.793251 -279.986382) (xy 178.752748 -280.014338) (xy 178.708286 -280.035436)
			(xy 178.661015 -280.049128) (xy 178.61216 -280.05506) (xy 178.562985 -280.053079) (xy 178.514766 -280.043235)
			(xy 178.46875 -280.025783) (xy 178.426129 -280.001176) (xy 178.388008 -279.970051) (xy 178.355373 -279.933214)
			(xy 178.32907 -279.891618) (xy 178.309779 -279.846342) (xy 178.298002 -279.798558) (xy 178.294042 -279.749504)
			(xy 177.005234 -279.749504) (xy 177.004739 -279.774111) (xy 176.996844 -279.822688) (xy 176.98126 -279.869369)
			(xy 176.958389 -279.912946) (xy 176.928824 -279.95229) (xy 176.893331 -279.986382) (xy 176.852828 -280.014338)
			(xy 176.808366 -280.035436) (xy 176.761095 -280.049128) (xy 176.71224 -280.05506) (xy 176.663065 -280.053079)
			(xy 176.614846 -280.043235) (xy 176.56883 -280.025783) (xy 176.526209 -280.001176) (xy 176.488088 -279.970051)
			(xy 176.455453 -279.933214) (xy 176.42915 -279.891618) (xy 176.409859 -279.846342) (xy 176.398082 -279.798558)
			(xy 176.394122 -279.749504) (xy 175.105314 -279.749504) (xy 175.104819 -279.774111) (xy 175.096924 -279.822688)
			(xy 175.08134 -279.869369) (xy 175.058469 -279.912946) (xy 175.028904 -279.95229) (xy 174.993411 -279.986382)
			(xy 174.952908 -280.014338) (xy 174.908446 -280.035436) (xy 174.861175 -280.049128) (xy 174.81232 -280.05506)
			(xy 174.763145 -280.053079) (xy 174.714926 -280.043235) (xy 174.66891 -280.025783) (xy 174.626289 -280.001176)
			(xy 174.588168 -279.970051) (xy 174.555533 -279.933214) (xy 174.52923 -279.891618) (xy 174.509939 -279.846342)
			(xy 174.498162 -279.798558) (xy 174.494202 -279.749504) (xy 173.20514 -279.749504) (xy 173.204645 -279.774111)
			(xy 173.19675 -279.822688) (xy 173.181166 -279.869369) (xy 173.158295 -279.912946) (xy 173.12873 -279.95229)
			(xy 173.093237 -279.986382) (xy 173.052734 -280.014338) (xy 173.008272 -280.035436) (xy 172.961001 -280.049128)
			(xy 172.912146 -280.05506) (xy 172.862971 -280.053079) (xy 172.814752 -280.043235) (xy 172.768736 -280.025783)
			(xy 172.726115 -280.001176) (xy 172.687994 -279.970051) (xy 172.655359 -279.933214) (xy 172.629056 -279.891618)
			(xy 172.609765 -279.846342) (xy 172.597988 -279.798558) (xy 172.594028 -279.749504) (xy 171.30522 -279.749504)
			(xy 171.304725 -279.774111) (xy 171.29683 -279.822688) (xy 171.281246 -279.869369) (xy 171.258375 -279.912946)
			(xy 171.22881 -279.95229) (xy 171.193317 -279.986382) (xy 171.152814 -280.014338) (xy 171.108352 -280.035436)
			(xy 171.061081 -280.049128) (xy 171.012226 -280.05506) (xy 170.963051 -280.053079) (xy 170.914832 -280.043235)
			(xy 170.868816 -280.025783) (xy 170.826195 -280.001176) (xy 170.788074 -279.970051) (xy 170.755439 -279.933214)
			(xy 170.729136 -279.891618) (xy 170.709845 -279.846342) (xy 170.698068 -279.798558) (xy 170.694108 -279.749504)
			(xy 169.4053 -279.749504) (xy 169.404805 -279.774111) (xy 169.39691 -279.822688) (xy 169.381326 -279.869369)
			(xy 169.358455 -279.912946) (xy 169.32889 -279.95229) (xy 169.293397 -279.986382) (xy 169.252894 -280.014338)
			(xy 169.208432 -280.035436) (xy 169.161161 -280.049128) (xy 169.112306 -280.05506) (xy 169.063131 -280.053079)
			(xy 169.014912 -280.043235) (xy 168.968896 -280.025783) (xy 168.926275 -280.001176) (xy 168.888154 -279.970051)
			(xy 168.855519 -279.933214) (xy 168.829216 -279.891618) (xy 168.809925 -279.846342) (xy 168.798148 -279.798558)
			(xy 168.794188 -279.749504) (xy 167.50538 -279.749504) (xy 167.504885 -279.774111) (xy 167.49699 -279.822688)
			(xy 167.481406 -279.869369) (xy 167.458535 -279.912946) (xy 167.42897 -279.95229) (xy 167.393477 -279.986382)
			(xy 167.352974 -280.014338) (xy 167.308512 -280.035436) (xy 167.261241 -280.049128) (xy 167.212386 -280.05506)
			(xy 167.163211 -280.053079) (xy 167.114992 -280.043235) (xy 167.068976 -280.025783) (xy 167.026355 -280.001176)
			(xy 166.988234 -279.970051) (xy 166.955599 -279.933214) (xy 166.929296 -279.891618) (xy 166.910005 -279.846342)
			(xy 166.898228 -279.798558) (xy 166.894268 -279.749504) (xy 165.605206 -279.749504) (xy 165.604711 -279.774111)
			(xy 165.596816 -279.822688) (xy 165.581232 -279.869369) (xy 165.558361 -279.912946) (xy 165.528796 -279.95229)
			(xy 165.493303 -279.986382) (xy 165.4528 -280.014338) (xy 165.408338 -280.035436) (xy 165.361067 -280.049128)
			(xy 165.312212 -280.05506) (xy 165.263037 -280.053079) (xy 165.214818 -280.043235) (xy 165.168802 -280.025783)
			(xy 165.126181 -280.001176) (xy 165.08806 -279.970051) (xy 165.055425 -279.933214) (xy 165.029122 -279.891618)
			(xy 165.009831 -279.846342) (xy 164.998054 -279.798558) (xy 164.994094 -279.749504) (xy 163.705286 -279.749504)
			(xy 163.704791 -279.774111) (xy 163.696896 -279.822688) (xy 163.681312 -279.869369) (xy 163.658441 -279.912946)
			(xy 163.628876 -279.95229) (xy 163.593383 -279.986382) (xy 163.55288 -280.014338) (xy 163.508418 -280.035436)
			(xy 163.461147 -280.049128) (xy 163.412292 -280.05506) (xy 163.363117 -280.053079) (xy 163.314898 -280.043235)
			(xy 163.268882 -280.025783) (xy 163.226261 -280.001176) (xy 163.18814 -279.970051) (xy 163.155505 -279.933214)
			(xy 163.129202 -279.891618) (xy 163.109911 -279.846342) (xy 163.098134 -279.798558) (xy 163.094174 -279.749504)
			(xy 161.805366 -279.749504) (xy 161.804871 -279.774111) (xy 161.796976 -279.822688) (xy 161.781392 -279.869369)
			(xy 161.758521 -279.912946) (xy 161.728956 -279.95229) (xy 161.693463 -279.986382) (xy 161.65296 -280.014338)
			(xy 161.608498 -280.035436) (xy 161.561227 -280.049128) (xy 161.512372 -280.05506) (xy 161.463197 -280.053079)
			(xy 161.414978 -280.043235) (xy 161.368962 -280.025783) (xy 161.326341 -280.001176) (xy 161.28822 -279.970051)
			(xy 161.255585 -279.933214) (xy 161.229282 -279.891618) (xy 161.209991 -279.846342) (xy 161.198214 -279.798558)
			(xy 161.194254 -279.749504) (xy 82.755227 -279.749504) (xy 82.755232 -279.749758) (xy 82.754737 -279.774365)
			(xy 82.746842 -279.822942) (xy 82.731258 -279.869623) (xy 82.708387 -279.9132) (xy 82.678822 -279.952544)
			(xy 82.643329 -279.986636) (xy 82.602826 -280.014592) (xy 82.558364 -280.03569) (xy 82.511093 -280.049382)
			(xy 82.462238 -280.055314) (xy 82.413063 -280.053333) (xy 82.364844 -280.043489) (xy 82.318828 -280.026037)
			(xy 82.276207 -280.00143) (xy 82.238086 -279.970305) (xy 82.205451 -279.933468) (xy 82.179148 -279.891872)
			(xy 82.159857 -279.846596) (xy 82.14808 -279.798812) (xy 82.14412 -279.749758) (xy 81.805272 -279.749758)
			(xy 81.804777 -279.774365) (xy 81.796882 -279.822942) (xy 81.781298 -279.869623) (xy 81.758427 -279.9132)
			(xy 81.728862 -279.952544) (xy 81.693369 -279.986636) (xy 81.652866 -280.014592) (xy 81.608404 -280.03569)
			(xy 81.561133 -280.049382) (xy 81.512278 -280.055314) (xy 81.463103 -280.053333) (xy 81.414884 -280.043489)
			(xy 81.368868 -280.026037) (xy 81.326247 -280.00143) (xy 81.288126 -279.970305) (xy 81.255491 -279.933468)
			(xy 81.229188 -279.891872) (xy 81.209897 -279.846596) (xy 81.19812 -279.798812) (xy 81.19416 -279.749758)
			(xy 79.905098 -279.749758) (xy 79.904603 -279.774365) (xy 79.896708 -279.822942) (xy 79.881124 -279.869623)
			(xy 79.858253 -279.9132) (xy 79.828688 -279.952544) (xy 79.793195 -279.986636) (xy 79.752692 -280.014592)
			(xy 79.70823 -280.03569) (xy 79.660959 -280.049382) (xy 79.612104 -280.055314) (xy 79.562929 -280.053333)
			(xy 79.51471 -280.043489) (xy 79.468694 -280.026037) (xy 79.426073 -280.00143) (xy 79.387952 -279.970305)
			(xy 79.355317 -279.933468) (xy 79.329014 -279.891872) (xy 79.309723 -279.846596) (xy 79.297946 -279.798812)
			(xy 79.293986 -279.749758) (xy 78.005173 -279.749758) (xy 78.004683 -279.774111) (xy 77.996788 -279.822688)
			(xy 77.981204 -279.869369) (xy 77.958333 -279.912946) (xy 77.928768 -279.95229) (xy 77.893275 -279.986382)
			(xy 77.852772 -280.014338) (xy 77.80831 -280.035436) (xy 77.761039 -280.049128) (xy 77.712184 -280.05506)
			(xy 77.663009 -280.053079) (xy 77.61479 -280.043235) (xy 77.568774 -280.025783) (xy 77.526153 -280.001176)
			(xy 77.488032 -279.970051) (xy 77.455397 -279.933214) (xy 77.429094 -279.891618) (xy 77.409803 -279.846342)
			(xy 77.398026 -279.798558) (xy 77.394066 -279.749504) (xy 76.105258 -279.749504) (xy 76.104763 -279.774111)
			(xy 76.096868 -279.822688) (xy 76.081284 -279.869369) (xy 76.058413 -279.912946) (xy 76.028848 -279.95229)
			(xy 75.993355 -279.986382) (xy 75.952852 -280.014338) (xy 75.90839 -280.035436) (xy 75.861119 -280.049128)
			(xy 75.812264 -280.05506) (xy 75.763089 -280.053079) (xy 75.71487 -280.043235) (xy 75.668854 -280.025783)
			(xy 75.626233 -280.001176) (xy 75.588112 -279.970051) (xy 75.555477 -279.933214) (xy 75.529174 -279.891618)
			(xy 75.509883 -279.846342) (xy 75.498106 -279.798558) (xy 75.494146 -279.749504) (xy 74.205084 -279.749504)
			(xy 74.204589 -279.774111) (xy 74.196694 -279.822688) (xy 74.18111 -279.869369) (xy 74.158239 -279.912946)
			(xy 74.128674 -279.95229) (xy 74.093181 -279.986382) (xy 74.052678 -280.014338) (xy 74.008216 -280.035436)
			(xy 73.960945 -280.049128) (xy 73.91209 -280.05506) (xy 73.862915 -280.053079) (xy 73.814696 -280.043235)
			(xy 73.76868 -280.025783) (xy 73.726059 -280.001176) (xy 73.687938 -279.970051) (xy 73.655303 -279.933214)
			(xy 73.629 -279.891618) (xy 73.609709 -279.846342) (xy 73.597932 -279.798558) (xy 73.593972 -279.749504)
			(xy 72.305164 -279.749504) (xy 72.304669 -279.774111) (xy 72.296774 -279.822688) (xy 72.28119 -279.869369)
			(xy 72.258319 -279.912946) (xy 72.228754 -279.95229) (xy 72.193261 -279.986382) (xy 72.152758 -280.014338)
			(xy 72.108296 -280.035436) (xy 72.061025 -280.049128) (xy 72.01217 -280.05506) (xy 71.962995 -280.053079)
			(xy 71.914776 -280.043235) (xy 71.86876 -280.025783) (xy 71.826139 -280.001176) (xy 71.788018 -279.970051)
			(xy 71.755383 -279.933214) (xy 71.72908 -279.891618) (xy 71.709789 -279.846342) (xy 71.698012 -279.798558)
			(xy 71.694052 -279.749504) (xy 70.405244 -279.749504) (xy 70.404749 -279.774111) (xy 70.396854 -279.822688)
			(xy 70.38127 -279.869369) (xy 70.358399 -279.912946) (xy 70.328834 -279.95229) (xy 70.293341 -279.986382)
			(xy 70.252838 -280.014338) (xy 70.208376 -280.035436) (xy 70.161105 -280.049128) (xy 70.11225 -280.05506)
			(xy 70.063075 -280.053079) (xy 70.014856 -280.043235) (xy 69.96884 -280.025783) (xy 69.926219 -280.001176)
			(xy 69.888098 -279.970051) (xy 69.855463 -279.933214) (xy 69.82916 -279.891618) (xy 69.809869 -279.846342)
			(xy 69.798092 -279.798558) (xy 69.794132 -279.749504) (xy 68.50507 -279.749504) (xy 68.504575 -279.774111)
			(xy 68.49668 -279.822688) (xy 68.481096 -279.869369) (xy 68.458225 -279.912946) (xy 68.42866 -279.95229)
			(xy 68.393167 -279.986382) (xy 68.352664 -280.014338) (xy 68.308202 -280.035436) (xy 68.260931 -280.049128)
			(xy 68.212076 -280.05506) (xy 68.162901 -280.053079) (xy 68.114682 -280.043235) (xy 68.068666 -280.025783)
			(xy 68.026045 -280.001176) (xy 67.987924 -279.970051) (xy 67.955289 -279.933214) (xy 67.928986 -279.891618)
			(xy 67.909695 -279.846342) (xy 67.897918 -279.798558) (xy 67.893958 -279.749504) (xy 66.60515 -279.749504)
			(xy 66.604655 -279.774111) (xy 66.59676 -279.822688) (xy 66.581176 -279.869369) (xy 66.558305 -279.912946)
			(xy 66.52874 -279.95229) (xy 66.493247 -279.986382) (xy 66.452744 -280.014338) (xy 66.408282 -280.035436)
			(xy 66.361011 -280.049128) (xy 66.312156 -280.05506) (xy 66.262981 -280.053079) (xy 66.214762 -280.043235)
			(xy 66.168746 -280.025783) (xy 66.126125 -280.001176) (xy 66.088004 -279.970051) (xy 66.055369 -279.933214)
			(xy 66.029066 -279.891618) (xy 66.009775 -279.846342) (xy 65.997998 -279.798558) (xy 65.994038 -279.749504)
			(xy 64.70523 -279.749504) (xy 64.704735 -279.774111) (xy 64.69684 -279.822688) (xy 64.681256 -279.869369)
			(xy 64.658385 -279.912946) (xy 64.62882 -279.95229) (xy 64.593327 -279.986382) (xy 64.552824 -280.014338)
			(xy 64.508362 -280.035436) (xy 64.461091 -280.049128) (xy 64.412236 -280.05506) (xy 64.363061 -280.053079)
			(xy 64.314842 -280.043235) (xy 64.268826 -280.025783) (xy 64.226205 -280.001176) (xy 64.188084 -279.970051)
			(xy 64.155449 -279.933214) (xy 64.129146 -279.891618) (xy 64.109855 -279.846342) (xy 64.098078 -279.798558)
			(xy 64.094118 -279.749504) (xy 62.805056 -279.749504) (xy 62.804561 -279.774111) (xy 62.796666 -279.822688)
			(xy 62.781082 -279.869369) (xy 62.758211 -279.912946) (xy 62.728646 -279.95229) (xy 62.693153 -279.986382)
			(xy 62.65265 -280.014338) (xy 62.608188 -280.035436) (xy 62.560917 -280.049128) (xy 62.512062 -280.05506)
			(xy 62.462887 -280.053079) (xy 62.414668 -280.043235) (xy 62.368652 -280.025783) (xy 62.326031 -280.001176)
			(xy 62.28791 -279.970051) (xy 62.255275 -279.933214) (xy 62.228972 -279.891618) (xy 62.209681 -279.846342)
			(xy 62.197904 -279.798558) (xy 62.193944 -279.749504) (xy 60.905136 -279.749504) (xy 60.904641 -279.774111)
			(xy 60.896746 -279.822688) (xy 60.881162 -279.869369) (xy 60.858291 -279.912946) (xy 60.828726 -279.95229)
			(xy 60.793233 -279.986382) (xy 60.75273 -280.014338) (xy 60.708268 -280.035436) (xy 60.660997 -280.049128)
			(xy 60.612142 -280.05506) (xy 60.562967 -280.053079) (xy 60.514748 -280.043235) (xy 60.468732 -280.025783)
			(xy 60.426111 -280.001176) (xy 60.38799 -279.970051) (xy 60.355355 -279.933214) (xy 60.329052 -279.891618)
			(xy 60.309761 -279.846342) (xy 60.297984 -279.798558) (xy 60.294024 -279.749504) (xy 59.005216 -279.749504)
			(xy 59.004721 -279.774111) (xy 58.996826 -279.822688) (xy 58.981242 -279.869369) (xy 58.958371 -279.912946)
			(xy 58.928806 -279.95229) (xy 58.893313 -279.986382) (xy 58.85281 -280.014338) (xy 58.808348 -280.035436)
			(xy 58.761077 -280.049128) (xy 58.712222 -280.05506) (xy 58.663047 -280.053079) (xy 58.614828 -280.043235)
			(xy 58.568812 -280.025783) (xy 58.526191 -280.001176) (xy 58.48807 -279.970051) (xy 58.455435 -279.933214)
			(xy 58.429132 -279.891618) (xy 58.409841 -279.846342) (xy 58.398064 -279.798558) (xy 58.394104 -279.749504)
			(xy 57.105042 -279.749504) (xy 57.104547 -279.774111) (xy 57.096652 -279.822688) (xy 57.081068 -279.869369)
			(xy 57.058197 -279.912946) (xy 57.028632 -279.95229) (xy 56.993139 -279.986382) (xy 56.952636 -280.014338)
			(xy 56.908174 -280.035436) (xy 56.860903 -280.049128) (xy 56.812048 -280.05506) (xy 56.762873 -280.053079)
			(xy 56.714654 -280.043235) (xy 56.668638 -280.025783) (xy 56.626017 -280.001176) (xy 56.587896 -279.970051)
			(xy 56.555261 -279.933214) (xy 56.528958 -279.891618) (xy 56.509667 -279.846342) (xy 56.49789 -279.798558)
			(xy 56.49393 -279.749504) (xy 55.205122 -279.749504) (xy 55.204627 -279.774111) (xy 55.196732 -279.822688)
			(xy 55.181148 -279.869369) (xy 55.158277 -279.912946) (xy 55.128712 -279.95229) (xy 55.093219 -279.986382)
			(xy 55.052716 -280.014338) (xy 55.008254 -280.035436) (xy 54.960983 -280.049128) (xy 54.912128 -280.05506)
			(xy 54.862953 -280.053079) (xy 54.814734 -280.043235) (xy 54.768718 -280.025783) (xy 54.726097 -280.001176)
			(xy 54.687976 -279.970051) (xy 54.655341 -279.933214) (xy 54.629038 -279.891618) (xy 54.609747 -279.846342)
			(xy 54.59797 -279.798558) (xy 54.59401 -279.749504) (xy 53.305202 -279.749504) (xy 53.304707 -279.774111)
			(xy 53.296812 -279.822688) (xy 53.281228 -279.869369) (xy 53.258357 -279.912946) (xy 53.228792 -279.95229)
			(xy 53.193299 -279.986382) (xy 53.152796 -280.014338) (xy 53.108334 -280.035436) (xy 53.061063 -280.049128)
			(xy 53.012208 -280.05506) (xy 52.963033 -280.053079) (xy 52.914814 -280.043235) (xy 52.868798 -280.025783)
			(xy 52.826177 -280.001176) (xy 52.788056 -279.970051) (xy 52.755421 -279.933214) (xy 52.729118 -279.891618)
			(xy 52.709827 -279.846342) (xy 52.69805 -279.798558) (xy 52.69409 -279.749504) (xy 51.405282 -279.749504)
			(xy 51.404787 -279.774111) (xy 51.396892 -279.822688) (xy 51.381308 -279.869369) (xy 51.358437 -279.912946)
			(xy 51.328872 -279.95229) (xy 51.293379 -279.986382) (xy 51.252876 -280.014338) (xy 51.208414 -280.035436)
			(xy 51.161143 -280.049128) (xy 51.112288 -280.05506) (xy 51.063113 -280.053079) (xy 51.014894 -280.043235)
			(xy 50.968878 -280.025783) (xy 50.926257 -280.001176) (xy 50.888136 -279.970051) (xy 50.855501 -279.933214)
			(xy 50.829198 -279.891618) (xy 50.809907 -279.846342) (xy 50.79813 -279.798558) (xy 50.79417 -279.749504)
			(xy 49.505108 -279.749504) (xy 49.504613 -279.774111) (xy 49.496718 -279.822688) (xy 49.481134 -279.869369)
			(xy 49.458263 -279.912946) (xy 49.428698 -279.95229) (xy 49.393205 -279.986382) (xy 49.352702 -280.014338)
			(xy 49.30824 -280.035436) (xy 49.260969 -280.049128) (xy 49.212114 -280.05506) (xy 49.162939 -280.053079)
			(xy 49.11472 -280.043235) (xy 49.068704 -280.025783) (xy 49.026083 -280.001176) (xy 48.987962 -279.970051)
			(xy 48.955327 -279.933214) (xy 48.929024 -279.891618) (xy 48.909733 -279.846342) (xy 48.897956 -279.798558)
			(xy 48.893996 -279.749504) (xy 47.605188 -279.749504) (xy 47.604693 -279.774111) (xy 47.596798 -279.822688)
			(xy 47.581214 -279.869369) (xy 47.558343 -279.912946) (xy 47.528778 -279.95229) (xy 47.493285 -279.986382)
			(xy 47.452782 -280.014338) (xy 47.40832 -280.035436) (xy 47.361049 -280.049128) (xy 47.312194 -280.05506)
			(xy 47.263019 -280.053079) (xy 47.2148 -280.043235) (xy 47.168784 -280.025783) (xy 47.126163 -280.001176)
			(xy 47.088042 -279.970051) (xy 47.055407 -279.933214) (xy 47.029104 -279.891618) (xy 47.009813 -279.846342)
			(xy 46.998036 -279.798558) (xy 46.994076 -279.749504) (xy 45.705268 -279.749504) (xy 45.704773 -279.774111)
			(xy 45.696878 -279.822688) (xy 45.681294 -279.869369) (xy 45.658423 -279.912946) (xy 45.628858 -279.95229)
			(xy 45.593365 -279.986382) (xy 45.552862 -280.014338) (xy 45.5084 -280.035436) (xy 45.461129 -280.049128)
			(xy 45.412274 -280.05506) (xy 45.363099 -280.053079) (xy 45.31488 -280.043235) (xy 45.268864 -280.025783)
			(xy 45.226243 -280.001176) (xy 45.188122 -279.970051) (xy 45.155487 -279.933214) (xy 45.129184 -279.891618)
			(xy 45.109893 -279.846342) (xy 45.098116 -279.798558) (xy 45.094156 -279.749504) (xy 0.508 -279.749504)
			(xy 0.508 -280.699718) (xy 45.094156 -280.699718) (xy 45.098116 -280.650664) (xy 45.109893 -280.60288)
			(xy 45.129184 -280.557604) (xy 45.155487 -280.516008) (xy 45.188122 -280.479171) (xy 45.226243 -280.448046)
			(xy 45.268864 -280.423439) (xy 45.31488 -280.405987) (xy 45.363099 -280.396143) (xy 45.412274 -280.394162)
			(xy 45.461129 -280.400094) (xy 45.5084 -280.413786) (xy 45.552862 -280.434884) (xy 45.593365 -280.46284)
			(xy 45.628858 -280.496932) (xy 45.658423 -280.536276) (xy 45.681294 -280.579853) (xy 45.696878 -280.626534)
			(xy 45.704773 -280.675111) (xy 45.705268 -280.699718) (xy 46.994076 -280.699718) (xy 46.998036 -280.650664)
			(xy 47.009813 -280.60288) (xy 47.029104 -280.557604) (xy 47.055407 -280.516008) (xy 47.088042 -280.479171)
			(xy 47.126163 -280.448046) (xy 47.168784 -280.423439) (xy 47.2148 -280.405987) (xy 47.263019 -280.396143)
			(xy 47.312194 -280.394162) (xy 47.361049 -280.400094) (xy 47.40832 -280.413786) (xy 47.452782 -280.434884)
			(xy 47.493285 -280.46284) (xy 47.528778 -280.496932) (xy 47.558343 -280.536276) (xy 47.581214 -280.579853)
			(xy 47.596798 -280.626534) (xy 47.604693 -280.675111) (xy 47.605188 -280.699718) (xy 48.893996 -280.699718)
			(xy 48.897956 -280.650664) (xy 48.909733 -280.60288) (xy 48.929024 -280.557604) (xy 48.955327 -280.516008)
			(xy 48.987962 -280.479171) (xy 49.026083 -280.448046) (xy 49.068704 -280.423439) (xy 49.11472 -280.405987)
			(xy 49.162939 -280.396143) (xy 49.212114 -280.394162) (xy 49.260969 -280.400094) (xy 49.30824 -280.413786)
			(xy 49.352702 -280.434884) (xy 49.393205 -280.46284) (xy 49.428698 -280.496932) (xy 49.458263 -280.536276)
			(xy 49.481134 -280.579853) (xy 49.496718 -280.626534) (xy 49.504613 -280.675111) (xy 49.505108 -280.699718)
			(xy 50.79417 -280.699718) (xy 50.79813 -280.650664) (xy 50.809907 -280.60288) (xy 50.829198 -280.557604)
			(xy 50.855501 -280.516008) (xy 50.888136 -280.479171) (xy 50.926257 -280.448046) (xy 50.968878 -280.423439)
			(xy 51.014894 -280.405987) (xy 51.063113 -280.396143) (xy 51.112288 -280.394162) (xy 51.161143 -280.400094)
			(xy 51.208414 -280.413786) (xy 51.252876 -280.434884) (xy 51.293379 -280.46284) (xy 51.328872 -280.496932)
			(xy 51.358437 -280.536276) (xy 51.381308 -280.579853) (xy 51.396892 -280.626534) (xy 51.404787 -280.675111)
			(xy 51.405282 -280.699718) (xy 52.69409 -280.699718) (xy 52.69805 -280.650664) (xy 52.709827 -280.60288)
			(xy 52.729118 -280.557604) (xy 52.755421 -280.516008) (xy 52.788056 -280.479171) (xy 52.826177 -280.448046)
			(xy 52.868798 -280.423439) (xy 52.914814 -280.405987) (xy 52.963033 -280.396143) (xy 53.012208 -280.394162)
			(xy 53.061063 -280.400094) (xy 53.108334 -280.413786) (xy 53.152796 -280.434884) (xy 53.193299 -280.46284)
			(xy 53.228792 -280.496932) (xy 53.258357 -280.536276) (xy 53.281228 -280.579853) (xy 53.296812 -280.626534)
			(xy 53.304707 -280.675111) (xy 53.305202 -280.699718) (xy 54.59401 -280.699718) (xy 54.59797 -280.650664)
			(xy 54.609747 -280.60288) (xy 54.629038 -280.557604) (xy 54.655341 -280.516008) (xy 54.687976 -280.479171)
			(xy 54.726097 -280.448046) (xy 54.768718 -280.423439) (xy 54.814734 -280.405987) (xy 54.862953 -280.396143)
			(xy 54.912128 -280.394162) (xy 54.960983 -280.400094) (xy 55.008254 -280.413786) (xy 55.052716 -280.434884)
			(xy 55.093219 -280.46284) (xy 55.128712 -280.496932) (xy 55.158277 -280.536276) (xy 55.181148 -280.579853)
			(xy 55.196732 -280.626534) (xy 55.204627 -280.675111) (xy 55.205122 -280.699718) (xy 56.49393 -280.699718)
			(xy 56.49789 -280.650664) (xy 56.509667 -280.60288) (xy 56.528958 -280.557604) (xy 56.555261 -280.516008)
			(xy 56.587896 -280.479171) (xy 56.626017 -280.448046) (xy 56.668638 -280.423439) (xy 56.714654 -280.405987)
			(xy 56.762873 -280.396143) (xy 56.812048 -280.394162) (xy 56.860903 -280.400094) (xy 56.908174 -280.413786)
			(xy 56.952636 -280.434884) (xy 56.993139 -280.46284) (xy 57.028632 -280.496932) (xy 57.058197 -280.536276)
			(xy 57.081068 -280.579853) (xy 57.096652 -280.626534) (xy 57.104547 -280.675111) (xy 57.105042 -280.699718)
			(xy 58.394104 -280.699718) (xy 58.398064 -280.650664) (xy 58.409841 -280.60288) (xy 58.429132 -280.557604)
			(xy 58.455435 -280.516008) (xy 58.48807 -280.479171) (xy 58.526191 -280.448046) (xy 58.568812 -280.423439)
			(xy 58.614828 -280.405987) (xy 58.663047 -280.396143) (xy 58.712222 -280.394162) (xy 58.761077 -280.400094)
			(xy 58.808348 -280.413786) (xy 58.85281 -280.434884) (xy 58.893313 -280.46284) (xy 58.928806 -280.496932)
			(xy 58.958371 -280.536276) (xy 58.981242 -280.579853) (xy 58.996826 -280.626534) (xy 59.004721 -280.675111)
			(xy 59.005216 -280.699718) (xy 60.294024 -280.699718) (xy 60.297984 -280.650664) (xy 60.309761 -280.60288)
			(xy 60.329052 -280.557604) (xy 60.355355 -280.516008) (xy 60.38799 -280.479171) (xy 60.426111 -280.448046)
			(xy 60.468732 -280.423439) (xy 60.514748 -280.405987) (xy 60.562967 -280.396143) (xy 60.612142 -280.394162)
			(xy 60.660997 -280.400094) (xy 60.708268 -280.413786) (xy 60.75273 -280.434884) (xy 60.793233 -280.46284)
			(xy 60.828726 -280.496932) (xy 60.858291 -280.536276) (xy 60.881162 -280.579853) (xy 60.896746 -280.626534)
			(xy 60.904641 -280.675111) (xy 60.905136 -280.699718) (xy 62.193944 -280.699718) (xy 62.197904 -280.650664)
			(xy 62.209681 -280.60288) (xy 62.228972 -280.557604) (xy 62.255275 -280.516008) (xy 62.28791 -280.479171)
			(xy 62.326031 -280.448046) (xy 62.368652 -280.423439) (xy 62.414668 -280.405987) (xy 62.462887 -280.396143)
			(xy 62.512062 -280.394162) (xy 62.560917 -280.400094) (xy 62.608188 -280.413786) (xy 62.65265 -280.434884)
			(xy 62.693153 -280.46284) (xy 62.728646 -280.496932) (xy 62.758211 -280.536276) (xy 62.781082 -280.579853)
			(xy 62.796666 -280.626534) (xy 62.804561 -280.675111) (xy 62.805056 -280.699718) (xy 64.094118 -280.699718)
			(xy 64.098078 -280.650664) (xy 64.109855 -280.60288) (xy 64.129146 -280.557604) (xy 64.155449 -280.516008)
			(xy 64.188084 -280.479171) (xy 64.226205 -280.448046) (xy 64.268826 -280.423439) (xy 64.314842 -280.405987)
			(xy 64.363061 -280.396143) (xy 64.412236 -280.394162) (xy 64.461091 -280.400094) (xy 64.508362 -280.413786)
			(xy 64.552824 -280.434884) (xy 64.593327 -280.46284) (xy 64.62882 -280.496932) (xy 64.658385 -280.536276)
			(xy 64.681256 -280.579853) (xy 64.69684 -280.626534) (xy 64.704735 -280.675111) (xy 64.70523 -280.699718)
			(xy 65.994038 -280.699718) (xy 65.997998 -280.650664) (xy 66.009775 -280.60288) (xy 66.029066 -280.557604)
			(xy 66.055369 -280.516008) (xy 66.088004 -280.479171) (xy 66.126125 -280.448046) (xy 66.168746 -280.423439)
			(xy 66.214762 -280.405987) (xy 66.262981 -280.396143) (xy 66.312156 -280.394162) (xy 66.361011 -280.400094)
			(xy 66.408282 -280.413786) (xy 66.452744 -280.434884) (xy 66.493247 -280.46284) (xy 66.52874 -280.496932)
			(xy 66.558305 -280.536276) (xy 66.581176 -280.579853) (xy 66.59676 -280.626534) (xy 66.604655 -280.675111)
			(xy 66.60515 -280.699718) (xy 67.893958 -280.699718) (xy 67.897918 -280.650664) (xy 67.909695 -280.60288)
			(xy 67.928986 -280.557604) (xy 67.955289 -280.516008) (xy 67.987924 -280.479171) (xy 68.026045 -280.448046)
			(xy 68.068666 -280.423439) (xy 68.114682 -280.405987) (xy 68.162901 -280.396143) (xy 68.212076 -280.394162)
			(xy 68.260931 -280.400094) (xy 68.308202 -280.413786) (xy 68.352664 -280.434884) (xy 68.393167 -280.46284)
			(xy 68.42866 -280.496932) (xy 68.458225 -280.536276) (xy 68.481096 -280.579853) (xy 68.49668 -280.626534)
			(xy 68.504575 -280.675111) (xy 68.50507 -280.699718) (xy 69.794132 -280.699718) (xy 69.798092 -280.650664)
			(xy 69.809869 -280.60288) (xy 69.82916 -280.557604) (xy 69.855463 -280.516008) (xy 69.888098 -280.479171)
			(xy 69.926219 -280.448046) (xy 69.96884 -280.423439) (xy 70.014856 -280.405987) (xy 70.063075 -280.396143)
			(xy 70.11225 -280.394162) (xy 70.161105 -280.400094) (xy 70.208376 -280.413786) (xy 70.252838 -280.434884)
			(xy 70.293341 -280.46284) (xy 70.328834 -280.496932) (xy 70.358399 -280.536276) (xy 70.38127 -280.579853)
			(xy 70.396854 -280.626534) (xy 70.404749 -280.675111) (xy 70.405244 -280.699718) (xy 71.694052 -280.699718)
			(xy 71.698012 -280.650664) (xy 71.709789 -280.60288) (xy 71.72908 -280.557604) (xy 71.755383 -280.516008)
			(xy 71.788018 -280.479171) (xy 71.826139 -280.448046) (xy 71.86876 -280.423439) (xy 71.914776 -280.405987)
			(xy 71.962995 -280.396143) (xy 72.01217 -280.394162) (xy 72.061025 -280.400094) (xy 72.108296 -280.413786)
			(xy 72.152758 -280.434884) (xy 72.193261 -280.46284) (xy 72.228754 -280.496932) (xy 72.258319 -280.536276)
			(xy 72.28119 -280.579853) (xy 72.296774 -280.626534) (xy 72.304669 -280.675111) (xy 72.305164 -280.699718)
			(xy 73.593972 -280.699718) (xy 73.597932 -280.650664) (xy 73.609709 -280.60288) (xy 73.629 -280.557604)
			(xy 73.655303 -280.516008) (xy 73.687938 -280.479171) (xy 73.726059 -280.448046) (xy 73.76868 -280.423439)
			(xy 73.814696 -280.405987) (xy 73.862915 -280.396143) (xy 73.91209 -280.394162) (xy 73.960945 -280.400094)
			(xy 74.008216 -280.413786) (xy 74.052678 -280.434884) (xy 74.093181 -280.46284) (xy 74.128674 -280.496932)
			(xy 74.158239 -280.536276) (xy 74.18111 -280.579853) (xy 74.196694 -280.626534) (xy 74.204589 -280.675111)
			(xy 74.205084 -280.699718) (xy 75.494146 -280.699718) (xy 75.498106 -280.650664) (xy 75.509883 -280.60288)
			(xy 75.529174 -280.557604) (xy 75.555477 -280.516008) (xy 75.588112 -280.479171) (xy 75.626233 -280.448046)
			(xy 75.668854 -280.423439) (xy 75.71487 -280.405987) (xy 75.763089 -280.396143) (xy 75.812264 -280.394162)
			(xy 75.861119 -280.400094) (xy 75.90839 -280.413786) (xy 75.952852 -280.434884) (xy 75.993355 -280.46284)
			(xy 76.028848 -280.496932) (xy 76.058413 -280.536276) (xy 76.081284 -280.579853) (xy 76.096868 -280.626534)
			(xy 76.104763 -280.675111) (xy 76.105258 -280.699718) (xy 77.394066 -280.699718) (xy 77.398026 -280.650664)
			(xy 77.409803 -280.60288) (xy 77.429094 -280.557604) (xy 77.455397 -280.516008) (xy 77.488032 -280.479171)
			(xy 77.526153 -280.448046) (xy 77.568774 -280.423439) (xy 77.61479 -280.405987) (xy 77.663009 -280.396143)
			(xy 77.712184 -280.394162) (xy 77.761039 -280.400094) (xy 77.80831 -280.413786) (xy 77.852772 -280.434884)
			(xy 77.893275 -280.46284) (xy 77.928768 -280.496932) (xy 77.958333 -280.536276) (xy 77.981204 -280.579853)
			(xy 77.996788 -280.626534) (xy 78.004683 -280.675111) (xy 78.005178 -280.699718) (xy 79.293986 -280.699718)
			(xy 79.297946 -280.650664) (xy 79.309723 -280.60288) (xy 79.329014 -280.557604) (xy 79.355317 -280.516008)
			(xy 79.387952 -280.479171) (xy 79.426073 -280.448046) (xy 79.468694 -280.423439) (xy 79.51471 -280.405987)
			(xy 79.562929 -280.396143) (xy 79.612104 -280.394162) (xy 79.660959 -280.400094) (xy 79.70823 -280.413786)
			(xy 79.752692 -280.434884) (xy 79.793195 -280.46284) (xy 79.828688 -280.496932) (xy 79.858253 -280.536276)
			(xy 79.881124 -280.579853) (xy 79.896708 -280.626534) (xy 79.904603 -280.675111) (xy 79.905098 -280.699718)
			(xy 161.194254 -280.699718) (xy 161.198214 -280.650664) (xy 161.209991 -280.60288) (xy 161.229282 -280.557604)
			(xy 161.255585 -280.516008) (xy 161.28822 -280.479171) (xy 161.326341 -280.448046) (xy 161.368962 -280.423439)
			(xy 161.414978 -280.405987) (xy 161.463197 -280.396143) (xy 161.512372 -280.394162) (xy 161.561227 -280.400094)
			(xy 161.608498 -280.413786) (xy 161.65296 -280.434884) (xy 161.693463 -280.46284) (xy 161.728956 -280.496932)
			(xy 161.758521 -280.536276) (xy 161.781392 -280.579853) (xy 161.796976 -280.626534) (xy 161.804871 -280.675111)
			(xy 161.805366 -280.699718) (xy 163.094174 -280.699718) (xy 163.098134 -280.650664) (xy 163.109911 -280.60288)
			(xy 163.129202 -280.557604) (xy 163.155505 -280.516008) (xy 163.18814 -280.479171) (xy 163.226261 -280.448046)
			(xy 163.268882 -280.423439) (xy 163.314898 -280.405987) (xy 163.363117 -280.396143) (xy 163.412292 -280.394162)
			(xy 163.461147 -280.400094) (xy 163.508418 -280.413786) (xy 163.55288 -280.434884) (xy 163.593383 -280.46284)
			(xy 163.628876 -280.496932) (xy 163.658441 -280.536276) (xy 163.681312 -280.579853) (xy 163.696896 -280.626534)
			(xy 163.704791 -280.675111) (xy 163.705286 -280.699718) (xy 164.994094 -280.699718) (xy 164.998054 -280.650664)
			(xy 165.009831 -280.60288) (xy 165.029122 -280.557604) (xy 165.055425 -280.516008) (xy 165.08806 -280.479171)
			(xy 165.126181 -280.448046) (xy 165.168802 -280.423439) (xy 165.214818 -280.405987) (xy 165.263037 -280.396143)
			(xy 165.312212 -280.394162) (xy 165.361067 -280.400094) (xy 165.408338 -280.413786) (xy 165.4528 -280.434884)
			(xy 165.493303 -280.46284) (xy 165.528796 -280.496932) (xy 165.558361 -280.536276) (xy 165.581232 -280.579853)
			(xy 165.596816 -280.626534) (xy 165.604711 -280.675111) (xy 165.605206 -280.699718) (xy 166.894268 -280.699718)
			(xy 166.898228 -280.650664) (xy 166.910005 -280.60288) (xy 166.929296 -280.557604) (xy 166.955599 -280.516008)
			(xy 166.988234 -280.479171) (xy 167.026355 -280.448046) (xy 167.068976 -280.423439) (xy 167.114992 -280.405987)
			(xy 167.163211 -280.396143) (xy 167.212386 -280.394162) (xy 167.261241 -280.400094) (xy 167.308512 -280.413786)
			(xy 167.352974 -280.434884) (xy 167.393477 -280.46284) (xy 167.42897 -280.496932) (xy 167.458535 -280.536276)
			(xy 167.481406 -280.579853) (xy 167.49699 -280.626534) (xy 167.504885 -280.675111) (xy 167.50538 -280.699718)
			(xy 168.794188 -280.699718) (xy 168.798148 -280.650664) (xy 168.809925 -280.60288) (xy 168.829216 -280.557604)
			(xy 168.855519 -280.516008) (xy 168.888154 -280.479171) (xy 168.926275 -280.448046) (xy 168.968896 -280.423439)
			(xy 169.014912 -280.405987) (xy 169.063131 -280.396143) (xy 169.112306 -280.394162) (xy 169.161161 -280.400094)
			(xy 169.208432 -280.413786) (xy 169.252894 -280.434884) (xy 169.293397 -280.46284) (xy 169.32889 -280.496932)
			(xy 169.358455 -280.536276) (xy 169.381326 -280.579853) (xy 169.39691 -280.626534) (xy 169.404805 -280.675111)
			(xy 169.4053 -280.699718) (xy 170.694108 -280.699718) (xy 170.698068 -280.650664) (xy 170.709845 -280.60288)
			(xy 170.729136 -280.557604) (xy 170.755439 -280.516008) (xy 170.788074 -280.479171) (xy 170.826195 -280.448046)
			(xy 170.868816 -280.423439) (xy 170.914832 -280.405987) (xy 170.963051 -280.396143) (xy 171.012226 -280.394162)
			(xy 171.061081 -280.400094) (xy 171.108352 -280.413786) (xy 171.152814 -280.434884) (xy 171.193317 -280.46284)
			(xy 171.22881 -280.496932) (xy 171.258375 -280.536276) (xy 171.281246 -280.579853) (xy 171.29683 -280.626534)
			(xy 171.304725 -280.675111) (xy 171.30522 -280.699718) (xy 172.594028 -280.699718) (xy 172.597988 -280.650664)
			(xy 172.609765 -280.60288) (xy 172.629056 -280.557604) (xy 172.655359 -280.516008) (xy 172.687994 -280.479171)
			(xy 172.726115 -280.448046) (xy 172.768736 -280.423439) (xy 172.814752 -280.405987) (xy 172.862971 -280.396143)
			(xy 172.912146 -280.394162) (xy 172.961001 -280.400094) (xy 173.008272 -280.413786) (xy 173.052734 -280.434884)
			(xy 173.093237 -280.46284) (xy 173.12873 -280.496932) (xy 173.158295 -280.536276) (xy 173.181166 -280.579853)
			(xy 173.19675 -280.626534) (xy 173.204645 -280.675111) (xy 173.20514 -280.699718) (xy 174.494202 -280.699718)
			(xy 174.498162 -280.650664) (xy 174.509939 -280.60288) (xy 174.52923 -280.557604) (xy 174.555533 -280.516008)
			(xy 174.588168 -280.479171) (xy 174.626289 -280.448046) (xy 174.66891 -280.423439) (xy 174.714926 -280.405987)
			(xy 174.763145 -280.396143) (xy 174.81232 -280.394162) (xy 174.861175 -280.400094) (xy 174.908446 -280.413786)
			(xy 174.952908 -280.434884) (xy 174.993411 -280.46284) (xy 175.028904 -280.496932) (xy 175.058469 -280.536276)
			(xy 175.08134 -280.579853) (xy 175.096924 -280.626534) (xy 175.104819 -280.675111) (xy 175.105314 -280.699718)
			(xy 176.394122 -280.699718) (xy 176.398082 -280.650664) (xy 176.409859 -280.60288) (xy 176.42915 -280.557604)
			(xy 176.455453 -280.516008) (xy 176.488088 -280.479171) (xy 176.526209 -280.448046) (xy 176.56883 -280.423439)
			(xy 176.614846 -280.405987) (xy 176.663065 -280.396143) (xy 176.71224 -280.394162) (xy 176.761095 -280.400094)
			(xy 176.808366 -280.413786) (xy 176.852828 -280.434884) (xy 176.893331 -280.46284) (xy 176.928824 -280.496932)
			(xy 176.958389 -280.536276) (xy 176.98126 -280.579853) (xy 176.996844 -280.626534) (xy 177.004739 -280.675111)
			(xy 177.005234 -280.699718) (xy 178.294042 -280.699718) (xy 178.298002 -280.650664) (xy 178.309779 -280.60288)
			(xy 178.32907 -280.557604) (xy 178.355373 -280.516008) (xy 178.388008 -280.479171) (xy 178.426129 -280.448046)
			(xy 178.46875 -280.423439) (xy 178.514766 -280.405987) (xy 178.562985 -280.396143) (xy 178.61216 -280.394162)
			(xy 178.661015 -280.400094) (xy 178.708286 -280.413786) (xy 178.752748 -280.434884) (xy 178.793251 -280.46284)
			(xy 178.828744 -280.496932) (xy 178.858309 -280.536276) (xy 178.88118 -280.579853) (xy 178.896764 -280.626534)
			(xy 178.904659 -280.675111) (xy 178.905154 -280.699718) (xy 180.194216 -280.699718) (xy 180.198176 -280.650664)
			(xy 180.209953 -280.60288) (xy 180.229244 -280.557604) (xy 180.255547 -280.516008) (xy 180.288182 -280.479171)
			(xy 180.326303 -280.448046) (xy 180.368924 -280.423439) (xy 180.41494 -280.405987) (xy 180.463159 -280.396143)
			(xy 180.512334 -280.394162) (xy 180.561189 -280.400094) (xy 180.60846 -280.413786) (xy 180.652922 -280.434884)
			(xy 180.693425 -280.46284) (xy 180.728918 -280.496932) (xy 180.758483 -280.536276) (xy 180.781354 -280.579853)
			(xy 180.796938 -280.626534) (xy 180.804833 -280.675111) (xy 180.805328 -280.699718) (xy 182.094136 -280.699718)
			(xy 182.098096 -280.650664) (xy 182.109873 -280.60288) (xy 182.129164 -280.557604) (xy 182.155467 -280.516008)
			(xy 182.188102 -280.479171) (xy 182.226223 -280.448046) (xy 182.268844 -280.423439) (xy 182.31486 -280.405987)
			(xy 182.363079 -280.396143) (xy 182.412254 -280.394162) (xy 182.461109 -280.400094) (xy 182.50838 -280.413786)
			(xy 182.552842 -280.434884) (xy 182.593345 -280.46284) (xy 182.628838 -280.496932) (xy 182.658403 -280.536276)
			(xy 182.681274 -280.579853) (xy 182.696858 -280.626534) (xy 182.704753 -280.675111) (xy 182.705248 -280.699718)
			(xy 183.994056 -280.699718) (xy 183.998016 -280.650664) (xy 184.009793 -280.60288) (xy 184.029084 -280.557604)
			(xy 184.055387 -280.516008) (xy 184.088022 -280.479171) (xy 184.126143 -280.448046) (xy 184.168764 -280.423439)
			(xy 184.21478 -280.405987) (xy 184.262999 -280.396143) (xy 184.312174 -280.394162) (xy 184.361029 -280.400094)
			(xy 184.4083 -280.413786) (xy 184.452762 -280.434884) (xy 184.493265 -280.46284) (xy 184.528758 -280.496932)
			(xy 184.558323 -280.536276) (xy 184.581194 -280.579853) (xy 184.596778 -280.626534) (xy 184.604673 -280.675111)
			(xy 184.605168 -280.699718) (xy 185.89423 -280.699718) (xy 185.89819 -280.650664) (xy 185.909967 -280.60288)
			(xy 185.929258 -280.557604) (xy 185.955561 -280.516008) (xy 185.988196 -280.479171) (xy 186.026317 -280.448046)
			(xy 186.068938 -280.423439) (xy 186.114954 -280.405987) (xy 186.163173 -280.396143) (xy 186.212348 -280.394162)
			(xy 186.261203 -280.400094) (xy 186.308474 -280.413786) (xy 186.352936 -280.434884) (xy 186.393439 -280.46284)
			(xy 186.428932 -280.496932) (xy 186.458497 -280.536276) (xy 186.481368 -280.579853) (xy 186.496952 -280.626534)
			(xy 186.504847 -280.675111) (xy 186.505342 -280.699718) (xy 187.79415 -280.699718) (xy 187.79811 -280.650664)
			(xy 187.809887 -280.60288) (xy 187.829178 -280.557604) (xy 187.855481 -280.516008) (xy 187.888116 -280.479171)
			(xy 187.926237 -280.448046) (xy 187.968858 -280.423439) (xy 188.014874 -280.405987) (xy 188.063093 -280.396143)
			(xy 188.112268 -280.394162) (xy 188.161123 -280.400094) (xy 188.208394 -280.413786) (xy 188.252856 -280.434884)
			(xy 188.293359 -280.46284) (xy 188.328852 -280.496932) (xy 188.358417 -280.536276) (xy 188.381288 -280.579853)
			(xy 188.396872 -280.626534) (xy 188.404767 -280.675111) (xy 188.405262 -280.699718) (xy 189.69407 -280.699718)
			(xy 189.69803 -280.650664) (xy 189.709807 -280.60288) (xy 189.729098 -280.557604) (xy 189.755401 -280.516008)
			(xy 189.788036 -280.479171) (xy 189.826157 -280.448046) (xy 189.868778 -280.423439) (xy 189.914794 -280.405987)
			(xy 189.963013 -280.396143) (xy 190.012188 -280.394162) (xy 190.061043 -280.400094) (xy 190.108314 -280.413786)
			(xy 190.152776 -280.434884) (xy 190.193279 -280.46284) (xy 190.228772 -280.496932) (xy 190.258337 -280.536276)
			(xy 190.281208 -280.579853) (xy 190.296792 -280.626534) (xy 190.304687 -280.675111) (xy 190.305182 -280.699718)
			(xy 191.594244 -280.699718) (xy 191.598204 -280.650664) (xy 191.609981 -280.60288) (xy 191.629272 -280.557604)
			(xy 191.655575 -280.516008) (xy 191.68821 -280.479171) (xy 191.726331 -280.448046) (xy 191.768952 -280.423439)
			(xy 191.814968 -280.405987) (xy 191.863187 -280.396143) (xy 191.912362 -280.394162) (xy 191.961217 -280.400094)
			(xy 192.008488 -280.413786) (xy 192.05295 -280.434884) (xy 192.093453 -280.46284) (xy 192.128946 -280.496932)
			(xy 192.158511 -280.536276) (xy 192.181382 -280.579853) (xy 192.196966 -280.626534) (xy 192.204861 -280.675111)
			(xy 192.205356 -280.699718) (xy 193.494164 -280.699718) (xy 193.498124 -280.650664) (xy 193.509901 -280.60288)
			(xy 193.529192 -280.557604) (xy 193.555495 -280.516008) (xy 193.58813 -280.479171) (xy 193.626251 -280.448046)
			(xy 193.668872 -280.423439) (xy 193.714888 -280.405987) (xy 193.763107 -280.396143) (xy 193.812282 -280.394162)
			(xy 193.861137 -280.400094) (xy 193.908408 -280.413786) (xy 193.95287 -280.434884) (xy 193.993373 -280.46284)
			(xy 194.028866 -280.496932) (xy 194.058431 -280.536276) (xy 194.081302 -280.579853) (xy 194.096886 -280.626534)
			(xy 194.104781 -280.675111) (xy 194.105276 -280.699718) (xy 195.394084 -280.699718) (xy 195.398044 -280.650664)
			(xy 195.409821 -280.60288) (xy 195.429112 -280.557604) (xy 195.455415 -280.516008) (xy 195.48805 -280.479171)
			(xy 195.526171 -280.448046) (xy 195.568792 -280.423439) (xy 195.614808 -280.405987) (xy 195.663027 -280.396143)
			(xy 195.712202 -280.394162) (xy 195.761057 -280.400094) (xy 195.808328 -280.413786) (xy 195.85279 -280.434884)
			(xy 195.893293 -280.46284) (xy 195.928786 -280.496932) (xy 195.958351 -280.536276) (xy 195.981222 -280.579853)
			(xy 195.996806 -280.626534) (xy 196.004701 -280.675111) (xy 196.005191 -280.699464) (xy 277.294098 -280.699464)
			(xy 277.298058 -280.65041) (xy 277.309835 -280.602626) (xy 277.329126 -280.55735) (xy 277.355429 -280.515754)
			(xy 277.388064 -280.478917) (xy 277.426185 -280.447792) (xy 277.468806 -280.423185) (xy 277.514822 -280.405733)
			(xy 277.563041 -280.395889) (xy 277.612216 -280.393908) (xy 277.661071 -280.39984) (xy 277.708342 -280.413532)
			(xy 277.752804 -280.43463) (xy 277.793307 -280.462586) (xy 277.8288 -280.496678) (xy 277.858365 -280.536022)
			(xy 277.881236 -280.579599) (xy 277.89682 -280.62628) (xy 277.904715 -280.674857) (xy 277.90521 -280.699464)
			(xy 279.194018 -280.699464) (xy 279.197978 -280.65041) (xy 279.209755 -280.602626) (xy 279.229046 -280.55735)
			(xy 279.255349 -280.515754) (xy 279.287984 -280.478917) (xy 279.326105 -280.447792) (xy 279.368726 -280.423185)
			(xy 279.414742 -280.405733) (xy 279.462961 -280.395889) (xy 279.512136 -280.393908) (xy 279.560991 -280.39984)
			(xy 279.608262 -280.413532) (xy 279.652724 -280.43463) (xy 279.693227 -280.462586) (xy 279.72872 -280.496678)
			(xy 279.758285 -280.536022) (xy 279.781156 -280.579599) (xy 279.79674 -280.62628) (xy 279.804635 -280.674857)
			(xy 279.80513 -280.699464) (xy 281.093938 -280.699464) (xy 281.097898 -280.65041) (xy 281.109675 -280.602626)
			(xy 281.128966 -280.55735) (xy 281.155269 -280.515754) (xy 281.187904 -280.478917) (xy 281.226025 -280.447792)
			(xy 281.268646 -280.423185) (xy 281.314662 -280.405733) (xy 281.362881 -280.395889) (xy 281.412056 -280.393908)
			(xy 281.460911 -280.39984) (xy 281.508182 -280.413532) (xy 281.552644 -280.43463) (xy 281.593147 -280.462586)
			(xy 281.62864 -280.496678) (xy 281.658205 -280.536022) (xy 281.681076 -280.579599) (xy 281.69666 -280.62628)
			(xy 281.704555 -280.674857) (xy 281.70505 -280.699464) (xy 282.994112 -280.699464) (xy 282.998072 -280.65041)
			(xy 283.009849 -280.602626) (xy 283.02914 -280.55735) (xy 283.055443 -280.515754) (xy 283.088078 -280.478917)
			(xy 283.126199 -280.447792) (xy 283.16882 -280.423185) (xy 283.214836 -280.405733) (xy 283.263055 -280.395889)
			(xy 283.31223 -280.393908) (xy 283.361085 -280.39984) (xy 283.408356 -280.413532) (xy 283.452818 -280.43463)
			(xy 283.493321 -280.462586) (xy 283.528814 -280.496678) (xy 283.558379 -280.536022) (xy 283.58125 -280.579599)
			(xy 283.596834 -280.62628) (xy 283.604729 -280.674857) (xy 283.605224 -280.699464) (xy 284.894032 -280.699464)
			(xy 284.897992 -280.65041) (xy 284.909769 -280.602626) (xy 284.92906 -280.55735) (xy 284.955363 -280.515754)
			(xy 284.987998 -280.478917) (xy 285.026119 -280.447792) (xy 285.06874 -280.423185) (xy 285.114756 -280.405733)
			(xy 285.162975 -280.395889) (xy 285.21215 -280.393908) (xy 285.261005 -280.39984) (xy 285.308276 -280.413532)
			(xy 285.352738 -280.43463) (xy 285.393241 -280.462586) (xy 285.428734 -280.496678) (xy 285.458299 -280.536022)
			(xy 285.48117 -280.579599) (xy 285.496754 -280.62628) (xy 285.504649 -280.674857) (xy 285.505144 -280.699464)
			(xy 286.793952 -280.699464) (xy 286.797912 -280.65041) (xy 286.809689 -280.602626) (xy 286.82898 -280.55735)
			(xy 286.855283 -280.515754) (xy 286.887918 -280.478917) (xy 286.926039 -280.447792) (xy 286.96866 -280.423185)
			(xy 287.014676 -280.405733) (xy 287.062895 -280.395889) (xy 287.11207 -280.393908) (xy 287.160925 -280.39984)
			(xy 287.208196 -280.413532) (xy 287.252658 -280.43463) (xy 287.293161 -280.462586) (xy 287.328654 -280.496678)
			(xy 287.358219 -280.536022) (xy 287.38109 -280.579599) (xy 287.396674 -280.62628) (xy 287.404569 -280.674857)
			(xy 287.405064 -280.699464) (xy 288.693872 -280.699464) (xy 288.697832 -280.65041) (xy 288.709609 -280.602626)
			(xy 288.7289 -280.55735) (xy 288.755203 -280.515754) (xy 288.787838 -280.478917) (xy 288.825959 -280.447792)
			(xy 288.86858 -280.423185) (xy 288.914596 -280.405733) (xy 288.962815 -280.395889) (xy 289.01199 -280.393908)
			(xy 289.060845 -280.39984) (xy 289.108116 -280.413532) (xy 289.152578 -280.43463) (xy 289.193081 -280.462586)
			(xy 289.228574 -280.496678) (xy 289.258139 -280.536022) (xy 289.28101 -280.579599) (xy 289.296594 -280.62628)
			(xy 289.304489 -280.674857) (xy 289.304984 -280.699464) (xy 290.594046 -280.699464) (xy 290.598006 -280.65041)
			(xy 290.609783 -280.602626) (xy 290.629074 -280.55735) (xy 290.655377 -280.515754) (xy 290.688012 -280.478917)
			(xy 290.726133 -280.447792) (xy 290.768754 -280.423185) (xy 290.81477 -280.405733) (xy 290.862989 -280.395889)
			(xy 290.912164 -280.393908) (xy 290.961019 -280.39984) (xy 291.00829 -280.413532) (xy 291.052752 -280.43463)
			(xy 291.093255 -280.462586) (xy 291.128748 -280.496678) (xy 291.158313 -280.536022) (xy 291.181184 -280.579599)
			(xy 291.196768 -280.62628) (xy 291.204663 -280.674857) (xy 291.205158 -280.699464) (xy 292.493966 -280.699464)
			(xy 292.497926 -280.65041) (xy 292.509703 -280.602626) (xy 292.528994 -280.55735) (xy 292.555297 -280.515754)
			(xy 292.587932 -280.478917) (xy 292.626053 -280.447792) (xy 292.668674 -280.423185) (xy 292.71469 -280.405733)
			(xy 292.762909 -280.395889) (xy 292.812084 -280.393908) (xy 292.860939 -280.39984) (xy 292.90821 -280.413532)
			(xy 292.952672 -280.43463) (xy 292.993175 -280.462586) (xy 293.028668 -280.496678) (xy 293.058233 -280.536022)
			(xy 293.081104 -280.579599) (xy 293.096688 -280.62628) (xy 293.104583 -280.674857) (xy 293.105078 -280.699464)
			(xy 294.393886 -280.699464) (xy 294.397846 -280.65041) (xy 294.409623 -280.602626) (xy 294.428914 -280.55735)
			(xy 294.455217 -280.515754) (xy 294.487852 -280.478917) (xy 294.525973 -280.447792) (xy 294.568594 -280.423185)
			(xy 294.61461 -280.405733) (xy 294.662829 -280.395889) (xy 294.712004 -280.393908) (xy 294.760859 -280.39984)
			(xy 294.80813 -280.413532) (xy 294.852592 -280.43463) (xy 294.893095 -280.462586) (xy 294.928588 -280.496678)
			(xy 294.958153 -280.536022) (xy 294.981024 -280.579599) (xy 294.996608 -280.62628) (xy 295.004503 -280.674857)
			(xy 295.004998 -280.699464) (xy 296.29406 -280.699464) (xy 296.29802 -280.65041) (xy 296.309797 -280.602626)
			(xy 296.329088 -280.55735) (xy 296.355391 -280.515754) (xy 296.388026 -280.478917) (xy 296.426147 -280.447792)
			(xy 296.468768 -280.423185) (xy 296.514784 -280.405733) (xy 296.563003 -280.395889) (xy 296.612178 -280.393908)
			(xy 296.661033 -280.39984) (xy 296.708304 -280.413532) (xy 296.752766 -280.43463) (xy 296.793269 -280.462586)
			(xy 296.828762 -280.496678) (xy 296.858327 -280.536022) (xy 296.881198 -280.579599) (xy 296.896782 -280.62628)
			(xy 296.904677 -280.674857) (xy 296.905172 -280.699464) (xy 298.19398 -280.699464) (xy 298.19794 -280.65041)
			(xy 298.209717 -280.602626) (xy 298.229008 -280.55735) (xy 298.255311 -280.515754) (xy 298.287946 -280.478917)
			(xy 298.326067 -280.447792) (xy 298.368688 -280.423185) (xy 298.414704 -280.405733) (xy 298.462923 -280.395889)
			(xy 298.512098 -280.393908) (xy 298.560953 -280.39984) (xy 298.608224 -280.413532) (xy 298.652686 -280.43463)
			(xy 298.693189 -280.462586) (xy 298.728682 -280.496678) (xy 298.758247 -280.536022) (xy 298.781118 -280.579599)
			(xy 298.796702 -280.62628) (xy 298.804597 -280.674857) (xy 298.805092 -280.699464) (xy 300.0939 -280.699464)
			(xy 300.09786 -280.65041) (xy 300.109637 -280.602626) (xy 300.128928 -280.55735) (xy 300.155231 -280.515754)
			(xy 300.187866 -280.478917) (xy 300.225987 -280.447792) (xy 300.268608 -280.423185) (xy 300.314624 -280.405733)
			(xy 300.362843 -280.395889) (xy 300.412018 -280.393908) (xy 300.460873 -280.39984) (xy 300.508144 -280.413532)
			(xy 300.552606 -280.43463) (xy 300.593109 -280.462586) (xy 300.628602 -280.496678) (xy 300.658167 -280.536022)
			(xy 300.681038 -280.579599) (xy 300.696622 -280.62628) (xy 300.704517 -280.674857) (xy 300.705012 -280.699464)
			(xy 301.994074 -280.699464) (xy 301.998034 -280.65041) (xy 302.009811 -280.602626) (xy 302.029102 -280.55735)
			(xy 302.055405 -280.515754) (xy 302.08804 -280.478917) (xy 302.126161 -280.447792) (xy 302.168782 -280.423185)
			(xy 302.214798 -280.405733) (xy 302.263017 -280.395889) (xy 302.312192 -280.393908) (xy 302.361047 -280.39984)
			(xy 302.408318 -280.413532) (xy 302.45278 -280.43463) (xy 302.493283 -280.462586) (xy 302.528776 -280.496678)
			(xy 302.558341 -280.536022) (xy 302.581212 -280.579599) (xy 302.596796 -280.62628) (xy 302.604691 -280.674857)
			(xy 302.605186 -280.699464) (xy 303.893994 -280.699464) (xy 303.897954 -280.65041) (xy 303.909731 -280.602626)
			(xy 303.929022 -280.55735) (xy 303.955325 -280.515754) (xy 303.98796 -280.478917) (xy 304.026081 -280.447792)
			(xy 304.068702 -280.423185) (xy 304.114718 -280.405733) (xy 304.162937 -280.395889) (xy 304.212112 -280.393908)
			(xy 304.260967 -280.39984) (xy 304.308238 -280.413532) (xy 304.3527 -280.43463) (xy 304.393203 -280.462586)
			(xy 304.428696 -280.496678) (xy 304.458261 -280.536022) (xy 304.481132 -280.579599) (xy 304.496716 -280.62628)
			(xy 304.504611 -280.674857) (xy 304.505106 -280.699464) (xy 305.793914 -280.699464) (xy 305.797874 -280.65041)
			(xy 305.809651 -280.602626) (xy 305.828942 -280.55735) (xy 305.855245 -280.515754) (xy 305.88788 -280.478917)
			(xy 305.926001 -280.447792) (xy 305.968622 -280.423185) (xy 306.014638 -280.405733) (xy 306.062857 -280.395889)
			(xy 306.112032 -280.393908) (xy 306.160887 -280.39984) (xy 306.208158 -280.413532) (xy 306.25262 -280.43463)
			(xy 306.293123 -280.462586) (xy 306.328616 -280.496678) (xy 306.358181 -280.536022) (xy 306.381052 -280.579599)
			(xy 306.396636 -280.62628) (xy 306.404531 -280.674857) (xy 306.405026 -280.699464) (xy 307.694088 -280.699464)
			(xy 307.698048 -280.65041) (xy 307.709825 -280.602626) (xy 307.729116 -280.55735) (xy 307.755419 -280.515754)
			(xy 307.788054 -280.478917) (xy 307.826175 -280.447792) (xy 307.868796 -280.423185) (xy 307.914812 -280.405733)
			(xy 307.963031 -280.395889) (xy 308.012206 -280.393908) (xy 308.061061 -280.39984) (xy 308.108332 -280.413532)
			(xy 308.152794 -280.43463) (xy 308.193297 -280.462586) (xy 308.22879 -280.496678) (xy 308.258355 -280.536022)
			(xy 308.281226 -280.579599) (xy 308.29681 -280.62628) (xy 308.304705 -280.674857) (xy 308.3052 -280.699464)
			(xy 309.594008 -280.699464) (xy 309.597968 -280.65041) (xy 309.609745 -280.602626) (xy 309.629036 -280.55735)
			(xy 309.655339 -280.515754) (xy 309.687974 -280.478917) (xy 309.726095 -280.447792) (xy 309.768716 -280.423185)
			(xy 309.814732 -280.405733) (xy 309.862951 -280.395889) (xy 309.912126 -280.393908) (xy 309.960981 -280.39984)
			(xy 310.008252 -280.413532) (xy 310.052714 -280.43463) (xy 310.093217 -280.462586) (xy 310.12871 -280.496678)
			(xy 310.158275 -280.536022) (xy 310.181146 -280.579599) (xy 310.19673 -280.62628) (xy 310.204625 -280.674857)
			(xy 310.20512 -280.699464) (xy 310.205115 -280.699718) (xy 311.493928 -280.699718) (xy 311.497888 -280.650664)
			(xy 311.509665 -280.60288) (xy 311.528956 -280.557604) (xy 311.555259 -280.516008) (xy 311.587894 -280.479171)
			(xy 311.626015 -280.448046) (xy 311.668636 -280.423439) (xy 311.714652 -280.405987) (xy 311.762871 -280.396143)
			(xy 311.812046 -280.394162) (xy 311.860901 -280.400094) (xy 311.908172 -280.413786) (xy 311.952634 -280.434884)
			(xy 311.993137 -280.46284) (xy 312.02863 -280.496932) (xy 312.058195 -280.536276) (xy 312.081066 -280.579853)
			(xy 312.09665 -280.626534) (xy 312.104545 -280.675111) (xy 312.105035 -280.699464) (xy 393.394196 -280.699464)
			(xy 393.398156 -280.65041) (xy 393.409933 -280.602626) (xy 393.429224 -280.55735) (xy 393.455527 -280.515754)
			(xy 393.488162 -280.478917) (xy 393.526283 -280.447792) (xy 393.568904 -280.423185) (xy 393.61492 -280.405733)
			(xy 393.663139 -280.395889) (xy 393.712314 -280.393908) (xy 393.761169 -280.39984) (xy 393.80844 -280.413532)
			(xy 393.852902 -280.43463) (xy 393.893405 -280.462586) (xy 393.928898 -280.496678) (xy 393.958463 -280.536022)
			(xy 393.981334 -280.579599) (xy 393.996918 -280.62628) (xy 394.004813 -280.674857) (xy 394.005308 -280.699464)
			(xy 395.294116 -280.699464) (xy 395.298076 -280.65041) (xy 395.309853 -280.602626) (xy 395.329144 -280.55735)
			(xy 395.355447 -280.515754) (xy 395.388082 -280.478917) (xy 395.426203 -280.447792) (xy 395.468824 -280.423185)
			(xy 395.51484 -280.405733) (xy 395.563059 -280.395889) (xy 395.612234 -280.393908) (xy 395.661089 -280.39984)
			(xy 395.70836 -280.413532) (xy 395.752822 -280.43463) (xy 395.793325 -280.462586) (xy 395.828818 -280.496678)
			(xy 395.858383 -280.536022) (xy 395.881254 -280.579599) (xy 395.896838 -280.62628) (xy 395.904733 -280.674857)
			(xy 395.905228 -280.699464) (xy 397.194036 -280.699464) (xy 397.197996 -280.65041) (xy 397.209773 -280.602626)
			(xy 397.229064 -280.55735) (xy 397.255367 -280.515754) (xy 397.288002 -280.478917) (xy 397.326123 -280.447792)
			(xy 397.368744 -280.423185) (xy 397.41476 -280.405733) (xy 397.462979 -280.395889) (xy 397.512154 -280.393908)
			(xy 397.561009 -280.39984) (xy 397.60828 -280.413532) (xy 397.652742 -280.43463) (xy 397.693245 -280.462586)
			(xy 397.728738 -280.496678) (xy 397.758303 -280.536022) (xy 397.781174 -280.579599) (xy 397.796758 -280.62628)
			(xy 397.804653 -280.674857) (xy 397.805148 -280.699464) (xy 399.09421 -280.699464) (xy 399.09817 -280.65041)
			(xy 399.109947 -280.602626) (xy 399.129238 -280.55735) (xy 399.155541 -280.515754) (xy 399.188176 -280.478917)
			(xy 399.226297 -280.447792) (xy 399.268918 -280.423185) (xy 399.314934 -280.405733) (xy 399.363153 -280.395889)
			(xy 399.412328 -280.393908) (xy 399.461183 -280.39984) (xy 399.508454 -280.413532) (xy 399.552916 -280.43463)
			(xy 399.593419 -280.462586) (xy 399.628912 -280.496678) (xy 399.658477 -280.536022) (xy 399.681348 -280.579599)
			(xy 399.696932 -280.62628) (xy 399.704827 -280.674857) (xy 399.705322 -280.699464) (xy 400.99413 -280.699464)
			(xy 400.99809 -280.65041) (xy 401.009867 -280.602626) (xy 401.029158 -280.55735) (xy 401.055461 -280.515754)
			(xy 401.088096 -280.478917) (xy 401.126217 -280.447792) (xy 401.168838 -280.423185) (xy 401.214854 -280.405733)
			(xy 401.263073 -280.395889) (xy 401.312248 -280.393908) (xy 401.361103 -280.39984) (xy 401.408374 -280.413532)
			(xy 401.452836 -280.43463) (xy 401.493339 -280.462586) (xy 401.528832 -280.496678) (xy 401.558397 -280.536022)
			(xy 401.581268 -280.579599) (xy 401.596852 -280.62628) (xy 401.604747 -280.674857) (xy 401.605242 -280.699464)
			(xy 402.89405 -280.699464) (xy 402.89801 -280.65041) (xy 402.909787 -280.602626) (xy 402.929078 -280.55735)
			(xy 402.955381 -280.515754) (xy 402.988016 -280.478917) (xy 403.026137 -280.447792) (xy 403.068758 -280.423185)
			(xy 403.114774 -280.405733) (xy 403.162993 -280.395889) (xy 403.212168 -280.393908) (xy 403.261023 -280.39984)
			(xy 403.308294 -280.413532) (xy 403.352756 -280.43463) (xy 403.393259 -280.462586) (xy 403.428752 -280.496678)
			(xy 403.458317 -280.536022) (xy 403.481188 -280.579599) (xy 403.496772 -280.62628) (xy 403.504667 -280.674857)
			(xy 403.505162 -280.699464) (xy 404.79397 -280.699464) (xy 404.79793 -280.65041) (xy 404.809707 -280.602626)
			(xy 404.828998 -280.55735) (xy 404.855301 -280.515754) (xy 404.887936 -280.478917) (xy 404.926057 -280.447792)
			(xy 404.968678 -280.423185) (xy 405.014694 -280.405733) (xy 405.062913 -280.395889) (xy 405.112088 -280.393908)
			(xy 405.160943 -280.39984) (xy 405.208214 -280.413532) (xy 405.252676 -280.43463) (xy 405.293179 -280.462586)
			(xy 405.328672 -280.496678) (xy 405.358237 -280.536022) (xy 405.381108 -280.579599) (xy 405.396692 -280.62628)
			(xy 405.404587 -280.674857) (xy 405.405082 -280.699464) (xy 406.694144 -280.699464) (xy 406.698104 -280.65041)
			(xy 406.709881 -280.602626) (xy 406.729172 -280.55735) (xy 406.755475 -280.515754) (xy 406.78811 -280.478917)
			(xy 406.826231 -280.447792) (xy 406.868852 -280.423185) (xy 406.914868 -280.405733) (xy 406.963087 -280.395889)
			(xy 407.012262 -280.393908) (xy 407.061117 -280.39984) (xy 407.108388 -280.413532) (xy 407.15285 -280.43463)
			(xy 407.193353 -280.462586) (xy 407.228846 -280.496678) (xy 407.258411 -280.536022) (xy 407.281282 -280.579599)
			(xy 407.296866 -280.62628) (xy 407.304761 -280.674857) (xy 407.305256 -280.699464) (xy 408.594064 -280.699464)
			(xy 408.598024 -280.65041) (xy 408.609801 -280.602626) (xy 408.629092 -280.55735) (xy 408.655395 -280.515754)
			(xy 408.68803 -280.478917) (xy 408.726151 -280.447792) (xy 408.768772 -280.423185) (xy 408.814788 -280.405733)
			(xy 408.863007 -280.395889) (xy 408.912182 -280.393908) (xy 408.961037 -280.39984) (xy 409.008308 -280.413532)
			(xy 409.05277 -280.43463) (xy 409.093273 -280.462586) (xy 409.128766 -280.496678) (xy 409.158331 -280.536022)
			(xy 409.181202 -280.579599) (xy 409.196786 -280.62628) (xy 409.204681 -280.674857) (xy 409.205176 -280.699464)
			(xy 410.493984 -280.699464) (xy 410.497944 -280.65041) (xy 410.509721 -280.602626) (xy 410.529012 -280.55735)
			(xy 410.555315 -280.515754) (xy 410.58795 -280.478917) (xy 410.626071 -280.447792) (xy 410.668692 -280.423185)
			(xy 410.714708 -280.405733) (xy 410.762927 -280.395889) (xy 410.812102 -280.393908) (xy 410.860957 -280.39984)
			(xy 410.908228 -280.413532) (xy 410.95269 -280.43463) (xy 410.993193 -280.462586) (xy 411.028686 -280.496678)
			(xy 411.058251 -280.536022) (xy 411.081122 -280.579599) (xy 411.096706 -280.62628) (xy 411.104601 -280.674857)
			(xy 411.105096 -280.699464) (xy 412.394158 -280.699464) (xy 412.398118 -280.65041) (xy 412.409895 -280.602626)
			(xy 412.429186 -280.55735) (xy 412.455489 -280.515754) (xy 412.488124 -280.478917) (xy 412.526245 -280.447792)
			(xy 412.568866 -280.423185) (xy 412.614882 -280.405733) (xy 412.663101 -280.395889) (xy 412.712276 -280.393908)
			(xy 412.761131 -280.39984) (xy 412.808402 -280.413532) (xy 412.852864 -280.43463) (xy 412.893367 -280.462586)
			(xy 412.92886 -280.496678) (xy 412.958425 -280.536022) (xy 412.981296 -280.579599) (xy 412.99688 -280.62628)
			(xy 413.004775 -280.674857) (xy 413.00527 -280.699464) (xy 414.294078 -280.699464) (xy 414.298038 -280.65041)
			(xy 414.309815 -280.602626) (xy 414.329106 -280.55735) (xy 414.355409 -280.515754) (xy 414.388044 -280.478917)
			(xy 414.426165 -280.447792) (xy 414.468786 -280.423185) (xy 414.514802 -280.405733) (xy 414.563021 -280.395889)
			(xy 414.612196 -280.393908) (xy 414.661051 -280.39984) (xy 414.708322 -280.413532) (xy 414.752784 -280.43463)
			(xy 414.793287 -280.462586) (xy 414.82878 -280.496678) (xy 414.858345 -280.536022) (xy 414.881216 -280.579599)
			(xy 414.8968 -280.62628) (xy 414.904695 -280.674857) (xy 414.90519 -280.699464) (xy 416.193998 -280.699464)
			(xy 416.197958 -280.65041) (xy 416.209735 -280.602626) (xy 416.229026 -280.55735) (xy 416.255329 -280.515754)
			(xy 416.287964 -280.478917) (xy 416.326085 -280.447792) (xy 416.368706 -280.423185) (xy 416.414722 -280.405733)
			(xy 416.462941 -280.395889) (xy 416.512116 -280.393908) (xy 416.560971 -280.39984) (xy 416.608242 -280.413532)
			(xy 416.652704 -280.43463) (xy 416.693207 -280.462586) (xy 416.7287 -280.496678) (xy 416.758265 -280.536022)
			(xy 416.781136 -280.579599) (xy 416.79672 -280.62628) (xy 416.804615 -280.674857) (xy 416.80511 -280.699464)
			(xy 418.094172 -280.699464) (xy 418.098132 -280.65041) (xy 418.109909 -280.602626) (xy 418.1292 -280.55735)
			(xy 418.155503 -280.515754) (xy 418.188138 -280.478917) (xy 418.226259 -280.447792) (xy 418.26888 -280.423185)
			(xy 418.314896 -280.405733) (xy 418.363115 -280.395889) (xy 418.41229 -280.393908) (xy 418.461145 -280.39984)
			(xy 418.508416 -280.413532) (xy 418.552878 -280.43463) (xy 418.593381 -280.462586) (xy 418.628874 -280.496678)
			(xy 418.658439 -280.536022) (xy 418.68131 -280.579599) (xy 418.696894 -280.62628) (xy 418.704789 -280.674857)
			(xy 418.705284 -280.699464) (xy 419.994092 -280.699464) (xy 419.998052 -280.65041) (xy 420.009829 -280.602626)
			(xy 420.02912 -280.55735) (xy 420.055423 -280.515754) (xy 420.088058 -280.478917) (xy 420.126179 -280.447792)
			(xy 420.1688 -280.423185) (xy 420.214816 -280.405733) (xy 420.263035 -280.395889) (xy 420.31221 -280.393908)
			(xy 420.361065 -280.39984) (xy 420.408336 -280.413532) (xy 420.452798 -280.43463) (xy 420.493301 -280.462586)
			(xy 420.528794 -280.496678) (xy 420.558359 -280.536022) (xy 420.58123 -280.579599) (xy 420.596814 -280.62628)
			(xy 420.604709 -280.674857) (xy 420.605204 -280.699464) (xy 421.894012 -280.699464) (xy 421.897972 -280.65041)
			(xy 421.909749 -280.602626) (xy 421.92904 -280.55735) (xy 421.955343 -280.515754) (xy 421.987978 -280.478917)
			(xy 422.026099 -280.447792) (xy 422.06872 -280.423185) (xy 422.114736 -280.405733) (xy 422.162955 -280.395889)
			(xy 422.21213 -280.393908) (xy 422.260985 -280.39984) (xy 422.308256 -280.413532) (xy 422.352718 -280.43463)
			(xy 422.393221 -280.462586) (xy 422.428714 -280.496678) (xy 422.458279 -280.536022) (xy 422.48115 -280.579599)
			(xy 422.496734 -280.62628) (xy 422.504629 -280.674857) (xy 422.505124 -280.699464) (xy 423.794186 -280.699464)
			(xy 423.798146 -280.65041) (xy 423.809923 -280.602626) (xy 423.829214 -280.55735) (xy 423.855517 -280.515754)
			(xy 423.888152 -280.478917) (xy 423.926273 -280.447792) (xy 423.968894 -280.423185) (xy 424.01491 -280.405733)
			(xy 424.063129 -280.395889) (xy 424.112304 -280.393908) (xy 424.161159 -280.39984) (xy 424.20843 -280.413532)
			(xy 424.252892 -280.43463) (xy 424.293395 -280.462586) (xy 424.328888 -280.496678) (xy 424.358453 -280.536022)
			(xy 424.381324 -280.579599) (xy 424.396908 -280.62628) (xy 424.404803 -280.674857) (xy 424.405298 -280.699464)
			(xy 425.694106 -280.699464) (xy 425.698066 -280.65041) (xy 425.709843 -280.602626) (xy 425.729134 -280.55735)
			(xy 425.755437 -280.515754) (xy 425.788072 -280.478917) (xy 425.826193 -280.447792) (xy 425.868814 -280.423185)
			(xy 425.91483 -280.405733) (xy 425.963049 -280.395889) (xy 426.012224 -280.393908) (xy 426.061079 -280.39984)
			(xy 426.10835 -280.413532) (xy 426.152812 -280.43463) (xy 426.193315 -280.462586) (xy 426.228808 -280.496678)
			(xy 426.258373 -280.536022) (xy 426.281244 -280.579599) (xy 426.296828 -280.62628) (xy 426.304723 -280.674857)
			(xy 426.305218 -280.699464) (xy 426.305213 -280.699718) (xy 427.594026 -280.699718) (xy 427.597986 -280.650664)
			(xy 427.609763 -280.60288) (xy 427.629054 -280.557604) (xy 427.655357 -280.516008) (xy 427.687992 -280.479171)
			(xy 427.726113 -280.448046) (xy 427.768734 -280.423439) (xy 427.81475 -280.405987) (xy 427.862969 -280.396143)
			(xy 427.912144 -280.394162) (xy 427.960999 -280.400094) (xy 428.00827 -280.413786) (xy 428.052732 -280.434884)
			(xy 428.093235 -280.46284) (xy 428.128728 -280.496932) (xy 428.158293 -280.536276) (xy 428.181164 -280.579853)
			(xy 428.196748 -280.626534) (xy 428.204643 -280.675111) (xy 428.205138 -280.699718) (xy 428.204643 -280.724325)
			(xy 428.196748 -280.772902) (xy 428.181164 -280.819583) (xy 428.158293 -280.86316) (xy 428.128728 -280.902504)
			(xy 428.093235 -280.936596) (xy 428.052732 -280.964552) (xy 428.00827 -280.98565) (xy 427.960999 -280.999342)
			(xy 427.912144 -281.005274) (xy 427.862969 -281.003293) (xy 427.81475 -280.993449) (xy 427.768734 -280.975997)
			(xy 427.726113 -280.95139) (xy 427.687992 -280.920265) (xy 427.655357 -280.883428) (xy 427.629054 -280.841832)
			(xy 427.609763 -280.796556) (xy 427.597986 -280.748772) (xy 427.594026 -280.699718) (xy 426.305213 -280.699718)
			(xy 426.304723 -280.724071) (xy 426.296828 -280.772648) (xy 426.281244 -280.819329) (xy 426.258373 -280.862906)
			(xy 426.228808 -280.90225) (xy 426.193315 -280.936342) (xy 426.152812 -280.964298) (xy 426.10835 -280.985396)
			(xy 426.061079 -280.999088) (xy 426.012224 -281.00502) (xy 425.963049 -281.003039) (xy 425.91483 -280.993195)
			(xy 425.868814 -280.975743) (xy 425.826193 -280.951136) (xy 425.788072 -280.920011) (xy 425.755437 -280.883174)
			(xy 425.729134 -280.841578) (xy 425.709843 -280.796302) (xy 425.698066 -280.748518) (xy 425.694106 -280.699464)
			(xy 424.405298 -280.699464) (xy 424.404803 -280.724071) (xy 424.396908 -280.772648) (xy 424.381324 -280.819329)
			(xy 424.358453 -280.862906) (xy 424.328888 -280.90225) (xy 424.293395 -280.936342) (xy 424.252892 -280.964298)
			(xy 424.20843 -280.985396) (xy 424.161159 -280.999088) (xy 424.112304 -281.00502) (xy 424.063129 -281.003039)
			(xy 424.01491 -280.993195) (xy 423.968894 -280.975743) (xy 423.926273 -280.951136) (xy 423.888152 -280.920011)
			(xy 423.855517 -280.883174) (xy 423.829214 -280.841578) (xy 423.809923 -280.796302) (xy 423.798146 -280.748518)
			(xy 423.794186 -280.699464) (xy 422.505124 -280.699464) (xy 422.504629 -280.724071) (xy 422.496734 -280.772648)
			(xy 422.48115 -280.819329) (xy 422.458279 -280.862906) (xy 422.428714 -280.90225) (xy 422.393221 -280.936342)
			(xy 422.352718 -280.964298) (xy 422.308256 -280.985396) (xy 422.260985 -280.999088) (xy 422.21213 -281.00502)
			(xy 422.162955 -281.003039) (xy 422.114736 -280.993195) (xy 422.06872 -280.975743) (xy 422.026099 -280.951136)
			(xy 421.987978 -280.920011) (xy 421.955343 -280.883174) (xy 421.92904 -280.841578) (xy 421.909749 -280.796302)
			(xy 421.897972 -280.748518) (xy 421.894012 -280.699464) (xy 420.605204 -280.699464) (xy 420.604709 -280.724071)
			(xy 420.596814 -280.772648) (xy 420.58123 -280.819329) (xy 420.558359 -280.862906) (xy 420.528794 -280.90225)
			(xy 420.493301 -280.936342) (xy 420.452798 -280.964298) (xy 420.408336 -280.985396) (xy 420.361065 -280.999088)
			(xy 420.31221 -281.00502) (xy 420.263035 -281.003039) (xy 420.214816 -280.993195) (xy 420.1688 -280.975743)
			(xy 420.126179 -280.951136) (xy 420.088058 -280.920011) (xy 420.055423 -280.883174) (xy 420.02912 -280.841578)
			(xy 420.009829 -280.796302) (xy 419.998052 -280.748518) (xy 419.994092 -280.699464) (xy 418.705284 -280.699464)
			(xy 418.704789 -280.724071) (xy 418.696894 -280.772648) (xy 418.68131 -280.819329) (xy 418.658439 -280.862906)
			(xy 418.628874 -280.90225) (xy 418.593381 -280.936342) (xy 418.552878 -280.964298) (xy 418.508416 -280.985396)
			(xy 418.461145 -280.999088) (xy 418.41229 -281.00502) (xy 418.363115 -281.003039) (xy 418.314896 -280.993195)
			(xy 418.26888 -280.975743) (xy 418.226259 -280.951136) (xy 418.188138 -280.920011) (xy 418.155503 -280.883174)
			(xy 418.1292 -280.841578) (xy 418.109909 -280.796302) (xy 418.098132 -280.748518) (xy 418.094172 -280.699464)
			(xy 416.80511 -280.699464) (xy 416.804615 -280.724071) (xy 416.79672 -280.772648) (xy 416.781136 -280.819329)
			(xy 416.758265 -280.862906) (xy 416.7287 -280.90225) (xy 416.693207 -280.936342) (xy 416.652704 -280.964298)
			(xy 416.608242 -280.985396) (xy 416.560971 -280.999088) (xy 416.512116 -281.00502) (xy 416.462941 -281.003039)
			(xy 416.414722 -280.993195) (xy 416.368706 -280.975743) (xy 416.326085 -280.951136) (xy 416.287964 -280.920011)
			(xy 416.255329 -280.883174) (xy 416.229026 -280.841578) (xy 416.209735 -280.796302) (xy 416.197958 -280.748518)
			(xy 416.193998 -280.699464) (xy 414.90519 -280.699464) (xy 414.904695 -280.724071) (xy 414.8968 -280.772648)
			(xy 414.881216 -280.819329) (xy 414.858345 -280.862906) (xy 414.82878 -280.90225) (xy 414.793287 -280.936342)
			(xy 414.752784 -280.964298) (xy 414.708322 -280.985396) (xy 414.661051 -280.999088) (xy 414.612196 -281.00502)
			(xy 414.563021 -281.003039) (xy 414.514802 -280.993195) (xy 414.468786 -280.975743) (xy 414.426165 -280.951136)
			(xy 414.388044 -280.920011) (xy 414.355409 -280.883174) (xy 414.329106 -280.841578) (xy 414.309815 -280.796302)
			(xy 414.298038 -280.748518) (xy 414.294078 -280.699464) (xy 413.00527 -280.699464) (xy 413.004775 -280.724071)
			(xy 412.99688 -280.772648) (xy 412.981296 -280.819329) (xy 412.958425 -280.862906) (xy 412.92886 -280.90225)
			(xy 412.893367 -280.936342) (xy 412.852864 -280.964298) (xy 412.808402 -280.985396) (xy 412.761131 -280.999088)
			(xy 412.712276 -281.00502) (xy 412.663101 -281.003039) (xy 412.614882 -280.993195) (xy 412.568866 -280.975743)
			(xy 412.526245 -280.951136) (xy 412.488124 -280.920011) (xy 412.455489 -280.883174) (xy 412.429186 -280.841578)
			(xy 412.409895 -280.796302) (xy 412.398118 -280.748518) (xy 412.394158 -280.699464) (xy 411.105096 -280.699464)
			(xy 411.104601 -280.724071) (xy 411.096706 -280.772648) (xy 411.081122 -280.819329) (xy 411.058251 -280.862906)
			(xy 411.028686 -280.90225) (xy 410.993193 -280.936342) (xy 410.95269 -280.964298) (xy 410.908228 -280.985396)
			(xy 410.860957 -280.999088) (xy 410.812102 -281.00502) (xy 410.762927 -281.003039) (xy 410.714708 -280.993195)
			(xy 410.668692 -280.975743) (xy 410.626071 -280.951136) (xy 410.58795 -280.920011) (xy 410.555315 -280.883174)
			(xy 410.529012 -280.841578) (xy 410.509721 -280.796302) (xy 410.497944 -280.748518) (xy 410.493984 -280.699464)
			(xy 409.205176 -280.699464) (xy 409.204681 -280.724071) (xy 409.196786 -280.772648) (xy 409.181202 -280.819329)
			(xy 409.158331 -280.862906) (xy 409.128766 -280.90225) (xy 409.093273 -280.936342) (xy 409.05277 -280.964298)
			(xy 409.008308 -280.985396) (xy 408.961037 -280.999088) (xy 408.912182 -281.00502) (xy 408.863007 -281.003039)
			(xy 408.814788 -280.993195) (xy 408.768772 -280.975743) (xy 408.726151 -280.951136) (xy 408.68803 -280.920011)
			(xy 408.655395 -280.883174) (xy 408.629092 -280.841578) (xy 408.609801 -280.796302) (xy 408.598024 -280.748518)
			(xy 408.594064 -280.699464) (xy 407.305256 -280.699464) (xy 407.304761 -280.724071) (xy 407.296866 -280.772648)
			(xy 407.281282 -280.819329) (xy 407.258411 -280.862906) (xy 407.228846 -280.90225) (xy 407.193353 -280.936342)
			(xy 407.15285 -280.964298) (xy 407.108388 -280.985396) (xy 407.061117 -280.999088) (xy 407.012262 -281.00502)
			(xy 406.963087 -281.003039) (xy 406.914868 -280.993195) (xy 406.868852 -280.975743) (xy 406.826231 -280.951136)
			(xy 406.78811 -280.920011) (xy 406.755475 -280.883174) (xy 406.729172 -280.841578) (xy 406.709881 -280.796302)
			(xy 406.698104 -280.748518) (xy 406.694144 -280.699464) (xy 405.405082 -280.699464) (xy 405.404587 -280.724071)
			(xy 405.396692 -280.772648) (xy 405.381108 -280.819329) (xy 405.358237 -280.862906) (xy 405.328672 -280.90225)
			(xy 405.293179 -280.936342) (xy 405.252676 -280.964298) (xy 405.208214 -280.985396) (xy 405.160943 -280.999088)
			(xy 405.112088 -281.00502) (xy 405.062913 -281.003039) (xy 405.014694 -280.993195) (xy 404.968678 -280.975743)
			(xy 404.926057 -280.951136) (xy 404.887936 -280.920011) (xy 404.855301 -280.883174) (xy 404.828998 -280.841578)
			(xy 404.809707 -280.796302) (xy 404.79793 -280.748518) (xy 404.79397 -280.699464) (xy 403.505162 -280.699464)
			(xy 403.504667 -280.724071) (xy 403.496772 -280.772648) (xy 403.481188 -280.819329) (xy 403.458317 -280.862906)
			(xy 403.428752 -280.90225) (xy 403.393259 -280.936342) (xy 403.352756 -280.964298) (xy 403.308294 -280.985396)
			(xy 403.261023 -280.999088) (xy 403.212168 -281.00502) (xy 403.162993 -281.003039) (xy 403.114774 -280.993195)
			(xy 403.068758 -280.975743) (xy 403.026137 -280.951136) (xy 402.988016 -280.920011) (xy 402.955381 -280.883174)
			(xy 402.929078 -280.841578) (xy 402.909787 -280.796302) (xy 402.89801 -280.748518) (xy 402.89405 -280.699464)
			(xy 401.605242 -280.699464) (xy 401.604747 -280.724071) (xy 401.596852 -280.772648) (xy 401.581268 -280.819329)
			(xy 401.558397 -280.862906) (xy 401.528832 -280.90225) (xy 401.493339 -280.936342) (xy 401.452836 -280.964298)
			(xy 401.408374 -280.985396) (xy 401.361103 -280.999088) (xy 401.312248 -281.00502) (xy 401.263073 -281.003039)
			(xy 401.214854 -280.993195) (xy 401.168838 -280.975743) (xy 401.126217 -280.951136) (xy 401.088096 -280.920011)
			(xy 401.055461 -280.883174) (xy 401.029158 -280.841578) (xy 401.009867 -280.796302) (xy 400.99809 -280.748518)
			(xy 400.99413 -280.699464) (xy 399.705322 -280.699464) (xy 399.704827 -280.724071) (xy 399.696932 -280.772648)
			(xy 399.681348 -280.819329) (xy 399.658477 -280.862906) (xy 399.628912 -280.90225) (xy 399.593419 -280.936342)
			(xy 399.552916 -280.964298) (xy 399.508454 -280.985396) (xy 399.461183 -280.999088) (xy 399.412328 -281.00502)
			(xy 399.363153 -281.003039) (xy 399.314934 -280.993195) (xy 399.268918 -280.975743) (xy 399.226297 -280.951136)
			(xy 399.188176 -280.920011) (xy 399.155541 -280.883174) (xy 399.129238 -280.841578) (xy 399.109947 -280.796302)
			(xy 399.09817 -280.748518) (xy 399.09421 -280.699464) (xy 397.805148 -280.699464) (xy 397.804653 -280.724071)
			(xy 397.796758 -280.772648) (xy 397.781174 -280.819329) (xy 397.758303 -280.862906) (xy 397.728738 -280.90225)
			(xy 397.693245 -280.936342) (xy 397.652742 -280.964298) (xy 397.60828 -280.985396) (xy 397.561009 -280.999088)
			(xy 397.512154 -281.00502) (xy 397.462979 -281.003039) (xy 397.41476 -280.993195) (xy 397.368744 -280.975743)
			(xy 397.326123 -280.951136) (xy 397.288002 -280.920011) (xy 397.255367 -280.883174) (xy 397.229064 -280.841578)
			(xy 397.209773 -280.796302) (xy 397.197996 -280.748518) (xy 397.194036 -280.699464) (xy 395.905228 -280.699464)
			(xy 395.904733 -280.724071) (xy 395.896838 -280.772648) (xy 395.881254 -280.819329) (xy 395.858383 -280.862906)
			(xy 395.828818 -280.90225) (xy 395.793325 -280.936342) (xy 395.752822 -280.964298) (xy 395.70836 -280.985396)
			(xy 395.661089 -280.999088) (xy 395.612234 -281.00502) (xy 395.563059 -281.003039) (xy 395.51484 -280.993195)
			(xy 395.468824 -280.975743) (xy 395.426203 -280.951136) (xy 395.388082 -280.920011) (xy 395.355447 -280.883174)
			(xy 395.329144 -280.841578) (xy 395.309853 -280.796302) (xy 395.298076 -280.748518) (xy 395.294116 -280.699464)
			(xy 394.005308 -280.699464) (xy 394.004813 -280.724071) (xy 393.996918 -280.772648) (xy 393.981334 -280.819329)
			(xy 393.958463 -280.862906) (xy 393.928898 -280.90225) (xy 393.893405 -280.936342) (xy 393.852902 -280.964298)
			(xy 393.80844 -280.985396) (xy 393.761169 -280.999088) (xy 393.712314 -281.00502) (xy 393.663139 -281.003039)
			(xy 393.61492 -280.993195) (xy 393.568904 -280.975743) (xy 393.526283 -280.951136) (xy 393.488162 -280.920011)
			(xy 393.455527 -280.883174) (xy 393.429224 -280.841578) (xy 393.409933 -280.796302) (xy 393.398156 -280.748518)
			(xy 393.394196 -280.699464) (xy 312.105035 -280.699464) (xy 312.10504 -280.699718) (xy 312.104545 -280.724325)
			(xy 312.09665 -280.772902) (xy 312.081066 -280.819583) (xy 312.058195 -280.86316) (xy 312.02863 -280.902504)
			(xy 311.993137 -280.936596) (xy 311.952634 -280.964552) (xy 311.908172 -280.98565) (xy 311.860901 -280.999342)
			(xy 311.812046 -281.005274) (xy 311.762871 -281.003293) (xy 311.714652 -280.993449) (xy 311.668636 -280.975997)
			(xy 311.626015 -280.95139) (xy 311.587894 -280.920265) (xy 311.555259 -280.883428) (xy 311.528956 -280.841832)
			(xy 311.509665 -280.796556) (xy 311.497888 -280.748772) (xy 311.493928 -280.699718) (xy 310.205115 -280.699718)
			(xy 310.204625 -280.724071) (xy 310.19673 -280.772648) (xy 310.181146 -280.819329) (xy 310.158275 -280.862906)
			(xy 310.12871 -280.90225) (xy 310.093217 -280.936342) (xy 310.052714 -280.964298) (xy 310.008252 -280.985396)
			(xy 309.960981 -280.999088) (xy 309.912126 -281.00502) (xy 309.862951 -281.003039) (xy 309.814732 -280.993195)
			(xy 309.768716 -280.975743) (xy 309.726095 -280.951136) (xy 309.687974 -280.920011) (xy 309.655339 -280.883174)
			(xy 309.629036 -280.841578) (xy 309.609745 -280.796302) (xy 309.597968 -280.748518) (xy 309.594008 -280.699464)
			(xy 308.3052 -280.699464) (xy 308.304705 -280.724071) (xy 308.29681 -280.772648) (xy 308.281226 -280.819329)
			(xy 308.258355 -280.862906) (xy 308.22879 -280.90225) (xy 308.193297 -280.936342) (xy 308.152794 -280.964298)
			(xy 308.108332 -280.985396) (xy 308.061061 -280.999088) (xy 308.012206 -281.00502) (xy 307.963031 -281.003039)
			(xy 307.914812 -280.993195) (xy 307.868796 -280.975743) (xy 307.826175 -280.951136) (xy 307.788054 -280.920011)
			(xy 307.755419 -280.883174) (xy 307.729116 -280.841578) (xy 307.709825 -280.796302) (xy 307.698048 -280.748518)
			(xy 307.694088 -280.699464) (xy 306.405026 -280.699464) (xy 306.404531 -280.724071) (xy 306.396636 -280.772648)
			(xy 306.381052 -280.819329) (xy 306.358181 -280.862906) (xy 306.328616 -280.90225) (xy 306.293123 -280.936342)
			(xy 306.25262 -280.964298) (xy 306.208158 -280.985396) (xy 306.160887 -280.999088) (xy 306.112032 -281.00502)
			(xy 306.062857 -281.003039) (xy 306.014638 -280.993195) (xy 305.968622 -280.975743) (xy 305.926001 -280.951136)
			(xy 305.88788 -280.920011) (xy 305.855245 -280.883174) (xy 305.828942 -280.841578) (xy 305.809651 -280.796302)
			(xy 305.797874 -280.748518) (xy 305.793914 -280.699464) (xy 304.505106 -280.699464) (xy 304.504611 -280.724071)
			(xy 304.496716 -280.772648) (xy 304.481132 -280.819329) (xy 304.458261 -280.862906) (xy 304.428696 -280.90225)
			(xy 304.393203 -280.936342) (xy 304.3527 -280.964298) (xy 304.308238 -280.985396) (xy 304.260967 -280.999088)
			(xy 304.212112 -281.00502) (xy 304.162937 -281.003039) (xy 304.114718 -280.993195) (xy 304.068702 -280.975743)
			(xy 304.026081 -280.951136) (xy 303.98796 -280.920011) (xy 303.955325 -280.883174) (xy 303.929022 -280.841578)
			(xy 303.909731 -280.796302) (xy 303.897954 -280.748518) (xy 303.893994 -280.699464) (xy 302.605186 -280.699464)
			(xy 302.604691 -280.724071) (xy 302.596796 -280.772648) (xy 302.581212 -280.819329) (xy 302.558341 -280.862906)
			(xy 302.528776 -280.90225) (xy 302.493283 -280.936342) (xy 302.45278 -280.964298) (xy 302.408318 -280.985396)
			(xy 302.361047 -280.999088) (xy 302.312192 -281.00502) (xy 302.263017 -281.003039) (xy 302.214798 -280.993195)
			(xy 302.168782 -280.975743) (xy 302.126161 -280.951136) (xy 302.08804 -280.920011) (xy 302.055405 -280.883174)
			(xy 302.029102 -280.841578) (xy 302.009811 -280.796302) (xy 301.998034 -280.748518) (xy 301.994074 -280.699464)
			(xy 300.705012 -280.699464) (xy 300.704517 -280.724071) (xy 300.696622 -280.772648) (xy 300.681038 -280.819329)
			(xy 300.658167 -280.862906) (xy 300.628602 -280.90225) (xy 300.593109 -280.936342) (xy 300.552606 -280.964298)
			(xy 300.508144 -280.985396) (xy 300.460873 -280.999088) (xy 300.412018 -281.00502) (xy 300.362843 -281.003039)
			(xy 300.314624 -280.993195) (xy 300.268608 -280.975743) (xy 300.225987 -280.951136) (xy 300.187866 -280.920011)
			(xy 300.155231 -280.883174) (xy 300.128928 -280.841578) (xy 300.109637 -280.796302) (xy 300.09786 -280.748518)
			(xy 300.0939 -280.699464) (xy 298.805092 -280.699464) (xy 298.804597 -280.724071) (xy 298.796702 -280.772648)
			(xy 298.781118 -280.819329) (xy 298.758247 -280.862906) (xy 298.728682 -280.90225) (xy 298.693189 -280.936342)
			(xy 298.652686 -280.964298) (xy 298.608224 -280.985396) (xy 298.560953 -280.999088) (xy 298.512098 -281.00502)
			(xy 298.462923 -281.003039) (xy 298.414704 -280.993195) (xy 298.368688 -280.975743) (xy 298.326067 -280.951136)
			(xy 298.287946 -280.920011) (xy 298.255311 -280.883174) (xy 298.229008 -280.841578) (xy 298.209717 -280.796302)
			(xy 298.19794 -280.748518) (xy 298.19398 -280.699464) (xy 296.905172 -280.699464) (xy 296.904677 -280.724071)
			(xy 296.896782 -280.772648) (xy 296.881198 -280.819329) (xy 296.858327 -280.862906) (xy 296.828762 -280.90225)
			(xy 296.793269 -280.936342) (xy 296.752766 -280.964298) (xy 296.708304 -280.985396) (xy 296.661033 -280.999088)
			(xy 296.612178 -281.00502) (xy 296.563003 -281.003039) (xy 296.514784 -280.993195) (xy 296.468768 -280.975743)
			(xy 296.426147 -280.951136) (xy 296.388026 -280.920011) (xy 296.355391 -280.883174) (xy 296.329088 -280.841578)
			(xy 296.309797 -280.796302) (xy 296.29802 -280.748518) (xy 296.29406 -280.699464) (xy 295.004998 -280.699464)
			(xy 295.004503 -280.724071) (xy 294.996608 -280.772648) (xy 294.981024 -280.819329) (xy 294.958153 -280.862906)
			(xy 294.928588 -280.90225) (xy 294.893095 -280.936342) (xy 294.852592 -280.964298) (xy 294.80813 -280.985396)
			(xy 294.760859 -280.999088) (xy 294.712004 -281.00502) (xy 294.662829 -281.003039) (xy 294.61461 -280.993195)
			(xy 294.568594 -280.975743) (xy 294.525973 -280.951136) (xy 294.487852 -280.920011) (xy 294.455217 -280.883174)
			(xy 294.428914 -280.841578) (xy 294.409623 -280.796302) (xy 294.397846 -280.748518) (xy 294.393886 -280.699464)
			(xy 293.105078 -280.699464) (xy 293.104583 -280.724071) (xy 293.096688 -280.772648) (xy 293.081104 -280.819329)
			(xy 293.058233 -280.862906) (xy 293.028668 -280.90225) (xy 292.993175 -280.936342) (xy 292.952672 -280.964298)
			(xy 292.90821 -280.985396) (xy 292.860939 -280.999088) (xy 292.812084 -281.00502) (xy 292.762909 -281.003039)
			(xy 292.71469 -280.993195) (xy 292.668674 -280.975743) (xy 292.626053 -280.951136) (xy 292.587932 -280.920011)
			(xy 292.555297 -280.883174) (xy 292.528994 -280.841578) (xy 292.509703 -280.796302) (xy 292.497926 -280.748518)
			(xy 292.493966 -280.699464) (xy 291.205158 -280.699464) (xy 291.204663 -280.724071) (xy 291.196768 -280.772648)
			(xy 291.181184 -280.819329) (xy 291.158313 -280.862906) (xy 291.128748 -280.90225) (xy 291.093255 -280.936342)
			(xy 291.052752 -280.964298) (xy 291.00829 -280.985396) (xy 290.961019 -280.999088) (xy 290.912164 -281.00502)
			(xy 290.862989 -281.003039) (xy 290.81477 -280.993195) (xy 290.768754 -280.975743) (xy 290.726133 -280.951136)
			(xy 290.688012 -280.920011) (xy 290.655377 -280.883174) (xy 290.629074 -280.841578) (xy 290.609783 -280.796302)
			(xy 290.598006 -280.748518) (xy 290.594046 -280.699464) (xy 289.304984 -280.699464) (xy 289.304489 -280.724071)
			(xy 289.296594 -280.772648) (xy 289.28101 -280.819329) (xy 289.258139 -280.862906) (xy 289.228574 -280.90225)
			(xy 289.193081 -280.936342) (xy 289.152578 -280.964298) (xy 289.108116 -280.985396) (xy 289.060845 -280.999088)
			(xy 289.01199 -281.00502) (xy 288.962815 -281.003039) (xy 288.914596 -280.993195) (xy 288.86858 -280.975743)
			(xy 288.825959 -280.951136) (xy 288.787838 -280.920011) (xy 288.755203 -280.883174) (xy 288.7289 -280.841578)
			(xy 288.709609 -280.796302) (xy 288.697832 -280.748518) (xy 288.693872 -280.699464) (xy 287.405064 -280.699464)
			(xy 287.404569 -280.724071) (xy 287.396674 -280.772648) (xy 287.38109 -280.819329) (xy 287.358219 -280.862906)
			(xy 287.328654 -280.90225) (xy 287.293161 -280.936342) (xy 287.252658 -280.964298) (xy 287.208196 -280.985396)
			(xy 287.160925 -280.999088) (xy 287.11207 -281.00502) (xy 287.062895 -281.003039) (xy 287.014676 -280.993195)
			(xy 286.96866 -280.975743) (xy 286.926039 -280.951136) (xy 286.887918 -280.920011) (xy 286.855283 -280.883174)
			(xy 286.82898 -280.841578) (xy 286.809689 -280.796302) (xy 286.797912 -280.748518) (xy 286.793952 -280.699464)
			(xy 285.505144 -280.699464) (xy 285.504649 -280.724071) (xy 285.496754 -280.772648) (xy 285.48117 -280.819329)
			(xy 285.458299 -280.862906) (xy 285.428734 -280.90225) (xy 285.393241 -280.936342) (xy 285.352738 -280.964298)
			(xy 285.308276 -280.985396) (xy 285.261005 -280.999088) (xy 285.21215 -281.00502) (xy 285.162975 -281.003039)
			(xy 285.114756 -280.993195) (xy 285.06874 -280.975743) (xy 285.026119 -280.951136) (xy 284.987998 -280.920011)
			(xy 284.955363 -280.883174) (xy 284.92906 -280.841578) (xy 284.909769 -280.796302) (xy 284.897992 -280.748518)
			(xy 284.894032 -280.699464) (xy 283.605224 -280.699464) (xy 283.604729 -280.724071) (xy 283.596834 -280.772648)
			(xy 283.58125 -280.819329) (xy 283.558379 -280.862906) (xy 283.528814 -280.90225) (xy 283.493321 -280.936342)
			(xy 283.452818 -280.964298) (xy 283.408356 -280.985396) (xy 283.361085 -280.999088) (xy 283.31223 -281.00502)
			(xy 283.263055 -281.003039) (xy 283.214836 -280.993195) (xy 283.16882 -280.975743) (xy 283.126199 -280.951136)
			(xy 283.088078 -280.920011) (xy 283.055443 -280.883174) (xy 283.02914 -280.841578) (xy 283.009849 -280.796302)
			(xy 282.998072 -280.748518) (xy 282.994112 -280.699464) (xy 281.70505 -280.699464) (xy 281.704555 -280.724071)
			(xy 281.69666 -280.772648) (xy 281.681076 -280.819329) (xy 281.658205 -280.862906) (xy 281.62864 -280.90225)
			(xy 281.593147 -280.936342) (xy 281.552644 -280.964298) (xy 281.508182 -280.985396) (xy 281.460911 -280.999088)
			(xy 281.412056 -281.00502) (xy 281.362881 -281.003039) (xy 281.314662 -280.993195) (xy 281.268646 -280.975743)
			(xy 281.226025 -280.951136) (xy 281.187904 -280.920011) (xy 281.155269 -280.883174) (xy 281.128966 -280.841578)
			(xy 281.109675 -280.796302) (xy 281.097898 -280.748518) (xy 281.093938 -280.699464) (xy 279.80513 -280.699464)
			(xy 279.804635 -280.724071) (xy 279.79674 -280.772648) (xy 279.781156 -280.819329) (xy 279.758285 -280.862906)
			(xy 279.72872 -280.90225) (xy 279.693227 -280.936342) (xy 279.652724 -280.964298) (xy 279.608262 -280.985396)
			(xy 279.560991 -280.999088) (xy 279.512136 -281.00502) (xy 279.462961 -281.003039) (xy 279.414742 -280.993195)
			(xy 279.368726 -280.975743) (xy 279.326105 -280.951136) (xy 279.287984 -280.920011) (xy 279.255349 -280.883174)
			(xy 279.229046 -280.841578) (xy 279.209755 -280.796302) (xy 279.197978 -280.748518) (xy 279.194018 -280.699464)
			(xy 277.90521 -280.699464) (xy 277.904715 -280.724071) (xy 277.89682 -280.772648) (xy 277.881236 -280.819329)
			(xy 277.858365 -280.862906) (xy 277.8288 -280.90225) (xy 277.793307 -280.936342) (xy 277.752804 -280.964298)
			(xy 277.708342 -280.985396) (xy 277.661071 -280.999088) (xy 277.612216 -281.00502) (xy 277.563041 -281.003039)
			(xy 277.514822 -280.993195) (xy 277.468806 -280.975743) (xy 277.426185 -280.951136) (xy 277.388064 -280.920011)
			(xy 277.355429 -280.883174) (xy 277.329126 -280.841578) (xy 277.309835 -280.796302) (xy 277.298058 -280.748518)
			(xy 277.294098 -280.699464) (xy 196.005191 -280.699464) (xy 196.005196 -280.699718) (xy 196.004701 -280.724325)
			(xy 195.996806 -280.772902) (xy 195.981222 -280.819583) (xy 195.958351 -280.86316) (xy 195.928786 -280.902504)
			(xy 195.893293 -280.936596) (xy 195.85279 -280.964552) (xy 195.808328 -280.98565) (xy 195.761057 -280.999342)
			(xy 195.712202 -281.005274) (xy 195.663027 -281.003293) (xy 195.614808 -280.993449) (xy 195.568792 -280.975997)
			(xy 195.526171 -280.95139) (xy 195.48805 -280.920265) (xy 195.455415 -280.883428) (xy 195.429112 -280.841832)
			(xy 195.409821 -280.796556) (xy 195.398044 -280.748772) (xy 195.394084 -280.699718) (xy 194.105276 -280.699718)
			(xy 194.104781 -280.724325) (xy 194.096886 -280.772902) (xy 194.081302 -280.819583) (xy 194.058431 -280.86316)
			(xy 194.028866 -280.902504) (xy 193.993373 -280.936596) (xy 193.95287 -280.964552) (xy 193.908408 -280.98565)
			(xy 193.861137 -280.999342) (xy 193.812282 -281.005274) (xy 193.763107 -281.003293) (xy 193.714888 -280.993449)
			(xy 193.668872 -280.975997) (xy 193.626251 -280.95139) (xy 193.58813 -280.920265) (xy 193.555495 -280.883428)
			(xy 193.529192 -280.841832) (xy 193.509901 -280.796556) (xy 193.498124 -280.748772) (xy 193.494164 -280.699718)
			(xy 192.205356 -280.699718) (xy 192.204861 -280.724325) (xy 192.196966 -280.772902) (xy 192.181382 -280.819583)
			(xy 192.158511 -280.86316) (xy 192.128946 -280.902504) (xy 192.093453 -280.936596) (xy 192.05295 -280.964552)
			(xy 192.008488 -280.98565) (xy 191.961217 -280.999342) (xy 191.912362 -281.005274) (xy 191.863187 -281.003293)
			(xy 191.814968 -280.993449) (xy 191.768952 -280.975997) (xy 191.726331 -280.95139) (xy 191.68821 -280.920265)
			(xy 191.655575 -280.883428) (xy 191.629272 -280.841832) (xy 191.609981 -280.796556) (xy 191.598204 -280.748772)
			(xy 191.594244 -280.699718) (xy 190.305182 -280.699718) (xy 190.304687 -280.724325) (xy 190.296792 -280.772902)
			(xy 190.281208 -280.819583) (xy 190.258337 -280.86316) (xy 190.228772 -280.902504) (xy 190.193279 -280.936596)
			(xy 190.152776 -280.964552) (xy 190.108314 -280.98565) (xy 190.061043 -280.999342) (xy 190.012188 -281.005274)
			(xy 189.963013 -281.003293) (xy 189.914794 -280.993449) (xy 189.868778 -280.975997) (xy 189.826157 -280.95139)
			(xy 189.788036 -280.920265) (xy 189.755401 -280.883428) (xy 189.729098 -280.841832) (xy 189.709807 -280.796556)
			(xy 189.69803 -280.748772) (xy 189.69407 -280.699718) (xy 188.405262 -280.699718) (xy 188.404767 -280.724325)
			(xy 188.396872 -280.772902) (xy 188.381288 -280.819583) (xy 188.358417 -280.86316) (xy 188.328852 -280.902504)
			(xy 188.293359 -280.936596) (xy 188.252856 -280.964552) (xy 188.208394 -280.98565) (xy 188.161123 -280.999342)
			(xy 188.112268 -281.005274) (xy 188.063093 -281.003293) (xy 188.014874 -280.993449) (xy 187.968858 -280.975997)
			(xy 187.926237 -280.95139) (xy 187.888116 -280.920265) (xy 187.855481 -280.883428) (xy 187.829178 -280.841832)
			(xy 187.809887 -280.796556) (xy 187.79811 -280.748772) (xy 187.79415 -280.699718) (xy 186.505342 -280.699718)
			(xy 186.504847 -280.724325) (xy 186.496952 -280.772902) (xy 186.481368 -280.819583) (xy 186.458497 -280.86316)
			(xy 186.428932 -280.902504) (xy 186.393439 -280.936596) (xy 186.352936 -280.964552) (xy 186.308474 -280.98565)
			(xy 186.261203 -280.999342) (xy 186.212348 -281.005274) (xy 186.163173 -281.003293) (xy 186.114954 -280.993449)
			(xy 186.068938 -280.975997) (xy 186.026317 -280.95139) (xy 185.988196 -280.920265) (xy 185.955561 -280.883428)
			(xy 185.929258 -280.841832) (xy 185.909967 -280.796556) (xy 185.89819 -280.748772) (xy 185.89423 -280.699718)
			(xy 184.605168 -280.699718) (xy 184.604673 -280.724325) (xy 184.596778 -280.772902) (xy 184.581194 -280.819583)
			(xy 184.558323 -280.86316) (xy 184.528758 -280.902504) (xy 184.493265 -280.936596) (xy 184.452762 -280.964552)
			(xy 184.4083 -280.98565) (xy 184.361029 -280.999342) (xy 184.312174 -281.005274) (xy 184.262999 -281.003293)
			(xy 184.21478 -280.993449) (xy 184.168764 -280.975997) (xy 184.126143 -280.95139) (xy 184.088022 -280.920265)
			(xy 184.055387 -280.883428) (xy 184.029084 -280.841832) (xy 184.009793 -280.796556) (xy 183.998016 -280.748772)
			(xy 183.994056 -280.699718) (xy 182.705248 -280.699718) (xy 182.704753 -280.724325) (xy 182.696858 -280.772902)
			(xy 182.681274 -280.819583) (xy 182.658403 -280.86316) (xy 182.628838 -280.902504) (xy 182.593345 -280.936596)
			(xy 182.552842 -280.964552) (xy 182.50838 -280.98565) (xy 182.461109 -280.999342) (xy 182.412254 -281.005274)
			(xy 182.363079 -281.003293) (xy 182.31486 -280.993449) (xy 182.268844 -280.975997) (xy 182.226223 -280.95139)
			(xy 182.188102 -280.920265) (xy 182.155467 -280.883428) (xy 182.129164 -280.841832) (xy 182.109873 -280.796556)
			(xy 182.098096 -280.748772) (xy 182.094136 -280.699718) (xy 180.805328 -280.699718) (xy 180.804833 -280.724325)
			(xy 180.796938 -280.772902) (xy 180.781354 -280.819583) (xy 180.758483 -280.86316) (xy 180.728918 -280.902504)
			(xy 180.693425 -280.936596) (xy 180.652922 -280.964552) (xy 180.60846 -280.98565) (xy 180.561189 -280.999342)
			(xy 180.512334 -281.005274) (xy 180.463159 -281.003293) (xy 180.41494 -280.993449) (xy 180.368924 -280.975997)
			(xy 180.326303 -280.95139) (xy 180.288182 -280.920265) (xy 180.255547 -280.883428) (xy 180.229244 -280.841832)
			(xy 180.209953 -280.796556) (xy 180.198176 -280.748772) (xy 180.194216 -280.699718) (xy 178.905154 -280.699718)
			(xy 178.904659 -280.724325) (xy 178.896764 -280.772902) (xy 178.88118 -280.819583) (xy 178.858309 -280.86316)
			(xy 178.828744 -280.902504) (xy 178.793251 -280.936596) (xy 178.752748 -280.964552) (xy 178.708286 -280.98565)
			(xy 178.661015 -280.999342) (xy 178.61216 -281.005274) (xy 178.562985 -281.003293) (xy 178.514766 -280.993449)
			(xy 178.46875 -280.975997) (xy 178.426129 -280.95139) (xy 178.388008 -280.920265) (xy 178.355373 -280.883428)
			(xy 178.32907 -280.841832) (xy 178.309779 -280.796556) (xy 178.298002 -280.748772) (xy 178.294042 -280.699718)
			(xy 177.005234 -280.699718) (xy 177.004739 -280.724325) (xy 176.996844 -280.772902) (xy 176.98126 -280.819583)
			(xy 176.958389 -280.86316) (xy 176.928824 -280.902504) (xy 176.893331 -280.936596) (xy 176.852828 -280.964552)
			(xy 176.808366 -280.98565) (xy 176.761095 -280.999342) (xy 176.71224 -281.005274) (xy 176.663065 -281.003293)
			(xy 176.614846 -280.993449) (xy 176.56883 -280.975997) (xy 176.526209 -280.95139) (xy 176.488088 -280.920265)
			(xy 176.455453 -280.883428) (xy 176.42915 -280.841832) (xy 176.409859 -280.796556) (xy 176.398082 -280.748772)
			(xy 176.394122 -280.699718) (xy 175.105314 -280.699718) (xy 175.104819 -280.724325) (xy 175.096924 -280.772902)
			(xy 175.08134 -280.819583) (xy 175.058469 -280.86316) (xy 175.028904 -280.902504) (xy 174.993411 -280.936596)
			(xy 174.952908 -280.964552) (xy 174.908446 -280.98565) (xy 174.861175 -280.999342) (xy 174.81232 -281.005274)
			(xy 174.763145 -281.003293) (xy 174.714926 -280.993449) (xy 174.66891 -280.975997) (xy 174.626289 -280.95139)
			(xy 174.588168 -280.920265) (xy 174.555533 -280.883428) (xy 174.52923 -280.841832) (xy 174.509939 -280.796556)
			(xy 174.498162 -280.748772) (xy 174.494202 -280.699718) (xy 173.20514 -280.699718) (xy 173.204645 -280.724325)
			(xy 173.19675 -280.772902) (xy 173.181166 -280.819583) (xy 173.158295 -280.86316) (xy 173.12873 -280.902504)
			(xy 173.093237 -280.936596) (xy 173.052734 -280.964552) (xy 173.008272 -280.98565) (xy 172.961001 -280.999342)
			(xy 172.912146 -281.005274) (xy 172.862971 -281.003293) (xy 172.814752 -280.993449) (xy 172.768736 -280.975997)
			(xy 172.726115 -280.95139) (xy 172.687994 -280.920265) (xy 172.655359 -280.883428) (xy 172.629056 -280.841832)
			(xy 172.609765 -280.796556) (xy 172.597988 -280.748772) (xy 172.594028 -280.699718) (xy 171.30522 -280.699718)
			(xy 171.304725 -280.724325) (xy 171.29683 -280.772902) (xy 171.281246 -280.819583) (xy 171.258375 -280.86316)
			(xy 171.22881 -280.902504) (xy 171.193317 -280.936596) (xy 171.152814 -280.964552) (xy 171.108352 -280.98565)
			(xy 171.061081 -280.999342) (xy 171.012226 -281.005274) (xy 170.963051 -281.003293) (xy 170.914832 -280.993449)
			(xy 170.868816 -280.975997) (xy 170.826195 -280.95139) (xy 170.788074 -280.920265) (xy 170.755439 -280.883428)
			(xy 170.729136 -280.841832) (xy 170.709845 -280.796556) (xy 170.698068 -280.748772) (xy 170.694108 -280.699718)
			(xy 169.4053 -280.699718) (xy 169.404805 -280.724325) (xy 169.39691 -280.772902) (xy 169.381326 -280.819583)
			(xy 169.358455 -280.86316) (xy 169.32889 -280.902504) (xy 169.293397 -280.936596) (xy 169.252894 -280.964552)
			(xy 169.208432 -280.98565) (xy 169.161161 -280.999342) (xy 169.112306 -281.005274) (xy 169.063131 -281.003293)
			(xy 169.014912 -280.993449) (xy 168.968896 -280.975997) (xy 168.926275 -280.95139) (xy 168.888154 -280.920265)
			(xy 168.855519 -280.883428) (xy 168.829216 -280.841832) (xy 168.809925 -280.796556) (xy 168.798148 -280.748772)
			(xy 168.794188 -280.699718) (xy 167.50538 -280.699718) (xy 167.504885 -280.724325) (xy 167.49699 -280.772902)
			(xy 167.481406 -280.819583) (xy 167.458535 -280.86316) (xy 167.42897 -280.902504) (xy 167.393477 -280.936596)
			(xy 167.352974 -280.964552) (xy 167.308512 -280.98565) (xy 167.261241 -280.999342) (xy 167.212386 -281.005274)
			(xy 167.163211 -281.003293) (xy 167.114992 -280.993449) (xy 167.068976 -280.975997) (xy 167.026355 -280.95139)
			(xy 166.988234 -280.920265) (xy 166.955599 -280.883428) (xy 166.929296 -280.841832) (xy 166.910005 -280.796556)
			(xy 166.898228 -280.748772) (xy 166.894268 -280.699718) (xy 165.605206 -280.699718) (xy 165.604711 -280.724325)
			(xy 165.596816 -280.772902) (xy 165.581232 -280.819583) (xy 165.558361 -280.86316) (xy 165.528796 -280.902504)
			(xy 165.493303 -280.936596) (xy 165.4528 -280.964552) (xy 165.408338 -280.98565) (xy 165.361067 -280.999342)
			(xy 165.312212 -281.005274) (xy 165.263037 -281.003293) (xy 165.214818 -280.993449) (xy 165.168802 -280.975997)
			(xy 165.126181 -280.95139) (xy 165.08806 -280.920265) (xy 165.055425 -280.883428) (xy 165.029122 -280.841832)
			(xy 165.009831 -280.796556) (xy 164.998054 -280.748772) (xy 164.994094 -280.699718) (xy 163.705286 -280.699718)
			(xy 163.704791 -280.724325) (xy 163.696896 -280.772902) (xy 163.681312 -280.819583) (xy 163.658441 -280.86316)
			(xy 163.628876 -280.902504) (xy 163.593383 -280.936596) (xy 163.55288 -280.964552) (xy 163.508418 -280.98565)
			(xy 163.461147 -280.999342) (xy 163.412292 -281.005274) (xy 163.363117 -281.003293) (xy 163.314898 -280.993449)
			(xy 163.268882 -280.975997) (xy 163.226261 -280.95139) (xy 163.18814 -280.920265) (xy 163.155505 -280.883428)
			(xy 163.129202 -280.841832) (xy 163.109911 -280.796556) (xy 163.098134 -280.748772) (xy 163.094174 -280.699718)
			(xy 161.805366 -280.699718) (xy 161.804871 -280.724325) (xy 161.796976 -280.772902) (xy 161.781392 -280.819583)
			(xy 161.758521 -280.86316) (xy 161.728956 -280.902504) (xy 161.693463 -280.936596) (xy 161.65296 -280.964552)
			(xy 161.608498 -280.98565) (xy 161.561227 -280.999342) (xy 161.512372 -281.005274) (xy 161.463197 -281.003293)
			(xy 161.414978 -280.993449) (xy 161.368962 -280.975997) (xy 161.326341 -280.95139) (xy 161.28822 -280.920265)
			(xy 161.255585 -280.883428) (xy 161.229282 -280.841832) (xy 161.209991 -280.796556) (xy 161.198214 -280.748772)
			(xy 161.194254 -280.699718) (xy 79.905098 -280.699718) (xy 79.904603 -280.724325) (xy 79.896708 -280.772902)
			(xy 79.881124 -280.819583) (xy 79.858253 -280.86316) (xy 79.828688 -280.902504) (xy 79.793195 -280.936596)
			(xy 79.752692 -280.964552) (xy 79.70823 -280.98565) (xy 79.660959 -280.999342) (xy 79.612104 -281.005274)
			(xy 79.562929 -281.003293) (xy 79.51471 -280.993449) (xy 79.468694 -280.975997) (xy 79.426073 -280.95139)
			(xy 79.387952 -280.920265) (xy 79.355317 -280.883428) (xy 79.329014 -280.841832) (xy 79.309723 -280.796556)
			(xy 79.297946 -280.748772) (xy 79.293986 -280.699718) (xy 78.005178 -280.699718) (xy 78.004683 -280.724325)
			(xy 77.996788 -280.772902) (xy 77.981204 -280.819583) (xy 77.958333 -280.86316) (xy 77.928768 -280.902504)
			(xy 77.893275 -280.936596) (xy 77.852772 -280.964552) (xy 77.80831 -280.98565) (xy 77.761039 -280.999342)
			(xy 77.712184 -281.005274) (xy 77.663009 -281.003293) (xy 77.61479 -280.993449) (xy 77.568774 -280.975997)
			(xy 77.526153 -280.95139) (xy 77.488032 -280.920265) (xy 77.455397 -280.883428) (xy 77.429094 -280.841832)
			(xy 77.409803 -280.796556) (xy 77.398026 -280.748772) (xy 77.394066 -280.699718) (xy 76.105258 -280.699718)
			(xy 76.104763 -280.724325) (xy 76.096868 -280.772902) (xy 76.081284 -280.819583) (xy 76.058413 -280.86316)
			(xy 76.028848 -280.902504) (xy 75.993355 -280.936596) (xy 75.952852 -280.964552) (xy 75.90839 -280.98565)
			(xy 75.861119 -280.999342) (xy 75.812264 -281.005274) (xy 75.763089 -281.003293) (xy 75.71487 -280.993449)
			(xy 75.668854 -280.975997) (xy 75.626233 -280.95139) (xy 75.588112 -280.920265) (xy 75.555477 -280.883428)
			(xy 75.529174 -280.841832) (xy 75.509883 -280.796556) (xy 75.498106 -280.748772) (xy 75.494146 -280.699718)
			(xy 74.205084 -280.699718) (xy 74.204589 -280.724325) (xy 74.196694 -280.772902) (xy 74.18111 -280.819583)
			(xy 74.158239 -280.86316) (xy 74.128674 -280.902504) (xy 74.093181 -280.936596) (xy 74.052678 -280.964552)
			(xy 74.008216 -280.98565) (xy 73.960945 -280.999342) (xy 73.91209 -281.005274) (xy 73.862915 -281.003293)
			(xy 73.814696 -280.993449) (xy 73.76868 -280.975997) (xy 73.726059 -280.95139) (xy 73.687938 -280.920265)
			(xy 73.655303 -280.883428) (xy 73.629 -280.841832) (xy 73.609709 -280.796556) (xy 73.597932 -280.748772)
			(xy 73.593972 -280.699718) (xy 72.305164 -280.699718) (xy 72.304669 -280.724325) (xy 72.296774 -280.772902)
			(xy 72.28119 -280.819583) (xy 72.258319 -280.86316) (xy 72.228754 -280.902504) (xy 72.193261 -280.936596)
			(xy 72.152758 -280.964552) (xy 72.108296 -280.98565) (xy 72.061025 -280.999342) (xy 72.01217 -281.005274)
			(xy 71.962995 -281.003293) (xy 71.914776 -280.993449) (xy 71.86876 -280.975997) (xy 71.826139 -280.95139)
			(xy 71.788018 -280.920265) (xy 71.755383 -280.883428) (xy 71.72908 -280.841832) (xy 71.709789 -280.796556)
			(xy 71.698012 -280.748772) (xy 71.694052 -280.699718) (xy 70.405244 -280.699718) (xy 70.404749 -280.724325)
			(xy 70.396854 -280.772902) (xy 70.38127 -280.819583) (xy 70.358399 -280.86316) (xy 70.328834 -280.902504)
			(xy 70.293341 -280.936596) (xy 70.252838 -280.964552) (xy 70.208376 -280.98565) (xy 70.161105 -280.999342)
			(xy 70.11225 -281.005274) (xy 70.063075 -281.003293) (xy 70.014856 -280.993449) (xy 69.96884 -280.975997)
			(xy 69.926219 -280.95139) (xy 69.888098 -280.920265) (xy 69.855463 -280.883428) (xy 69.82916 -280.841832)
			(xy 69.809869 -280.796556) (xy 69.798092 -280.748772) (xy 69.794132 -280.699718) (xy 68.50507 -280.699718)
			(xy 68.504575 -280.724325) (xy 68.49668 -280.772902) (xy 68.481096 -280.819583) (xy 68.458225 -280.86316)
			(xy 68.42866 -280.902504) (xy 68.393167 -280.936596) (xy 68.352664 -280.964552) (xy 68.308202 -280.98565)
			(xy 68.260931 -280.999342) (xy 68.212076 -281.005274) (xy 68.162901 -281.003293) (xy 68.114682 -280.993449)
			(xy 68.068666 -280.975997) (xy 68.026045 -280.95139) (xy 67.987924 -280.920265) (xy 67.955289 -280.883428)
			(xy 67.928986 -280.841832) (xy 67.909695 -280.796556) (xy 67.897918 -280.748772) (xy 67.893958 -280.699718)
			(xy 66.60515 -280.699718) (xy 66.604655 -280.724325) (xy 66.59676 -280.772902) (xy 66.581176 -280.819583)
			(xy 66.558305 -280.86316) (xy 66.52874 -280.902504) (xy 66.493247 -280.936596) (xy 66.452744 -280.964552)
			(xy 66.408282 -280.98565) (xy 66.361011 -280.999342) (xy 66.312156 -281.005274) (xy 66.262981 -281.003293)
			(xy 66.214762 -280.993449) (xy 66.168746 -280.975997) (xy 66.126125 -280.95139) (xy 66.088004 -280.920265)
			(xy 66.055369 -280.883428) (xy 66.029066 -280.841832) (xy 66.009775 -280.796556) (xy 65.997998 -280.748772)
			(xy 65.994038 -280.699718) (xy 64.70523 -280.699718) (xy 64.704735 -280.724325) (xy 64.69684 -280.772902)
			(xy 64.681256 -280.819583) (xy 64.658385 -280.86316) (xy 64.62882 -280.902504) (xy 64.593327 -280.936596)
			(xy 64.552824 -280.964552) (xy 64.508362 -280.98565) (xy 64.461091 -280.999342) (xy 64.412236 -281.005274)
			(xy 64.363061 -281.003293) (xy 64.314842 -280.993449) (xy 64.268826 -280.975997) (xy 64.226205 -280.95139)
			(xy 64.188084 -280.920265) (xy 64.155449 -280.883428) (xy 64.129146 -280.841832) (xy 64.109855 -280.796556)
			(xy 64.098078 -280.748772) (xy 64.094118 -280.699718) (xy 62.805056 -280.699718) (xy 62.804561 -280.724325)
			(xy 62.796666 -280.772902) (xy 62.781082 -280.819583) (xy 62.758211 -280.86316) (xy 62.728646 -280.902504)
			(xy 62.693153 -280.936596) (xy 62.65265 -280.964552) (xy 62.608188 -280.98565) (xy 62.560917 -280.999342)
			(xy 62.512062 -281.005274) (xy 62.462887 -281.003293) (xy 62.414668 -280.993449) (xy 62.368652 -280.975997)
			(xy 62.326031 -280.95139) (xy 62.28791 -280.920265) (xy 62.255275 -280.883428) (xy 62.228972 -280.841832)
			(xy 62.209681 -280.796556) (xy 62.197904 -280.748772) (xy 62.193944 -280.699718) (xy 60.905136 -280.699718)
			(xy 60.904641 -280.724325) (xy 60.896746 -280.772902) (xy 60.881162 -280.819583) (xy 60.858291 -280.86316)
			(xy 60.828726 -280.902504) (xy 60.793233 -280.936596) (xy 60.75273 -280.964552) (xy 60.708268 -280.98565)
			(xy 60.660997 -280.999342) (xy 60.612142 -281.005274) (xy 60.562967 -281.003293) (xy 60.514748 -280.993449)
			(xy 60.468732 -280.975997) (xy 60.426111 -280.95139) (xy 60.38799 -280.920265) (xy 60.355355 -280.883428)
			(xy 60.329052 -280.841832) (xy 60.309761 -280.796556) (xy 60.297984 -280.748772) (xy 60.294024 -280.699718)
			(xy 59.005216 -280.699718) (xy 59.004721 -280.724325) (xy 58.996826 -280.772902) (xy 58.981242 -280.819583)
			(xy 58.958371 -280.86316) (xy 58.928806 -280.902504) (xy 58.893313 -280.936596) (xy 58.85281 -280.964552)
			(xy 58.808348 -280.98565) (xy 58.761077 -280.999342) (xy 58.712222 -281.005274) (xy 58.663047 -281.003293)
			(xy 58.614828 -280.993449) (xy 58.568812 -280.975997) (xy 58.526191 -280.95139) (xy 58.48807 -280.920265)
			(xy 58.455435 -280.883428) (xy 58.429132 -280.841832) (xy 58.409841 -280.796556) (xy 58.398064 -280.748772)
			(xy 58.394104 -280.699718) (xy 57.105042 -280.699718) (xy 57.104547 -280.724325) (xy 57.096652 -280.772902)
			(xy 57.081068 -280.819583) (xy 57.058197 -280.86316) (xy 57.028632 -280.902504) (xy 56.993139 -280.936596)
			(xy 56.952636 -280.964552) (xy 56.908174 -280.98565) (xy 56.860903 -280.999342) (xy 56.812048 -281.005274)
			(xy 56.762873 -281.003293) (xy 56.714654 -280.993449) (xy 56.668638 -280.975997) (xy 56.626017 -280.95139)
			(xy 56.587896 -280.920265) (xy 56.555261 -280.883428) (xy 56.528958 -280.841832) (xy 56.509667 -280.796556)
			(xy 56.49789 -280.748772) (xy 56.49393 -280.699718) (xy 55.205122 -280.699718) (xy 55.204627 -280.724325)
			(xy 55.196732 -280.772902) (xy 55.181148 -280.819583) (xy 55.158277 -280.86316) (xy 55.128712 -280.902504)
			(xy 55.093219 -280.936596) (xy 55.052716 -280.964552) (xy 55.008254 -280.98565) (xy 54.960983 -280.999342)
			(xy 54.912128 -281.005274) (xy 54.862953 -281.003293) (xy 54.814734 -280.993449) (xy 54.768718 -280.975997)
			(xy 54.726097 -280.95139) (xy 54.687976 -280.920265) (xy 54.655341 -280.883428) (xy 54.629038 -280.841832)
			(xy 54.609747 -280.796556) (xy 54.59797 -280.748772) (xy 54.59401 -280.699718) (xy 53.305202 -280.699718)
			(xy 53.304707 -280.724325) (xy 53.296812 -280.772902) (xy 53.281228 -280.819583) (xy 53.258357 -280.86316)
			(xy 53.228792 -280.902504) (xy 53.193299 -280.936596) (xy 53.152796 -280.964552) (xy 53.108334 -280.98565)
			(xy 53.061063 -280.999342) (xy 53.012208 -281.005274) (xy 52.963033 -281.003293) (xy 52.914814 -280.993449)
			(xy 52.868798 -280.975997) (xy 52.826177 -280.95139) (xy 52.788056 -280.920265) (xy 52.755421 -280.883428)
			(xy 52.729118 -280.841832) (xy 52.709827 -280.796556) (xy 52.69805 -280.748772) (xy 52.69409 -280.699718)
			(xy 51.405282 -280.699718) (xy 51.404787 -280.724325) (xy 51.396892 -280.772902) (xy 51.381308 -280.819583)
			(xy 51.358437 -280.86316) (xy 51.328872 -280.902504) (xy 51.293379 -280.936596) (xy 51.252876 -280.964552)
			(xy 51.208414 -280.98565) (xy 51.161143 -280.999342) (xy 51.112288 -281.005274) (xy 51.063113 -281.003293)
			(xy 51.014894 -280.993449) (xy 50.968878 -280.975997) (xy 50.926257 -280.95139) (xy 50.888136 -280.920265)
			(xy 50.855501 -280.883428) (xy 50.829198 -280.841832) (xy 50.809907 -280.796556) (xy 50.79813 -280.748772)
			(xy 50.79417 -280.699718) (xy 49.505108 -280.699718) (xy 49.504613 -280.724325) (xy 49.496718 -280.772902)
			(xy 49.481134 -280.819583) (xy 49.458263 -280.86316) (xy 49.428698 -280.902504) (xy 49.393205 -280.936596)
			(xy 49.352702 -280.964552) (xy 49.30824 -280.98565) (xy 49.260969 -280.999342) (xy 49.212114 -281.005274)
			(xy 49.162939 -281.003293) (xy 49.11472 -280.993449) (xy 49.068704 -280.975997) (xy 49.026083 -280.95139)
			(xy 48.987962 -280.920265) (xy 48.955327 -280.883428) (xy 48.929024 -280.841832) (xy 48.909733 -280.796556)
			(xy 48.897956 -280.748772) (xy 48.893996 -280.699718) (xy 47.605188 -280.699718) (xy 47.604693 -280.724325)
			(xy 47.596798 -280.772902) (xy 47.581214 -280.819583) (xy 47.558343 -280.86316) (xy 47.528778 -280.902504)
			(xy 47.493285 -280.936596) (xy 47.452782 -280.964552) (xy 47.40832 -280.98565) (xy 47.361049 -280.999342)
			(xy 47.312194 -281.005274) (xy 47.263019 -281.003293) (xy 47.2148 -280.993449) (xy 47.168784 -280.975997)
			(xy 47.126163 -280.95139) (xy 47.088042 -280.920265) (xy 47.055407 -280.883428) (xy 47.029104 -280.841832)
			(xy 47.009813 -280.796556) (xy 46.998036 -280.748772) (xy 46.994076 -280.699718) (xy 45.705268 -280.699718)
			(xy 45.704773 -280.724325) (xy 45.696878 -280.772902) (xy 45.681294 -280.819583) (xy 45.658423 -280.86316)
			(xy 45.628858 -280.902504) (xy 45.593365 -280.936596) (xy 45.552862 -280.964552) (xy 45.5084 -280.98565)
			(xy 45.461129 -280.999342) (xy 45.412274 -281.005274) (xy 45.363099 -281.003293) (xy 45.31488 -280.993449)
			(xy 45.268864 -280.975997) (xy 45.226243 -280.95139) (xy 45.188122 -280.920265) (xy 45.155487 -280.883428)
			(xy 45.129184 -280.841832) (xy 45.109893 -280.796556) (xy 45.098116 -280.748772) (xy 45.094156 -280.699718)
			(xy 0.508 -280.699718) (xy 0.508 -281.649932) (xy 81.19416 -281.649932) (xy 81.19812 -281.600878)
			(xy 81.209897 -281.553094) (xy 81.229188 -281.507818) (xy 81.255491 -281.466222) (xy 81.288126 -281.429385)
			(xy 81.326247 -281.39826) (xy 81.368868 -281.373653) (xy 81.414884 -281.356201) (xy 81.463103 -281.346357)
			(xy 81.512278 -281.344376) (xy 81.561133 -281.350308) (xy 81.608404 -281.364) (xy 81.652866 -281.385098)
			(xy 81.693369 -281.413054) (xy 81.728862 -281.447146) (xy 81.758427 -281.48649) (xy 81.781298 -281.530067)
			(xy 81.796882 -281.576748) (xy 81.804777 -281.625325) (xy 81.805272 -281.649932) (xy 82.14412 -281.649932)
			(xy 82.14808 -281.600878) (xy 82.159857 -281.553094) (xy 82.179148 -281.507818) (xy 82.205451 -281.466222)
			(xy 82.238086 -281.429385) (xy 82.276207 -281.39826) (xy 82.318828 -281.373653) (xy 82.364844 -281.356201)
			(xy 82.413063 -281.346357) (xy 82.462238 -281.344376) (xy 82.511093 -281.350308) (xy 82.558364 -281.364)
			(xy 82.602826 -281.385098) (xy 82.643329 -281.413054) (xy 82.678822 -281.447146) (xy 82.708387 -281.48649)
			(xy 82.731258 -281.530067) (xy 82.746842 -281.576748) (xy 82.754737 -281.625325) (xy 82.755232 -281.649932)
			(xy 197.294258 -281.649932) (xy 197.298218 -281.600878) (xy 197.309995 -281.553094) (xy 197.329286 -281.507818)
			(xy 197.355589 -281.466222) (xy 197.388224 -281.429385) (xy 197.426345 -281.39826) (xy 197.468966 -281.373653)
			(xy 197.514982 -281.356201) (xy 197.563201 -281.346357) (xy 197.612376 -281.344376) (xy 197.661231 -281.350308)
			(xy 197.708502 -281.364) (xy 197.752964 -281.385098) (xy 197.793467 -281.413054) (xy 197.82896 -281.447146)
			(xy 197.858525 -281.48649) (xy 197.881396 -281.530067) (xy 197.89698 -281.576748) (xy 197.904875 -281.625325)
			(xy 197.90537 -281.649932) (xy 198.244218 -281.649932) (xy 198.248178 -281.600878) (xy 198.259955 -281.553094)
			(xy 198.279246 -281.507818) (xy 198.305549 -281.466222) (xy 198.338184 -281.429385) (xy 198.376305 -281.39826)
			(xy 198.418926 -281.373653) (xy 198.464942 -281.356201) (xy 198.513161 -281.346357) (xy 198.562336 -281.344376)
			(xy 198.611191 -281.350308) (xy 198.658462 -281.364) (xy 198.702924 -281.385098) (xy 198.743427 -281.413054)
			(xy 198.77892 -281.447146) (xy 198.808485 -281.48649) (xy 198.831356 -281.530067) (xy 198.84694 -281.576748)
			(xy 198.854835 -281.625325) (xy 198.85533 -281.649932) (xy 313.394102 -281.649932) (xy 313.398062 -281.600878)
			(xy 313.409839 -281.553094) (xy 313.42913 -281.507818) (xy 313.455433 -281.466222) (xy 313.488068 -281.429385)
			(xy 313.526189 -281.39826) (xy 313.56881 -281.373653) (xy 313.614826 -281.356201) (xy 313.663045 -281.346357)
			(xy 313.71222 -281.344376) (xy 313.761075 -281.350308) (xy 313.808346 -281.364) (xy 313.852808 -281.385098)
			(xy 313.893311 -281.413054) (xy 313.928804 -281.447146) (xy 313.958369 -281.48649) (xy 313.98124 -281.530067)
			(xy 313.996824 -281.576748) (xy 314.004719 -281.625325) (xy 314.005214 -281.649932) (xy 314.344062 -281.649932)
			(xy 314.348022 -281.600878) (xy 314.359799 -281.553094) (xy 314.37909 -281.507818) (xy 314.405393 -281.466222)
			(xy 314.438028 -281.429385) (xy 314.476149 -281.39826) (xy 314.51877 -281.373653) (xy 314.564786 -281.356201)
			(xy 314.613005 -281.346357) (xy 314.66218 -281.344376) (xy 314.711035 -281.350308) (xy 314.758306 -281.364)
			(xy 314.802768 -281.385098) (xy 314.843271 -281.413054) (xy 314.878764 -281.447146) (xy 314.908329 -281.48649)
			(xy 314.9312 -281.530067) (xy 314.946784 -281.576748) (xy 314.954679 -281.625325) (xy 314.955174 -281.649932)
			(xy 429.4942 -281.649932) (xy 429.49816 -281.600878) (xy 429.509937 -281.553094) (xy 429.529228 -281.507818)
			(xy 429.555531 -281.466222) (xy 429.588166 -281.429385) (xy 429.626287 -281.39826) (xy 429.668908 -281.373653)
			(xy 429.714924 -281.356201) (xy 429.763143 -281.346357) (xy 429.812318 -281.344376) (xy 429.861173 -281.350308)
			(xy 429.908444 -281.364) (xy 429.952906 -281.385098) (xy 429.993409 -281.413054) (xy 430.028902 -281.447146)
			(xy 430.058467 -281.48649) (xy 430.081338 -281.530067) (xy 430.096922 -281.576748) (xy 430.104817 -281.625325)
			(xy 430.105312 -281.649932) (xy 430.44416 -281.649932) (xy 430.44812 -281.600878) (xy 430.459897 -281.553094)
			(xy 430.479188 -281.507818) (xy 430.505491 -281.466222) (xy 430.538126 -281.429385) (xy 430.576247 -281.39826)
			(xy 430.618868 -281.373653) (xy 430.664884 -281.356201) (xy 430.713103 -281.346357) (xy 430.762278 -281.344376)
			(xy 430.811133 -281.350308) (xy 430.858404 -281.364) (xy 430.902866 -281.385098) (xy 430.943369 -281.413054)
			(xy 430.978862 -281.447146) (xy 431.008427 -281.48649) (xy 431.031298 -281.530067) (xy 431.046882 -281.576748)
			(xy 431.054777 -281.625325) (xy 431.055272 -281.649932) (xy 431.054777 -281.674539) (xy 431.046882 -281.723116)
			(xy 431.031298 -281.769797) (xy 431.008427 -281.813374) (xy 430.978862 -281.852718) (xy 430.943369 -281.88681)
			(xy 430.902866 -281.914766) (xy 430.858404 -281.935864) (xy 430.811133 -281.949556) (xy 430.762278 -281.955488)
			(xy 430.713103 -281.953507) (xy 430.664884 -281.943663) (xy 430.618868 -281.926211) (xy 430.576247 -281.901604)
			(xy 430.538126 -281.870479) (xy 430.505491 -281.833642) (xy 430.479188 -281.792046) (xy 430.459897 -281.74677)
			(xy 430.44812 -281.698986) (xy 430.44416 -281.649932) (xy 430.105312 -281.649932) (xy 430.104817 -281.674539)
			(xy 430.096922 -281.723116) (xy 430.081338 -281.769797) (xy 430.058467 -281.813374) (xy 430.028902 -281.852718)
			(xy 429.993409 -281.88681) (xy 429.952906 -281.914766) (xy 429.908444 -281.935864) (xy 429.861173 -281.949556)
			(xy 429.812318 -281.955488) (xy 429.763143 -281.953507) (xy 429.714924 -281.943663) (xy 429.668908 -281.926211)
			(xy 429.626287 -281.901604) (xy 429.588166 -281.870479) (xy 429.555531 -281.833642) (xy 429.529228 -281.792046)
			(xy 429.509937 -281.74677) (xy 429.49816 -281.698986) (xy 429.4942 -281.649932) (xy 314.955174 -281.649932)
			(xy 314.954679 -281.674539) (xy 314.946784 -281.723116) (xy 314.9312 -281.769797) (xy 314.908329 -281.813374)
			(xy 314.878764 -281.852718) (xy 314.843271 -281.88681) (xy 314.802768 -281.914766) (xy 314.758306 -281.935864)
			(xy 314.711035 -281.949556) (xy 314.66218 -281.955488) (xy 314.613005 -281.953507) (xy 314.564786 -281.943663)
			(xy 314.51877 -281.926211) (xy 314.476149 -281.901604) (xy 314.438028 -281.870479) (xy 314.405393 -281.833642)
			(xy 314.37909 -281.792046) (xy 314.359799 -281.74677) (xy 314.348022 -281.698986) (xy 314.344062 -281.649932)
			(xy 314.005214 -281.649932) (xy 314.004719 -281.674539) (xy 313.996824 -281.723116) (xy 313.98124 -281.769797)
			(xy 313.958369 -281.813374) (xy 313.928804 -281.852718) (xy 313.893311 -281.88681) (xy 313.852808 -281.914766)
			(xy 313.808346 -281.935864) (xy 313.761075 -281.949556) (xy 313.71222 -281.955488) (xy 313.663045 -281.953507)
			(xy 313.614826 -281.943663) (xy 313.56881 -281.926211) (xy 313.526189 -281.901604) (xy 313.488068 -281.870479)
			(xy 313.455433 -281.833642) (xy 313.42913 -281.792046) (xy 313.409839 -281.74677) (xy 313.398062 -281.698986)
			(xy 313.394102 -281.649932) (xy 198.85533 -281.649932) (xy 198.854835 -281.674539) (xy 198.84694 -281.723116)
			(xy 198.831356 -281.769797) (xy 198.808485 -281.813374) (xy 198.77892 -281.852718) (xy 198.743427 -281.88681)
			(xy 198.702924 -281.914766) (xy 198.658462 -281.935864) (xy 198.611191 -281.949556) (xy 198.562336 -281.955488)
			(xy 198.513161 -281.953507) (xy 198.464942 -281.943663) (xy 198.418926 -281.926211) (xy 198.376305 -281.901604)
			(xy 198.338184 -281.870479) (xy 198.305549 -281.833642) (xy 198.279246 -281.792046) (xy 198.259955 -281.74677)
			(xy 198.248178 -281.698986) (xy 198.244218 -281.649932) (xy 197.90537 -281.649932) (xy 197.904875 -281.674539)
			(xy 197.89698 -281.723116) (xy 197.881396 -281.769797) (xy 197.858525 -281.813374) (xy 197.82896 -281.852718)
			(xy 197.793467 -281.88681) (xy 197.752964 -281.914766) (xy 197.708502 -281.935864) (xy 197.661231 -281.949556)
			(xy 197.612376 -281.955488) (xy 197.563201 -281.953507) (xy 197.514982 -281.943663) (xy 197.468966 -281.926211)
			(xy 197.426345 -281.901604) (xy 197.388224 -281.870479) (xy 197.355589 -281.833642) (xy 197.329286 -281.792046)
			(xy 197.309995 -281.74677) (xy 197.298218 -281.698986) (xy 197.294258 -281.649932) (xy 82.755232 -281.649932)
			(xy 82.754737 -281.674539) (xy 82.746842 -281.723116) (xy 82.731258 -281.769797) (xy 82.708387 -281.813374)
			(xy 82.678822 -281.852718) (xy 82.643329 -281.88681) (xy 82.602826 -281.914766) (xy 82.558364 -281.935864)
			(xy 82.511093 -281.949556) (xy 82.462238 -281.955488) (xy 82.413063 -281.953507) (xy 82.364844 -281.943663)
			(xy 82.318828 -281.926211) (xy 82.276207 -281.901604) (xy 82.238086 -281.870479) (xy 82.205451 -281.833642)
			(xy 82.179148 -281.792046) (xy 82.159857 -281.74677) (xy 82.14808 -281.698986) (xy 82.14412 -281.649932)
			(xy 81.805272 -281.649932) (xy 81.804777 -281.674539) (xy 81.796882 -281.723116) (xy 81.781298 -281.769797)
			(xy 81.758427 -281.813374) (xy 81.728862 -281.852718) (xy 81.693369 -281.88681) (xy 81.652866 -281.914766)
			(xy 81.608404 -281.935864) (xy 81.561133 -281.949556) (xy 81.512278 -281.955488) (xy 81.463103 -281.953507)
			(xy 81.414884 -281.943663) (xy 81.368868 -281.926211) (xy 81.326247 -281.901604) (xy 81.288126 -281.870479)
			(xy 81.255491 -281.833642) (xy 81.229188 -281.792046) (xy 81.209897 -281.74677) (xy 81.19812 -281.698986)
			(xy 81.19416 -281.649932) (xy 0.508 -281.649932) (xy 0.508 -282.599892) (xy 76.444106 -282.599892)
			(xy 76.448066 -282.550838) (xy 76.459843 -282.503054) (xy 76.479134 -282.457778) (xy 76.505437 -282.416182)
			(xy 76.538072 -282.379345) (xy 76.576193 -282.34822) (xy 76.618814 -282.323613) (xy 76.66483 -282.306161)
			(xy 76.713049 -282.296317) (xy 76.762224 -282.294336) (xy 76.811079 -282.300268) (xy 76.85835 -282.31396)
			(xy 76.902812 -282.335058) (xy 76.943315 -282.363014) (xy 76.978808 -282.397106) (xy 77.008373 -282.43645)
			(xy 77.031244 -282.480027) (xy 77.046828 -282.526708) (xy 77.054723 -282.575285) (xy 77.055218 -282.599892)
			(xy 77.394066 -282.599892) (xy 77.398026 -282.550838) (xy 77.409803 -282.503054) (xy 77.429094 -282.457778)
			(xy 77.455397 -282.416182) (xy 77.488032 -282.379345) (xy 77.526153 -282.34822) (xy 77.568774 -282.323613)
			(xy 77.61479 -282.306161) (xy 77.663009 -282.296317) (xy 77.712184 -282.294336) (xy 77.761039 -282.300268)
			(xy 77.80831 -282.31396) (xy 77.852772 -282.335058) (xy 77.893275 -282.363014) (xy 77.928768 -282.397106)
			(xy 77.958333 -282.43645) (xy 77.981204 -282.480027) (xy 77.996788 -282.526708) (xy 78.004683 -282.575285)
			(xy 78.005178 -282.599892) (xy 79.293986 -282.599892) (xy 79.297946 -282.550838) (xy 79.309723 -282.503054)
			(xy 79.329014 -282.457778) (xy 79.355317 -282.416182) (xy 79.387952 -282.379345) (xy 79.426073 -282.34822)
			(xy 79.468694 -282.323613) (xy 79.51471 -282.306161) (xy 79.562929 -282.296317) (xy 79.612104 -282.294336)
			(xy 79.660959 -282.300268) (xy 79.70823 -282.31396) (xy 79.752692 -282.335058) (xy 79.793195 -282.363014)
			(xy 79.828688 -282.397106) (xy 79.858253 -282.43645) (xy 79.881124 -282.480027) (xy 79.896708 -282.526708)
			(xy 79.904603 -282.575285) (xy 79.905098 -282.599892) (xy 80.243946 -282.599892) (xy 80.247906 -282.550838)
			(xy 80.259683 -282.503054) (xy 80.278974 -282.457778) (xy 80.305277 -282.416182) (xy 80.337912 -282.379345)
			(xy 80.376033 -282.34822) (xy 80.418654 -282.323613) (xy 80.46467 -282.306161) (xy 80.512889 -282.296317)
			(xy 80.562064 -282.294336) (xy 80.610919 -282.300268) (xy 80.65819 -282.31396) (xy 80.702652 -282.335058)
			(xy 80.743155 -282.363014) (xy 80.778648 -282.397106) (xy 80.808213 -282.43645) (xy 80.831084 -282.480027)
			(xy 80.846668 -282.526708) (xy 80.854563 -282.575285) (xy 80.855058 -282.599892) (xy 192.544204 -282.599892)
			(xy 192.548164 -282.550838) (xy 192.559941 -282.503054) (xy 192.579232 -282.457778) (xy 192.605535 -282.416182)
			(xy 192.63817 -282.379345) (xy 192.676291 -282.34822) (xy 192.718912 -282.323613) (xy 192.764928 -282.306161)
			(xy 192.813147 -282.296317) (xy 192.862322 -282.294336) (xy 192.911177 -282.300268) (xy 192.958448 -282.31396)
			(xy 193.00291 -282.335058) (xy 193.043413 -282.363014) (xy 193.078906 -282.397106) (xy 193.108471 -282.43645)
			(xy 193.131342 -282.480027) (xy 193.146926 -282.526708) (xy 193.154821 -282.575285) (xy 193.155316 -282.599892)
			(xy 193.494164 -282.599892) (xy 193.498124 -282.550838) (xy 193.509901 -282.503054) (xy 193.529192 -282.457778)
			(xy 193.555495 -282.416182) (xy 193.58813 -282.379345) (xy 193.626251 -282.34822) (xy 193.668872 -282.323613)
			(xy 193.714888 -282.306161) (xy 193.763107 -282.296317) (xy 193.812282 -282.294336) (xy 193.861137 -282.300268)
			(xy 193.908408 -282.31396) (xy 193.95287 -282.335058) (xy 193.993373 -282.363014) (xy 194.028866 -282.397106)
			(xy 194.058431 -282.43645) (xy 194.081302 -282.480027) (xy 194.096886 -282.526708) (xy 194.104781 -282.575285)
			(xy 194.105276 -282.599892) (xy 195.394084 -282.599892) (xy 195.398044 -282.550838) (xy 195.409821 -282.503054)
			(xy 195.429112 -282.457778) (xy 195.455415 -282.416182) (xy 195.48805 -282.379345) (xy 195.526171 -282.34822)
			(xy 195.568792 -282.323613) (xy 195.614808 -282.306161) (xy 195.663027 -282.296317) (xy 195.712202 -282.294336)
			(xy 195.761057 -282.300268) (xy 195.808328 -282.31396) (xy 195.85279 -282.335058) (xy 195.893293 -282.363014)
			(xy 195.928786 -282.397106) (xy 195.958351 -282.43645) (xy 195.981222 -282.480027) (xy 195.996806 -282.526708)
			(xy 196.004701 -282.575285) (xy 196.005196 -282.599892) (xy 196.344044 -282.599892) (xy 196.348004 -282.550838)
			(xy 196.359781 -282.503054) (xy 196.379072 -282.457778) (xy 196.405375 -282.416182) (xy 196.43801 -282.379345)
			(xy 196.476131 -282.34822) (xy 196.518752 -282.323613) (xy 196.564768 -282.306161) (xy 196.612987 -282.296317)
			(xy 196.662162 -282.294336) (xy 196.711017 -282.300268) (xy 196.758288 -282.31396) (xy 196.80275 -282.335058)
			(xy 196.843253 -282.363014) (xy 196.878746 -282.397106) (xy 196.908311 -282.43645) (xy 196.931182 -282.480027)
			(xy 196.946766 -282.526708) (xy 196.954661 -282.575285) (xy 196.955156 -282.599892) (xy 308.644048 -282.599892)
			(xy 308.648008 -282.550838) (xy 308.659785 -282.503054) (xy 308.679076 -282.457778) (xy 308.705379 -282.416182)
			(xy 308.738014 -282.379345) (xy 308.776135 -282.34822) (xy 308.818756 -282.323613) (xy 308.864772 -282.306161)
			(xy 308.912991 -282.296317) (xy 308.962166 -282.294336) (xy 309.011021 -282.300268) (xy 309.058292 -282.31396)
			(xy 309.102754 -282.335058) (xy 309.143257 -282.363014) (xy 309.17875 -282.397106) (xy 309.208315 -282.43645)
			(xy 309.231186 -282.480027) (xy 309.24677 -282.526708) (xy 309.254665 -282.575285) (xy 309.25516 -282.599892)
			(xy 309.594008 -282.599892) (xy 309.597968 -282.550838) (xy 309.609745 -282.503054) (xy 309.629036 -282.457778)
			(xy 309.655339 -282.416182) (xy 309.687974 -282.379345) (xy 309.726095 -282.34822) (xy 309.768716 -282.323613)
			(xy 309.814732 -282.306161) (xy 309.862951 -282.296317) (xy 309.912126 -282.294336) (xy 309.960981 -282.300268)
			(xy 310.008252 -282.31396) (xy 310.052714 -282.335058) (xy 310.093217 -282.363014) (xy 310.12871 -282.397106)
			(xy 310.158275 -282.43645) (xy 310.181146 -282.480027) (xy 310.19673 -282.526708) (xy 310.204625 -282.575285)
			(xy 310.20512 -282.599892) (xy 311.493928 -282.599892) (xy 311.497888 -282.550838) (xy 311.509665 -282.503054)
			(xy 311.528956 -282.457778) (xy 311.555259 -282.416182) (xy 311.587894 -282.379345) (xy 311.626015 -282.34822)
			(xy 311.668636 -282.323613) (xy 311.714652 -282.306161) (xy 311.762871 -282.296317) (xy 311.812046 -282.294336)
			(xy 311.860901 -282.300268) (xy 311.908172 -282.31396) (xy 311.952634 -282.335058) (xy 311.993137 -282.363014)
			(xy 312.02863 -282.397106) (xy 312.058195 -282.43645) (xy 312.081066 -282.480027) (xy 312.09665 -282.526708)
			(xy 312.104545 -282.575285) (xy 312.10504 -282.599892) (xy 312.443888 -282.599892) (xy 312.447848 -282.550838)
			(xy 312.459625 -282.503054) (xy 312.478916 -282.457778) (xy 312.505219 -282.416182) (xy 312.537854 -282.379345)
			(xy 312.575975 -282.34822) (xy 312.618596 -282.323613) (xy 312.664612 -282.306161) (xy 312.712831 -282.296317)
			(xy 312.762006 -282.294336) (xy 312.810861 -282.300268) (xy 312.858132 -282.31396) (xy 312.902594 -282.335058)
			(xy 312.943097 -282.363014) (xy 312.97859 -282.397106) (xy 313.008155 -282.43645) (xy 313.031026 -282.480027)
			(xy 313.04661 -282.526708) (xy 313.054505 -282.575285) (xy 313.055 -282.599892) (xy 424.744146 -282.599892)
			(xy 424.748106 -282.550838) (xy 424.759883 -282.503054) (xy 424.779174 -282.457778) (xy 424.805477 -282.416182)
			(xy 424.838112 -282.379345) (xy 424.876233 -282.34822) (xy 424.918854 -282.323613) (xy 424.96487 -282.306161)
			(xy 425.013089 -282.296317) (xy 425.062264 -282.294336) (xy 425.111119 -282.300268) (xy 425.15839 -282.31396)
			(xy 425.202852 -282.335058) (xy 425.243355 -282.363014) (xy 425.278848 -282.397106) (xy 425.308413 -282.43645)
			(xy 425.331284 -282.480027) (xy 425.346868 -282.526708) (xy 425.354763 -282.575285) (xy 425.355258 -282.599892)
			(xy 425.694106 -282.599892) (xy 425.698066 -282.550838) (xy 425.709843 -282.503054) (xy 425.729134 -282.457778)
			(xy 425.755437 -282.416182) (xy 425.788072 -282.379345) (xy 425.826193 -282.34822) (xy 425.868814 -282.323613)
			(xy 425.91483 -282.306161) (xy 425.963049 -282.296317) (xy 426.012224 -282.294336) (xy 426.061079 -282.300268)
			(xy 426.10835 -282.31396) (xy 426.152812 -282.335058) (xy 426.193315 -282.363014) (xy 426.228808 -282.397106)
			(xy 426.258373 -282.43645) (xy 426.281244 -282.480027) (xy 426.296828 -282.526708) (xy 426.304723 -282.575285)
			(xy 426.305218 -282.599892) (xy 427.594026 -282.599892) (xy 427.597986 -282.550838) (xy 427.609763 -282.503054)
			(xy 427.629054 -282.457778) (xy 427.655357 -282.416182) (xy 427.687992 -282.379345) (xy 427.726113 -282.34822)
			(xy 427.768734 -282.323613) (xy 427.81475 -282.306161) (xy 427.862969 -282.296317) (xy 427.912144 -282.294336)
			(xy 427.960999 -282.300268) (xy 428.00827 -282.31396) (xy 428.052732 -282.335058) (xy 428.093235 -282.363014)
			(xy 428.128728 -282.397106) (xy 428.158293 -282.43645) (xy 428.181164 -282.480027) (xy 428.196748 -282.526708)
			(xy 428.204643 -282.575285) (xy 428.205138 -282.599892) (xy 428.543986 -282.599892) (xy 428.547946 -282.550838)
			(xy 428.559723 -282.503054) (xy 428.579014 -282.457778) (xy 428.605317 -282.416182) (xy 428.637952 -282.379345)
			(xy 428.676073 -282.34822) (xy 428.718694 -282.323613) (xy 428.76471 -282.306161) (xy 428.812929 -282.296317)
			(xy 428.862104 -282.294336) (xy 428.910959 -282.300268) (xy 428.95823 -282.31396) (xy 429.002692 -282.335058)
			(xy 429.043195 -282.363014) (xy 429.078688 -282.397106) (xy 429.108253 -282.43645) (xy 429.131124 -282.480027)
			(xy 429.146708 -282.526708) (xy 429.154603 -282.575285) (xy 429.155098 -282.599892) (xy 429.154603 -282.624499)
			(xy 429.146708 -282.673076) (xy 429.131124 -282.719757) (xy 429.108253 -282.763334) (xy 429.078688 -282.802678)
			(xy 429.043195 -282.83677) (xy 429.002692 -282.864726) (xy 428.95823 -282.885824) (xy 428.910959 -282.899516)
			(xy 428.862104 -282.905448) (xy 428.812929 -282.903467) (xy 428.76471 -282.893623) (xy 428.718694 -282.876171)
			(xy 428.676073 -282.851564) (xy 428.637952 -282.820439) (xy 428.605317 -282.783602) (xy 428.579014 -282.742006)
			(xy 428.559723 -282.69673) (xy 428.547946 -282.648946) (xy 428.543986 -282.599892) (xy 428.205138 -282.599892)
			(xy 428.204643 -282.624499) (xy 428.196748 -282.673076) (xy 428.181164 -282.719757) (xy 428.158293 -282.763334)
			(xy 428.128728 -282.802678) (xy 428.093235 -282.83677) (xy 428.052732 -282.864726) (xy 428.00827 -282.885824)
			(xy 427.960999 -282.899516) (xy 427.912144 -282.905448) (xy 427.862969 -282.903467) (xy 427.81475 -282.893623)
			(xy 427.768734 -282.876171) (xy 427.726113 -282.851564) (xy 427.687992 -282.820439) (xy 427.655357 -282.783602)
			(xy 427.629054 -282.742006) (xy 427.609763 -282.69673) (xy 427.597986 -282.648946) (xy 427.594026 -282.599892)
			(xy 426.305218 -282.599892) (xy 426.304723 -282.624499) (xy 426.296828 -282.673076) (xy 426.281244 -282.719757)
			(xy 426.258373 -282.763334) (xy 426.228808 -282.802678) (xy 426.193315 -282.83677) (xy 426.152812 -282.864726)
			(xy 426.10835 -282.885824) (xy 426.061079 -282.899516) (xy 426.012224 -282.905448) (xy 425.963049 -282.903467)
			(xy 425.91483 -282.893623) (xy 425.868814 -282.876171) (xy 425.826193 -282.851564) (xy 425.788072 -282.820439)
			(xy 425.755437 -282.783602) (xy 425.729134 -282.742006) (xy 425.709843 -282.69673) (xy 425.698066 -282.648946)
			(xy 425.694106 -282.599892) (xy 425.355258 -282.599892) (xy 425.354763 -282.624499) (xy 425.346868 -282.673076)
			(xy 425.331284 -282.719757) (xy 425.308413 -282.763334) (xy 425.278848 -282.802678) (xy 425.243355 -282.83677)
			(xy 425.202852 -282.864726) (xy 425.15839 -282.885824) (xy 425.111119 -282.899516) (xy 425.062264 -282.905448)
			(xy 425.013089 -282.903467) (xy 424.96487 -282.893623) (xy 424.918854 -282.876171) (xy 424.876233 -282.851564)
			(xy 424.838112 -282.820439) (xy 424.805477 -282.783602) (xy 424.779174 -282.742006) (xy 424.759883 -282.69673)
			(xy 424.748106 -282.648946) (xy 424.744146 -282.599892) (xy 313.055 -282.599892) (xy 313.054505 -282.624499)
			(xy 313.04661 -282.673076) (xy 313.031026 -282.719757) (xy 313.008155 -282.763334) (xy 312.97859 -282.802678)
			(xy 312.943097 -282.83677) (xy 312.902594 -282.864726) (xy 312.858132 -282.885824) (xy 312.810861 -282.899516)
			(xy 312.762006 -282.905448) (xy 312.712831 -282.903467) (xy 312.664612 -282.893623) (xy 312.618596 -282.876171)
			(xy 312.575975 -282.851564) (xy 312.537854 -282.820439) (xy 312.505219 -282.783602) (xy 312.478916 -282.742006)
			(xy 312.459625 -282.69673) (xy 312.447848 -282.648946) (xy 312.443888 -282.599892) (xy 312.10504 -282.599892)
			(xy 312.104545 -282.624499) (xy 312.09665 -282.673076) (xy 312.081066 -282.719757) (xy 312.058195 -282.763334)
			(xy 312.02863 -282.802678) (xy 311.993137 -282.83677) (xy 311.952634 -282.864726) (xy 311.908172 -282.885824)
			(xy 311.860901 -282.899516) (xy 311.812046 -282.905448) (xy 311.762871 -282.903467) (xy 311.714652 -282.893623)
			(xy 311.668636 -282.876171) (xy 311.626015 -282.851564) (xy 311.587894 -282.820439) (xy 311.555259 -282.783602)
			(xy 311.528956 -282.742006) (xy 311.509665 -282.69673) (xy 311.497888 -282.648946) (xy 311.493928 -282.599892)
			(xy 310.20512 -282.599892) (xy 310.204625 -282.624499) (xy 310.19673 -282.673076) (xy 310.181146 -282.719757)
			(xy 310.158275 -282.763334) (xy 310.12871 -282.802678) (xy 310.093217 -282.83677) (xy 310.052714 -282.864726)
			(xy 310.008252 -282.885824) (xy 309.960981 -282.899516) (xy 309.912126 -282.905448) (xy 309.862951 -282.903467)
			(xy 309.814732 -282.893623) (xy 309.768716 -282.876171) (xy 309.726095 -282.851564) (xy 309.687974 -282.820439)
			(xy 309.655339 -282.783602) (xy 309.629036 -282.742006) (xy 309.609745 -282.69673) (xy 309.597968 -282.648946)
			(xy 309.594008 -282.599892) (xy 309.25516 -282.599892) (xy 309.254665 -282.624499) (xy 309.24677 -282.673076)
			(xy 309.231186 -282.719757) (xy 309.208315 -282.763334) (xy 309.17875 -282.802678) (xy 309.143257 -282.83677)
			(xy 309.102754 -282.864726) (xy 309.058292 -282.885824) (xy 309.011021 -282.899516) (xy 308.962166 -282.905448)
			(xy 308.912991 -282.903467) (xy 308.864772 -282.893623) (xy 308.818756 -282.876171) (xy 308.776135 -282.851564)
			(xy 308.738014 -282.820439) (xy 308.705379 -282.783602) (xy 308.679076 -282.742006) (xy 308.659785 -282.69673)
			(xy 308.648008 -282.648946) (xy 308.644048 -282.599892) (xy 196.955156 -282.599892) (xy 196.954661 -282.624499)
			(xy 196.946766 -282.673076) (xy 196.931182 -282.719757) (xy 196.908311 -282.763334) (xy 196.878746 -282.802678)
			(xy 196.843253 -282.83677) (xy 196.80275 -282.864726) (xy 196.758288 -282.885824) (xy 196.711017 -282.899516)
			(xy 196.662162 -282.905448) (xy 196.612987 -282.903467) (xy 196.564768 -282.893623) (xy 196.518752 -282.876171)
			(xy 196.476131 -282.851564) (xy 196.43801 -282.820439) (xy 196.405375 -282.783602) (xy 196.379072 -282.742006)
			(xy 196.359781 -282.69673) (xy 196.348004 -282.648946) (xy 196.344044 -282.599892) (xy 196.005196 -282.599892)
			(xy 196.004701 -282.624499) (xy 195.996806 -282.673076) (xy 195.981222 -282.719757) (xy 195.958351 -282.763334)
			(xy 195.928786 -282.802678) (xy 195.893293 -282.83677) (xy 195.85279 -282.864726) (xy 195.808328 -282.885824)
			(xy 195.761057 -282.899516) (xy 195.712202 -282.905448) (xy 195.663027 -282.903467) (xy 195.614808 -282.893623)
			(xy 195.568792 -282.876171) (xy 195.526171 -282.851564) (xy 195.48805 -282.820439) (xy 195.455415 -282.783602)
			(xy 195.429112 -282.742006) (xy 195.409821 -282.69673) (xy 195.398044 -282.648946) (xy 195.394084 -282.599892)
			(xy 194.105276 -282.599892) (xy 194.104781 -282.624499) (xy 194.096886 -282.673076) (xy 194.081302 -282.719757)
			(xy 194.058431 -282.763334) (xy 194.028866 -282.802678) (xy 193.993373 -282.83677) (xy 193.95287 -282.864726)
			(xy 193.908408 -282.885824) (xy 193.861137 -282.899516) (xy 193.812282 -282.905448) (xy 193.763107 -282.903467)
			(xy 193.714888 -282.893623) (xy 193.668872 -282.876171) (xy 193.626251 -282.851564) (xy 193.58813 -282.820439)
			(xy 193.555495 -282.783602) (xy 193.529192 -282.742006) (xy 193.509901 -282.69673) (xy 193.498124 -282.648946)
			(xy 193.494164 -282.599892) (xy 193.155316 -282.599892) (xy 193.154821 -282.624499) (xy 193.146926 -282.673076)
			(xy 193.131342 -282.719757) (xy 193.108471 -282.763334) (xy 193.078906 -282.802678) (xy 193.043413 -282.83677)
			(xy 193.00291 -282.864726) (xy 192.958448 -282.885824) (xy 192.911177 -282.899516) (xy 192.862322 -282.905448)
			(xy 192.813147 -282.903467) (xy 192.764928 -282.893623) (xy 192.718912 -282.876171) (xy 192.676291 -282.851564)
			(xy 192.63817 -282.820439) (xy 192.605535 -282.783602) (xy 192.579232 -282.742006) (xy 192.559941 -282.69673)
			(xy 192.548164 -282.648946) (xy 192.544204 -282.599892) (xy 80.855058 -282.599892) (xy 80.854563 -282.624499)
			(xy 80.846668 -282.673076) (xy 80.831084 -282.719757) (xy 80.808213 -282.763334) (xy 80.778648 -282.802678)
			(xy 80.743155 -282.83677) (xy 80.702652 -282.864726) (xy 80.65819 -282.885824) (xy 80.610919 -282.899516)
			(xy 80.562064 -282.905448) (xy 80.512889 -282.903467) (xy 80.46467 -282.893623) (xy 80.418654 -282.876171)
			(xy 80.376033 -282.851564) (xy 80.337912 -282.820439) (xy 80.305277 -282.783602) (xy 80.278974 -282.742006)
			(xy 80.259683 -282.69673) (xy 80.247906 -282.648946) (xy 80.243946 -282.599892) (xy 79.905098 -282.599892)
			(xy 79.904603 -282.624499) (xy 79.896708 -282.673076) (xy 79.881124 -282.719757) (xy 79.858253 -282.763334)
			(xy 79.828688 -282.802678) (xy 79.793195 -282.83677) (xy 79.752692 -282.864726) (xy 79.70823 -282.885824)
			(xy 79.660959 -282.899516) (xy 79.612104 -282.905448) (xy 79.562929 -282.903467) (xy 79.51471 -282.893623)
			(xy 79.468694 -282.876171) (xy 79.426073 -282.851564) (xy 79.387952 -282.820439) (xy 79.355317 -282.783602)
			(xy 79.329014 -282.742006) (xy 79.309723 -282.69673) (xy 79.297946 -282.648946) (xy 79.293986 -282.599892)
			(xy 78.005178 -282.599892) (xy 78.004683 -282.624499) (xy 77.996788 -282.673076) (xy 77.981204 -282.719757)
			(xy 77.958333 -282.763334) (xy 77.928768 -282.802678) (xy 77.893275 -282.83677) (xy 77.852772 -282.864726)
			(xy 77.80831 -282.885824) (xy 77.761039 -282.899516) (xy 77.712184 -282.905448) (xy 77.663009 -282.903467)
			(xy 77.61479 -282.893623) (xy 77.568774 -282.876171) (xy 77.526153 -282.851564) (xy 77.488032 -282.820439)
			(xy 77.455397 -282.783602) (xy 77.429094 -282.742006) (xy 77.409803 -282.69673) (xy 77.398026 -282.648946)
			(xy 77.394066 -282.599892) (xy 77.055218 -282.599892) (xy 77.054723 -282.624499) (xy 77.046828 -282.673076)
			(xy 77.031244 -282.719757) (xy 77.008373 -282.763334) (xy 76.978808 -282.802678) (xy 76.943315 -282.83677)
			(xy 76.902812 -282.864726) (xy 76.85835 -282.885824) (xy 76.811079 -282.899516) (xy 76.762224 -282.905448)
			(xy 76.713049 -282.903467) (xy 76.66483 -282.893623) (xy 76.618814 -282.876171) (xy 76.576193 -282.851564)
			(xy 76.538072 -282.820439) (xy 76.505437 -282.783602) (xy 76.479134 -282.742006) (xy 76.459843 -282.69673)
			(xy 76.448066 -282.648946) (xy 76.444106 -282.599892) (xy 0.508 -282.599892) (xy 0.508 -283.549852)
			(xy 74.543932 -283.549852) (xy 74.547892 -283.500798) (xy 74.559669 -283.453014) (xy 74.57896 -283.407738)
			(xy 74.605263 -283.366142) (xy 74.637898 -283.329305) (xy 74.676019 -283.29818) (xy 74.71864 -283.273573)
			(xy 74.764656 -283.256121) (xy 74.812875 -283.246277) (xy 74.86205 -283.244296) (xy 74.910905 -283.250228)
			(xy 74.958176 -283.26392) (xy 75.002638 -283.285018) (xy 75.043141 -283.312974) (xy 75.078634 -283.347066)
			(xy 75.108199 -283.38641) (xy 75.13107 -283.429987) (xy 75.146654 -283.476668) (xy 75.154549 -283.525245)
			(xy 75.155044 -283.549852) (xy 75.494146 -283.549852) (xy 75.498106 -283.500798) (xy 75.509883 -283.453014)
			(xy 75.529174 -283.407738) (xy 75.555477 -283.366142) (xy 75.588112 -283.329305) (xy 75.626233 -283.29818)
			(xy 75.668854 -283.273573) (xy 75.71487 -283.256121) (xy 75.763089 -283.246277) (xy 75.812264 -283.244296)
			(xy 75.861119 -283.250228) (xy 75.90839 -283.26392) (xy 75.952852 -283.285018) (xy 75.993355 -283.312974)
			(xy 76.028848 -283.347066) (xy 76.058413 -283.38641) (xy 76.081284 -283.429987) (xy 76.096868 -283.476668)
			(xy 76.104763 -283.525245) (xy 76.105258 -283.549852) (xy 81.19416 -283.549852) (xy 81.19812 -283.500798)
			(xy 81.209897 -283.453014) (xy 81.229188 -283.407738) (xy 81.255491 -283.366142) (xy 81.288126 -283.329305)
			(xy 81.326247 -283.29818) (xy 81.368868 -283.273573) (xy 81.414884 -283.256121) (xy 81.463103 -283.246277)
			(xy 81.512278 -283.244296) (xy 81.561133 -283.250228) (xy 81.608404 -283.26392) (xy 81.652866 -283.285018)
			(xy 81.693369 -283.312974) (xy 81.728862 -283.347066) (xy 81.758427 -283.38641) (xy 81.781298 -283.429987)
			(xy 81.796882 -283.476668) (xy 81.804777 -283.525245) (xy 81.805272 -283.549852) (xy 82.14412 -283.549852)
			(xy 82.14808 -283.500798) (xy 82.159857 -283.453014) (xy 82.179148 -283.407738) (xy 82.205451 -283.366142)
			(xy 82.238086 -283.329305) (xy 82.276207 -283.29818) (xy 82.318828 -283.273573) (xy 82.364844 -283.256121)
			(xy 82.413063 -283.246277) (xy 82.462238 -283.244296) (xy 82.511093 -283.250228) (xy 82.558364 -283.26392)
			(xy 82.602826 -283.285018) (xy 82.643329 -283.312974) (xy 82.678822 -283.347066) (xy 82.708387 -283.38641)
			(xy 82.731258 -283.429987) (xy 82.746842 -283.476668) (xy 82.754737 -283.525245) (xy 82.755232 -283.549852)
			(xy 190.64403 -283.549852) (xy 190.64799 -283.500798) (xy 190.659767 -283.453014) (xy 190.679058 -283.407738)
			(xy 190.705361 -283.366142) (xy 190.737996 -283.329305) (xy 190.776117 -283.29818) (xy 190.818738 -283.273573)
			(xy 190.864754 -283.256121) (xy 190.912973 -283.246277) (xy 190.962148 -283.244296) (xy 191.011003 -283.250228)
			(xy 191.058274 -283.26392) (xy 191.102736 -283.285018) (xy 191.143239 -283.312974) (xy 191.178732 -283.347066)
			(xy 191.208297 -283.38641) (xy 191.231168 -283.429987) (xy 191.246752 -283.476668) (xy 191.254647 -283.525245)
			(xy 191.255142 -283.549852) (xy 191.594244 -283.549852) (xy 191.598204 -283.500798) (xy 191.609981 -283.453014)
			(xy 191.629272 -283.407738) (xy 191.655575 -283.366142) (xy 191.68821 -283.329305) (xy 191.726331 -283.29818)
			(xy 191.768952 -283.273573) (xy 191.814968 -283.256121) (xy 191.863187 -283.246277) (xy 191.912362 -283.244296)
			(xy 191.961217 -283.250228) (xy 192.008488 -283.26392) (xy 192.05295 -283.285018) (xy 192.093453 -283.312974)
			(xy 192.128946 -283.347066) (xy 192.158511 -283.38641) (xy 192.181382 -283.429987) (xy 192.196966 -283.476668)
			(xy 192.204861 -283.525245) (xy 192.205356 -283.549852) (xy 197.294258 -283.549852) (xy 197.298218 -283.500798)
			(xy 197.309995 -283.453014) (xy 197.329286 -283.407738) (xy 197.355589 -283.366142) (xy 197.388224 -283.329305)
			(xy 197.426345 -283.29818) (xy 197.468966 -283.273573) (xy 197.514982 -283.256121) (xy 197.563201 -283.246277)
			(xy 197.612376 -283.244296) (xy 197.661231 -283.250228) (xy 197.708502 -283.26392) (xy 197.752964 -283.285018)
			(xy 197.793467 -283.312974) (xy 197.82896 -283.347066) (xy 197.858525 -283.38641) (xy 197.881396 -283.429987)
			(xy 197.89698 -283.476668) (xy 197.904875 -283.525245) (xy 197.90537 -283.549852) (xy 198.244218 -283.549852)
			(xy 198.248178 -283.500798) (xy 198.259955 -283.453014) (xy 198.279246 -283.407738) (xy 198.305549 -283.366142)
			(xy 198.338184 -283.329305) (xy 198.376305 -283.29818) (xy 198.418926 -283.273573) (xy 198.464942 -283.256121)
			(xy 198.513161 -283.246277) (xy 198.562336 -283.244296) (xy 198.611191 -283.250228) (xy 198.658462 -283.26392)
			(xy 198.702924 -283.285018) (xy 198.743427 -283.312974) (xy 198.77892 -283.347066) (xy 198.808485 -283.38641)
			(xy 198.831356 -283.429987) (xy 198.84694 -283.476668) (xy 198.854835 -283.525245) (xy 198.85533 -283.549852)
			(xy 306.744128 -283.549852) (xy 306.748088 -283.500798) (xy 306.759865 -283.453014) (xy 306.779156 -283.407738)
			(xy 306.805459 -283.366142) (xy 306.838094 -283.329305) (xy 306.876215 -283.29818) (xy 306.918836 -283.273573)
			(xy 306.964852 -283.256121) (xy 307.013071 -283.246277) (xy 307.062246 -283.244296) (xy 307.111101 -283.250228)
			(xy 307.158372 -283.26392) (xy 307.202834 -283.285018) (xy 307.243337 -283.312974) (xy 307.27883 -283.347066)
			(xy 307.308395 -283.38641) (xy 307.331266 -283.429987) (xy 307.34685 -283.476668) (xy 307.354745 -283.525245)
			(xy 307.35524 -283.549852) (xy 307.694088 -283.549852) (xy 307.698048 -283.500798) (xy 307.709825 -283.453014)
			(xy 307.729116 -283.407738) (xy 307.755419 -283.366142) (xy 307.788054 -283.329305) (xy 307.826175 -283.29818)
			(xy 307.868796 -283.273573) (xy 307.914812 -283.256121) (xy 307.963031 -283.246277) (xy 308.012206 -283.244296)
			(xy 308.061061 -283.250228) (xy 308.108332 -283.26392) (xy 308.152794 -283.285018) (xy 308.193297 -283.312974)
			(xy 308.22879 -283.347066) (xy 308.258355 -283.38641) (xy 308.281226 -283.429987) (xy 308.29681 -283.476668)
			(xy 308.304705 -283.525245) (xy 308.3052 -283.549852) (xy 313.394102 -283.549852) (xy 313.398062 -283.500798)
			(xy 313.409839 -283.453014) (xy 313.42913 -283.407738) (xy 313.455433 -283.366142) (xy 313.488068 -283.329305)
			(xy 313.526189 -283.29818) (xy 313.56881 -283.273573) (xy 313.614826 -283.256121) (xy 313.663045 -283.246277)
			(xy 313.71222 -283.244296) (xy 313.761075 -283.250228) (xy 313.808346 -283.26392) (xy 313.852808 -283.285018)
			(xy 313.893311 -283.312974) (xy 313.928804 -283.347066) (xy 313.958369 -283.38641) (xy 313.98124 -283.429987)
			(xy 313.996824 -283.476668) (xy 314.004719 -283.525245) (xy 314.005214 -283.549852) (xy 314.344062 -283.549852)
			(xy 314.348022 -283.500798) (xy 314.359799 -283.453014) (xy 314.37909 -283.407738) (xy 314.405393 -283.366142)
			(xy 314.438028 -283.329305) (xy 314.476149 -283.29818) (xy 314.51877 -283.273573) (xy 314.564786 -283.256121)
			(xy 314.613005 -283.246277) (xy 314.66218 -283.244296) (xy 314.711035 -283.250228) (xy 314.758306 -283.26392)
			(xy 314.802768 -283.285018) (xy 314.843271 -283.312974) (xy 314.878764 -283.347066) (xy 314.908329 -283.38641)
			(xy 314.9312 -283.429987) (xy 314.946784 -283.476668) (xy 314.954679 -283.525245) (xy 314.955174 -283.549852)
			(xy 422.844226 -283.549852) (xy 422.848186 -283.500798) (xy 422.859963 -283.453014) (xy 422.879254 -283.407738)
			(xy 422.905557 -283.366142) (xy 422.938192 -283.329305) (xy 422.976313 -283.29818) (xy 423.018934 -283.273573)
			(xy 423.06495 -283.256121) (xy 423.113169 -283.246277) (xy 423.162344 -283.244296) (xy 423.211199 -283.250228)
			(xy 423.25847 -283.26392) (xy 423.302932 -283.285018) (xy 423.343435 -283.312974) (xy 423.378928 -283.347066)
			(xy 423.408493 -283.38641) (xy 423.431364 -283.429987) (xy 423.446948 -283.476668) (xy 423.454843 -283.525245)
			(xy 423.455338 -283.549852) (xy 423.794186 -283.549852) (xy 423.798146 -283.500798) (xy 423.809923 -283.453014)
			(xy 423.829214 -283.407738) (xy 423.855517 -283.366142) (xy 423.888152 -283.329305) (xy 423.926273 -283.29818)
			(xy 423.968894 -283.273573) (xy 424.01491 -283.256121) (xy 424.063129 -283.246277) (xy 424.112304 -283.244296)
			(xy 424.161159 -283.250228) (xy 424.20843 -283.26392) (xy 424.252892 -283.285018) (xy 424.293395 -283.312974)
			(xy 424.328888 -283.347066) (xy 424.358453 -283.38641) (xy 424.381324 -283.429987) (xy 424.396908 -283.476668)
			(xy 424.404803 -283.525245) (xy 424.405298 -283.549852) (xy 429.4942 -283.549852) (xy 429.49816 -283.500798)
			(xy 429.509937 -283.453014) (xy 429.529228 -283.407738) (xy 429.555531 -283.366142) (xy 429.588166 -283.329305)
			(xy 429.626287 -283.29818) (xy 429.668908 -283.273573) (xy 429.714924 -283.256121) (xy 429.763143 -283.246277)
			(xy 429.812318 -283.244296) (xy 429.861173 -283.250228) (xy 429.908444 -283.26392) (xy 429.952906 -283.285018)
			(xy 429.993409 -283.312974) (xy 430.028902 -283.347066) (xy 430.058467 -283.38641) (xy 430.081338 -283.429987)
			(xy 430.096922 -283.476668) (xy 430.104817 -283.525245) (xy 430.105312 -283.549852) (xy 430.44416 -283.549852)
			(xy 430.44812 -283.500798) (xy 430.459897 -283.453014) (xy 430.479188 -283.407738) (xy 430.505491 -283.366142)
			(xy 430.538126 -283.329305) (xy 430.576247 -283.29818) (xy 430.618868 -283.273573) (xy 430.664884 -283.256121)
			(xy 430.713103 -283.246277) (xy 430.762278 -283.244296) (xy 430.811133 -283.250228) (xy 430.858404 -283.26392)
			(xy 430.902866 -283.285018) (xy 430.943369 -283.312974) (xy 430.978862 -283.347066) (xy 431.008427 -283.38641)
			(xy 431.031298 -283.429987) (xy 431.046882 -283.476668) (xy 431.054777 -283.525245) (xy 431.055272 -283.549852)
			(xy 431.054777 -283.574459) (xy 431.046882 -283.623036) (xy 431.031298 -283.669717) (xy 431.008427 -283.713294)
			(xy 430.978862 -283.752638) (xy 430.943369 -283.78673) (xy 430.902866 -283.814686) (xy 430.858404 -283.835784)
			(xy 430.811133 -283.849476) (xy 430.762278 -283.855408) (xy 430.713103 -283.853427) (xy 430.664884 -283.843583)
			(xy 430.618868 -283.826131) (xy 430.576247 -283.801524) (xy 430.538126 -283.770399) (xy 430.505491 -283.733562)
			(xy 430.479188 -283.691966) (xy 430.459897 -283.64669) (xy 430.44812 -283.598906) (xy 430.44416 -283.549852)
			(xy 430.105312 -283.549852) (xy 430.104817 -283.574459) (xy 430.096922 -283.623036) (xy 430.081338 -283.669717)
			(xy 430.058467 -283.713294) (xy 430.028902 -283.752638) (xy 429.993409 -283.78673) (xy 429.952906 -283.814686)
			(xy 429.908444 -283.835784) (xy 429.861173 -283.849476) (xy 429.812318 -283.855408) (xy 429.763143 -283.853427)
			(xy 429.714924 -283.843583) (xy 429.668908 -283.826131) (xy 429.626287 -283.801524) (xy 429.588166 -283.770399)
			(xy 429.555531 -283.733562) (xy 429.529228 -283.691966) (xy 429.509937 -283.64669) (xy 429.49816 -283.598906)
			(xy 429.4942 -283.549852) (xy 424.405298 -283.549852) (xy 424.404803 -283.574459) (xy 424.396908 -283.623036)
			(xy 424.381324 -283.669717) (xy 424.358453 -283.713294) (xy 424.328888 -283.752638) (xy 424.293395 -283.78673)
			(xy 424.252892 -283.814686) (xy 424.20843 -283.835784) (xy 424.161159 -283.849476) (xy 424.112304 -283.855408)
			(xy 424.063129 -283.853427) (xy 424.01491 -283.843583) (xy 423.968894 -283.826131) (xy 423.926273 -283.801524)
			(xy 423.888152 -283.770399) (xy 423.855517 -283.733562) (xy 423.829214 -283.691966) (xy 423.809923 -283.64669)
			(xy 423.798146 -283.598906) (xy 423.794186 -283.549852) (xy 423.455338 -283.549852) (xy 423.454843 -283.574459)
			(xy 423.446948 -283.623036) (xy 423.431364 -283.669717) (xy 423.408493 -283.713294) (xy 423.378928 -283.752638)
			(xy 423.343435 -283.78673) (xy 423.302932 -283.814686) (xy 423.25847 -283.835784) (xy 423.211199 -283.849476)
			(xy 423.162344 -283.855408) (xy 423.113169 -283.853427) (xy 423.06495 -283.843583) (xy 423.018934 -283.826131)
			(xy 422.976313 -283.801524) (xy 422.938192 -283.770399) (xy 422.905557 -283.733562) (xy 422.879254 -283.691966)
			(xy 422.859963 -283.64669) (xy 422.848186 -283.598906) (xy 422.844226 -283.549852) (xy 314.955174 -283.549852)
			(xy 314.954679 -283.574459) (xy 314.946784 -283.623036) (xy 314.9312 -283.669717) (xy 314.908329 -283.713294)
			(xy 314.878764 -283.752638) (xy 314.843271 -283.78673) (xy 314.802768 -283.814686) (xy 314.758306 -283.835784)
			(xy 314.711035 -283.849476) (xy 314.66218 -283.855408) (xy 314.613005 -283.853427) (xy 314.564786 -283.843583)
			(xy 314.51877 -283.826131) (xy 314.476149 -283.801524) (xy 314.438028 -283.770399) (xy 314.405393 -283.733562)
			(xy 314.37909 -283.691966) (xy 314.359799 -283.64669) (xy 314.348022 -283.598906) (xy 314.344062 -283.549852)
			(xy 314.005214 -283.549852) (xy 314.004719 -283.574459) (xy 313.996824 -283.623036) (xy 313.98124 -283.669717)
			(xy 313.958369 -283.713294) (xy 313.928804 -283.752638) (xy 313.893311 -283.78673) (xy 313.852808 -283.814686)
			(xy 313.808346 -283.835784) (xy 313.761075 -283.849476) (xy 313.71222 -283.855408) (xy 313.663045 -283.853427)
			(xy 313.614826 -283.843583) (xy 313.56881 -283.826131) (xy 313.526189 -283.801524) (xy 313.488068 -283.770399)
			(xy 313.455433 -283.733562) (xy 313.42913 -283.691966) (xy 313.409839 -283.64669) (xy 313.398062 -283.598906)
			(xy 313.394102 -283.549852) (xy 308.3052 -283.549852) (xy 308.304705 -283.574459) (xy 308.29681 -283.623036)
			(xy 308.281226 -283.669717) (xy 308.258355 -283.713294) (xy 308.22879 -283.752638) (xy 308.193297 -283.78673)
			(xy 308.152794 -283.814686) (xy 308.108332 -283.835784) (xy 308.061061 -283.849476) (xy 308.012206 -283.855408)
			(xy 307.963031 -283.853427) (xy 307.914812 -283.843583) (xy 307.868796 -283.826131) (xy 307.826175 -283.801524)
			(xy 307.788054 -283.770399) (xy 307.755419 -283.733562) (xy 307.729116 -283.691966) (xy 307.709825 -283.64669)
			(xy 307.698048 -283.598906) (xy 307.694088 -283.549852) (xy 307.35524 -283.549852) (xy 307.354745 -283.574459)
			(xy 307.34685 -283.623036) (xy 307.331266 -283.669717) (xy 307.308395 -283.713294) (xy 307.27883 -283.752638)
			(xy 307.243337 -283.78673) (xy 307.202834 -283.814686) (xy 307.158372 -283.835784) (xy 307.111101 -283.849476)
			(xy 307.062246 -283.855408) (xy 307.013071 -283.853427) (xy 306.964852 -283.843583) (xy 306.918836 -283.826131)
			(xy 306.876215 -283.801524) (xy 306.838094 -283.770399) (xy 306.805459 -283.733562) (xy 306.779156 -283.691966)
			(xy 306.759865 -283.64669) (xy 306.748088 -283.598906) (xy 306.744128 -283.549852) (xy 198.85533 -283.549852)
			(xy 198.854835 -283.574459) (xy 198.84694 -283.623036) (xy 198.831356 -283.669717) (xy 198.808485 -283.713294)
			(xy 198.77892 -283.752638) (xy 198.743427 -283.78673) (xy 198.702924 -283.814686) (xy 198.658462 -283.835784)
			(xy 198.611191 -283.849476) (xy 198.562336 -283.855408) (xy 198.513161 -283.853427) (xy 198.464942 -283.843583)
			(xy 198.418926 -283.826131) (xy 198.376305 -283.801524) (xy 198.338184 -283.770399) (xy 198.305549 -283.733562)
			(xy 198.279246 -283.691966) (xy 198.259955 -283.64669) (xy 198.248178 -283.598906) (xy 198.244218 -283.549852)
			(xy 197.90537 -283.549852) (xy 197.904875 -283.574459) (xy 197.89698 -283.623036) (xy 197.881396 -283.669717)
			(xy 197.858525 -283.713294) (xy 197.82896 -283.752638) (xy 197.793467 -283.78673) (xy 197.752964 -283.814686)
			(xy 197.708502 -283.835784) (xy 197.661231 -283.849476) (xy 197.612376 -283.855408) (xy 197.563201 -283.853427)
			(xy 197.514982 -283.843583) (xy 197.468966 -283.826131) (xy 197.426345 -283.801524) (xy 197.388224 -283.770399)
			(xy 197.355589 -283.733562) (xy 197.329286 -283.691966) (xy 197.309995 -283.64669) (xy 197.298218 -283.598906)
			(xy 197.294258 -283.549852) (xy 192.205356 -283.549852) (xy 192.204861 -283.574459) (xy 192.196966 -283.623036)
			(xy 192.181382 -283.669717) (xy 192.158511 -283.713294) (xy 192.128946 -283.752638) (xy 192.093453 -283.78673)
			(xy 192.05295 -283.814686) (xy 192.008488 -283.835784) (xy 191.961217 -283.849476) (xy 191.912362 -283.855408)
			(xy 191.863187 -283.853427) (xy 191.814968 -283.843583) (xy 191.768952 -283.826131) (xy 191.726331 -283.801524)
			(xy 191.68821 -283.770399) (xy 191.655575 -283.733562) (xy 191.629272 -283.691966) (xy 191.609981 -283.64669)
			(xy 191.598204 -283.598906) (xy 191.594244 -283.549852) (xy 191.255142 -283.549852) (xy 191.254647 -283.574459)
			(xy 191.246752 -283.623036) (xy 191.231168 -283.669717) (xy 191.208297 -283.713294) (xy 191.178732 -283.752638)
			(xy 191.143239 -283.78673) (xy 191.102736 -283.814686) (xy 191.058274 -283.835784) (xy 191.011003 -283.849476)
			(xy 190.962148 -283.855408) (xy 190.912973 -283.853427) (xy 190.864754 -283.843583) (xy 190.818738 -283.826131)
			(xy 190.776117 -283.801524) (xy 190.737996 -283.770399) (xy 190.705361 -283.733562) (xy 190.679058 -283.691966)
			(xy 190.659767 -283.64669) (xy 190.64799 -283.598906) (xy 190.64403 -283.549852) (xy 82.755232 -283.549852)
			(xy 82.754737 -283.574459) (xy 82.746842 -283.623036) (xy 82.731258 -283.669717) (xy 82.708387 -283.713294)
			(xy 82.678822 -283.752638) (xy 82.643329 -283.78673) (xy 82.602826 -283.814686) (xy 82.558364 -283.835784)
			(xy 82.511093 -283.849476) (xy 82.462238 -283.855408) (xy 82.413063 -283.853427) (xy 82.364844 -283.843583)
			(xy 82.318828 -283.826131) (xy 82.276207 -283.801524) (xy 82.238086 -283.770399) (xy 82.205451 -283.733562)
			(xy 82.179148 -283.691966) (xy 82.159857 -283.64669) (xy 82.14808 -283.598906) (xy 82.14412 -283.549852)
			(xy 81.805272 -283.549852) (xy 81.804777 -283.574459) (xy 81.796882 -283.623036) (xy 81.781298 -283.669717)
			(xy 81.758427 -283.713294) (xy 81.728862 -283.752638) (xy 81.693369 -283.78673) (xy 81.652866 -283.814686)
			(xy 81.608404 -283.835784) (xy 81.561133 -283.849476) (xy 81.512278 -283.855408) (xy 81.463103 -283.853427)
			(xy 81.414884 -283.843583) (xy 81.368868 -283.826131) (xy 81.326247 -283.801524) (xy 81.288126 -283.770399)
			(xy 81.255491 -283.733562) (xy 81.229188 -283.691966) (xy 81.209897 -283.64669) (xy 81.19812 -283.598906)
			(xy 81.19416 -283.549852) (xy 76.105258 -283.549852) (xy 76.104763 -283.574459) (xy 76.096868 -283.623036)
			(xy 76.081284 -283.669717) (xy 76.058413 -283.713294) (xy 76.028848 -283.752638) (xy 75.993355 -283.78673)
			(xy 75.952852 -283.814686) (xy 75.90839 -283.835784) (xy 75.861119 -283.849476) (xy 75.812264 -283.855408)
			(xy 75.763089 -283.853427) (xy 75.71487 -283.843583) (xy 75.668854 -283.826131) (xy 75.626233 -283.801524)
			(xy 75.588112 -283.770399) (xy 75.555477 -283.733562) (xy 75.529174 -283.691966) (xy 75.509883 -283.64669)
			(xy 75.498106 -283.598906) (xy 75.494146 -283.549852) (xy 75.155044 -283.549852) (xy 75.154549 -283.574459)
			(xy 75.146654 -283.623036) (xy 75.13107 -283.669717) (xy 75.108199 -283.713294) (xy 75.078634 -283.752638)
			(xy 75.043141 -283.78673) (xy 75.002638 -283.814686) (xy 74.958176 -283.835784) (xy 74.910905 -283.849476)
			(xy 74.86205 -283.855408) (xy 74.812875 -283.853427) (xy 74.764656 -283.843583) (xy 74.71864 -283.826131)
			(xy 74.676019 -283.801524) (xy 74.637898 -283.770399) (xy 74.605263 -283.733562) (xy 74.57896 -283.691966)
			(xy 74.559669 -283.64669) (xy 74.547892 -283.598906) (xy 74.543932 -283.549852) (xy 0.508 -283.549852)
			(xy 0.508 -284.499812) (xy 76.444106 -284.499812) (xy 76.448066 -284.450758) (xy 76.459843 -284.402974)
			(xy 76.479134 -284.357698) (xy 76.505437 -284.316102) (xy 76.538072 -284.279265) (xy 76.576193 -284.24814)
			(xy 76.618814 -284.223533) (xy 76.66483 -284.206081) (xy 76.713049 -284.196237) (xy 76.762224 -284.194256)
			(xy 76.811079 -284.200188) (xy 76.85835 -284.21388) (xy 76.902812 -284.234978) (xy 76.943315 -284.262934)
			(xy 76.978808 -284.297026) (xy 77.008373 -284.33637) (xy 77.031244 -284.379947) (xy 77.046828 -284.426628)
			(xy 77.054723 -284.475205) (xy 77.055218 -284.499812) (xy 77.394066 -284.499812) (xy 77.398026 -284.450758)
			(xy 77.409803 -284.402974) (xy 77.429094 -284.357698) (xy 77.455397 -284.316102) (xy 77.488032 -284.279265)
			(xy 77.526153 -284.24814) (xy 77.568774 -284.223533) (xy 77.61479 -284.206081) (xy 77.663009 -284.196237)
			(xy 77.712184 -284.194256) (xy 77.761039 -284.200188) (xy 77.80831 -284.21388) (xy 77.852772 -284.234978)
			(xy 77.893275 -284.262934) (xy 77.928768 -284.297026) (xy 77.958333 -284.33637) (xy 77.981204 -284.379947)
			(xy 77.996788 -284.426628) (xy 78.004683 -284.475205) (xy 78.005178 -284.499812) (xy 79.293986 -284.499812)
			(xy 79.297946 -284.450758) (xy 79.309723 -284.402974) (xy 79.329014 -284.357698) (xy 79.355317 -284.316102)
			(xy 79.387952 -284.279265) (xy 79.426073 -284.24814) (xy 79.468694 -284.223533) (xy 79.51471 -284.206081)
			(xy 79.562929 -284.196237) (xy 79.612104 -284.194256) (xy 79.660959 -284.200188) (xy 79.70823 -284.21388)
			(xy 79.752692 -284.234978) (xy 79.793195 -284.262934) (xy 79.828688 -284.297026) (xy 79.858253 -284.33637)
			(xy 79.881124 -284.379947) (xy 79.896708 -284.426628) (xy 79.904603 -284.475205) (xy 79.905098 -284.499812)
			(xy 80.243946 -284.499812) (xy 80.247906 -284.450758) (xy 80.259683 -284.402974) (xy 80.278974 -284.357698)
			(xy 80.305277 -284.316102) (xy 80.337912 -284.279265) (xy 80.376033 -284.24814) (xy 80.418654 -284.223533)
			(xy 80.46467 -284.206081) (xy 80.512889 -284.196237) (xy 80.562064 -284.194256) (xy 80.610919 -284.200188)
			(xy 80.65819 -284.21388) (xy 80.702652 -284.234978) (xy 80.743155 -284.262934) (xy 80.778648 -284.297026)
			(xy 80.808213 -284.33637) (xy 80.831084 -284.379947) (xy 80.846668 -284.426628) (xy 80.854563 -284.475205)
			(xy 80.855058 -284.499812) (xy 192.544204 -284.499812) (xy 192.548164 -284.450758) (xy 192.559941 -284.402974)
			(xy 192.579232 -284.357698) (xy 192.605535 -284.316102) (xy 192.63817 -284.279265) (xy 192.676291 -284.24814)
			(xy 192.718912 -284.223533) (xy 192.764928 -284.206081) (xy 192.813147 -284.196237) (xy 192.862322 -284.194256)
			(xy 192.911177 -284.200188) (xy 192.958448 -284.21388) (xy 193.00291 -284.234978) (xy 193.043413 -284.262934)
			(xy 193.078906 -284.297026) (xy 193.108471 -284.33637) (xy 193.131342 -284.379947) (xy 193.146926 -284.426628)
			(xy 193.154821 -284.475205) (xy 193.155316 -284.499812) (xy 193.494164 -284.499812) (xy 193.498124 -284.450758)
			(xy 193.509901 -284.402974) (xy 193.529192 -284.357698) (xy 193.555495 -284.316102) (xy 193.58813 -284.279265)
			(xy 193.626251 -284.24814) (xy 193.668872 -284.223533) (xy 193.714888 -284.206081) (xy 193.763107 -284.196237)
			(xy 193.812282 -284.194256) (xy 193.861137 -284.200188) (xy 193.908408 -284.21388) (xy 193.95287 -284.234978)
			(xy 193.993373 -284.262934) (xy 194.028866 -284.297026) (xy 194.058431 -284.33637) (xy 194.081302 -284.379947)
			(xy 194.096886 -284.426628) (xy 194.104781 -284.475205) (xy 194.105276 -284.499812) (xy 195.394084 -284.499812)
			(xy 195.398044 -284.450758) (xy 195.409821 -284.402974) (xy 195.429112 -284.357698) (xy 195.455415 -284.316102)
			(xy 195.48805 -284.279265) (xy 195.526171 -284.24814) (xy 195.568792 -284.223533) (xy 195.614808 -284.206081)
			(xy 195.663027 -284.196237) (xy 195.712202 -284.194256) (xy 195.761057 -284.200188) (xy 195.808328 -284.21388)
			(xy 195.85279 -284.234978) (xy 195.893293 -284.262934) (xy 195.928786 -284.297026) (xy 195.958351 -284.33637)
			(xy 195.981222 -284.379947) (xy 195.996806 -284.426628) (xy 196.004701 -284.475205) (xy 196.005196 -284.499812)
			(xy 196.344044 -284.499812) (xy 196.348004 -284.450758) (xy 196.359781 -284.402974) (xy 196.379072 -284.357698)
			(xy 196.405375 -284.316102) (xy 196.43801 -284.279265) (xy 196.476131 -284.24814) (xy 196.518752 -284.223533)
			(xy 196.564768 -284.206081) (xy 196.612987 -284.196237) (xy 196.662162 -284.194256) (xy 196.711017 -284.200188)
			(xy 196.758288 -284.21388) (xy 196.80275 -284.234978) (xy 196.843253 -284.262934) (xy 196.878746 -284.297026)
			(xy 196.908311 -284.33637) (xy 196.931182 -284.379947) (xy 196.946766 -284.426628) (xy 196.954661 -284.475205)
			(xy 196.955156 -284.499812) (xy 308.644048 -284.499812) (xy 308.648008 -284.450758) (xy 308.659785 -284.402974)
			(xy 308.679076 -284.357698) (xy 308.705379 -284.316102) (xy 308.738014 -284.279265) (xy 308.776135 -284.24814)
			(xy 308.818756 -284.223533) (xy 308.864772 -284.206081) (xy 308.912991 -284.196237) (xy 308.962166 -284.194256)
			(xy 309.011021 -284.200188) (xy 309.058292 -284.21388) (xy 309.102754 -284.234978) (xy 309.143257 -284.262934)
			(xy 309.17875 -284.297026) (xy 309.208315 -284.33637) (xy 309.231186 -284.379947) (xy 309.24677 -284.426628)
			(xy 309.254665 -284.475205) (xy 309.25516 -284.499812) (xy 309.594008 -284.499812) (xy 309.597968 -284.450758)
			(xy 309.609745 -284.402974) (xy 309.629036 -284.357698) (xy 309.655339 -284.316102) (xy 309.687974 -284.279265)
			(xy 309.726095 -284.24814) (xy 309.768716 -284.223533) (xy 309.814732 -284.206081) (xy 309.862951 -284.196237)
			(xy 309.912126 -284.194256) (xy 309.960981 -284.200188) (xy 310.008252 -284.21388) (xy 310.052714 -284.234978)
			(xy 310.093217 -284.262934) (xy 310.12871 -284.297026) (xy 310.158275 -284.33637) (xy 310.181146 -284.379947)
			(xy 310.19673 -284.426628) (xy 310.204625 -284.475205) (xy 310.20512 -284.499812) (xy 311.493928 -284.499812)
			(xy 311.497888 -284.450758) (xy 311.509665 -284.402974) (xy 311.528956 -284.357698) (xy 311.555259 -284.316102)
			(xy 311.587894 -284.279265) (xy 311.626015 -284.24814) (xy 311.668636 -284.223533) (xy 311.714652 -284.206081)
			(xy 311.762871 -284.196237) (xy 311.812046 -284.194256) (xy 311.860901 -284.200188) (xy 311.908172 -284.21388)
			(xy 311.952634 -284.234978) (xy 311.993137 -284.262934) (xy 312.02863 -284.297026) (xy 312.058195 -284.33637)
			(xy 312.081066 -284.379947) (xy 312.09665 -284.426628) (xy 312.104545 -284.475205) (xy 312.10504 -284.499812)
			(xy 312.443888 -284.499812) (xy 312.447848 -284.450758) (xy 312.459625 -284.402974) (xy 312.478916 -284.357698)
			(xy 312.505219 -284.316102) (xy 312.537854 -284.279265) (xy 312.575975 -284.24814) (xy 312.618596 -284.223533)
			(xy 312.664612 -284.206081) (xy 312.712831 -284.196237) (xy 312.762006 -284.194256) (xy 312.810861 -284.200188)
			(xy 312.858132 -284.21388) (xy 312.902594 -284.234978) (xy 312.943097 -284.262934) (xy 312.97859 -284.297026)
			(xy 313.008155 -284.33637) (xy 313.031026 -284.379947) (xy 313.04661 -284.426628) (xy 313.054505 -284.475205)
			(xy 313.055 -284.499812) (xy 424.744146 -284.499812) (xy 424.748106 -284.450758) (xy 424.759883 -284.402974)
			(xy 424.779174 -284.357698) (xy 424.805477 -284.316102) (xy 424.838112 -284.279265) (xy 424.876233 -284.24814)
			(xy 424.918854 -284.223533) (xy 424.96487 -284.206081) (xy 425.013089 -284.196237) (xy 425.062264 -284.194256)
			(xy 425.111119 -284.200188) (xy 425.15839 -284.21388) (xy 425.202852 -284.234978) (xy 425.243355 -284.262934)
			(xy 425.278848 -284.297026) (xy 425.308413 -284.33637) (xy 425.331284 -284.379947) (xy 425.346868 -284.426628)
			(xy 425.354763 -284.475205) (xy 425.355258 -284.499812) (xy 425.694106 -284.499812) (xy 425.698066 -284.450758)
			(xy 425.709843 -284.402974) (xy 425.729134 -284.357698) (xy 425.755437 -284.316102) (xy 425.788072 -284.279265)
			(xy 425.826193 -284.24814) (xy 425.868814 -284.223533) (xy 425.91483 -284.206081) (xy 425.963049 -284.196237)
			(xy 426.012224 -284.194256) (xy 426.061079 -284.200188) (xy 426.10835 -284.21388) (xy 426.152812 -284.234978)
			(xy 426.193315 -284.262934) (xy 426.228808 -284.297026) (xy 426.258373 -284.33637) (xy 426.281244 -284.379947)
			(xy 426.296828 -284.426628) (xy 426.304723 -284.475205) (xy 426.305218 -284.499812) (xy 427.594026 -284.499812)
			(xy 427.597986 -284.450758) (xy 427.609763 -284.402974) (xy 427.629054 -284.357698) (xy 427.655357 -284.316102)
			(xy 427.687992 -284.279265) (xy 427.726113 -284.24814) (xy 427.768734 -284.223533) (xy 427.81475 -284.206081)
			(xy 427.862969 -284.196237) (xy 427.912144 -284.194256) (xy 427.960999 -284.200188) (xy 428.00827 -284.21388)
			(xy 428.052732 -284.234978) (xy 428.093235 -284.262934) (xy 428.128728 -284.297026) (xy 428.158293 -284.33637)
			(xy 428.181164 -284.379947) (xy 428.196748 -284.426628) (xy 428.204643 -284.475205) (xy 428.205138 -284.499812)
			(xy 428.543986 -284.499812) (xy 428.547946 -284.450758) (xy 428.559723 -284.402974) (xy 428.579014 -284.357698)
			(xy 428.605317 -284.316102) (xy 428.637952 -284.279265) (xy 428.676073 -284.24814) (xy 428.718694 -284.223533)
			(xy 428.76471 -284.206081) (xy 428.812929 -284.196237) (xy 428.862104 -284.194256) (xy 428.910959 -284.200188)
			(xy 428.95823 -284.21388) (xy 429.002692 -284.234978) (xy 429.043195 -284.262934) (xy 429.078688 -284.297026)
			(xy 429.108253 -284.33637) (xy 429.131124 -284.379947) (xy 429.146708 -284.426628) (xy 429.154603 -284.475205)
			(xy 429.155098 -284.499812) (xy 429.154603 -284.524419) (xy 429.146708 -284.572996) (xy 429.131124 -284.619677)
			(xy 429.108253 -284.663254) (xy 429.078688 -284.702598) (xy 429.043195 -284.73669) (xy 429.002692 -284.764646)
			(xy 428.95823 -284.785744) (xy 428.910959 -284.799436) (xy 428.862104 -284.805368) (xy 428.812929 -284.803387)
			(xy 428.76471 -284.793543) (xy 428.718694 -284.776091) (xy 428.676073 -284.751484) (xy 428.637952 -284.720359)
			(xy 428.605317 -284.683522) (xy 428.579014 -284.641926) (xy 428.559723 -284.59665) (xy 428.547946 -284.548866)
			(xy 428.543986 -284.499812) (xy 428.205138 -284.499812) (xy 428.204643 -284.524419) (xy 428.196748 -284.572996)
			(xy 428.181164 -284.619677) (xy 428.158293 -284.663254) (xy 428.128728 -284.702598) (xy 428.093235 -284.73669)
			(xy 428.052732 -284.764646) (xy 428.00827 -284.785744) (xy 427.960999 -284.799436) (xy 427.912144 -284.805368)
			(xy 427.862969 -284.803387) (xy 427.81475 -284.793543) (xy 427.768734 -284.776091) (xy 427.726113 -284.751484)
			(xy 427.687992 -284.720359) (xy 427.655357 -284.683522) (xy 427.629054 -284.641926) (xy 427.609763 -284.59665)
			(xy 427.597986 -284.548866) (xy 427.594026 -284.499812) (xy 426.305218 -284.499812) (xy 426.304723 -284.524419)
			(xy 426.296828 -284.572996) (xy 426.281244 -284.619677) (xy 426.258373 -284.663254) (xy 426.228808 -284.702598)
			(xy 426.193315 -284.73669) (xy 426.152812 -284.764646) (xy 426.10835 -284.785744) (xy 426.061079 -284.799436)
			(xy 426.012224 -284.805368) (xy 425.963049 -284.803387) (xy 425.91483 -284.793543) (xy 425.868814 -284.776091)
			(xy 425.826193 -284.751484) (xy 425.788072 -284.720359) (xy 425.755437 -284.683522) (xy 425.729134 -284.641926)
			(xy 425.709843 -284.59665) (xy 425.698066 -284.548866) (xy 425.694106 -284.499812) (xy 425.355258 -284.499812)
			(xy 425.354763 -284.524419) (xy 425.346868 -284.572996) (xy 425.331284 -284.619677) (xy 425.308413 -284.663254)
			(xy 425.278848 -284.702598) (xy 425.243355 -284.73669) (xy 425.202852 -284.764646) (xy 425.15839 -284.785744)
			(xy 425.111119 -284.799436) (xy 425.062264 -284.805368) (xy 425.013089 -284.803387) (xy 424.96487 -284.793543)
			(xy 424.918854 -284.776091) (xy 424.876233 -284.751484) (xy 424.838112 -284.720359) (xy 424.805477 -284.683522)
			(xy 424.779174 -284.641926) (xy 424.759883 -284.59665) (xy 424.748106 -284.548866) (xy 424.744146 -284.499812)
			(xy 313.055 -284.499812) (xy 313.054505 -284.524419) (xy 313.04661 -284.572996) (xy 313.031026 -284.619677)
			(xy 313.008155 -284.663254) (xy 312.97859 -284.702598) (xy 312.943097 -284.73669) (xy 312.902594 -284.764646)
			(xy 312.858132 -284.785744) (xy 312.810861 -284.799436) (xy 312.762006 -284.805368) (xy 312.712831 -284.803387)
			(xy 312.664612 -284.793543) (xy 312.618596 -284.776091) (xy 312.575975 -284.751484) (xy 312.537854 -284.720359)
			(xy 312.505219 -284.683522) (xy 312.478916 -284.641926) (xy 312.459625 -284.59665) (xy 312.447848 -284.548866)
			(xy 312.443888 -284.499812) (xy 312.10504 -284.499812) (xy 312.104545 -284.524419) (xy 312.09665 -284.572996)
			(xy 312.081066 -284.619677) (xy 312.058195 -284.663254) (xy 312.02863 -284.702598) (xy 311.993137 -284.73669)
			(xy 311.952634 -284.764646) (xy 311.908172 -284.785744) (xy 311.860901 -284.799436) (xy 311.812046 -284.805368)
			(xy 311.762871 -284.803387) (xy 311.714652 -284.793543) (xy 311.668636 -284.776091) (xy 311.626015 -284.751484)
			(xy 311.587894 -284.720359) (xy 311.555259 -284.683522) (xy 311.528956 -284.641926) (xy 311.509665 -284.59665)
			(xy 311.497888 -284.548866) (xy 311.493928 -284.499812) (xy 310.20512 -284.499812) (xy 310.204625 -284.524419)
			(xy 310.19673 -284.572996) (xy 310.181146 -284.619677) (xy 310.158275 -284.663254) (xy 310.12871 -284.702598)
			(xy 310.093217 -284.73669) (xy 310.052714 -284.764646) (xy 310.008252 -284.785744) (xy 309.960981 -284.799436)
			(xy 309.912126 -284.805368) (xy 309.862951 -284.803387) (xy 309.814732 -284.793543) (xy 309.768716 -284.776091)
			(xy 309.726095 -284.751484) (xy 309.687974 -284.720359) (xy 309.655339 -284.683522) (xy 309.629036 -284.641926)
			(xy 309.609745 -284.59665) (xy 309.597968 -284.548866) (xy 309.594008 -284.499812) (xy 309.25516 -284.499812)
			(xy 309.254665 -284.524419) (xy 309.24677 -284.572996) (xy 309.231186 -284.619677) (xy 309.208315 -284.663254)
			(xy 309.17875 -284.702598) (xy 309.143257 -284.73669) (xy 309.102754 -284.764646) (xy 309.058292 -284.785744)
			(xy 309.011021 -284.799436) (xy 308.962166 -284.805368) (xy 308.912991 -284.803387) (xy 308.864772 -284.793543)
			(xy 308.818756 -284.776091) (xy 308.776135 -284.751484) (xy 308.738014 -284.720359) (xy 308.705379 -284.683522)
			(xy 308.679076 -284.641926) (xy 308.659785 -284.59665) (xy 308.648008 -284.548866) (xy 308.644048 -284.499812)
			(xy 196.955156 -284.499812) (xy 196.954661 -284.524419) (xy 196.946766 -284.572996) (xy 196.931182 -284.619677)
			(xy 196.908311 -284.663254) (xy 196.878746 -284.702598) (xy 196.843253 -284.73669) (xy 196.80275 -284.764646)
			(xy 196.758288 -284.785744) (xy 196.711017 -284.799436) (xy 196.662162 -284.805368) (xy 196.612987 -284.803387)
			(xy 196.564768 -284.793543) (xy 196.518752 -284.776091) (xy 196.476131 -284.751484) (xy 196.43801 -284.720359)
			(xy 196.405375 -284.683522) (xy 196.379072 -284.641926) (xy 196.359781 -284.59665) (xy 196.348004 -284.548866)
			(xy 196.344044 -284.499812) (xy 196.005196 -284.499812) (xy 196.004701 -284.524419) (xy 195.996806 -284.572996)
			(xy 195.981222 -284.619677) (xy 195.958351 -284.663254) (xy 195.928786 -284.702598) (xy 195.893293 -284.73669)
			(xy 195.85279 -284.764646) (xy 195.808328 -284.785744) (xy 195.761057 -284.799436) (xy 195.712202 -284.805368)
			(xy 195.663027 -284.803387) (xy 195.614808 -284.793543) (xy 195.568792 -284.776091) (xy 195.526171 -284.751484)
			(xy 195.48805 -284.720359) (xy 195.455415 -284.683522) (xy 195.429112 -284.641926) (xy 195.409821 -284.59665)
			(xy 195.398044 -284.548866) (xy 195.394084 -284.499812) (xy 194.105276 -284.499812) (xy 194.104781 -284.524419)
			(xy 194.096886 -284.572996) (xy 194.081302 -284.619677) (xy 194.058431 -284.663254) (xy 194.028866 -284.702598)
			(xy 193.993373 -284.73669) (xy 193.95287 -284.764646) (xy 193.908408 -284.785744) (xy 193.861137 -284.799436)
			(xy 193.812282 -284.805368) (xy 193.763107 -284.803387) (xy 193.714888 -284.793543) (xy 193.668872 -284.776091)
			(xy 193.626251 -284.751484) (xy 193.58813 -284.720359) (xy 193.555495 -284.683522) (xy 193.529192 -284.641926)
			(xy 193.509901 -284.59665) (xy 193.498124 -284.548866) (xy 193.494164 -284.499812) (xy 193.155316 -284.499812)
			(xy 193.154821 -284.524419) (xy 193.146926 -284.572996) (xy 193.131342 -284.619677) (xy 193.108471 -284.663254)
			(xy 193.078906 -284.702598) (xy 193.043413 -284.73669) (xy 193.00291 -284.764646) (xy 192.958448 -284.785744)
			(xy 192.911177 -284.799436) (xy 192.862322 -284.805368) (xy 192.813147 -284.803387) (xy 192.764928 -284.793543)
			(xy 192.718912 -284.776091) (xy 192.676291 -284.751484) (xy 192.63817 -284.720359) (xy 192.605535 -284.683522)
			(xy 192.579232 -284.641926) (xy 192.559941 -284.59665) (xy 192.548164 -284.548866) (xy 192.544204 -284.499812)
			(xy 80.855058 -284.499812) (xy 80.854563 -284.524419) (xy 80.846668 -284.572996) (xy 80.831084 -284.619677)
			(xy 80.808213 -284.663254) (xy 80.778648 -284.702598) (xy 80.743155 -284.73669) (xy 80.702652 -284.764646)
			(xy 80.65819 -284.785744) (xy 80.610919 -284.799436) (xy 80.562064 -284.805368) (xy 80.512889 -284.803387)
			(xy 80.46467 -284.793543) (xy 80.418654 -284.776091) (xy 80.376033 -284.751484) (xy 80.337912 -284.720359)
			(xy 80.305277 -284.683522) (xy 80.278974 -284.641926) (xy 80.259683 -284.59665) (xy 80.247906 -284.548866)
			(xy 80.243946 -284.499812) (xy 79.905098 -284.499812) (xy 79.904603 -284.524419) (xy 79.896708 -284.572996)
			(xy 79.881124 -284.619677) (xy 79.858253 -284.663254) (xy 79.828688 -284.702598) (xy 79.793195 -284.73669)
			(xy 79.752692 -284.764646) (xy 79.70823 -284.785744) (xy 79.660959 -284.799436) (xy 79.612104 -284.805368)
			(xy 79.562929 -284.803387) (xy 79.51471 -284.793543) (xy 79.468694 -284.776091) (xy 79.426073 -284.751484)
			(xy 79.387952 -284.720359) (xy 79.355317 -284.683522) (xy 79.329014 -284.641926) (xy 79.309723 -284.59665)
			(xy 79.297946 -284.548866) (xy 79.293986 -284.499812) (xy 78.005178 -284.499812) (xy 78.004683 -284.524419)
			(xy 77.996788 -284.572996) (xy 77.981204 -284.619677) (xy 77.958333 -284.663254) (xy 77.928768 -284.702598)
			(xy 77.893275 -284.73669) (xy 77.852772 -284.764646) (xy 77.80831 -284.785744) (xy 77.761039 -284.799436)
			(xy 77.712184 -284.805368) (xy 77.663009 -284.803387) (xy 77.61479 -284.793543) (xy 77.568774 -284.776091)
			(xy 77.526153 -284.751484) (xy 77.488032 -284.720359) (xy 77.455397 -284.683522) (xy 77.429094 -284.641926)
			(xy 77.409803 -284.59665) (xy 77.398026 -284.548866) (xy 77.394066 -284.499812) (xy 77.055218 -284.499812)
			(xy 77.054723 -284.524419) (xy 77.046828 -284.572996) (xy 77.031244 -284.619677) (xy 77.008373 -284.663254)
			(xy 76.978808 -284.702598) (xy 76.943315 -284.73669) (xy 76.902812 -284.764646) (xy 76.85835 -284.785744)
			(xy 76.811079 -284.799436) (xy 76.762224 -284.805368) (xy 76.713049 -284.803387) (xy 76.66483 -284.793543)
			(xy 76.618814 -284.776091) (xy 76.576193 -284.751484) (xy 76.538072 -284.720359) (xy 76.505437 -284.683522)
			(xy 76.479134 -284.641926) (xy 76.459843 -284.59665) (xy 76.448066 -284.548866) (xy 76.444106 -284.499812)
			(xy 0.508 -284.499812) (xy 0.508 -285.449772) (xy 74.543932 -285.449772) (xy 74.547892 -285.400718)
			(xy 74.559669 -285.352934) (xy 74.57896 -285.307658) (xy 74.605263 -285.266062) (xy 74.637898 -285.229225)
			(xy 74.676019 -285.1981) (xy 74.71864 -285.173493) (xy 74.764656 -285.156041) (xy 74.812875 -285.146197)
			(xy 74.86205 -285.144216) (xy 74.910905 -285.150148) (xy 74.958176 -285.16384) (xy 75.002638 -285.184938)
			(xy 75.043141 -285.212894) (xy 75.078634 -285.246986) (xy 75.108199 -285.28633) (xy 75.13107 -285.329907)
			(xy 75.146654 -285.376588) (xy 75.154549 -285.425165) (xy 75.155044 -285.449772) (xy 75.494146 -285.449772)
			(xy 75.498106 -285.400718) (xy 75.509883 -285.352934) (xy 75.529174 -285.307658) (xy 75.555477 -285.266062)
			(xy 75.588112 -285.229225) (xy 75.626233 -285.1981) (xy 75.668854 -285.173493) (xy 75.71487 -285.156041)
			(xy 75.763089 -285.146197) (xy 75.812264 -285.144216) (xy 75.861119 -285.150148) (xy 75.90839 -285.16384)
			(xy 75.952852 -285.184938) (xy 75.993355 -285.212894) (xy 76.028848 -285.246986) (xy 76.058413 -285.28633)
			(xy 76.081284 -285.329907) (xy 76.096868 -285.376588) (xy 76.104763 -285.425165) (xy 76.105258 -285.449772)
			(xy 81.19416 -285.449772) (xy 81.19812 -285.400718) (xy 81.209897 -285.352934) (xy 81.229188 -285.307658)
			(xy 81.255491 -285.266062) (xy 81.288126 -285.229225) (xy 81.326247 -285.1981) (xy 81.368868 -285.173493)
			(xy 81.414884 -285.156041) (xy 81.463103 -285.146197) (xy 81.512278 -285.144216) (xy 81.561133 -285.150148)
			(xy 81.608404 -285.16384) (xy 81.652866 -285.184938) (xy 81.693369 -285.212894) (xy 81.728862 -285.246986)
			(xy 81.758427 -285.28633) (xy 81.781298 -285.329907) (xy 81.796882 -285.376588) (xy 81.804777 -285.425165)
			(xy 81.805272 -285.449772) (xy 82.14412 -285.449772) (xy 82.14808 -285.400718) (xy 82.159857 -285.352934)
			(xy 82.179148 -285.307658) (xy 82.205451 -285.266062) (xy 82.238086 -285.229225) (xy 82.276207 -285.1981)
			(xy 82.318828 -285.173493) (xy 82.364844 -285.156041) (xy 82.413063 -285.146197) (xy 82.462238 -285.144216)
			(xy 82.511093 -285.150148) (xy 82.558364 -285.16384) (xy 82.602826 -285.184938) (xy 82.643329 -285.212894)
			(xy 82.678822 -285.246986) (xy 82.708387 -285.28633) (xy 82.731258 -285.329907) (xy 82.746842 -285.376588)
			(xy 82.754737 -285.425165) (xy 82.755232 -285.449772) (xy 190.64403 -285.449772) (xy 190.64799 -285.400718)
			(xy 190.659767 -285.352934) (xy 190.679058 -285.307658) (xy 190.705361 -285.266062) (xy 190.737996 -285.229225)
			(xy 190.776117 -285.1981) (xy 190.818738 -285.173493) (xy 190.864754 -285.156041) (xy 190.912973 -285.146197)
			(xy 190.962148 -285.144216) (xy 191.011003 -285.150148) (xy 191.058274 -285.16384) (xy 191.102736 -285.184938)
			(xy 191.143239 -285.212894) (xy 191.178732 -285.246986) (xy 191.208297 -285.28633) (xy 191.231168 -285.329907)
			(xy 191.246752 -285.376588) (xy 191.254647 -285.425165) (xy 191.255142 -285.449772) (xy 191.594244 -285.449772)
			(xy 191.598204 -285.400718) (xy 191.609981 -285.352934) (xy 191.629272 -285.307658) (xy 191.655575 -285.266062)
			(xy 191.68821 -285.229225) (xy 191.726331 -285.1981) (xy 191.768952 -285.173493) (xy 191.814968 -285.156041)
			(xy 191.863187 -285.146197) (xy 191.912362 -285.144216) (xy 191.961217 -285.150148) (xy 192.008488 -285.16384)
			(xy 192.05295 -285.184938) (xy 192.093453 -285.212894) (xy 192.128946 -285.246986) (xy 192.158511 -285.28633)
			(xy 192.181382 -285.329907) (xy 192.196966 -285.376588) (xy 192.204861 -285.425165) (xy 192.205356 -285.449772)
			(xy 197.294258 -285.449772) (xy 197.298218 -285.400718) (xy 197.309995 -285.352934) (xy 197.329286 -285.307658)
			(xy 197.355589 -285.266062) (xy 197.388224 -285.229225) (xy 197.426345 -285.1981) (xy 197.468966 -285.173493)
			(xy 197.514982 -285.156041) (xy 197.563201 -285.146197) (xy 197.612376 -285.144216) (xy 197.661231 -285.150148)
			(xy 197.708502 -285.16384) (xy 197.752964 -285.184938) (xy 197.793467 -285.212894) (xy 197.82896 -285.246986)
			(xy 197.858525 -285.28633) (xy 197.881396 -285.329907) (xy 197.89698 -285.376588) (xy 197.904875 -285.425165)
			(xy 197.90537 -285.449772) (xy 198.244218 -285.449772) (xy 198.248178 -285.400718) (xy 198.259955 -285.352934)
			(xy 198.279246 -285.307658) (xy 198.305549 -285.266062) (xy 198.338184 -285.229225) (xy 198.376305 -285.1981)
			(xy 198.418926 -285.173493) (xy 198.464942 -285.156041) (xy 198.513161 -285.146197) (xy 198.562336 -285.144216)
			(xy 198.611191 -285.150148) (xy 198.658462 -285.16384) (xy 198.702924 -285.184938) (xy 198.743427 -285.212894)
			(xy 198.77892 -285.246986) (xy 198.808485 -285.28633) (xy 198.831356 -285.329907) (xy 198.84694 -285.376588)
			(xy 198.854835 -285.425165) (xy 198.85533 -285.449772) (xy 306.744128 -285.449772) (xy 306.748088 -285.400718)
			(xy 306.759865 -285.352934) (xy 306.779156 -285.307658) (xy 306.805459 -285.266062) (xy 306.838094 -285.229225)
			(xy 306.876215 -285.1981) (xy 306.918836 -285.173493) (xy 306.964852 -285.156041) (xy 307.013071 -285.146197)
			(xy 307.062246 -285.144216) (xy 307.111101 -285.150148) (xy 307.158372 -285.16384) (xy 307.202834 -285.184938)
			(xy 307.243337 -285.212894) (xy 307.27883 -285.246986) (xy 307.308395 -285.28633) (xy 307.331266 -285.329907)
			(xy 307.34685 -285.376588) (xy 307.354745 -285.425165) (xy 307.35524 -285.449772) (xy 307.694088 -285.449772)
			(xy 307.698048 -285.400718) (xy 307.709825 -285.352934) (xy 307.729116 -285.307658) (xy 307.755419 -285.266062)
			(xy 307.788054 -285.229225) (xy 307.826175 -285.1981) (xy 307.868796 -285.173493) (xy 307.914812 -285.156041)
			(xy 307.963031 -285.146197) (xy 308.012206 -285.144216) (xy 308.061061 -285.150148) (xy 308.108332 -285.16384)
			(xy 308.152794 -285.184938) (xy 308.193297 -285.212894) (xy 308.22879 -285.246986) (xy 308.258355 -285.28633)
			(xy 308.281226 -285.329907) (xy 308.29681 -285.376588) (xy 308.304705 -285.425165) (xy 308.3052 -285.449772)
			(xy 313.394102 -285.449772) (xy 313.398062 -285.400718) (xy 313.409839 -285.352934) (xy 313.42913 -285.307658)
			(xy 313.455433 -285.266062) (xy 313.488068 -285.229225) (xy 313.526189 -285.1981) (xy 313.56881 -285.173493)
			(xy 313.614826 -285.156041) (xy 313.663045 -285.146197) (xy 313.71222 -285.144216) (xy 313.761075 -285.150148)
			(xy 313.808346 -285.16384) (xy 313.852808 -285.184938) (xy 313.893311 -285.212894) (xy 313.928804 -285.246986)
			(xy 313.958369 -285.28633) (xy 313.98124 -285.329907) (xy 313.996824 -285.376588) (xy 314.004719 -285.425165)
			(xy 314.005214 -285.449772) (xy 314.344062 -285.449772) (xy 314.348022 -285.400718) (xy 314.359799 -285.352934)
			(xy 314.37909 -285.307658) (xy 314.405393 -285.266062) (xy 314.438028 -285.229225) (xy 314.476149 -285.1981)
			(xy 314.51877 -285.173493) (xy 314.564786 -285.156041) (xy 314.613005 -285.146197) (xy 314.66218 -285.144216)
			(xy 314.711035 -285.150148) (xy 314.758306 -285.16384) (xy 314.802768 -285.184938) (xy 314.843271 -285.212894)
			(xy 314.878764 -285.246986) (xy 314.908329 -285.28633) (xy 314.9312 -285.329907) (xy 314.946784 -285.376588)
			(xy 314.954679 -285.425165) (xy 314.955174 -285.449772) (xy 422.844226 -285.449772) (xy 422.848186 -285.400718)
			(xy 422.859963 -285.352934) (xy 422.879254 -285.307658) (xy 422.905557 -285.266062) (xy 422.938192 -285.229225)
			(xy 422.976313 -285.1981) (xy 423.018934 -285.173493) (xy 423.06495 -285.156041) (xy 423.113169 -285.146197)
			(xy 423.162344 -285.144216) (xy 423.211199 -285.150148) (xy 423.25847 -285.16384) (xy 423.302932 -285.184938)
			(xy 423.343435 -285.212894) (xy 423.378928 -285.246986) (xy 423.408493 -285.28633) (xy 423.431364 -285.329907)
			(xy 423.446948 -285.376588) (xy 423.454843 -285.425165) (xy 423.455338 -285.449772) (xy 423.794186 -285.449772)
			(xy 423.798146 -285.400718) (xy 423.809923 -285.352934) (xy 423.829214 -285.307658) (xy 423.855517 -285.266062)
			(xy 423.888152 -285.229225) (xy 423.926273 -285.1981) (xy 423.968894 -285.173493) (xy 424.01491 -285.156041)
			(xy 424.063129 -285.146197) (xy 424.112304 -285.144216) (xy 424.161159 -285.150148) (xy 424.20843 -285.16384)
			(xy 424.252892 -285.184938) (xy 424.293395 -285.212894) (xy 424.328888 -285.246986) (xy 424.358453 -285.28633)
			(xy 424.381324 -285.329907) (xy 424.396908 -285.376588) (xy 424.404803 -285.425165) (xy 424.405298 -285.449772)
			(xy 429.4942 -285.449772) (xy 429.49816 -285.400718) (xy 429.509937 -285.352934) (xy 429.529228 -285.307658)
			(xy 429.555531 -285.266062) (xy 429.588166 -285.229225) (xy 429.626287 -285.1981) (xy 429.668908 -285.173493)
			(xy 429.714924 -285.156041) (xy 429.763143 -285.146197) (xy 429.812318 -285.144216) (xy 429.861173 -285.150148)
			(xy 429.908444 -285.16384) (xy 429.952906 -285.184938) (xy 429.993409 -285.212894) (xy 430.028902 -285.246986)
			(xy 430.058467 -285.28633) (xy 430.081338 -285.329907) (xy 430.096922 -285.376588) (xy 430.104817 -285.425165)
			(xy 430.105312 -285.449772) (xy 430.44416 -285.449772) (xy 430.44812 -285.400718) (xy 430.459897 -285.352934)
			(xy 430.479188 -285.307658) (xy 430.505491 -285.266062) (xy 430.538126 -285.229225) (xy 430.576247 -285.1981)
			(xy 430.618868 -285.173493) (xy 430.664884 -285.156041) (xy 430.713103 -285.146197) (xy 430.762278 -285.144216)
			(xy 430.811133 -285.150148) (xy 430.858404 -285.16384) (xy 430.902866 -285.184938) (xy 430.943369 -285.212894)
			(xy 430.978862 -285.246986) (xy 431.008427 -285.28633) (xy 431.031298 -285.329907) (xy 431.046882 -285.376588)
			(xy 431.054777 -285.425165) (xy 431.055272 -285.449772) (xy 431.054777 -285.474379) (xy 431.046882 -285.522956)
			(xy 431.031298 -285.569637) (xy 431.008427 -285.613214) (xy 430.978862 -285.652558) (xy 430.943369 -285.68665)
			(xy 430.902866 -285.714606) (xy 430.858404 -285.735704) (xy 430.811133 -285.749396) (xy 430.762278 -285.755328)
			(xy 430.713103 -285.753347) (xy 430.664884 -285.743503) (xy 430.618868 -285.726051) (xy 430.576247 -285.701444)
			(xy 430.538126 -285.670319) (xy 430.505491 -285.633482) (xy 430.479188 -285.591886) (xy 430.459897 -285.54661)
			(xy 430.44812 -285.498826) (xy 430.44416 -285.449772) (xy 430.105312 -285.449772) (xy 430.104817 -285.474379)
			(xy 430.096922 -285.522956) (xy 430.081338 -285.569637) (xy 430.058467 -285.613214) (xy 430.028902 -285.652558)
			(xy 429.993409 -285.68665) (xy 429.952906 -285.714606) (xy 429.908444 -285.735704) (xy 429.861173 -285.749396)
			(xy 429.812318 -285.755328) (xy 429.763143 -285.753347) (xy 429.714924 -285.743503) (xy 429.668908 -285.726051)
			(xy 429.626287 -285.701444) (xy 429.588166 -285.670319) (xy 429.555531 -285.633482) (xy 429.529228 -285.591886)
			(xy 429.509937 -285.54661) (xy 429.49816 -285.498826) (xy 429.4942 -285.449772) (xy 424.405298 -285.449772)
			(xy 424.404803 -285.474379) (xy 424.396908 -285.522956) (xy 424.381324 -285.569637) (xy 424.358453 -285.613214)
			(xy 424.328888 -285.652558) (xy 424.293395 -285.68665) (xy 424.252892 -285.714606) (xy 424.20843 -285.735704)
			(xy 424.161159 -285.749396) (xy 424.112304 -285.755328) (xy 424.063129 -285.753347) (xy 424.01491 -285.743503)
			(xy 423.968894 -285.726051) (xy 423.926273 -285.701444) (xy 423.888152 -285.670319) (xy 423.855517 -285.633482)
			(xy 423.829214 -285.591886) (xy 423.809923 -285.54661) (xy 423.798146 -285.498826) (xy 423.794186 -285.449772)
			(xy 423.455338 -285.449772) (xy 423.454843 -285.474379) (xy 423.446948 -285.522956) (xy 423.431364 -285.569637)
			(xy 423.408493 -285.613214) (xy 423.378928 -285.652558) (xy 423.343435 -285.68665) (xy 423.302932 -285.714606)
			(xy 423.25847 -285.735704) (xy 423.211199 -285.749396) (xy 423.162344 -285.755328) (xy 423.113169 -285.753347)
			(xy 423.06495 -285.743503) (xy 423.018934 -285.726051) (xy 422.976313 -285.701444) (xy 422.938192 -285.670319)
			(xy 422.905557 -285.633482) (xy 422.879254 -285.591886) (xy 422.859963 -285.54661) (xy 422.848186 -285.498826)
			(xy 422.844226 -285.449772) (xy 314.955174 -285.449772) (xy 314.954679 -285.474379) (xy 314.946784 -285.522956)
			(xy 314.9312 -285.569637) (xy 314.908329 -285.613214) (xy 314.878764 -285.652558) (xy 314.843271 -285.68665)
			(xy 314.802768 -285.714606) (xy 314.758306 -285.735704) (xy 314.711035 -285.749396) (xy 314.66218 -285.755328)
			(xy 314.613005 -285.753347) (xy 314.564786 -285.743503) (xy 314.51877 -285.726051) (xy 314.476149 -285.701444)
			(xy 314.438028 -285.670319) (xy 314.405393 -285.633482) (xy 314.37909 -285.591886) (xy 314.359799 -285.54661)
			(xy 314.348022 -285.498826) (xy 314.344062 -285.449772) (xy 314.005214 -285.449772) (xy 314.004719 -285.474379)
			(xy 313.996824 -285.522956) (xy 313.98124 -285.569637) (xy 313.958369 -285.613214) (xy 313.928804 -285.652558)
			(xy 313.893311 -285.68665) (xy 313.852808 -285.714606) (xy 313.808346 -285.735704) (xy 313.761075 -285.749396)
			(xy 313.71222 -285.755328) (xy 313.663045 -285.753347) (xy 313.614826 -285.743503) (xy 313.56881 -285.726051)
			(xy 313.526189 -285.701444) (xy 313.488068 -285.670319) (xy 313.455433 -285.633482) (xy 313.42913 -285.591886)
			(xy 313.409839 -285.54661) (xy 313.398062 -285.498826) (xy 313.394102 -285.449772) (xy 308.3052 -285.449772)
			(xy 308.304705 -285.474379) (xy 308.29681 -285.522956) (xy 308.281226 -285.569637) (xy 308.258355 -285.613214)
			(xy 308.22879 -285.652558) (xy 308.193297 -285.68665) (xy 308.152794 -285.714606) (xy 308.108332 -285.735704)
			(xy 308.061061 -285.749396) (xy 308.012206 -285.755328) (xy 307.963031 -285.753347) (xy 307.914812 -285.743503)
			(xy 307.868796 -285.726051) (xy 307.826175 -285.701444) (xy 307.788054 -285.670319) (xy 307.755419 -285.633482)
			(xy 307.729116 -285.591886) (xy 307.709825 -285.54661) (xy 307.698048 -285.498826) (xy 307.694088 -285.449772)
			(xy 307.35524 -285.449772) (xy 307.354745 -285.474379) (xy 307.34685 -285.522956) (xy 307.331266 -285.569637)
			(xy 307.308395 -285.613214) (xy 307.27883 -285.652558) (xy 307.243337 -285.68665) (xy 307.202834 -285.714606)
			(xy 307.158372 -285.735704) (xy 307.111101 -285.749396) (xy 307.062246 -285.755328) (xy 307.013071 -285.753347)
			(xy 306.964852 -285.743503) (xy 306.918836 -285.726051) (xy 306.876215 -285.701444) (xy 306.838094 -285.670319)
			(xy 306.805459 -285.633482) (xy 306.779156 -285.591886) (xy 306.759865 -285.54661) (xy 306.748088 -285.498826)
			(xy 306.744128 -285.449772) (xy 198.85533 -285.449772) (xy 198.854835 -285.474379) (xy 198.84694 -285.522956)
			(xy 198.831356 -285.569637) (xy 198.808485 -285.613214) (xy 198.77892 -285.652558) (xy 198.743427 -285.68665)
			(xy 198.702924 -285.714606) (xy 198.658462 -285.735704) (xy 198.611191 -285.749396) (xy 198.562336 -285.755328)
			(xy 198.513161 -285.753347) (xy 198.464942 -285.743503) (xy 198.418926 -285.726051) (xy 198.376305 -285.701444)
			(xy 198.338184 -285.670319) (xy 198.305549 -285.633482) (xy 198.279246 -285.591886) (xy 198.259955 -285.54661)
			(xy 198.248178 -285.498826) (xy 198.244218 -285.449772) (xy 197.90537 -285.449772) (xy 197.904875 -285.474379)
			(xy 197.89698 -285.522956) (xy 197.881396 -285.569637) (xy 197.858525 -285.613214) (xy 197.82896 -285.652558)
			(xy 197.793467 -285.68665) (xy 197.752964 -285.714606) (xy 197.708502 -285.735704) (xy 197.661231 -285.749396)
			(xy 197.612376 -285.755328) (xy 197.563201 -285.753347) (xy 197.514982 -285.743503) (xy 197.468966 -285.726051)
			(xy 197.426345 -285.701444) (xy 197.388224 -285.670319) (xy 197.355589 -285.633482) (xy 197.329286 -285.591886)
			(xy 197.309995 -285.54661) (xy 197.298218 -285.498826) (xy 197.294258 -285.449772) (xy 192.205356 -285.449772)
			(xy 192.204861 -285.474379) (xy 192.196966 -285.522956) (xy 192.181382 -285.569637) (xy 192.158511 -285.613214)
			(xy 192.128946 -285.652558) (xy 192.093453 -285.68665) (xy 192.05295 -285.714606) (xy 192.008488 -285.735704)
			(xy 191.961217 -285.749396) (xy 191.912362 -285.755328) (xy 191.863187 -285.753347) (xy 191.814968 -285.743503)
			(xy 191.768952 -285.726051) (xy 191.726331 -285.701444) (xy 191.68821 -285.670319) (xy 191.655575 -285.633482)
			(xy 191.629272 -285.591886) (xy 191.609981 -285.54661) (xy 191.598204 -285.498826) (xy 191.594244 -285.449772)
			(xy 191.255142 -285.449772) (xy 191.254647 -285.474379) (xy 191.246752 -285.522956) (xy 191.231168 -285.569637)
			(xy 191.208297 -285.613214) (xy 191.178732 -285.652558) (xy 191.143239 -285.68665) (xy 191.102736 -285.714606)
			(xy 191.058274 -285.735704) (xy 191.011003 -285.749396) (xy 190.962148 -285.755328) (xy 190.912973 -285.753347)
			(xy 190.864754 -285.743503) (xy 190.818738 -285.726051) (xy 190.776117 -285.701444) (xy 190.737996 -285.670319)
			(xy 190.705361 -285.633482) (xy 190.679058 -285.591886) (xy 190.659767 -285.54661) (xy 190.64799 -285.498826)
			(xy 190.64403 -285.449772) (xy 82.755232 -285.449772) (xy 82.754737 -285.474379) (xy 82.746842 -285.522956)
			(xy 82.731258 -285.569637) (xy 82.708387 -285.613214) (xy 82.678822 -285.652558) (xy 82.643329 -285.68665)
			(xy 82.602826 -285.714606) (xy 82.558364 -285.735704) (xy 82.511093 -285.749396) (xy 82.462238 -285.755328)
			(xy 82.413063 -285.753347) (xy 82.364844 -285.743503) (xy 82.318828 -285.726051) (xy 82.276207 -285.701444)
			(xy 82.238086 -285.670319) (xy 82.205451 -285.633482) (xy 82.179148 -285.591886) (xy 82.159857 -285.54661)
			(xy 82.14808 -285.498826) (xy 82.14412 -285.449772) (xy 81.805272 -285.449772) (xy 81.804777 -285.474379)
			(xy 81.796882 -285.522956) (xy 81.781298 -285.569637) (xy 81.758427 -285.613214) (xy 81.728862 -285.652558)
			(xy 81.693369 -285.68665) (xy 81.652866 -285.714606) (xy 81.608404 -285.735704) (xy 81.561133 -285.749396)
			(xy 81.512278 -285.755328) (xy 81.463103 -285.753347) (xy 81.414884 -285.743503) (xy 81.368868 -285.726051)
			(xy 81.326247 -285.701444) (xy 81.288126 -285.670319) (xy 81.255491 -285.633482) (xy 81.229188 -285.591886)
			(xy 81.209897 -285.54661) (xy 81.19812 -285.498826) (xy 81.19416 -285.449772) (xy 76.105258 -285.449772)
			(xy 76.104763 -285.474379) (xy 76.096868 -285.522956) (xy 76.081284 -285.569637) (xy 76.058413 -285.613214)
			(xy 76.028848 -285.652558) (xy 75.993355 -285.68665) (xy 75.952852 -285.714606) (xy 75.90839 -285.735704)
			(xy 75.861119 -285.749396) (xy 75.812264 -285.755328) (xy 75.763089 -285.753347) (xy 75.71487 -285.743503)
			(xy 75.668854 -285.726051) (xy 75.626233 -285.701444) (xy 75.588112 -285.670319) (xy 75.555477 -285.633482)
			(xy 75.529174 -285.591886) (xy 75.509883 -285.54661) (xy 75.498106 -285.498826) (xy 75.494146 -285.449772)
			(xy 75.155044 -285.449772) (xy 75.154549 -285.474379) (xy 75.146654 -285.522956) (xy 75.13107 -285.569637)
			(xy 75.108199 -285.613214) (xy 75.078634 -285.652558) (xy 75.043141 -285.68665) (xy 75.002638 -285.714606)
			(xy 74.958176 -285.735704) (xy 74.910905 -285.749396) (xy 74.86205 -285.755328) (xy 74.812875 -285.753347)
			(xy 74.764656 -285.743503) (xy 74.71864 -285.726051) (xy 74.676019 -285.701444) (xy 74.637898 -285.670319)
			(xy 74.605263 -285.633482) (xy 74.57896 -285.591886) (xy 74.559669 -285.54661) (xy 74.547892 -285.498826)
			(xy 74.543932 -285.449772) (xy 0.508 -285.449772) (xy 0.508 -286.399986) (xy 76.444106 -286.399986)
			(xy 76.448066 -286.350932) (xy 76.459843 -286.303148) (xy 76.479134 -286.257872) (xy 76.505437 -286.216276)
			(xy 76.538072 -286.179439) (xy 76.576193 -286.148314) (xy 76.618814 -286.123707) (xy 76.66483 -286.106255)
			(xy 76.713049 -286.096411) (xy 76.762224 -286.09443) (xy 76.811079 -286.100362) (xy 76.85835 -286.114054)
			(xy 76.902812 -286.135152) (xy 76.943315 -286.163108) (xy 76.978808 -286.1972) (xy 77.008373 -286.236544)
			(xy 77.031244 -286.280121) (xy 77.046828 -286.326802) (xy 77.054723 -286.375379) (xy 77.055218 -286.399986)
			(xy 77.394066 -286.399986) (xy 77.398026 -286.350932) (xy 77.409803 -286.303148) (xy 77.429094 -286.257872)
			(xy 77.455397 -286.216276) (xy 77.488032 -286.179439) (xy 77.526153 -286.148314) (xy 77.568774 -286.123707)
			(xy 77.61479 -286.106255) (xy 77.663009 -286.096411) (xy 77.712184 -286.09443) (xy 77.761039 -286.100362)
			(xy 77.80831 -286.114054) (xy 77.852772 -286.135152) (xy 77.893275 -286.163108) (xy 77.928768 -286.1972)
			(xy 77.958333 -286.236544) (xy 77.981204 -286.280121) (xy 77.996788 -286.326802) (xy 78.004683 -286.375379)
			(xy 78.005173 -286.399732) (xy 79.293986 -286.399732) (xy 79.297946 -286.350678) (xy 79.309723 -286.302894)
			(xy 79.329014 -286.257618) (xy 79.355317 -286.216022) (xy 79.387952 -286.179185) (xy 79.426073 -286.14806)
			(xy 79.468694 -286.123453) (xy 79.51471 -286.106001) (xy 79.562929 -286.096157) (xy 79.612104 -286.094176)
			(xy 79.660959 -286.100108) (xy 79.70823 -286.1138) (xy 79.752692 -286.134898) (xy 79.793195 -286.162854)
			(xy 79.828688 -286.196946) (xy 79.858253 -286.23629) (xy 79.881124 -286.279867) (xy 79.896708 -286.326548)
			(xy 79.904603 -286.375125) (xy 79.905098 -286.399732) (xy 80.243946 -286.399732) (xy 80.247906 -286.350678)
			(xy 80.259683 -286.302894) (xy 80.278974 -286.257618) (xy 80.305277 -286.216022) (xy 80.337912 -286.179185)
			(xy 80.376033 -286.14806) (xy 80.418654 -286.123453) (xy 80.46467 -286.106001) (xy 80.512889 -286.096157)
			(xy 80.562064 -286.094176) (xy 80.610919 -286.100108) (xy 80.65819 -286.1138) (xy 80.702652 -286.134898)
			(xy 80.743155 -286.162854) (xy 80.778648 -286.196946) (xy 80.808213 -286.23629) (xy 80.831084 -286.279867)
			(xy 80.846668 -286.326548) (xy 80.854563 -286.375125) (xy 80.855058 -286.399732) (xy 80.855053 -286.399986)
			(xy 192.544204 -286.399986) (xy 192.548164 -286.350932) (xy 192.559941 -286.303148) (xy 192.579232 -286.257872)
			(xy 192.605535 -286.216276) (xy 192.63817 -286.179439) (xy 192.676291 -286.148314) (xy 192.718912 -286.123707)
			(xy 192.764928 -286.106255) (xy 192.813147 -286.096411) (xy 192.862322 -286.09443) (xy 192.911177 -286.100362)
			(xy 192.958448 -286.114054) (xy 193.00291 -286.135152) (xy 193.043413 -286.163108) (xy 193.078906 -286.1972)
			(xy 193.108471 -286.236544) (xy 193.131342 -286.280121) (xy 193.146926 -286.326802) (xy 193.154821 -286.375379)
			(xy 193.155316 -286.399986) (xy 193.494164 -286.399986) (xy 193.498124 -286.350932) (xy 193.509901 -286.303148)
			(xy 193.529192 -286.257872) (xy 193.555495 -286.216276) (xy 193.58813 -286.179439) (xy 193.626251 -286.148314)
			(xy 193.668872 -286.123707) (xy 193.714888 -286.106255) (xy 193.763107 -286.096411) (xy 193.812282 -286.09443)
			(xy 193.861137 -286.100362) (xy 193.908408 -286.114054) (xy 193.95287 -286.135152) (xy 193.993373 -286.163108)
			(xy 194.028866 -286.1972) (xy 194.058431 -286.236544) (xy 194.081302 -286.280121) (xy 194.096886 -286.326802)
			(xy 194.104781 -286.375379) (xy 194.105271 -286.399732) (xy 195.394084 -286.399732) (xy 195.398044 -286.350678)
			(xy 195.409821 -286.302894) (xy 195.429112 -286.257618) (xy 195.455415 -286.216022) (xy 195.48805 -286.179185)
			(xy 195.526171 -286.14806) (xy 195.568792 -286.123453) (xy 195.614808 -286.106001) (xy 195.663027 -286.096157)
			(xy 195.712202 -286.094176) (xy 195.761057 -286.100108) (xy 195.808328 -286.1138) (xy 195.85279 -286.134898)
			(xy 195.893293 -286.162854) (xy 195.928786 -286.196946) (xy 195.958351 -286.23629) (xy 195.981222 -286.279867)
			(xy 195.996806 -286.326548) (xy 196.004701 -286.375125) (xy 196.005196 -286.399732) (xy 196.344044 -286.399732)
			(xy 196.348004 -286.350678) (xy 196.359781 -286.302894) (xy 196.379072 -286.257618) (xy 196.405375 -286.216022)
			(xy 196.43801 -286.179185) (xy 196.476131 -286.14806) (xy 196.518752 -286.123453) (xy 196.564768 -286.106001)
			(xy 196.612987 -286.096157) (xy 196.662162 -286.094176) (xy 196.711017 -286.100108) (xy 196.758288 -286.1138)
			(xy 196.80275 -286.134898) (xy 196.843253 -286.162854) (xy 196.878746 -286.196946) (xy 196.908311 -286.23629)
			(xy 196.931182 -286.279867) (xy 196.946766 -286.326548) (xy 196.954661 -286.375125) (xy 196.955156 -286.399732)
			(xy 196.955151 -286.399986) (xy 308.644048 -286.399986) (xy 308.648008 -286.350932) (xy 308.659785 -286.303148)
			(xy 308.679076 -286.257872) (xy 308.705379 -286.216276) (xy 308.738014 -286.179439) (xy 308.776135 -286.148314)
			(xy 308.818756 -286.123707) (xy 308.864772 -286.106255) (xy 308.912991 -286.096411) (xy 308.962166 -286.09443)
			(xy 309.011021 -286.100362) (xy 309.058292 -286.114054) (xy 309.102754 -286.135152) (xy 309.143257 -286.163108)
			(xy 309.17875 -286.1972) (xy 309.208315 -286.236544) (xy 309.231186 -286.280121) (xy 309.24677 -286.326802)
			(xy 309.254665 -286.375379) (xy 309.25516 -286.399986) (xy 309.594008 -286.399986) (xy 309.597968 -286.350932)
			(xy 309.609745 -286.303148) (xy 309.629036 -286.257872) (xy 309.655339 -286.216276) (xy 309.687974 -286.179439)
			(xy 309.726095 -286.148314) (xy 309.768716 -286.123707) (xy 309.814732 -286.106255) (xy 309.862951 -286.096411)
			(xy 309.912126 -286.09443) (xy 309.960981 -286.100362) (xy 310.008252 -286.114054) (xy 310.052714 -286.135152)
			(xy 310.093217 -286.163108) (xy 310.12871 -286.1972) (xy 310.158275 -286.236544) (xy 310.181146 -286.280121)
			(xy 310.19673 -286.326802) (xy 310.204625 -286.375379) (xy 310.205115 -286.399732) (xy 311.493928 -286.399732)
			(xy 311.497888 -286.350678) (xy 311.509665 -286.302894) (xy 311.528956 -286.257618) (xy 311.555259 -286.216022)
			(xy 311.587894 -286.179185) (xy 311.626015 -286.14806) (xy 311.668636 -286.123453) (xy 311.714652 -286.106001)
			(xy 311.762871 -286.096157) (xy 311.812046 -286.094176) (xy 311.860901 -286.100108) (xy 311.908172 -286.1138)
			(xy 311.952634 -286.134898) (xy 311.993137 -286.162854) (xy 312.02863 -286.196946) (xy 312.058195 -286.23629)
			(xy 312.081066 -286.279867) (xy 312.09665 -286.326548) (xy 312.104545 -286.375125) (xy 312.10504 -286.399732)
			(xy 312.443888 -286.399732) (xy 312.447848 -286.350678) (xy 312.459625 -286.302894) (xy 312.478916 -286.257618)
			(xy 312.505219 -286.216022) (xy 312.537854 -286.179185) (xy 312.575975 -286.14806) (xy 312.618596 -286.123453)
			(xy 312.664612 -286.106001) (xy 312.712831 -286.096157) (xy 312.762006 -286.094176) (xy 312.810861 -286.100108)
			(xy 312.858132 -286.1138) (xy 312.902594 -286.134898) (xy 312.943097 -286.162854) (xy 312.97859 -286.196946)
			(xy 313.008155 -286.23629) (xy 313.031026 -286.279867) (xy 313.04661 -286.326548) (xy 313.054505 -286.375125)
			(xy 313.055 -286.399732) (xy 313.054995 -286.399986) (xy 424.744146 -286.399986) (xy 424.748106 -286.350932)
			(xy 424.759883 -286.303148) (xy 424.779174 -286.257872) (xy 424.805477 -286.216276) (xy 424.838112 -286.179439)
			(xy 424.876233 -286.148314) (xy 424.918854 -286.123707) (xy 424.96487 -286.106255) (xy 425.013089 -286.096411)
			(xy 425.062264 -286.09443) (xy 425.111119 -286.100362) (xy 425.15839 -286.114054) (xy 425.202852 -286.135152)
			(xy 425.243355 -286.163108) (xy 425.278848 -286.1972) (xy 425.308413 -286.236544) (xy 425.331284 -286.280121)
			(xy 425.346868 -286.326802) (xy 425.354763 -286.375379) (xy 425.355258 -286.399986) (xy 425.694106 -286.399986)
			(xy 425.698066 -286.350932) (xy 425.709843 -286.303148) (xy 425.729134 -286.257872) (xy 425.755437 -286.216276)
			(xy 425.788072 -286.179439) (xy 425.826193 -286.148314) (xy 425.868814 -286.123707) (xy 425.91483 -286.106255)
			(xy 425.963049 -286.096411) (xy 426.012224 -286.09443) (xy 426.061079 -286.100362) (xy 426.10835 -286.114054)
			(xy 426.152812 -286.135152) (xy 426.193315 -286.163108) (xy 426.228808 -286.1972) (xy 426.258373 -286.236544)
			(xy 426.281244 -286.280121) (xy 426.296828 -286.326802) (xy 426.304723 -286.375379) (xy 426.305213 -286.399732)
			(xy 427.594026 -286.399732) (xy 427.597986 -286.350678) (xy 427.609763 -286.302894) (xy 427.629054 -286.257618)
			(xy 427.655357 -286.216022) (xy 427.687992 -286.179185) (xy 427.726113 -286.14806) (xy 427.768734 -286.123453)
			(xy 427.81475 -286.106001) (xy 427.862969 -286.096157) (xy 427.912144 -286.094176) (xy 427.960999 -286.100108)
			(xy 428.00827 -286.1138) (xy 428.052732 -286.134898) (xy 428.093235 -286.162854) (xy 428.128728 -286.196946)
			(xy 428.158293 -286.23629) (xy 428.181164 -286.279867) (xy 428.196748 -286.326548) (xy 428.204643 -286.375125)
			(xy 428.205138 -286.399732) (xy 428.543986 -286.399732) (xy 428.547946 -286.350678) (xy 428.559723 -286.302894)
			(xy 428.579014 -286.257618) (xy 428.605317 -286.216022) (xy 428.637952 -286.179185) (xy 428.676073 -286.14806)
			(xy 428.718694 -286.123453) (xy 428.76471 -286.106001) (xy 428.812929 -286.096157) (xy 428.862104 -286.094176)
			(xy 428.910959 -286.100108) (xy 428.95823 -286.1138) (xy 429.002692 -286.134898) (xy 429.043195 -286.162854)
			(xy 429.078688 -286.196946) (xy 429.108253 -286.23629) (xy 429.131124 -286.279867) (xy 429.146708 -286.326548)
			(xy 429.154603 -286.375125) (xy 429.155098 -286.399732) (xy 429.154603 -286.424339) (xy 429.146708 -286.472916)
			(xy 429.131124 -286.519597) (xy 429.108253 -286.563174) (xy 429.078688 -286.602518) (xy 429.043195 -286.63661)
			(xy 429.002692 -286.664566) (xy 428.95823 -286.685664) (xy 428.910959 -286.699356) (xy 428.862104 -286.705288)
			(xy 428.812929 -286.703307) (xy 428.76471 -286.693463) (xy 428.718694 -286.676011) (xy 428.676073 -286.651404)
			(xy 428.637952 -286.620279) (xy 428.605317 -286.583442) (xy 428.579014 -286.541846) (xy 428.559723 -286.49657)
			(xy 428.547946 -286.448786) (xy 428.543986 -286.399732) (xy 428.205138 -286.399732) (xy 428.204643 -286.424339)
			(xy 428.196748 -286.472916) (xy 428.181164 -286.519597) (xy 428.158293 -286.563174) (xy 428.128728 -286.602518)
			(xy 428.093235 -286.63661) (xy 428.052732 -286.664566) (xy 428.00827 -286.685664) (xy 427.960999 -286.699356)
			(xy 427.912144 -286.705288) (xy 427.862969 -286.703307) (xy 427.81475 -286.693463) (xy 427.768734 -286.676011)
			(xy 427.726113 -286.651404) (xy 427.687992 -286.620279) (xy 427.655357 -286.583442) (xy 427.629054 -286.541846)
			(xy 427.609763 -286.49657) (xy 427.597986 -286.448786) (xy 427.594026 -286.399732) (xy 426.305213 -286.399732)
			(xy 426.305218 -286.399986) (xy 426.304723 -286.424593) (xy 426.296828 -286.47317) (xy 426.281244 -286.519851)
			(xy 426.258373 -286.563428) (xy 426.228808 -286.602772) (xy 426.193315 -286.636864) (xy 426.152812 -286.66482)
			(xy 426.10835 -286.685918) (xy 426.061079 -286.69961) (xy 426.012224 -286.705542) (xy 425.963049 -286.703561)
			(xy 425.91483 -286.693717) (xy 425.868814 -286.676265) (xy 425.826193 -286.651658) (xy 425.788072 -286.620533)
			(xy 425.755437 -286.583696) (xy 425.729134 -286.5421) (xy 425.709843 -286.496824) (xy 425.698066 -286.44904)
			(xy 425.694106 -286.399986) (xy 425.355258 -286.399986) (xy 425.354763 -286.424593) (xy 425.346868 -286.47317)
			(xy 425.331284 -286.519851) (xy 425.308413 -286.563428) (xy 425.278848 -286.602772) (xy 425.243355 -286.636864)
			(xy 425.202852 -286.66482) (xy 425.15839 -286.685918) (xy 425.111119 -286.69961) (xy 425.062264 -286.705542)
			(xy 425.013089 -286.703561) (xy 424.96487 -286.693717) (xy 424.918854 -286.676265) (xy 424.876233 -286.651658)
			(xy 424.838112 -286.620533) (xy 424.805477 -286.583696) (xy 424.779174 -286.5421) (xy 424.759883 -286.496824)
			(xy 424.748106 -286.44904) (xy 424.744146 -286.399986) (xy 313.054995 -286.399986) (xy 313.054505 -286.424339)
			(xy 313.04661 -286.472916) (xy 313.031026 -286.519597) (xy 313.008155 -286.563174) (xy 312.97859 -286.602518)
			(xy 312.943097 -286.63661) (xy 312.902594 -286.664566) (xy 312.858132 -286.685664) (xy 312.810861 -286.699356)
			(xy 312.762006 -286.705288) (xy 312.712831 -286.703307) (xy 312.664612 -286.693463) (xy 312.618596 -286.676011)
			(xy 312.575975 -286.651404) (xy 312.537854 -286.620279) (xy 312.505219 -286.583442) (xy 312.478916 -286.541846)
			(xy 312.459625 -286.49657) (xy 312.447848 -286.448786) (xy 312.443888 -286.399732) (xy 312.10504 -286.399732)
			(xy 312.104545 -286.424339) (xy 312.09665 -286.472916) (xy 312.081066 -286.519597) (xy 312.058195 -286.563174)
			(xy 312.02863 -286.602518) (xy 311.993137 -286.63661) (xy 311.952634 -286.664566) (xy 311.908172 -286.685664)
			(xy 311.860901 -286.699356) (xy 311.812046 -286.705288) (xy 311.762871 -286.703307) (xy 311.714652 -286.693463)
			(xy 311.668636 -286.676011) (xy 311.626015 -286.651404) (xy 311.587894 -286.620279) (xy 311.555259 -286.583442)
			(xy 311.528956 -286.541846) (xy 311.509665 -286.49657) (xy 311.497888 -286.448786) (xy 311.493928 -286.399732)
			(xy 310.205115 -286.399732) (xy 310.20512 -286.399986) (xy 310.204625 -286.424593) (xy 310.19673 -286.47317)
			(xy 310.181146 -286.519851) (xy 310.158275 -286.563428) (xy 310.12871 -286.602772) (xy 310.093217 -286.636864)
			(xy 310.052714 -286.66482) (xy 310.008252 -286.685918) (xy 309.960981 -286.69961) (xy 309.912126 -286.705542)
			(xy 309.862951 -286.703561) (xy 309.814732 -286.693717) (xy 309.768716 -286.676265) (xy 309.726095 -286.651658)
			(xy 309.687974 -286.620533) (xy 309.655339 -286.583696) (xy 309.629036 -286.5421) (xy 309.609745 -286.496824)
			(xy 309.597968 -286.44904) (xy 309.594008 -286.399986) (xy 309.25516 -286.399986) (xy 309.254665 -286.424593)
			(xy 309.24677 -286.47317) (xy 309.231186 -286.519851) (xy 309.208315 -286.563428) (xy 309.17875 -286.602772)
			(xy 309.143257 -286.636864) (xy 309.102754 -286.66482) (xy 309.058292 -286.685918) (xy 309.011021 -286.69961)
			(xy 308.962166 -286.705542) (xy 308.912991 -286.703561) (xy 308.864772 -286.693717) (xy 308.818756 -286.676265)
			(xy 308.776135 -286.651658) (xy 308.738014 -286.620533) (xy 308.705379 -286.583696) (xy 308.679076 -286.5421)
			(xy 308.659785 -286.496824) (xy 308.648008 -286.44904) (xy 308.644048 -286.399986) (xy 196.955151 -286.399986)
			(xy 196.954661 -286.424339) (xy 196.946766 -286.472916) (xy 196.931182 -286.519597) (xy 196.908311 -286.563174)
			(xy 196.878746 -286.602518) (xy 196.843253 -286.63661) (xy 196.80275 -286.664566) (xy 196.758288 -286.685664)
			(xy 196.711017 -286.699356) (xy 196.662162 -286.705288) (xy 196.612987 -286.703307) (xy 196.564768 -286.693463)
			(xy 196.518752 -286.676011) (xy 196.476131 -286.651404) (xy 196.43801 -286.620279) (xy 196.405375 -286.583442)
			(xy 196.379072 -286.541846) (xy 196.359781 -286.49657) (xy 196.348004 -286.448786) (xy 196.344044 -286.399732)
			(xy 196.005196 -286.399732) (xy 196.004701 -286.424339) (xy 195.996806 -286.472916) (xy 195.981222 -286.519597)
			(xy 195.958351 -286.563174) (xy 195.928786 -286.602518) (xy 195.893293 -286.63661) (xy 195.85279 -286.664566)
			(xy 195.808328 -286.685664) (xy 195.761057 -286.699356) (xy 195.712202 -286.705288) (xy 195.663027 -286.703307)
			(xy 195.614808 -286.693463) (xy 195.568792 -286.676011) (xy 195.526171 -286.651404) (xy 195.48805 -286.620279)
			(xy 195.455415 -286.583442) (xy 195.429112 -286.541846) (xy 195.409821 -286.49657) (xy 195.398044 -286.448786)
			(xy 195.394084 -286.399732) (xy 194.105271 -286.399732) (xy 194.105276 -286.399986) (xy 194.104781 -286.424593)
			(xy 194.096886 -286.47317) (xy 194.081302 -286.519851) (xy 194.058431 -286.563428) (xy 194.028866 -286.602772)
			(xy 193.993373 -286.636864) (xy 193.95287 -286.66482) (xy 193.908408 -286.685918) (xy 193.861137 -286.69961)
			(xy 193.812282 -286.705542) (xy 193.763107 -286.703561) (xy 193.714888 -286.693717) (xy 193.668872 -286.676265)
			(xy 193.626251 -286.651658) (xy 193.58813 -286.620533) (xy 193.555495 -286.583696) (xy 193.529192 -286.5421)
			(xy 193.509901 -286.496824) (xy 193.498124 -286.44904) (xy 193.494164 -286.399986) (xy 193.155316 -286.399986)
			(xy 193.154821 -286.424593) (xy 193.146926 -286.47317) (xy 193.131342 -286.519851) (xy 193.108471 -286.563428)
			(xy 193.078906 -286.602772) (xy 193.043413 -286.636864) (xy 193.00291 -286.66482) (xy 192.958448 -286.685918)
			(xy 192.911177 -286.69961) (xy 192.862322 -286.705542) (xy 192.813147 -286.703561) (xy 192.764928 -286.693717)
			(xy 192.718912 -286.676265) (xy 192.676291 -286.651658) (xy 192.63817 -286.620533) (xy 192.605535 -286.583696)
			(xy 192.579232 -286.5421) (xy 192.559941 -286.496824) (xy 192.548164 -286.44904) (xy 192.544204 -286.399986)
			(xy 80.855053 -286.399986) (xy 80.854563 -286.424339) (xy 80.846668 -286.472916) (xy 80.831084 -286.519597)
			(xy 80.808213 -286.563174) (xy 80.778648 -286.602518) (xy 80.743155 -286.63661) (xy 80.702652 -286.664566)
			(xy 80.65819 -286.685664) (xy 80.610919 -286.699356) (xy 80.562064 -286.705288) (xy 80.512889 -286.703307)
			(xy 80.46467 -286.693463) (xy 80.418654 -286.676011) (xy 80.376033 -286.651404) (xy 80.337912 -286.620279)
			(xy 80.305277 -286.583442) (xy 80.278974 -286.541846) (xy 80.259683 -286.49657) (xy 80.247906 -286.448786)
			(xy 80.243946 -286.399732) (xy 79.905098 -286.399732) (xy 79.904603 -286.424339) (xy 79.896708 -286.472916)
			(xy 79.881124 -286.519597) (xy 79.858253 -286.563174) (xy 79.828688 -286.602518) (xy 79.793195 -286.63661)
			(xy 79.752692 -286.664566) (xy 79.70823 -286.685664) (xy 79.660959 -286.699356) (xy 79.612104 -286.705288)
			(xy 79.562929 -286.703307) (xy 79.51471 -286.693463) (xy 79.468694 -286.676011) (xy 79.426073 -286.651404)
			(xy 79.387952 -286.620279) (xy 79.355317 -286.583442) (xy 79.329014 -286.541846) (xy 79.309723 -286.49657)
			(xy 79.297946 -286.448786) (xy 79.293986 -286.399732) (xy 78.005173 -286.399732) (xy 78.005178 -286.399986)
			(xy 78.004683 -286.424593) (xy 77.996788 -286.47317) (xy 77.981204 -286.519851) (xy 77.958333 -286.563428)
			(xy 77.928768 -286.602772) (xy 77.893275 -286.636864) (xy 77.852772 -286.66482) (xy 77.80831 -286.685918)
			(xy 77.761039 -286.69961) (xy 77.712184 -286.705542) (xy 77.663009 -286.703561) (xy 77.61479 -286.693717)
			(xy 77.568774 -286.676265) (xy 77.526153 -286.651658) (xy 77.488032 -286.620533) (xy 77.455397 -286.583696)
			(xy 77.429094 -286.5421) (xy 77.409803 -286.496824) (xy 77.398026 -286.44904) (xy 77.394066 -286.399986)
			(xy 77.055218 -286.399986) (xy 77.054723 -286.424593) (xy 77.046828 -286.47317) (xy 77.031244 -286.519851)
			(xy 77.008373 -286.563428) (xy 76.978808 -286.602772) (xy 76.943315 -286.636864) (xy 76.902812 -286.66482)
			(xy 76.85835 -286.685918) (xy 76.811079 -286.69961) (xy 76.762224 -286.705542) (xy 76.713049 -286.703561)
			(xy 76.66483 -286.693717) (xy 76.618814 -286.676265) (xy 76.576193 -286.651658) (xy 76.538072 -286.620533)
			(xy 76.505437 -286.583696) (xy 76.479134 -286.5421) (xy 76.459843 -286.496824) (xy 76.448066 -286.44904)
			(xy 76.444106 -286.399986) (xy 0.508 -286.399986) (xy 0.508 -287.349946) (xy 74.543932 -287.349946)
			(xy 74.547892 -287.300892) (xy 74.559669 -287.253108) (xy 74.57896 -287.207832) (xy 74.605263 -287.166236)
			(xy 74.637898 -287.129399) (xy 74.676019 -287.098274) (xy 74.71864 -287.073667) (xy 74.764656 -287.056215)
			(xy 74.812875 -287.046371) (xy 74.86205 -287.04439) (xy 74.910905 -287.050322) (xy 74.958176 -287.064014)
			(xy 75.002638 -287.085112) (xy 75.043141 -287.113068) (xy 75.078634 -287.14716) (xy 75.108199 -287.186504)
			(xy 75.13107 -287.230081) (xy 75.146654 -287.276762) (xy 75.154549 -287.325339) (xy 75.155044 -287.349946)
			(xy 75.494146 -287.349946) (xy 75.498106 -287.300892) (xy 75.509883 -287.253108) (xy 75.529174 -287.207832)
			(xy 75.555477 -287.166236) (xy 75.588112 -287.129399) (xy 75.626233 -287.098274) (xy 75.668854 -287.073667)
			(xy 75.71487 -287.056215) (xy 75.763089 -287.046371) (xy 75.812264 -287.04439) (xy 75.861119 -287.050322)
			(xy 75.90839 -287.064014) (xy 75.952852 -287.085112) (xy 75.993355 -287.113068) (xy 76.028848 -287.14716)
			(xy 76.058413 -287.186504) (xy 76.081284 -287.230081) (xy 76.096868 -287.276762) (xy 76.104763 -287.325339)
			(xy 76.105258 -287.349946) (xy 81.19416 -287.349946) (xy 81.19812 -287.300892) (xy 81.209897 -287.253108)
			(xy 81.229188 -287.207832) (xy 81.255491 -287.166236) (xy 81.288126 -287.129399) (xy 81.326247 -287.098274)
			(xy 81.368868 -287.073667) (xy 81.414884 -287.056215) (xy 81.463103 -287.046371) (xy 81.512278 -287.04439)
			(xy 81.561133 -287.050322) (xy 81.608404 -287.064014) (xy 81.652866 -287.085112) (xy 81.693369 -287.113068)
			(xy 81.728862 -287.14716) (xy 81.758427 -287.186504) (xy 81.781298 -287.230081) (xy 81.796882 -287.276762)
			(xy 81.804777 -287.325339) (xy 81.805272 -287.349946) (xy 82.14412 -287.349946) (xy 82.14808 -287.300892)
			(xy 82.159857 -287.253108) (xy 82.179148 -287.207832) (xy 82.205451 -287.166236) (xy 82.238086 -287.129399)
			(xy 82.276207 -287.098274) (xy 82.318828 -287.073667) (xy 82.364844 -287.056215) (xy 82.413063 -287.046371)
			(xy 82.462238 -287.04439) (xy 82.511093 -287.050322) (xy 82.558364 -287.064014) (xy 82.602826 -287.085112)
			(xy 82.643329 -287.113068) (xy 82.678822 -287.14716) (xy 82.708387 -287.186504) (xy 82.731258 -287.230081)
			(xy 82.746842 -287.276762) (xy 82.754737 -287.325339) (xy 82.755232 -287.349946) (xy 190.64403 -287.349946)
			(xy 190.64799 -287.300892) (xy 190.659767 -287.253108) (xy 190.679058 -287.207832) (xy 190.705361 -287.166236)
			(xy 190.737996 -287.129399) (xy 190.776117 -287.098274) (xy 190.818738 -287.073667) (xy 190.864754 -287.056215)
			(xy 190.912973 -287.046371) (xy 190.962148 -287.04439) (xy 191.011003 -287.050322) (xy 191.058274 -287.064014)
			(xy 191.102736 -287.085112) (xy 191.143239 -287.113068) (xy 191.178732 -287.14716) (xy 191.208297 -287.186504)
			(xy 191.231168 -287.230081) (xy 191.246752 -287.276762) (xy 191.254647 -287.325339) (xy 191.255142 -287.349946)
			(xy 191.594244 -287.349946) (xy 191.598204 -287.300892) (xy 191.609981 -287.253108) (xy 191.629272 -287.207832)
			(xy 191.655575 -287.166236) (xy 191.68821 -287.129399) (xy 191.726331 -287.098274) (xy 191.768952 -287.073667)
			(xy 191.814968 -287.056215) (xy 191.863187 -287.046371) (xy 191.912362 -287.04439) (xy 191.961217 -287.050322)
			(xy 192.008488 -287.064014) (xy 192.05295 -287.085112) (xy 192.093453 -287.113068) (xy 192.128946 -287.14716)
			(xy 192.158511 -287.186504) (xy 192.181382 -287.230081) (xy 192.196966 -287.276762) (xy 192.204861 -287.325339)
			(xy 192.205356 -287.349946) (xy 197.294258 -287.349946) (xy 197.298218 -287.300892) (xy 197.309995 -287.253108)
			(xy 197.329286 -287.207832) (xy 197.355589 -287.166236) (xy 197.388224 -287.129399) (xy 197.426345 -287.098274)
			(xy 197.468966 -287.073667) (xy 197.514982 -287.056215) (xy 197.563201 -287.046371) (xy 197.612376 -287.04439)
			(xy 197.661231 -287.050322) (xy 197.708502 -287.064014) (xy 197.752964 -287.085112) (xy 197.793467 -287.113068)
			(xy 197.82896 -287.14716) (xy 197.858525 -287.186504) (xy 197.881396 -287.230081) (xy 197.89698 -287.276762)
			(xy 197.904875 -287.325339) (xy 197.90537 -287.349946) (xy 198.244218 -287.349946) (xy 198.248178 -287.300892)
			(xy 198.259955 -287.253108) (xy 198.279246 -287.207832) (xy 198.305549 -287.166236) (xy 198.338184 -287.129399)
			(xy 198.376305 -287.098274) (xy 198.418926 -287.073667) (xy 198.464942 -287.056215) (xy 198.513161 -287.046371)
			(xy 198.562336 -287.04439) (xy 198.611191 -287.050322) (xy 198.658462 -287.064014) (xy 198.702924 -287.085112)
			(xy 198.743427 -287.113068) (xy 198.77892 -287.14716) (xy 198.808485 -287.186504) (xy 198.831356 -287.230081)
			(xy 198.84694 -287.276762) (xy 198.854835 -287.325339) (xy 198.85533 -287.349946) (xy 306.744128 -287.349946)
			(xy 306.748088 -287.300892) (xy 306.759865 -287.253108) (xy 306.779156 -287.207832) (xy 306.805459 -287.166236)
			(xy 306.838094 -287.129399) (xy 306.876215 -287.098274) (xy 306.918836 -287.073667) (xy 306.964852 -287.056215)
			(xy 307.013071 -287.046371) (xy 307.062246 -287.04439) (xy 307.111101 -287.050322) (xy 307.158372 -287.064014)
			(xy 307.202834 -287.085112) (xy 307.243337 -287.113068) (xy 307.27883 -287.14716) (xy 307.308395 -287.186504)
			(xy 307.331266 -287.230081) (xy 307.34685 -287.276762) (xy 307.354745 -287.325339) (xy 307.35524 -287.349946)
			(xy 307.694088 -287.349946) (xy 307.698048 -287.300892) (xy 307.709825 -287.253108) (xy 307.729116 -287.207832)
			(xy 307.755419 -287.166236) (xy 307.788054 -287.129399) (xy 307.826175 -287.098274) (xy 307.868796 -287.073667)
			(xy 307.914812 -287.056215) (xy 307.963031 -287.046371) (xy 308.012206 -287.04439) (xy 308.061061 -287.050322)
			(xy 308.108332 -287.064014) (xy 308.152794 -287.085112) (xy 308.193297 -287.113068) (xy 308.22879 -287.14716)
			(xy 308.258355 -287.186504) (xy 308.281226 -287.230081) (xy 308.29681 -287.276762) (xy 308.304705 -287.325339)
			(xy 308.3052 -287.349946) (xy 313.394102 -287.349946) (xy 313.398062 -287.300892) (xy 313.409839 -287.253108)
			(xy 313.42913 -287.207832) (xy 313.455433 -287.166236) (xy 313.488068 -287.129399) (xy 313.526189 -287.098274)
			(xy 313.56881 -287.073667) (xy 313.614826 -287.056215) (xy 313.663045 -287.046371) (xy 313.71222 -287.04439)
			(xy 313.761075 -287.050322) (xy 313.808346 -287.064014) (xy 313.852808 -287.085112) (xy 313.893311 -287.113068)
			(xy 313.928804 -287.14716) (xy 313.958369 -287.186504) (xy 313.98124 -287.230081) (xy 313.996824 -287.276762)
			(xy 314.004719 -287.325339) (xy 314.005214 -287.349946) (xy 314.344062 -287.349946) (xy 314.348022 -287.300892)
			(xy 314.359799 -287.253108) (xy 314.37909 -287.207832) (xy 314.405393 -287.166236) (xy 314.438028 -287.129399)
			(xy 314.476149 -287.098274) (xy 314.51877 -287.073667) (xy 314.564786 -287.056215) (xy 314.613005 -287.046371)
			(xy 314.66218 -287.04439) (xy 314.711035 -287.050322) (xy 314.758306 -287.064014) (xy 314.802768 -287.085112)
			(xy 314.843271 -287.113068) (xy 314.878764 -287.14716) (xy 314.908329 -287.186504) (xy 314.9312 -287.230081)
			(xy 314.946784 -287.276762) (xy 314.954679 -287.325339) (xy 314.955174 -287.349946) (xy 422.844226 -287.349946)
			(xy 422.848186 -287.300892) (xy 422.859963 -287.253108) (xy 422.879254 -287.207832) (xy 422.905557 -287.166236)
			(xy 422.938192 -287.129399) (xy 422.976313 -287.098274) (xy 423.018934 -287.073667) (xy 423.06495 -287.056215)
			(xy 423.113169 -287.046371) (xy 423.162344 -287.04439) (xy 423.211199 -287.050322) (xy 423.25847 -287.064014)
			(xy 423.302932 -287.085112) (xy 423.343435 -287.113068) (xy 423.378928 -287.14716) (xy 423.408493 -287.186504)
			(xy 423.431364 -287.230081) (xy 423.446948 -287.276762) (xy 423.454843 -287.325339) (xy 423.455338 -287.349946)
			(xy 423.794186 -287.349946) (xy 423.798146 -287.300892) (xy 423.809923 -287.253108) (xy 423.829214 -287.207832)
			(xy 423.855517 -287.166236) (xy 423.888152 -287.129399) (xy 423.926273 -287.098274) (xy 423.968894 -287.073667)
			(xy 424.01491 -287.056215) (xy 424.063129 -287.046371) (xy 424.112304 -287.04439) (xy 424.161159 -287.050322)
			(xy 424.20843 -287.064014) (xy 424.252892 -287.085112) (xy 424.293395 -287.113068) (xy 424.328888 -287.14716)
			(xy 424.358453 -287.186504) (xy 424.381324 -287.230081) (xy 424.396908 -287.276762) (xy 424.404803 -287.325339)
			(xy 424.405298 -287.349946) (xy 429.4942 -287.349946) (xy 429.49816 -287.300892) (xy 429.509937 -287.253108)
			(xy 429.529228 -287.207832) (xy 429.555531 -287.166236) (xy 429.588166 -287.129399) (xy 429.626287 -287.098274)
			(xy 429.668908 -287.073667) (xy 429.714924 -287.056215) (xy 429.763143 -287.046371) (xy 429.812318 -287.04439)
			(xy 429.861173 -287.050322) (xy 429.908444 -287.064014) (xy 429.952906 -287.085112) (xy 429.993409 -287.113068)
			(xy 430.028902 -287.14716) (xy 430.058467 -287.186504) (xy 430.081338 -287.230081) (xy 430.096922 -287.276762)
			(xy 430.104817 -287.325339) (xy 430.105312 -287.349946) (xy 430.44416 -287.349946) (xy 430.44812 -287.300892)
			(xy 430.459897 -287.253108) (xy 430.479188 -287.207832) (xy 430.505491 -287.166236) (xy 430.538126 -287.129399)
			(xy 430.576247 -287.098274) (xy 430.618868 -287.073667) (xy 430.664884 -287.056215) (xy 430.713103 -287.046371)
			(xy 430.762278 -287.04439) (xy 430.811133 -287.050322) (xy 430.858404 -287.064014) (xy 430.902866 -287.085112)
			(xy 430.943369 -287.113068) (xy 430.978862 -287.14716) (xy 431.008427 -287.186504) (xy 431.031298 -287.230081)
			(xy 431.046882 -287.276762) (xy 431.054777 -287.325339) (xy 431.055272 -287.349946) (xy 431.054777 -287.374553)
			(xy 431.046882 -287.42313) (xy 431.031298 -287.469811) (xy 431.008427 -287.513388) (xy 430.978862 -287.552732)
			(xy 430.943369 -287.586824) (xy 430.902866 -287.61478) (xy 430.858404 -287.635878) (xy 430.811133 -287.64957)
			(xy 430.762278 -287.655502) (xy 430.713103 -287.653521) (xy 430.664884 -287.643677) (xy 430.618868 -287.626225)
			(xy 430.576247 -287.601618) (xy 430.538126 -287.570493) (xy 430.505491 -287.533656) (xy 430.479188 -287.49206)
			(xy 430.459897 -287.446784) (xy 430.44812 -287.399) (xy 430.44416 -287.349946) (xy 430.105312 -287.349946)
			(xy 430.104817 -287.374553) (xy 430.096922 -287.42313) (xy 430.081338 -287.469811) (xy 430.058467 -287.513388)
			(xy 430.028902 -287.552732) (xy 429.993409 -287.586824) (xy 429.952906 -287.61478) (xy 429.908444 -287.635878)
			(xy 429.861173 -287.64957) (xy 429.812318 -287.655502) (xy 429.763143 -287.653521) (xy 429.714924 -287.643677)
			(xy 429.668908 -287.626225) (xy 429.626287 -287.601618) (xy 429.588166 -287.570493) (xy 429.555531 -287.533656)
			(xy 429.529228 -287.49206) (xy 429.509937 -287.446784) (xy 429.49816 -287.399) (xy 429.4942 -287.349946)
			(xy 424.405298 -287.349946) (xy 424.404803 -287.374553) (xy 424.396908 -287.42313) (xy 424.381324 -287.469811)
			(xy 424.358453 -287.513388) (xy 424.328888 -287.552732) (xy 424.293395 -287.586824) (xy 424.252892 -287.61478)
			(xy 424.20843 -287.635878) (xy 424.161159 -287.64957) (xy 424.112304 -287.655502) (xy 424.063129 -287.653521)
			(xy 424.01491 -287.643677) (xy 423.968894 -287.626225) (xy 423.926273 -287.601618) (xy 423.888152 -287.570493)
			(xy 423.855517 -287.533656) (xy 423.829214 -287.49206) (xy 423.809923 -287.446784) (xy 423.798146 -287.399)
			(xy 423.794186 -287.349946) (xy 423.455338 -287.349946) (xy 423.454843 -287.374553) (xy 423.446948 -287.42313)
			(xy 423.431364 -287.469811) (xy 423.408493 -287.513388) (xy 423.378928 -287.552732) (xy 423.343435 -287.586824)
			(xy 423.302932 -287.61478) (xy 423.25847 -287.635878) (xy 423.211199 -287.64957) (xy 423.162344 -287.655502)
			(xy 423.113169 -287.653521) (xy 423.06495 -287.643677) (xy 423.018934 -287.626225) (xy 422.976313 -287.601618)
			(xy 422.938192 -287.570493) (xy 422.905557 -287.533656) (xy 422.879254 -287.49206) (xy 422.859963 -287.446784)
			(xy 422.848186 -287.399) (xy 422.844226 -287.349946) (xy 314.955174 -287.349946) (xy 314.954679 -287.374553)
			(xy 314.946784 -287.42313) (xy 314.9312 -287.469811) (xy 314.908329 -287.513388) (xy 314.878764 -287.552732)
			(xy 314.843271 -287.586824) (xy 314.802768 -287.61478) (xy 314.758306 -287.635878) (xy 314.711035 -287.64957)
			(xy 314.66218 -287.655502) (xy 314.613005 -287.653521) (xy 314.564786 -287.643677) (xy 314.51877 -287.626225)
			(xy 314.476149 -287.601618) (xy 314.438028 -287.570493) (xy 314.405393 -287.533656) (xy 314.37909 -287.49206)
			(xy 314.359799 -287.446784) (xy 314.348022 -287.399) (xy 314.344062 -287.349946) (xy 314.005214 -287.349946)
			(xy 314.004719 -287.374553) (xy 313.996824 -287.42313) (xy 313.98124 -287.469811) (xy 313.958369 -287.513388)
			(xy 313.928804 -287.552732) (xy 313.893311 -287.586824) (xy 313.852808 -287.61478) (xy 313.808346 -287.635878)
			(xy 313.761075 -287.64957) (xy 313.71222 -287.655502) (xy 313.663045 -287.653521) (xy 313.614826 -287.643677)
			(xy 313.56881 -287.626225) (xy 313.526189 -287.601618) (xy 313.488068 -287.570493) (xy 313.455433 -287.533656)
			(xy 313.42913 -287.49206) (xy 313.409839 -287.446784) (xy 313.398062 -287.399) (xy 313.394102 -287.349946)
			(xy 308.3052 -287.349946) (xy 308.304705 -287.374553) (xy 308.29681 -287.42313) (xy 308.281226 -287.469811)
			(xy 308.258355 -287.513388) (xy 308.22879 -287.552732) (xy 308.193297 -287.586824) (xy 308.152794 -287.61478)
			(xy 308.108332 -287.635878) (xy 308.061061 -287.64957) (xy 308.012206 -287.655502) (xy 307.963031 -287.653521)
			(xy 307.914812 -287.643677) (xy 307.868796 -287.626225) (xy 307.826175 -287.601618) (xy 307.788054 -287.570493)
			(xy 307.755419 -287.533656) (xy 307.729116 -287.49206) (xy 307.709825 -287.446784) (xy 307.698048 -287.399)
			(xy 307.694088 -287.349946) (xy 307.35524 -287.349946) (xy 307.354745 -287.374553) (xy 307.34685 -287.42313)
			(xy 307.331266 -287.469811) (xy 307.308395 -287.513388) (xy 307.27883 -287.552732) (xy 307.243337 -287.586824)
			(xy 307.202834 -287.61478) (xy 307.158372 -287.635878) (xy 307.111101 -287.64957) (xy 307.062246 -287.655502)
			(xy 307.013071 -287.653521) (xy 306.964852 -287.643677) (xy 306.918836 -287.626225) (xy 306.876215 -287.601618)
			(xy 306.838094 -287.570493) (xy 306.805459 -287.533656) (xy 306.779156 -287.49206) (xy 306.759865 -287.446784)
			(xy 306.748088 -287.399) (xy 306.744128 -287.349946) (xy 198.85533 -287.349946) (xy 198.854835 -287.374553)
			(xy 198.84694 -287.42313) (xy 198.831356 -287.469811) (xy 198.808485 -287.513388) (xy 198.77892 -287.552732)
			(xy 198.743427 -287.586824) (xy 198.702924 -287.61478) (xy 198.658462 -287.635878) (xy 198.611191 -287.64957)
			(xy 198.562336 -287.655502) (xy 198.513161 -287.653521) (xy 198.464942 -287.643677) (xy 198.418926 -287.626225)
			(xy 198.376305 -287.601618) (xy 198.338184 -287.570493) (xy 198.305549 -287.533656) (xy 198.279246 -287.49206)
			(xy 198.259955 -287.446784) (xy 198.248178 -287.399) (xy 198.244218 -287.349946) (xy 197.90537 -287.349946)
			(xy 197.904875 -287.374553) (xy 197.89698 -287.42313) (xy 197.881396 -287.469811) (xy 197.858525 -287.513388)
			(xy 197.82896 -287.552732) (xy 197.793467 -287.586824) (xy 197.752964 -287.61478) (xy 197.708502 -287.635878)
			(xy 197.661231 -287.64957) (xy 197.612376 -287.655502) (xy 197.563201 -287.653521) (xy 197.514982 -287.643677)
			(xy 197.468966 -287.626225) (xy 197.426345 -287.601618) (xy 197.388224 -287.570493) (xy 197.355589 -287.533656)
			(xy 197.329286 -287.49206) (xy 197.309995 -287.446784) (xy 197.298218 -287.399) (xy 197.294258 -287.349946)
			(xy 192.205356 -287.349946) (xy 192.204861 -287.374553) (xy 192.196966 -287.42313) (xy 192.181382 -287.469811)
			(xy 192.158511 -287.513388) (xy 192.128946 -287.552732) (xy 192.093453 -287.586824) (xy 192.05295 -287.61478)
			(xy 192.008488 -287.635878) (xy 191.961217 -287.64957) (xy 191.912362 -287.655502) (xy 191.863187 -287.653521)
			(xy 191.814968 -287.643677) (xy 191.768952 -287.626225) (xy 191.726331 -287.601618) (xy 191.68821 -287.570493)
			(xy 191.655575 -287.533656) (xy 191.629272 -287.49206) (xy 191.609981 -287.446784) (xy 191.598204 -287.399)
			(xy 191.594244 -287.349946) (xy 191.255142 -287.349946) (xy 191.254647 -287.374553) (xy 191.246752 -287.42313)
			(xy 191.231168 -287.469811) (xy 191.208297 -287.513388) (xy 191.178732 -287.552732) (xy 191.143239 -287.586824)
			(xy 191.102736 -287.61478) (xy 191.058274 -287.635878) (xy 191.011003 -287.64957) (xy 190.962148 -287.655502)
			(xy 190.912973 -287.653521) (xy 190.864754 -287.643677) (xy 190.818738 -287.626225) (xy 190.776117 -287.601618)
			(xy 190.737996 -287.570493) (xy 190.705361 -287.533656) (xy 190.679058 -287.49206) (xy 190.659767 -287.446784)
			(xy 190.64799 -287.399) (xy 190.64403 -287.349946) (xy 82.755232 -287.349946) (xy 82.754737 -287.374553)
			(xy 82.746842 -287.42313) (xy 82.731258 -287.469811) (xy 82.708387 -287.513388) (xy 82.678822 -287.552732)
			(xy 82.643329 -287.586824) (xy 82.602826 -287.61478) (xy 82.558364 -287.635878) (xy 82.511093 -287.64957)
			(xy 82.462238 -287.655502) (xy 82.413063 -287.653521) (xy 82.364844 -287.643677) (xy 82.318828 -287.626225)
			(xy 82.276207 -287.601618) (xy 82.238086 -287.570493) (xy 82.205451 -287.533656) (xy 82.179148 -287.49206)
			(xy 82.159857 -287.446784) (xy 82.14808 -287.399) (xy 82.14412 -287.349946) (xy 81.805272 -287.349946)
			(xy 81.804777 -287.374553) (xy 81.796882 -287.42313) (xy 81.781298 -287.469811) (xy 81.758427 -287.513388)
			(xy 81.728862 -287.552732) (xy 81.693369 -287.586824) (xy 81.652866 -287.61478) (xy 81.608404 -287.635878)
			(xy 81.561133 -287.64957) (xy 81.512278 -287.655502) (xy 81.463103 -287.653521) (xy 81.414884 -287.643677)
			(xy 81.368868 -287.626225) (xy 81.326247 -287.601618) (xy 81.288126 -287.570493) (xy 81.255491 -287.533656)
			(xy 81.229188 -287.49206) (xy 81.209897 -287.446784) (xy 81.19812 -287.399) (xy 81.19416 -287.349946)
			(xy 76.105258 -287.349946) (xy 76.104763 -287.374553) (xy 76.096868 -287.42313) (xy 76.081284 -287.469811)
			(xy 76.058413 -287.513388) (xy 76.028848 -287.552732) (xy 75.993355 -287.586824) (xy 75.952852 -287.61478)
			(xy 75.90839 -287.635878) (xy 75.861119 -287.64957) (xy 75.812264 -287.655502) (xy 75.763089 -287.653521)
			(xy 75.71487 -287.643677) (xy 75.668854 -287.626225) (xy 75.626233 -287.601618) (xy 75.588112 -287.570493)
			(xy 75.555477 -287.533656) (xy 75.529174 -287.49206) (xy 75.509883 -287.446784) (xy 75.498106 -287.399)
			(xy 75.494146 -287.349946) (xy 75.155044 -287.349946) (xy 75.154549 -287.374553) (xy 75.146654 -287.42313)
			(xy 75.13107 -287.469811) (xy 75.108199 -287.513388) (xy 75.078634 -287.552732) (xy 75.043141 -287.586824)
			(xy 75.002638 -287.61478) (xy 74.958176 -287.635878) (xy 74.910905 -287.64957) (xy 74.86205 -287.655502)
			(xy 74.812875 -287.653521) (xy 74.764656 -287.643677) (xy 74.71864 -287.626225) (xy 74.676019 -287.601618)
			(xy 74.637898 -287.570493) (xy 74.605263 -287.533656) (xy 74.57896 -287.49206) (xy 74.559669 -287.446784)
			(xy 74.547892 -287.399) (xy 74.543932 -287.349946) (xy 0.508 -287.349946) (xy 0.508 -287.850408)
			(xy 37.944539 -287.850408) (xy 37.944539 -287.798392) (xy 37.952677 -287.747016) (xy 37.968751 -287.697546)
			(xy 37.992366 -287.651199) (xy 38.02294 -287.609117) (xy 38.059722 -287.572337) (xy 38.101804 -287.541763)
			(xy 38.148151 -287.518148) (xy 38.197622 -287.502075) (xy 38.248998 -287.493939) (xy 38.275006 -287.493456)
			(xy 39.224966 -287.493456) (xy 39.250978 -287.493901) (xy 39.302363 -287.502035) (xy 39.351843 -287.518107)
			(xy 39.398199 -287.541722) (xy 39.44029 -287.572299) (xy 39.477079 -287.609084) (xy 39.50766 -287.651172)
			(xy 39.53128 -287.697525) (xy 39.547357 -287.747004) (xy 39.555496 -287.798388) (xy 39.555496 -287.850405)
			(xy 40.794466 -287.850405) (xy 40.794466 -287.798395) (xy 40.802602 -287.747025) (xy 40.818674 -287.697561)
			(xy 40.842285 -287.651219) (xy 40.872855 -287.609142) (xy 40.909631 -287.572364) (xy 40.951707 -287.541792)
			(xy 40.998048 -287.518179) (xy 41.047512 -287.502105) (xy 41.098881 -287.493967) (xy 41.124886 -287.493456)
			(xy 42.074846 -287.493456) (xy 42.100852 -287.493934) (xy 42.152223 -287.502077) (xy 42.201688 -287.518155)
			(xy 42.248029 -287.541773) (xy 42.290106 -287.572348) (xy 42.326882 -287.609129) (xy 42.357451 -287.65121)
			(xy 42.381063 -287.697554) (xy 42.397134 -287.747022) (xy 42.40527 -287.798394) (xy 42.40527 -287.850406)
			(xy 42.397134 -287.901778) (xy 42.381063 -287.951246) (xy 42.357451 -287.99759) (xy 42.326882 -288.039671)
			(xy 42.290106 -288.076452) (xy 42.248029 -288.107027) (xy 42.201688 -288.130645) (xy 42.152223 -288.146723)
			(xy 42.100852 -288.154866) (xy 42.074846 -288.15538) (xy 41.124886 -288.15538) (xy 41.098881 -288.154833)
			(xy 41.047512 -288.146695) (xy 40.998048 -288.130621) (xy 40.951707 -288.107008) (xy 40.909631 -288.076436)
			(xy 40.872855 -288.039658) (xy 40.842285 -287.997581) (xy 40.818674 -287.951239) (xy 40.802602 -287.901775)
			(xy 40.794466 -287.850405) (xy 39.555496 -287.850405) (xy 39.555496 -287.850412) (xy 39.547357 -287.901796)
			(xy 39.53128 -287.951275) (xy 39.50766 -287.997628) (xy 39.477079 -288.039716) (xy 39.44029 -288.076501)
			(xy 39.398199 -288.107078) (xy 39.351843 -288.130693) (xy 39.302363 -288.146765) (xy 39.250978 -288.154899)
			(xy 39.224966 -288.15538) (xy 38.275006 -288.15538) (xy 38.248998 -288.154861) (xy 38.197622 -288.146725)
			(xy 38.148151 -288.130652) (xy 38.101804 -288.107037) (xy 38.059722 -288.076463) (xy 38.02294 -288.039683)
			(xy 37.992366 -287.997601) (xy 37.968751 -287.951254) (xy 37.952677 -287.901784) (xy 37.944539 -287.850408)
			(xy 0.508 -287.850408) (xy 0.508 -288.299906) (xy 76.444106 -288.299906) (xy 76.448066 -288.250852)
			(xy 76.459843 -288.203068) (xy 76.479134 -288.157792) (xy 76.505437 -288.116196) (xy 76.538072 -288.079359)
			(xy 76.576193 -288.048234) (xy 76.618814 -288.023627) (xy 76.66483 -288.006175) (xy 76.713049 -287.996331)
			(xy 76.762224 -287.99435) (xy 76.811079 -288.000282) (xy 76.85835 -288.013974) (xy 76.902812 -288.035072)
			(xy 76.943315 -288.063028) (xy 76.978808 -288.09712) (xy 77.008373 -288.136464) (xy 77.031244 -288.180041)
			(xy 77.046828 -288.226722) (xy 77.054723 -288.275299) (xy 77.055218 -288.299906) (xy 77.394066 -288.299906)
			(xy 77.398026 -288.250852) (xy 77.409803 -288.203068) (xy 77.429094 -288.157792) (xy 77.455397 -288.116196)
			(xy 77.488032 -288.079359) (xy 77.526153 -288.048234) (xy 77.568774 -288.023627) (xy 77.61479 -288.006175)
			(xy 77.663009 -287.996331) (xy 77.712184 -287.99435) (xy 77.761039 -288.000282) (xy 77.80831 -288.013974)
			(xy 77.852772 -288.035072) (xy 77.893275 -288.063028) (xy 77.928768 -288.09712) (xy 77.958333 -288.136464)
			(xy 77.981204 -288.180041) (xy 77.996788 -288.226722) (xy 78.004683 -288.275299) (xy 78.005178 -288.299906)
			(xy 79.293986 -288.299906) (xy 79.297946 -288.250852) (xy 79.309723 -288.203068) (xy 79.329014 -288.157792)
			(xy 79.355317 -288.116196) (xy 79.387952 -288.079359) (xy 79.426073 -288.048234) (xy 79.468694 -288.023627)
			(xy 79.51471 -288.006175) (xy 79.562929 -287.996331) (xy 79.612104 -287.99435) (xy 79.660959 -288.000282)
			(xy 79.70823 -288.013974) (xy 79.752692 -288.035072) (xy 79.793195 -288.063028) (xy 79.828688 -288.09712)
			(xy 79.858253 -288.136464) (xy 79.881124 -288.180041) (xy 79.896708 -288.226722) (xy 79.904603 -288.275299)
			(xy 79.905098 -288.299906) (xy 80.243946 -288.299906) (xy 80.247906 -288.250852) (xy 80.259683 -288.203068)
			(xy 80.278974 -288.157792) (xy 80.305277 -288.116196) (xy 80.337912 -288.079359) (xy 80.376033 -288.048234)
			(xy 80.418654 -288.023627) (xy 80.46467 -288.006175) (xy 80.512889 -287.996331) (xy 80.562064 -287.99435)
			(xy 80.610919 -288.000282) (xy 80.65819 -288.013974) (xy 80.702652 -288.035072) (xy 80.743155 -288.063028)
			(xy 80.778648 -288.09712) (xy 80.808213 -288.136464) (xy 80.831084 -288.180041) (xy 80.846668 -288.226722)
			(xy 80.854563 -288.275299) (xy 80.855058 -288.299906) (xy 192.544204 -288.299906) (xy 192.548164 -288.250852)
			(xy 192.559941 -288.203068) (xy 192.579232 -288.157792) (xy 192.605535 -288.116196) (xy 192.63817 -288.079359)
			(xy 192.676291 -288.048234) (xy 192.718912 -288.023627) (xy 192.764928 -288.006175) (xy 192.813147 -287.996331)
			(xy 192.862322 -287.99435) (xy 192.911177 -288.000282) (xy 192.958448 -288.013974) (xy 193.00291 -288.035072)
			(xy 193.043413 -288.063028) (xy 193.078906 -288.09712) (xy 193.108471 -288.136464) (xy 193.131342 -288.180041)
			(xy 193.146926 -288.226722) (xy 193.154821 -288.275299) (xy 193.155316 -288.299906) (xy 193.494164 -288.299906)
			(xy 193.498124 -288.250852) (xy 193.509901 -288.203068) (xy 193.529192 -288.157792) (xy 193.555495 -288.116196)
			(xy 193.58813 -288.079359) (xy 193.626251 -288.048234) (xy 193.668872 -288.023627) (xy 193.714888 -288.006175)
			(xy 193.763107 -287.996331) (xy 193.812282 -287.99435) (xy 193.861137 -288.000282) (xy 193.908408 -288.013974)
			(xy 193.95287 -288.035072) (xy 193.993373 -288.063028) (xy 194.028866 -288.09712) (xy 194.058431 -288.136464)
			(xy 194.081302 -288.180041) (xy 194.096886 -288.226722) (xy 194.104781 -288.275299) (xy 194.105276 -288.299906)
			(xy 195.394084 -288.299906) (xy 195.398044 -288.250852) (xy 195.409821 -288.203068) (xy 195.429112 -288.157792)
			(xy 195.455415 -288.116196) (xy 195.48805 -288.079359) (xy 195.526171 -288.048234) (xy 195.568792 -288.023627)
			(xy 195.614808 -288.006175) (xy 195.663027 -287.996331) (xy 195.712202 -287.99435) (xy 195.761057 -288.000282)
			(xy 195.808328 -288.013974) (xy 195.85279 -288.035072) (xy 195.893293 -288.063028) (xy 195.928786 -288.09712)
			(xy 195.958351 -288.136464) (xy 195.981222 -288.180041) (xy 195.996806 -288.226722) (xy 196.004701 -288.275299)
			(xy 196.005196 -288.299906) (xy 196.344044 -288.299906) (xy 196.348004 -288.250852) (xy 196.359781 -288.203068)
			(xy 196.379072 -288.157792) (xy 196.405375 -288.116196) (xy 196.43801 -288.079359) (xy 196.476131 -288.048234)
			(xy 196.518752 -288.023627) (xy 196.564768 -288.006175) (xy 196.612987 -287.996331) (xy 196.662162 -287.99435)
			(xy 196.711017 -288.000282) (xy 196.758288 -288.013974) (xy 196.80275 -288.035072) (xy 196.843253 -288.063028)
			(xy 196.878746 -288.09712) (xy 196.908311 -288.136464) (xy 196.931182 -288.180041) (xy 196.946766 -288.226722)
			(xy 196.954661 -288.275299) (xy 196.955156 -288.299906) (xy 308.644048 -288.299906) (xy 308.648008 -288.250852)
			(xy 308.659785 -288.203068) (xy 308.679076 -288.157792) (xy 308.705379 -288.116196) (xy 308.738014 -288.079359)
			(xy 308.776135 -288.048234) (xy 308.818756 -288.023627) (xy 308.864772 -288.006175) (xy 308.912991 -287.996331)
			(xy 308.962166 -287.99435) (xy 309.011021 -288.000282) (xy 309.058292 -288.013974) (xy 309.102754 -288.035072)
			(xy 309.143257 -288.063028) (xy 309.17875 -288.09712) (xy 309.208315 -288.136464) (xy 309.231186 -288.180041)
			(xy 309.24677 -288.226722) (xy 309.254665 -288.275299) (xy 309.25516 -288.299906) (xy 309.594008 -288.299906)
			(xy 309.597968 -288.250852) (xy 309.609745 -288.203068) (xy 309.629036 -288.157792) (xy 309.655339 -288.116196)
			(xy 309.687974 -288.079359) (xy 309.726095 -288.048234) (xy 309.768716 -288.023627) (xy 309.814732 -288.006175)
			(xy 309.862951 -287.996331) (xy 309.912126 -287.99435) (xy 309.960981 -288.000282) (xy 310.008252 -288.013974)
			(xy 310.052714 -288.035072) (xy 310.093217 -288.063028) (xy 310.12871 -288.09712) (xy 310.158275 -288.136464)
			(xy 310.181146 -288.180041) (xy 310.19673 -288.226722) (xy 310.204625 -288.275299) (xy 310.20512 -288.299906)
			(xy 311.493928 -288.299906) (xy 311.497888 -288.250852) (xy 311.509665 -288.203068) (xy 311.528956 -288.157792)
			(xy 311.555259 -288.116196) (xy 311.587894 -288.079359) (xy 311.626015 -288.048234) (xy 311.668636 -288.023627)
			(xy 311.714652 -288.006175) (xy 311.762871 -287.996331) (xy 311.812046 -287.99435) (xy 311.860901 -288.000282)
			(xy 311.908172 -288.013974) (xy 311.952634 -288.035072) (xy 311.993137 -288.063028) (xy 312.02863 -288.09712)
			(xy 312.058195 -288.136464) (xy 312.081066 -288.180041) (xy 312.09665 -288.226722) (xy 312.104545 -288.275299)
			(xy 312.10504 -288.299906) (xy 312.443888 -288.299906) (xy 312.447848 -288.250852) (xy 312.459625 -288.203068)
			(xy 312.478916 -288.157792) (xy 312.505219 -288.116196) (xy 312.537854 -288.079359) (xy 312.575975 -288.048234)
			(xy 312.618596 -288.023627) (xy 312.664612 -288.006175) (xy 312.712831 -287.996331) (xy 312.762006 -287.99435)
			(xy 312.810861 -288.000282) (xy 312.858132 -288.013974) (xy 312.902594 -288.035072) (xy 312.943097 -288.063028)
			(xy 312.97859 -288.09712) (xy 313.008155 -288.136464) (xy 313.031026 -288.180041) (xy 313.04661 -288.226722)
			(xy 313.054505 -288.275299) (xy 313.055 -288.299906) (xy 424.744146 -288.299906) (xy 424.748106 -288.250852)
			(xy 424.759883 -288.203068) (xy 424.779174 -288.157792) (xy 424.805477 -288.116196) (xy 424.838112 -288.079359)
			(xy 424.876233 -288.048234) (xy 424.918854 -288.023627) (xy 424.96487 -288.006175) (xy 425.013089 -287.996331)
			(xy 425.062264 -287.99435) (xy 425.111119 -288.000282) (xy 425.15839 -288.013974) (xy 425.202852 -288.035072)
			(xy 425.243355 -288.063028) (xy 425.278848 -288.09712) (xy 425.308413 -288.136464) (xy 425.331284 -288.180041)
			(xy 425.346868 -288.226722) (xy 425.354763 -288.275299) (xy 425.355258 -288.299906) (xy 425.694106 -288.299906)
			(xy 425.698066 -288.250852) (xy 425.709843 -288.203068) (xy 425.729134 -288.157792) (xy 425.755437 -288.116196)
			(xy 425.788072 -288.079359) (xy 425.826193 -288.048234) (xy 425.868814 -288.023627) (xy 425.91483 -288.006175)
			(xy 425.963049 -287.996331) (xy 426.012224 -287.99435) (xy 426.061079 -288.000282) (xy 426.10835 -288.013974)
			(xy 426.152812 -288.035072) (xy 426.193315 -288.063028) (xy 426.228808 -288.09712) (xy 426.258373 -288.136464)
			(xy 426.281244 -288.180041) (xy 426.296828 -288.226722) (xy 426.304723 -288.275299) (xy 426.305218 -288.299906)
			(xy 427.594026 -288.299906) (xy 427.597986 -288.250852) (xy 427.609763 -288.203068) (xy 427.629054 -288.157792)
			(xy 427.655357 -288.116196) (xy 427.687992 -288.079359) (xy 427.726113 -288.048234) (xy 427.768734 -288.023627)
			(xy 427.81475 -288.006175) (xy 427.862969 -287.996331) (xy 427.912144 -287.99435) (xy 427.960999 -288.000282)
			(xy 428.00827 -288.013974) (xy 428.052732 -288.035072) (xy 428.093235 -288.063028) (xy 428.128728 -288.09712)
			(xy 428.158293 -288.136464) (xy 428.181164 -288.180041) (xy 428.196748 -288.226722) (xy 428.204643 -288.275299)
			(xy 428.205138 -288.299906) (xy 428.543986 -288.299906) (xy 428.547946 -288.250852) (xy 428.559723 -288.203068)
			(xy 428.579014 -288.157792) (xy 428.605317 -288.116196) (xy 428.637952 -288.079359) (xy 428.676073 -288.048234)
			(xy 428.718694 -288.023627) (xy 428.76471 -288.006175) (xy 428.812929 -287.996331) (xy 428.862104 -287.99435)
			(xy 428.910959 -288.000282) (xy 428.95823 -288.013974) (xy 429.002692 -288.035072) (xy 429.043195 -288.063028)
			(xy 429.078688 -288.09712) (xy 429.108253 -288.136464) (xy 429.131124 -288.180041) (xy 429.146708 -288.226722)
			(xy 429.154603 -288.275299) (xy 429.155098 -288.299906) (xy 429.154603 -288.324513) (xy 429.146708 -288.37309)
			(xy 429.131124 -288.419771) (xy 429.108253 -288.463348) (xy 429.078688 -288.502692) (xy 429.043195 -288.536784)
			(xy 429.002692 -288.56474) (xy 428.95823 -288.585838) (xy 428.910959 -288.59953) (xy 428.862104 -288.605462)
			(xy 428.812929 -288.603481) (xy 428.76471 -288.593637) (xy 428.718694 -288.576185) (xy 428.676073 -288.551578)
			(xy 428.637952 -288.520453) (xy 428.605317 -288.483616) (xy 428.579014 -288.44202) (xy 428.559723 -288.396744)
			(xy 428.547946 -288.34896) (xy 428.543986 -288.299906) (xy 428.205138 -288.299906) (xy 428.204643 -288.324513)
			(xy 428.196748 -288.37309) (xy 428.181164 -288.419771) (xy 428.158293 -288.463348) (xy 428.128728 -288.502692)
			(xy 428.093235 -288.536784) (xy 428.052732 -288.56474) (xy 428.00827 -288.585838) (xy 427.960999 -288.59953)
			(xy 427.912144 -288.605462) (xy 427.862969 -288.603481) (xy 427.81475 -288.593637) (xy 427.768734 -288.576185)
			(xy 427.726113 -288.551578) (xy 427.687992 -288.520453) (xy 427.655357 -288.483616) (xy 427.629054 -288.44202)
			(xy 427.609763 -288.396744) (xy 427.597986 -288.34896) (xy 427.594026 -288.299906) (xy 426.305218 -288.299906)
			(xy 426.304723 -288.324513) (xy 426.296828 -288.37309) (xy 426.281244 -288.419771) (xy 426.258373 -288.463348)
			(xy 426.228808 -288.502692) (xy 426.193315 -288.536784) (xy 426.152812 -288.56474) (xy 426.10835 -288.585838)
			(xy 426.061079 -288.59953) (xy 426.012224 -288.605462) (xy 425.963049 -288.603481) (xy 425.91483 -288.593637)
			(xy 425.868814 -288.576185) (xy 425.826193 -288.551578) (xy 425.788072 -288.520453) (xy 425.755437 -288.483616)
			(xy 425.729134 -288.44202) (xy 425.709843 -288.396744) (xy 425.698066 -288.34896) (xy 425.694106 -288.299906)
			(xy 425.355258 -288.299906) (xy 425.354763 -288.324513) (xy 425.346868 -288.37309) (xy 425.331284 -288.419771)
			(xy 425.308413 -288.463348) (xy 425.278848 -288.502692) (xy 425.243355 -288.536784) (xy 425.202852 -288.56474)
			(xy 425.15839 -288.585838) (xy 425.111119 -288.59953) (xy 425.062264 -288.605462) (xy 425.013089 -288.603481)
			(xy 424.96487 -288.593637) (xy 424.918854 -288.576185) (xy 424.876233 -288.551578) (xy 424.838112 -288.520453)
			(xy 424.805477 -288.483616) (xy 424.779174 -288.44202) (xy 424.759883 -288.396744) (xy 424.748106 -288.34896)
			(xy 424.744146 -288.299906) (xy 313.055 -288.299906) (xy 313.054505 -288.324513) (xy 313.04661 -288.37309)
			(xy 313.031026 -288.419771) (xy 313.008155 -288.463348) (xy 312.97859 -288.502692) (xy 312.943097 -288.536784)
			(xy 312.902594 -288.56474) (xy 312.858132 -288.585838) (xy 312.810861 -288.59953) (xy 312.762006 -288.605462)
			(xy 312.712831 -288.603481) (xy 312.664612 -288.593637) (xy 312.618596 -288.576185) (xy 312.575975 -288.551578)
			(xy 312.537854 -288.520453) (xy 312.505219 -288.483616) (xy 312.478916 -288.44202) (xy 312.459625 -288.396744)
			(xy 312.447848 -288.34896) (xy 312.443888 -288.299906) (xy 312.10504 -288.299906) (xy 312.104545 -288.324513)
			(xy 312.09665 -288.37309) (xy 312.081066 -288.419771) (xy 312.058195 -288.463348) (xy 312.02863 -288.502692)
			(xy 311.993137 -288.536784) (xy 311.952634 -288.56474) (xy 311.908172 -288.585838) (xy 311.860901 -288.59953)
			(xy 311.812046 -288.605462) (xy 311.762871 -288.603481) (xy 311.714652 -288.593637) (xy 311.668636 -288.576185)
			(xy 311.626015 -288.551578) (xy 311.587894 -288.520453) (xy 311.555259 -288.483616) (xy 311.528956 -288.44202)
			(xy 311.509665 -288.396744) (xy 311.497888 -288.34896) (xy 311.493928 -288.299906) (xy 310.20512 -288.299906)
			(xy 310.204625 -288.324513) (xy 310.19673 -288.37309) (xy 310.181146 -288.419771) (xy 310.158275 -288.463348)
			(xy 310.12871 -288.502692) (xy 310.093217 -288.536784) (xy 310.052714 -288.56474) (xy 310.008252 -288.585838)
			(xy 309.960981 -288.59953) (xy 309.912126 -288.605462) (xy 309.862951 -288.603481) (xy 309.814732 -288.593637)
			(xy 309.768716 -288.576185) (xy 309.726095 -288.551578) (xy 309.687974 -288.520453) (xy 309.655339 -288.483616)
			(xy 309.629036 -288.44202) (xy 309.609745 -288.396744) (xy 309.597968 -288.34896) (xy 309.594008 -288.299906)
			(xy 309.25516 -288.299906) (xy 309.254665 -288.324513) (xy 309.24677 -288.37309) (xy 309.231186 -288.419771)
			(xy 309.208315 -288.463348) (xy 309.17875 -288.502692) (xy 309.143257 -288.536784) (xy 309.102754 -288.56474)
			(xy 309.058292 -288.585838) (xy 309.011021 -288.59953) (xy 308.962166 -288.605462) (xy 308.912991 -288.603481)
			(xy 308.864772 -288.593637) (xy 308.818756 -288.576185) (xy 308.776135 -288.551578) (xy 308.738014 -288.520453)
			(xy 308.705379 -288.483616) (xy 308.679076 -288.44202) (xy 308.659785 -288.396744) (xy 308.648008 -288.34896)
			(xy 308.644048 -288.299906) (xy 196.955156 -288.299906) (xy 196.954661 -288.324513) (xy 196.946766 -288.37309)
			(xy 196.931182 -288.419771) (xy 196.908311 -288.463348) (xy 196.878746 -288.502692) (xy 196.843253 -288.536784)
			(xy 196.80275 -288.56474) (xy 196.758288 -288.585838) (xy 196.711017 -288.59953) (xy 196.662162 -288.605462)
			(xy 196.612987 -288.603481) (xy 196.564768 -288.593637) (xy 196.518752 -288.576185) (xy 196.476131 -288.551578)
			(xy 196.43801 -288.520453) (xy 196.405375 -288.483616) (xy 196.379072 -288.44202) (xy 196.359781 -288.396744)
			(xy 196.348004 -288.34896) (xy 196.344044 -288.299906) (xy 196.005196 -288.299906) (xy 196.004701 -288.324513)
			(xy 195.996806 -288.37309) (xy 195.981222 -288.419771) (xy 195.958351 -288.463348) (xy 195.928786 -288.502692)
			(xy 195.893293 -288.536784) (xy 195.85279 -288.56474) (xy 195.808328 -288.585838) (xy 195.761057 -288.59953)
			(xy 195.712202 -288.605462) (xy 195.663027 -288.603481) (xy 195.614808 -288.593637) (xy 195.568792 -288.576185)
			(xy 195.526171 -288.551578) (xy 195.48805 -288.520453) (xy 195.455415 -288.483616) (xy 195.429112 -288.44202)
			(xy 195.409821 -288.396744) (xy 195.398044 -288.34896) (xy 195.394084 -288.299906) (xy 194.105276 -288.299906)
			(xy 194.104781 -288.324513) (xy 194.096886 -288.37309) (xy 194.081302 -288.419771) (xy 194.058431 -288.463348)
			(xy 194.028866 -288.502692) (xy 193.993373 -288.536784) (xy 193.95287 -288.56474) (xy 193.908408 -288.585838)
			(xy 193.861137 -288.59953) (xy 193.812282 -288.605462) (xy 193.763107 -288.603481) (xy 193.714888 -288.593637)
			(xy 193.668872 -288.576185) (xy 193.626251 -288.551578) (xy 193.58813 -288.520453) (xy 193.555495 -288.483616)
			(xy 193.529192 -288.44202) (xy 193.509901 -288.396744) (xy 193.498124 -288.34896) (xy 193.494164 -288.299906)
			(xy 193.155316 -288.299906) (xy 193.154821 -288.324513) (xy 193.146926 -288.37309) (xy 193.131342 -288.419771)
			(xy 193.108471 -288.463348) (xy 193.078906 -288.502692) (xy 193.043413 -288.536784) (xy 193.00291 -288.56474)
			(xy 192.958448 -288.585838) (xy 192.911177 -288.59953) (xy 192.862322 -288.605462) (xy 192.813147 -288.603481)
			(xy 192.764928 -288.593637) (xy 192.718912 -288.576185) (xy 192.676291 -288.551578) (xy 192.63817 -288.520453)
			(xy 192.605535 -288.483616) (xy 192.579232 -288.44202) (xy 192.559941 -288.396744) (xy 192.548164 -288.34896)
			(xy 192.544204 -288.299906) (xy 80.855058 -288.299906) (xy 80.854563 -288.324513) (xy 80.846668 -288.37309)
			(xy 80.831084 -288.419771) (xy 80.808213 -288.463348) (xy 80.778648 -288.502692) (xy 80.743155 -288.536784)
			(xy 80.702652 -288.56474) (xy 80.65819 -288.585838) (xy 80.610919 -288.59953) (xy 80.562064 -288.605462)
			(xy 80.512889 -288.603481) (xy 80.46467 -288.593637) (xy 80.418654 -288.576185) (xy 80.376033 -288.551578)
			(xy 80.337912 -288.520453) (xy 80.305277 -288.483616) (xy 80.278974 -288.44202) (xy 80.259683 -288.396744)
			(xy 80.247906 -288.34896) (xy 80.243946 -288.299906) (xy 79.905098 -288.299906) (xy 79.904603 -288.324513)
			(xy 79.896708 -288.37309) (xy 79.881124 -288.419771) (xy 79.858253 -288.463348) (xy 79.828688 -288.502692)
			(xy 79.793195 -288.536784) (xy 79.752692 -288.56474) (xy 79.70823 -288.585838) (xy 79.660959 -288.59953)
			(xy 79.612104 -288.605462) (xy 79.562929 -288.603481) (xy 79.51471 -288.593637) (xy 79.468694 -288.576185)
			(xy 79.426073 -288.551578) (xy 79.387952 -288.520453) (xy 79.355317 -288.483616) (xy 79.329014 -288.44202)
			(xy 79.309723 -288.396744) (xy 79.297946 -288.34896) (xy 79.293986 -288.299906) (xy 78.005178 -288.299906)
			(xy 78.004683 -288.324513) (xy 77.996788 -288.37309) (xy 77.981204 -288.419771) (xy 77.958333 -288.463348)
			(xy 77.928768 -288.502692) (xy 77.893275 -288.536784) (xy 77.852772 -288.56474) (xy 77.80831 -288.585838)
			(xy 77.761039 -288.59953) (xy 77.712184 -288.605462) (xy 77.663009 -288.603481) (xy 77.61479 -288.593637)
			(xy 77.568774 -288.576185) (xy 77.526153 -288.551578) (xy 77.488032 -288.520453) (xy 77.455397 -288.483616)
			(xy 77.429094 -288.44202) (xy 77.409803 -288.396744) (xy 77.398026 -288.34896) (xy 77.394066 -288.299906)
			(xy 77.055218 -288.299906) (xy 77.054723 -288.324513) (xy 77.046828 -288.37309) (xy 77.031244 -288.419771)
			(xy 77.008373 -288.463348) (xy 76.978808 -288.502692) (xy 76.943315 -288.536784) (xy 76.902812 -288.56474)
			(xy 76.85835 -288.585838) (xy 76.811079 -288.59953) (xy 76.762224 -288.605462) (xy 76.713049 -288.603481)
			(xy 76.66483 -288.593637) (xy 76.618814 -288.576185) (xy 76.576193 -288.551578) (xy 76.538072 -288.520453)
			(xy 76.505437 -288.483616) (xy 76.479134 -288.44202) (xy 76.459843 -288.396744) (xy 76.448066 -288.34896)
			(xy 76.444106 -288.299906) (xy 0.508 -288.299906) (xy 0.508 -288.800413) (xy 36.0443 -288.800413)
			(xy 36.0443 -288.748387) (xy 36.052439 -288.697003) (xy 36.068516 -288.647524) (xy 36.092136 -288.60117)
			(xy 36.122718 -288.559082) (xy 36.159507 -288.522297) (xy 36.201598 -288.49172) (xy 36.247954 -288.468104)
			(xy 36.297434 -288.452031) (xy 36.348819 -288.443897) (xy 36.374832 -288.443416) (xy 37.324792 -288.443416)
			(xy 37.3508 -288.443943) (xy 37.402175 -288.452079) (xy 37.451646 -288.468151) (xy 37.497993 -288.491765)
			(xy 37.540075 -288.522339) (xy 37.576856 -288.559119) (xy 37.60743 -288.601201) (xy 37.631045 -288.647547)
			(xy 37.647119 -288.697017) (xy 37.655257 -288.748392) (xy 37.655257 -288.800408) (xy 37.655257 -288.800411)
			(xy 42.694299 -288.800411) (xy 42.694299 -288.748389) (xy 42.702438 -288.697007) (xy 42.718514 -288.64753)
			(xy 42.742132 -288.601178) (xy 42.77271 -288.559091) (xy 42.809496 -288.522306) (xy 42.851583 -288.491729)
			(xy 42.897936 -288.468111) (xy 42.947413 -288.452036) (xy 42.998795 -288.443899) (xy 43.024806 -288.443416)
			(xy 43.974766 -288.443416) (xy 44.000775 -288.443941) (xy 44.052154 -288.452074) (xy 44.101628 -288.468144)
			(xy 44.147978 -288.491757) (xy 44.190064 -288.52233) (xy 44.226848 -288.55911) (xy 44.257426 -288.601193)
			(xy 44.281043 -288.647541) (xy 44.297119 -288.697013) (xy 44.305257 -288.748391) (xy 44.305257 -288.800409)
			(xy 44.297119 -288.851787) (xy 44.281043 -288.901259) (xy 44.257426 -288.947607) (xy 44.226848 -288.98969)
			(xy 44.190064 -289.02647) (xy 44.147978 -289.057043) (xy 44.101628 -289.080656) (xy 44.052154 -289.096726)
			(xy 44.000775 -289.104859) (xy 43.974766 -289.10534) (xy 43.024806 -289.10534) (xy 42.998795 -289.104901)
			(xy 42.947413 -289.096764) (xy 42.897936 -289.080689) (xy 42.851583 -289.057071) (xy 42.809496 -289.026494)
			(xy 42.77271 -288.989709) (xy 42.742132 -288.947622) (xy 42.718514 -288.90127) (xy 42.702438 -288.851793)
			(xy 42.694299 -288.800411) (xy 37.655257 -288.800411) (xy 37.647119 -288.851783) (xy 37.631045 -288.901253)
			(xy 37.60743 -288.947599) (xy 37.576856 -288.989681) (xy 37.540075 -289.026461) (xy 37.497993 -289.057035)
			(xy 37.451646 -289.080649) (xy 37.402175 -289.096721) (xy 37.3508 -289.104857) (xy 37.324792 -289.10534)
			(xy 36.374832 -289.10534) (xy 36.348819 -289.104903) (xy 36.297434 -289.096769) (xy 36.247954 -289.080696)
			(xy 36.201598 -289.05708) (xy 36.159507 -289.026503) (xy 36.122718 -288.989718) (xy 36.092136 -288.94763)
			(xy 36.068516 -288.901276) (xy 36.052439 -288.851797) (xy 36.0443 -288.800413) (xy 0.508 -288.800413)
			(xy 0.508 -297.350788) (xy 36.044382 -297.350788) (xy 36.044382 -297.298812) (xy 36.052512 -297.247477)
			(xy 36.068572 -297.198045) (xy 36.092168 -297.151734) (xy 36.122717 -297.109685) (xy 36.159468 -297.072931)
			(xy 36.201516 -297.042379) (xy 36.247825 -297.018781) (xy 36.297255 -297.002717) (xy 36.34859 -296.994583)
			(xy 36.374578 -296.994072) (xy 37.324538 -296.994072) (xy 37.350522 -296.994624) (xy 37.401848 -297.002759)
			(xy 37.451271 -297.018822) (xy 37.497572 -297.042419) (xy 37.539613 -297.072968) (xy 37.576357 -297.109716)
			(xy 37.606901 -297.15176) (xy 37.630492 -297.198064) (xy 37.64655 -297.247489) (xy 37.654679 -297.298816)
			(xy 37.654679 -297.350784) (xy 37.654678 -297.350788) (xy 152.144482 -297.350788) (xy 152.144482 -297.298812)
			(xy 152.152612 -297.247477) (xy 152.168672 -297.198046) (xy 152.192268 -297.151735) (xy 152.222816 -297.109685)
			(xy 152.259567 -297.072932) (xy 152.301615 -297.04238) (xy 152.347923 -297.018782) (xy 152.397354 -297.002717)
			(xy 152.448688 -296.994583) (xy 152.474676 -296.994072) (xy 153.424636 -296.994072) (xy 153.45062 -296.994624)
			(xy 153.501947 -297.002759) (xy 153.55137 -297.018822) (xy 153.597671 -297.042418) (xy 153.639712 -297.072967)
			(xy 153.676457 -297.109715) (xy 153.707001 -297.151759) (xy 153.730592 -297.198064) (xy 153.74665 -297.247488)
			(xy 153.754779 -297.298816) (xy 153.754779 -297.350784) (xy 153.754778 -297.350792) (xy 268.244255 -297.350792)
			(xy 268.244255 -297.298808) (xy 268.252388 -297.247465) (xy 268.268452 -297.198025) (xy 268.292053 -297.151708)
			(xy 268.322609 -297.109653) (xy 268.359368 -297.072896) (xy 268.401425 -297.042342) (xy 268.447744 -297.018744)
			(xy 268.497184 -297.002683) (xy 268.548528 -296.994554) (xy 268.57452 -296.994072) (xy 269.52448 -296.994072)
			(xy 269.550469 -296.994594) (xy 269.601807 -297.002722) (xy 269.651241 -297.018781) (xy 269.697554 -297.042377)
			(xy 269.739606 -297.072927) (xy 269.77636 -297.109679) (xy 269.806913 -297.151729) (xy 269.830511 -297.198041)
			(xy 269.846573 -297.247474) (xy 269.854705 -297.298811) (xy 269.854705 -297.350789) (xy 269.854705 -297.350792)
			(xy 384.344355 -297.350792) (xy 384.344355 -297.298808) (xy 384.352488 -297.247465) (xy 384.368552 -297.198026)
			(xy 384.392153 -297.151709) (xy 384.422709 -297.109654) (xy 384.459467 -297.072897) (xy 384.501524 -297.042343)
			(xy 384.547842 -297.018745) (xy 384.597282 -297.002683) (xy 384.648626 -296.994554) (xy 384.674618 -296.994072)
			(xy 385.624578 -296.994072) (xy 385.650567 -296.994593) (xy 385.701905 -297.002721) (xy 385.751339 -297.018781)
			(xy 385.797653 -297.042376) (xy 385.839705 -297.072926) (xy 385.87646 -297.109678) (xy 385.907013 -297.151728)
			(xy 385.930611 -297.19804) (xy 385.946673 -297.247474) (xy 385.954805 -297.298811) (xy 385.954805 -297.350789)
			(xy 385.946673 -297.402126) (xy 385.930611 -297.45156) (xy 385.907013 -297.497872) (xy 385.87646 -297.539922)
			(xy 385.839705 -297.576674) (xy 385.797653 -297.607224) (xy 385.751339 -297.630819) (xy 385.701905 -297.646879)
			(xy 385.650567 -297.655007) (xy 385.624578 -297.655488) (xy 384.674618 -297.655488) (xy 384.648626 -297.655046)
			(xy 384.597282 -297.646917) (xy 384.547842 -297.630855) (xy 384.501524 -297.607257) (xy 384.459467 -297.576703)
			(xy 384.422709 -297.539946) (xy 384.392153 -297.497891) (xy 384.368552 -297.451574) (xy 384.352488 -297.402135)
			(xy 384.344355 -297.350792) (xy 269.854705 -297.350792) (xy 269.846573 -297.402126) (xy 269.830511 -297.451559)
			(xy 269.806913 -297.497871) (xy 269.77636 -297.539921) (xy 269.739606 -297.576673) (xy 269.697554 -297.607223)
			(xy 269.651241 -297.630819) (xy 269.601807 -297.646878) (xy 269.550469 -297.655006) (xy 269.52448 -297.655488)
			(xy 268.57452 -297.655488) (xy 268.548528 -297.655046) (xy 268.497184 -297.646917) (xy 268.447744 -297.630856)
			(xy 268.401425 -297.607258) (xy 268.359368 -297.576704) (xy 268.322609 -297.539947) (xy 268.292053 -297.497892)
			(xy 268.268452 -297.451575) (xy 268.252388 -297.402135) (xy 268.244255 -297.350792) (xy 153.754778 -297.350792)
			(xy 153.74665 -297.402112) (xy 153.730592 -297.451536) (xy 153.707001 -297.497841) (xy 153.676457 -297.539885)
			(xy 153.639712 -297.576633) (xy 153.597671 -297.607182) (xy 153.55137 -297.630778) (xy 153.501947 -297.646841)
			(xy 153.45062 -297.654976) (xy 153.424636 -297.655488) (xy 152.474676 -297.655488) (xy 152.448688 -297.655017)
			(xy 152.397354 -297.646883) (xy 152.347923 -297.630818) (xy 152.301615 -297.60722) (xy 152.259567 -297.576668)
			(xy 152.222816 -297.539915) (xy 152.192268 -297.497865) (xy 152.168672 -297.451554) (xy 152.152612 -297.402123)
			(xy 152.144482 -297.350788) (xy 37.654678 -297.350788) (xy 37.64655 -297.402111) (xy 37.630492 -297.451536)
			(xy 37.606901 -297.49784) (xy 37.576357 -297.539884) (xy 37.539613 -297.576632) (xy 37.497572 -297.607181)
			(xy 37.451271 -297.630778) (xy 37.401848 -297.646841) (xy 37.350522 -297.654976) (xy 37.324538 -297.655488)
			(xy 36.374578 -297.655488) (xy 36.34859 -297.655017) (xy 36.297255 -297.646883) (xy 36.247825 -297.630819)
			(xy 36.201516 -297.607221) (xy 36.159468 -297.576669) (xy 36.122717 -297.539915) (xy 36.092168 -297.497866)
			(xy 36.068572 -297.451555) (xy 36.052512 -297.402123) (xy 36.044382 -297.350788) (xy 0.508 -297.350788)
			(xy 0.508 -298.77569) (xy 39.369695 -298.77569) (xy 39.369695 -298.72371) (xy 39.377827 -298.67237)
			(xy 39.393891 -298.622935) (xy 39.417492 -298.576621) (xy 39.448047 -298.53457) (xy 39.484805 -298.497817)
			(xy 39.52686 -298.467268) (xy 39.573177 -298.443674) (xy 39.622615 -298.427617) (xy 39.673956 -298.419492)
			(xy 39.699946 -298.419012) (xy 40.649906 -298.419012) (xy 40.675894 -298.419482) (xy 40.727231 -298.427614)
			(xy 40.776664 -298.443676) (xy 40.822975 -298.467274) (xy 40.865025 -298.497826) (xy 40.901778 -298.534579)
			(xy 40.932329 -298.57663) (xy 40.955926 -298.622942) (xy 40.971988 -298.672375) (xy 40.980118 -298.723712)
			(xy 40.980118 -298.775685) (xy 387.669821 -298.775685) (xy 387.669821 -298.723715) (xy 387.677951 -298.672385)
			(xy 387.69401 -298.622959) (xy 387.717603 -298.576653) (xy 387.74815 -298.534608) (xy 387.784897 -298.497859)
			(xy 387.826941 -298.467311) (xy 387.873246 -298.443716) (xy 387.922671 -298.427654) (xy 387.974001 -298.419523)
			(xy 387.999986 -298.419012) (xy 388.949946 -298.419012) (xy 388.975932 -298.419485) (xy 389.027264 -298.427622)
			(xy 389.076692 -298.443688) (xy 389.122998 -298.467288) (xy 389.165042 -298.49784) (xy 389.20179 -298.534593)
			(xy 389.232337 -298.576642) (xy 389.25593 -298.622951) (xy 389.271989 -298.67238) (xy 389.280119 -298.723714)
			(xy 389.280119 -298.775686) (xy 389.271989 -298.82702) (xy 389.25593 -298.876449) (xy 389.232337 -298.922758)
			(xy 389.20179 -298.964807) (xy 389.165042 -299.00156) (xy 389.122998 -299.032112) (xy 389.076692 -299.055712)
			(xy 389.027264 -299.071778) (xy 388.975932 -299.079915) (xy 388.949946 -299.080428) (xy 387.999986 -299.080428)
			(xy 387.974001 -299.079877) (xy 387.922671 -299.071746) (xy 387.873246 -299.055684) (xy 387.826941 -299.032089)
			(xy 387.784897 -299.001541) (xy 387.74815 -298.964792) (xy 387.717603 -298.922747) (xy 387.69401 -298.876441)
			(xy 387.677951 -298.827015) (xy 387.669821 -298.775685) (xy 40.980118 -298.775685) (xy 40.980118 -298.775688)
			(xy 40.971988 -298.827025) (xy 40.955926 -298.876458) (xy 40.932329 -298.92277) (xy 40.901778 -298.964821)
			(xy 40.865025 -299.001574) (xy 40.822975 -299.032126) (xy 40.776664 -299.055724) (xy 40.727231 -299.071786)
			(xy 40.675894 -299.079918) (xy 40.649906 -299.080428) (xy 39.699946 -299.080428) (xy 39.673956 -299.079908)
			(xy 39.622615 -299.071783) (xy 39.573177 -299.055726) (xy 39.52686 -299.032132) (xy 39.484805 -299.001583)
			(xy 39.448047 -298.96483) (xy 39.417492 -298.922779) (xy 39.393891 -298.876465) (xy 39.377827 -298.82703)
			(xy 39.369695 -298.77569) (xy 0.508 -298.77569) (xy 0.508 -299.25101) (xy 36.044102 -299.25101) (xy 36.044102 -299.19899)
			(xy 36.052239 -299.147611) (xy 36.068313 -299.098138) (xy 36.091929 -299.051788) (xy 36.122504 -299.009703)
			(xy 36.159286 -298.972918) (xy 36.201369 -298.94234) (xy 36.247718 -298.918722) (xy 36.29719 -298.902644)
			(xy 36.348568 -298.894504) (xy 36.374578 -298.893992) (xy 37.324538 -298.893992) (xy 37.35054 -298.894597)
			(xy 37.401902 -298.902737) (xy 37.451358 -298.918812) (xy 37.497691 -298.942425) (xy 37.539761 -298.972994)
			(xy 37.576531 -299.009768) (xy 37.607095 -299.051841) (xy 37.630703 -299.098177) (xy 37.646771 -299.147635)
			(xy 37.654906 -299.198998) (xy 37.654906 -299.251002) (xy 37.654905 -299.25101) (xy 152.144202 -299.25101)
			(xy 152.144202 -299.19899) (xy 152.152339 -299.147612) (xy 152.168413 -299.098138) (xy 152.192028 -299.051788)
			(xy 152.222603 -299.009703) (xy 152.259385 -298.972919) (xy 152.301468 -298.942341) (xy 152.347816 -298.918722)
			(xy 152.397288 -298.902645) (xy 152.448666 -298.894504) (xy 152.474676 -298.893992) (xy 153.424636 -298.893992)
			(xy 153.450638 -298.894597) (xy 153.502 -298.902737) (xy 153.551457 -298.918811) (xy 153.59779 -298.942424)
			(xy 153.63986 -298.972993) (xy 153.67663 -299.009767) (xy 153.707195 -299.05184) (xy 153.730803 -299.098177)
			(xy 153.746871 -299.147635) (xy 153.755006 -299.198998) (xy 153.755006 -299.251002) (xy 153.755005 -299.251009)
			(xy 154.994602 -299.251009) (xy 154.994602 -299.198991) (xy 155.002739 -299.147613) (xy 155.018812 -299.098141)
			(xy 155.042426 -299.051792) (xy 155.073 -299.009707) (xy 155.10978 -298.972923) (xy 155.151861 -298.942345)
			(xy 155.198208 -298.918726) (xy 155.247678 -298.902647) (xy 155.299055 -298.894505) (xy 155.325064 -298.893992)
			(xy 156.275024 -298.893992) (xy 156.301026 -298.894596) (xy 156.35239 -298.902735) (xy 156.401848 -298.918808)
			(xy 156.448184 -298.94242) (xy 156.490255 -298.972989) (xy 156.527026 -299.009763) (xy 156.557593 -299.051837)
			(xy 156.581201 -299.098174) (xy 156.597271 -299.147633) (xy 156.605406 -299.198998) (xy 156.605406 -299.251002)
			(xy 156.605404 -299.251014) (xy 268.243976 -299.251014) (xy 268.243976 -299.198986) (xy 268.252115 -299.147599)
			(xy 268.268193 -299.098118) (xy 268.291814 -299.051761) (xy 268.322396 -299.009671) (xy 268.359186 -298.972883)
			(xy 268.401279 -298.942303) (xy 268.447637 -298.918685) (xy 268.497119 -298.90261) (xy 268.548506 -298.894474)
			(xy 268.57452 -298.893992) (xy 269.52448 -298.893992) (xy 269.550487 -298.894566) (xy 269.60186 -298.9027)
			(xy 269.651328 -298.91877) (xy 269.697673 -298.942382) (xy 269.739754 -298.972953) (xy 269.776534 -299.009731)
			(xy 269.807108 -299.05181) (xy 269.830722 -299.098153) (xy 269.846796 -299.147621) (xy 269.854933 -299.198993)
			(xy 269.854933 -299.251007) (xy 269.854932 -299.251013) (xy 271.094376 -299.251013) (xy 271.094376 -299.198987)
			(xy 271.102514 -299.147601) (xy 271.118592 -299.098121) (xy 271.142212 -299.051765) (xy 271.172792 -299.009675)
			(xy 271.209581 -298.972887) (xy 271.251672 -298.942307) (xy 271.298028 -298.918689) (xy 271.347509 -298.902613)
			(xy 271.398895 -298.894475) (xy 271.424908 -298.893992) (xy 272.374868 -298.893992) (xy 272.400875 -298.894565)
			(xy 272.45225 -298.902697) (xy 272.50172 -298.918767) (xy 272.548067 -298.942378) (xy 272.590149 -298.972949)
			(xy 272.626931 -299.009727) (xy 272.657506 -299.051806) (xy 272.681121 -299.09815) (xy 272.697195 -299.147619)
			(xy 272.705333 -299.198993) (xy 272.705333 -299.251007) (xy 272.705332 -299.251014) (xy 384.344076 -299.251014)
			(xy 384.344076 -299.198986) (xy 384.352215 -299.147599) (xy 384.368293 -299.098118) (xy 384.391913 -299.051762)
			(xy 384.422495 -299.009672) (xy 384.459285 -298.972884) (xy 384.501377 -298.942304) (xy 384.547735 -298.918686)
			(xy 384.597217 -298.902611) (xy 384.648604 -298.894474) (xy 384.674618 -298.893992) (xy 385.624578 -298.893992)
			(xy 385.650585 -298.894566) (xy 385.701958 -298.902699) (xy 385.751427 -298.91877) (xy 385.797772 -298.942381)
			(xy 385.839853 -298.972952) (xy 385.876634 -299.00973) (xy 385.907207 -299.051809) (xy 385.930822 -299.098153)
			(xy 385.946896 -299.14762) (xy 385.955033 -299.198993) (xy 385.955033 -299.251007) (xy 385.946896 -299.30238)
			(xy 385.930822 -299.351847) (xy 385.907207 -299.398191) (xy 385.876634 -299.44027) (xy 385.839853 -299.477048)
			(xy 385.797772 -299.507619) (xy 385.751427 -299.53123) (xy 385.701958 -299.547301) (xy 385.650585 -299.555434)
			(xy 385.624578 -299.555916) (xy 384.674618 -299.555916) (xy 384.648604 -299.555526) (xy 384.597217 -299.547389)
			(xy 384.547735 -299.531314) (xy 384.501377 -299.507696) (xy 384.459285 -299.477116) (xy 384.422495 -299.440328)
			(xy 384.391913 -299.398238) (xy 384.368293 -299.351882) (xy 384.352215 -299.302401) (xy 384.344076 -299.251014)
			(xy 272.705332 -299.251014) (xy 272.697195 -299.302381) (xy 272.681121 -299.35185) (xy 272.657506 -299.398194)
			(xy 272.626931 -299.440273) (xy 272.590149 -299.477051) (xy 272.548067 -299.507622) (xy 272.50172 -299.531233)
			(xy 272.45225 -299.547303) (xy 272.400875 -299.555435) (xy 272.374868 -299.555916) (xy 271.424908 -299.555916)
			(xy 271.398895 -299.555525) (xy 271.347509 -299.547387) (xy 271.298028 -299.531311) (xy 271.251672 -299.507693)
			(xy 271.209581 -299.477113) (xy 271.172792 -299.440325) (xy 271.142212 -299.398235) (xy 271.118592 -299.351879)
			(xy 271.102514 -299.302399) (xy 271.094376 -299.251013) (xy 269.854932 -299.251013) (xy 269.846796 -299.302379)
			(xy 269.830722 -299.351847) (xy 269.807108 -299.39819) (xy 269.776534 -299.440269) (xy 269.739754 -299.477047)
			(xy 269.697673 -299.507618) (xy 269.651328 -299.53123) (xy 269.60186 -299.5473) (xy 269.550487 -299.555434)
			(xy 269.52448 -299.555916) (xy 268.57452 -299.555916) (xy 268.548506 -299.555526) (xy 268.497119 -299.54739)
			(xy 268.447637 -299.531315) (xy 268.401279 -299.507697) (xy 268.359186 -299.477117) (xy 268.322396 -299.440329)
			(xy 268.291814 -299.398239) (xy 268.268193 -299.351882) (xy 268.252115 -299.302401) (xy 268.243976 -299.251014)
			(xy 156.605404 -299.251014) (xy 156.597271 -299.302367) (xy 156.581201 -299.351826) (xy 156.557593 -299.398163)
			(xy 156.527026 -299.440237) (xy 156.490255 -299.477011) (xy 156.448184 -299.50758) (xy 156.401848 -299.531192)
			(xy 156.35239 -299.547265) (xy 156.301026 -299.555404) (xy 156.275024 -299.555916) (xy 155.325064 -299.555916)
			(xy 155.299055 -299.555495) (xy 155.247678 -299.547353) (xy 155.198208 -299.531274) (xy 155.151861 -299.507655)
			(xy 155.10978 -299.477077) (xy 155.073 -299.440293) (xy 155.042426 -299.398208) (xy 155.018812 -299.351859)
			(xy 155.002739 -299.302387) (xy 154.994602 -299.251009) (xy 153.755005 -299.251009) (xy 153.746871 -299.302365)
			(xy 153.730803 -299.351823) (xy 153.707195 -299.39816) (xy 153.67663 -299.440233) (xy 153.63986 -299.477007)
			(xy 153.59779 -299.507576) (xy 153.551457 -299.531189) (xy 153.502 -299.547263) (xy 153.450638 -299.555403)
			(xy 153.424636 -299.555916) (xy 152.474676 -299.555916) (xy 152.448666 -299.555496) (xy 152.397288 -299.547355)
			(xy 152.347816 -299.531278) (xy 152.301468 -299.507659) (xy 152.259385 -299.477081) (xy 152.222603 -299.440297)
			(xy 152.192028 -299.398212) (xy 152.168413 -299.351862) (xy 152.152339 -299.302388) (xy 152.144202 -299.25101)
			(xy 37.654905 -299.25101) (xy 37.646771 -299.302365) (xy 37.630703 -299.351823) (xy 37.607095 -299.398159)
			(xy 37.576531 -299.440232) (xy 37.539761 -299.477006) (xy 37.497691 -299.507575) (xy 37.451358 -299.531188)
			(xy 37.401902 -299.547263) (xy 37.35054 -299.555403) (xy 37.324538 -299.555916) (xy 36.374578 -299.555916)
			(xy 36.348568 -299.555496) (xy 36.29719 -299.547356) (xy 36.247718 -299.531278) (xy 36.201369 -299.50766)
			(xy 36.159286 -299.477082) (xy 36.122504 -299.440297) (xy 36.091929 -299.398212) (xy 36.068313 -299.351862)
			(xy 36.052239 -299.302389) (xy 36.044102 -299.25101) (xy 0.508 -299.25101) (xy 0.508 -301.599854)
			(xy 38.444182 -301.599854) (xy 38.448142 -301.5508) (xy 38.459919 -301.503016) (xy 38.47921 -301.45774)
			(xy 38.505513 -301.416144) (xy 38.538148 -301.379307) (xy 38.576269 -301.348182) (xy 38.61889 -301.323575)
			(xy 38.664906 -301.306123) (xy 38.713125 -301.296279) (xy 38.7623 -301.294298) (xy 38.811155 -301.30023)
			(xy 38.858426 -301.313922) (xy 38.902888 -301.33502) (xy 38.943391 -301.362976) (xy 38.978884 -301.397068)
			(xy 39.008449 -301.436412) (xy 39.03132 -301.479989) (xy 39.046904 -301.52667) (xy 39.054799 -301.575247)
			(xy 39.055294 -301.599854) (xy 39.394142 -301.599854) (xy 39.398102 -301.5508) (xy 39.409879 -301.503016)
			(xy 39.42917 -301.45774) (xy 39.455473 -301.416144) (xy 39.488108 -301.379307) (xy 39.526229 -301.348182)
			(xy 39.56885 -301.323575) (xy 39.614866 -301.306123) (xy 39.663085 -301.296279) (xy 39.71226 -301.294298)
			(xy 39.761115 -301.30023) (xy 39.808386 -301.313922) (xy 39.852848 -301.33502) (xy 39.893351 -301.362976)
			(xy 39.928844 -301.397068) (xy 39.958409 -301.436412) (xy 39.98128 -301.479989) (xy 39.996864 -301.52667)
			(xy 40.004759 -301.575247) (xy 40.005254 -301.599854) (xy 41.294062 -301.599854) (xy 41.298022 -301.5508)
			(xy 41.309799 -301.503016) (xy 41.32909 -301.45774) (xy 41.355393 -301.416144) (xy 41.388028 -301.379307)
			(xy 41.426149 -301.348182) (xy 41.46877 -301.323575) (xy 41.514786 -301.306123) (xy 41.563005 -301.296279)
			(xy 41.61218 -301.294298) (xy 41.661035 -301.30023) (xy 41.708306 -301.313922) (xy 41.752768 -301.33502)
			(xy 41.793271 -301.362976) (xy 41.828764 -301.397068) (xy 41.858329 -301.436412) (xy 41.8812 -301.479989)
			(xy 41.896784 -301.52667) (xy 41.904679 -301.575247) (xy 41.905174 -301.599854) (xy 42.244022 -301.599854)
			(xy 42.247982 -301.5508) (xy 42.259759 -301.503016) (xy 42.27905 -301.45774) (xy 42.305353 -301.416144)
			(xy 42.337988 -301.379307) (xy 42.376109 -301.348182) (xy 42.41873 -301.323575) (xy 42.464746 -301.306123)
			(xy 42.512965 -301.296279) (xy 42.56214 -301.294298) (xy 42.610995 -301.30023) (xy 42.658266 -301.313922)
			(xy 42.702728 -301.33502) (xy 42.743231 -301.362976) (xy 42.778724 -301.397068) (xy 42.808289 -301.436412)
			(xy 42.83116 -301.479989) (xy 42.846744 -301.52667) (xy 42.854639 -301.575247) (xy 42.855134 -301.599854)
			(xy 154.54428 -301.599854) (xy 154.54824 -301.5508) (xy 154.560017 -301.503016) (xy 154.579308 -301.45774)
			(xy 154.605611 -301.416144) (xy 154.638246 -301.379307) (xy 154.676367 -301.348182) (xy 154.718988 -301.323575)
			(xy 154.765004 -301.306123) (xy 154.813223 -301.296279) (xy 154.862398 -301.294298) (xy 154.911253 -301.30023)
			(xy 154.958524 -301.313922) (xy 155.002986 -301.33502) (xy 155.043489 -301.362976) (xy 155.078982 -301.397068)
			(xy 155.108547 -301.436412) (xy 155.131418 -301.479989) (xy 155.147002 -301.52667) (xy 155.154897 -301.575247)
			(xy 155.155392 -301.599854) (xy 155.49424 -301.599854) (xy 155.4982 -301.5508) (xy 155.509977 -301.503016)
			(xy 155.529268 -301.45774) (xy 155.555571 -301.416144) (xy 155.588206 -301.379307) (xy 155.626327 -301.348182)
			(xy 155.668948 -301.323575) (xy 155.714964 -301.306123) (xy 155.763183 -301.296279) (xy 155.812358 -301.294298)
			(xy 155.861213 -301.30023) (xy 155.908484 -301.313922) (xy 155.952946 -301.33502) (xy 155.993449 -301.362976)
			(xy 156.028942 -301.397068) (xy 156.058507 -301.436412) (xy 156.081378 -301.479989) (xy 156.096962 -301.52667)
			(xy 156.104857 -301.575247) (xy 156.105352 -301.599854) (xy 157.39416 -301.599854) (xy 157.39812 -301.5508)
			(xy 157.409897 -301.503016) (xy 157.429188 -301.45774) (xy 157.455491 -301.416144) (xy 157.488126 -301.379307)
			(xy 157.526247 -301.348182) (xy 157.568868 -301.323575) (xy 157.614884 -301.306123) (xy 157.663103 -301.296279)
			(xy 157.712278 -301.294298) (xy 157.761133 -301.30023) (xy 157.808404 -301.313922) (xy 157.852866 -301.33502)
			(xy 157.893369 -301.362976) (xy 157.928862 -301.397068) (xy 157.958427 -301.436412) (xy 157.981298 -301.479989)
			(xy 157.996882 -301.52667) (xy 158.004777 -301.575247) (xy 158.005272 -301.599854) (xy 158.34412 -301.599854)
			(xy 158.34808 -301.5508) (xy 158.359857 -301.503016) (xy 158.379148 -301.45774) (xy 158.405451 -301.416144)
			(xy 158.438086 -301.379307) (xy 158.476207 -301.348182) (xy 158.518828 -301.323575) (xy 158.564844 -301.306123)
			(xy 158.613063 -301.296279) (xy 158.662238 -301.294298) (xy 158.711093 -301.30023) (xy 158.758364 -301.313922)
			(xy 158.802826 -301.33502) (xy 158.843329 -301.362976) (xy 158.878822 -301.397068) (xy 158.908387 -301.436412)
			(xy 158.931258 -301.479989) (xy 158.946842 -301.52667) (xy 158.954737 -301.575247) (xy 158.955232 -301.599854)
			(xy 270.644124 -301.599854) (xy 270.648084 -301.5508) (xy 270.659861 -301.503016) (xy 270.679152 -301.45774)
			(xy 270.705455 -301.416144) (xy 270.73809 -301.379307) (xy 270.776211 -301.348182) (xy 270.818832 -301.323575)
			(xy 270.864848 -301.306123) (xy 270.913067 -301.296279) (xy 270.962242 -301.294298) (xy 271.011097 -301.30023)
			(xy 271.058368 -301.313922) (xy 271.10283 -301.33502) (xy 271.143333 -301.362976) (xy 271.178826 -301.397068)
			(xy 271.208391 -301.436412) (xy 271.231262 -301.479989) (xy 271.246846 -301.52667) (xy 271.254741 -301.575247)
			(xy 271.255236 -301.599854) (xy 271.594084 -301.599854) (xy 271.598044 -301.5508) (xy 271.609821 -301.503016)
			(xy 271.629112 -301.45774) (xy 271.655415 -301.416144) (xy 271.68805 -301.379307) (xy 271.726171 -301.348182)
			(xy 271.768792 -301.323575) (xy 271.814808 -301.306123) (xy 271.863027 -301.296279) (xy 271.912202 -301.294298)
			(xy 271.961057 -301.30023) (xy 272.008328 -301.313922) (xy 272.05279 -301.33502) (xy 272.093293 -301.362976)
			(xy 272.128786 -301.397068) (xy 272.158351 -301.436412) (xy 272.181222 -301.479989) (xy 272.196806 -301.52667)
			(xy 272.204701 -301.575247) (xy 272.205196 -301.599854) (xy 273.494004 -301.599854) (xy 273.497964 -301.5508)
			(xy 273.509741 -301.503016) (xy 273.529032 -301.45774) (xy 273.555335 -301.416144) (xy 273.58797 -301.379307)
			(xy 273.626091 -301.348182) (xy 273.668712 -301.323575) (xy 273.714728 -301.306123) (xy 273.762947 -301.296279)
			(xy 273.812122 -301.294298) (xy 273.860977 -301.30023) (xy 273.908248 -301.313922) (xy 273.95271 -301.33502)
			(xy 273.993213 -301.362976) (xy 274.028706 -301.397068) (xy 274.058271 -301.436412) (xy 274.081142 -301.479989)
			(xy 274.096726 -301.52667) (xy 274.104621 -301.575247) (xy 274.105116 -301.599854) (xy 274.443964 -301.599854)
			(xy 274.447924 -301.5508) (xy 274.459701 -301.503016) (xy 274.478992 -301.45774) (xy 274.505295 -301.416144)
			(xy 274.53793 -301.379307) (xy 274.576051 -301.348182) (xy 274.618672 -301.323575) (xy 274.664688 -301.306123)
			(xy 274.712907 -301.296279) (xy 274.762082 -301.294298) (xy 274.810937 -301.30023) (xy 274.858208 -301.313922)
			(xy 274.90267 -301.33502) (xy 274.943173 -301.362976) (xy 274.978666 -301.397068) (xy 275.008231 -301.436412)
			(xy 275.031102 -301.479989) (xy 275.046686 -301.52667) (xy 275.054581 -301.575247) (xy 275.055076 -301.599854)
			(xy 386.744222 -301.599854) (xy 386.748182 -301.5508) (xy 386.759959 -301.503016) (xy 386.77925 -301.45774)
			(xy 386.805553 -301.416144) (xy 386.838188 -301.379307) (xy 386.876309 -301.348182) (xy 386.91893 -301.323575)
			(xy 386.964946 -301.306123) (xy 387.013165 -301.296279) (xy 387.06234 -301.294298) (xy 387.111195 -301.30023)
			(xy 387.158466 -301.313922) (xy 387.202928 -301.33502) (xy 387.243431 -301.362976) (xy 387.278924 -301.397068)
			(xy 387.308489 -301.436412) (xy 387.33136 -301.479989) (xy 387.346944 -301.52667) (xy 387.354839 -301.575247)
			(xy 387.355334 -301.599854) (xy 387.694182 -301.599854) (xy 387.698142 -301.5508) (xy 387.709919 -301.503016)
			(xy 387.72921 -301.45774) (xy 387.755513 -301.416144) (xy 387.788148 -301.379307) (xy 387.826269 -301.348182)
			(xy 387.86889 -301.323575) (xy 387.914906 -301.306123) (xy 387.963125 -301.296279) (xy 388.0123 -301.294298)
			(xy 388.061155 -301.30023) (xy 388.108426 -301.313922) (xy 388.152888 -301.33502) (xy 388.193391 -301.362976)
			(xy 388.228884 -301.397068) (xy 388.258449 -301.436412) (xy 388.28132 -301.479989) (xy 388.296904 -301.52667)
			(xy 388.304799 -301.575247) (xy 388.305294 -301.599854) (xy 389.594102 -301.599854) (xy 389.598062 -301.5508)
			(xy 389.609839 -301.503016) (xy 389.62913 -301.45774) (xy 389.655433 -301.416144) (xy 389.688068 -301.379307)
			(xy 389.726189 -301.348182) (xy 389.76881 -301.323575) (xy 389.814826 -301.306123) (xy 389.863045 -301.296279)
			(xy 389.91222 -301.294298) (xy 389.961075 -301.30023) (xy 390.008346 -301.313922) (xy 390.052808 -301.33502)
			(xy 390.093311 -301.362976) (xy 390.128804 -301.397068) (xy 390.158369 -301.436412) (xy 390.18124 -301.479989)
			(xy 390.196824 -301.52667) (xy 390.204719 -301.575247) (xy 390.205214 -301.599854) (xy 390.544062 -301.599854)
			(xy 390.548022 -301.5508) (xy 390.559799 -301.503016) (xy 390.57909 -301.45774) (xy 390.605393 -301.416144)
			(xy 390.638028 -301.379307) (xy 390.676149 -301.348182) (xy 390.71877 -301.323575) (xy 390.764786 -301.306123)
			(xy 390.813005 -301.296279) (xy 390.86218 -301.294298) (xy 390.911035 -301.30023) (xy 390.958306 -301.313922)
			(xy 391.002768 -301.33502) (xy 391.043271 -301.362976) (xy 391.078764 -301.397068) (xy 391.108329 -301.436412)
			(xy 391.1312 -301.479989) (xy 391.146784 -301.52667) (xy 391.154679 -301.575247) (xy 391.155174 -301.599854)
			(xy 391.154679 -301.624461) (xy 391.146784 -301.673038) (xy 391.1312 -301.719719) (xy 391.108329 -301.763296)
			(xy 391.078764 -301.80264) (xy 391.043271 -301.836732) (xy 391.002768 -301.864688) (xy 390.958306 -301.885786)
			(xy 390.911035 -301.899478) (xy 390.86218 -301.90541) (xy 390.813005 -301.903429) (xy 390.764786 -301.893585)
			(xy 390.71877 -301.876133) (xy 390.676149 -301.851526) (xy 390.638028 -301.820401) (xy 390.605393 -301.783564)
			(xy 390.57909 -301.741968) (xy 390.559799 -301.696692) (xy 390.548022 -301.648908) (xy 390.544062 -301.599854)
			(xy 390.205214 -301.599854) (xy 390.204719 -301.624461) (xy 390.196824 -301.673038) (xy 390.18124 -301.719719)
			(xy 390.158369 -301.763296) (xy 390.128804 -301.80264) (xy 390.093311 -301.836732) (xy 390.052808 -301.864688)
			(xy 390.008346 -301.885786) (xy 389.961075 -301.899478) (xy 389.91222 -301.90541) (xy 389.863045 -301.903429)
			(xy 389.814826 -301.893585) (xy 389.76881 -301.876133) (xy 389.726189 -301.851526) (xy 389.688068 -301.820401)
			(xy 389.655433 -301.783564) (xy 389.62913 -301.741968) (xy 389.609839 -301.696692) (xy 389.598062 -301.648908)
			(xy 389.594102 -301.599854) (xy 388.305294 -301.599854) (xy 388.304799 -301.624461) (xy 388.296904 -301.673038)
			(xy 388.28132 -301.719719) (xy 388.258449 -301.763296) (xy 388.228884 -301.80264) (xy 388.193391 -301.836732)
			(xy 388.152888 -301.864688) (xy 388.108426 -301.885786) (xy 388.061155 -301.899478) (xy 388.0123 -301.90541)
			(xy 387.963125 -301.903429) (xy 387.914906 -301.893585) (xy 387.86889 -301.876133) (xy 387.826269 -301.851526)
			(xy 387.788148 -301.820401) (xy 387.755513 -301.783564) (xy 387.72921 -301.741968) (xy 387.709919 -301.696692)
			(xy 387.698142 -301.648908) (xy 387.694182 -301.599854) (xy 387.355334 -301.599854) (xy 387.354839 -301.624461)
			(xy 387.346944 -301.673038) (xy 387.33136 -301.719719) (xy 387.308489 -301.763296) (xy 387.278924 -301.80264)
			(xy 387.243431 -301.836732) (xy 387.202928 -301.864688) (xy 387.158466 -301.885786) (xy 387.111195 -301.899478)
			(xy 387.06234 -301.90541) (xy 387.013165 -301.903429) (xy 386.964946 -301.893585) (xy 386.91893 -301.876133)
			(xy 386.876309 -301.851526) (xy 386.838188 -301.820401) (xy 386.805553 -301.783564) (xy 386.77925 -301.741968)
			(xy 386.759959 -301.696692) (xy 386.748182 -301.648908) (xy 386.744222 -301.599854) (xy 275.055076 -301.599854)
			(xy 275.054581 -301.624461) (xy 275.046686 -301.673038) (xy 275.031102 -301.719719) (xy 275.008231 -301.763296)
			(xy 274.978666 -301.80264) (xy 274.943173 -301.836732) (xy 274.90267 -301.864688) (xy 274.858208 -301.885786)
			(xy 274.810937 -301.899478) (xy 274.762082 -301.90541) (xy 274.712907 -301.903429) (xy 274.664688 -301.893585)
			(xy 274.618672 -301.876133) (xy 274.576051 -301.851526) (xy 274.53793 -301.820401) (xy 274.505295 -301.783564)
			(xy 274.478992 -301.741968) (xy 274.459701 -301.696692) (xy 274.447924 -301.648908) (xy 274.443964 -301.599854)
			(xy 274.105116 -301.599854) (xy 274.104621 -301.624461) (xy 274.096726 -301.673038) (xy 274.081142 -301.719719)
			(xy 274.058271 -301.763296) (xy 274.028706 -301.80264) (xy 273.993213 -301.836732) (xy 273.95271 -301.864688)
			(xy 273.908248 -301.885786) (xy 273.860977 -301.899478) (xy 273.812122 -301.90541) (xy 273.762947 -301.903429)
			(xy 273.714728 -301.893585) (xy 273.668712 -301.876133) (xy 273.626091 -301.851526) (xy 273.58797 -301.820401)
			(xy 273.555335 -301.783564) (xy 273.529032 -301.741968) (xy 273.509741 -301.696692) (xy 273.497964 -301.648908)
			(xy 273.494004 -301.599854) (xy 272.205196 -301.599854) (xy 272.204701 -301.624461) (xy 272.196806 -301.673038)
			(xy 272.181222 -301.719719) (xy 272.158351 -301.763296) (xy 272.128786 -301.80264) (xy 272.093293 -301.836732)
			(xy 272.05279 -301.864688) (xy 272.008328 -301.885786) (xy 271.961057 -301.899478) (xy 271.912202 -301.90541)
			(xy 271.863027 -301.903429) (xy 271.814808 -301.893585) (xy 271.768792 -301.876133) (xy 271.726171 -301.851526)
			(xy 271.68805 -301.820401) (xy 271.655415 -301.783564) (xy 271.629112 -301.741968) (xy 271.609821 -301.696692)
			(xy 271.598044 -301.648908) (xy 271.594084 -301.599854) (xy 271.255236 -301.599854) (xy 271.254741 -301.624461)
			(xy 271.246846 -301.673038) (xy 271.231262 -301.719719) (xy 271.208391 -301.763296) (xy 271.178826 -301.80264)
			(xy 271.143333 -301.836732) (xy 271.10283 -301.864688) (xy 271.058368 -301.885786) (xy 271.011097 -301.899478)
			(xy 270.962242 -301.90541) (xy 270.913067 -301.903429) (xy 270.864848 -301.893585) (xy 270.818832 -301.876133)
			(xy 270.776211 -301.851526) (xy 270.73809 -301.820401) (xy 270.705455 -301.783564) (xy 270.679152 -301.741968)
			(xy 270.659861 -301.696692) (xy 270.648084 -301.648908) (xy 270.644124 -301.599854) (xy 158.955232 -301.599854)
			(xy 158.954737 -301.624461) (xy 158.946842 -301.673038) (xy 158.931258 -301.719719) (xy 158.908387 -301.763296)
			(xy 158.878822 -301.80264) (xy 158.843329 -301.836732) (xy 158.802826 -301.864688) (xy 158.758364 -301.885786)
			(xy 158.711093 -301.899478) (xy 158.662238 -301.90541) (xy 158.613063 -301.903429) (xy 158.564844 -301.893585)
			(xy 158.518828 -301.876133) (xy 158.476207 -301.851526) (xy 158.438086 -301.820401) (xy 158.405451 -301.783564)
			(xy 158.379148 -301.741968) (xy 158.359857 -301.696692) (xy 158.34808 -301.648908) (xy 158.34412 -301.599854)
			(xy 158.005272 -301.599854) (xy 158.004777 -301.624461) (xy 157.996882 -301.673038) (xy 157.981298 -301.719719)
			(xy 157.958427 -301.763296) (xy 157.928862 -301.80264) (xy 157.893369 -301.836732) (xy 157.852866 -301.864688)
			(xy 157.808404 -301.885786) (xy 157.761133 -301.899478) (xy 157.712278 -301.90541) (xy 157.663103 -301.903429)
			(xy 157.614884 -301.893585) (xy 157.568868 -301.876133) (xy 157.526247 -301.851526) (xy 157.488126 -301.820401)
			(xy 157.455491 -301.783564) (xy 157.429188 -301.741968) (xy 157.409897 -301.696692) (xy 157.39812 -301.648908)
			(xy 157.39416 -301.599854) (xy 156.105352 -301.599854) (xy 156.104857 -301.624461) (xy 156.096962 -301.673038)
			(xy 156.081378 -301.719719) (xy 156.058507 -301.763296) (xy 156.028942 -301.80264) (xy 155.993449 -301.836732)
			(xy 155.952946 -301.864688) (xy 155.908484 -301.885786) (xy 155.861213 -301.899478) (xy 155.812358 -301.90541)
			(xy 155.763183 -301.903429) (xy 155.714964 -301.893585) (xy 155.668948 -301.876133) (xy 155.626327 -301.851526)
			(xy 155.588206 -301.820401) (xy 155.555571 -301.783564) (xy 155.529268 -301.741968) (xy 155.509977 -301.696692)
			(xy 155.4982 -301.648908) (xy 155.49424 -301.599854) (xy 155.155392 -301.599854) (xy 155.154897 -301.624461)
			(xy 155.147002 -301.673038) (xy 155.131418 -301.719719) (xy 155.108547 -301.763296) (xy 155.078982 -301.80264)
			(xy 155.043489 -301.836732) (xy 155.002986 -301.864688) (xy 154.958524 -301.885786) (xy 154.911253 -301.899478)
			(xy 154.862398 -301.90541) (xy 154.813223 -301.903429) (xy 154.765004 -301.893585) (xy 154.718988 -301.876133)
			(xy 154.676367 -301.851526) (xy 154.638246 -301.820401) (xy 154.605611 -301.783564) (xy 154.579308 -301.741968)
			(xy 154.560017 -301.696692) (xy 154.54824 -301.648908) (xy 154.54428 -301.599854) (xy 42.855134 -301.599854)
			(xy 42.854639 -301.624461) (xy 42.846744 -301.673038) (xy 42.83116 -301.719719) (xy 42.808289 -301.763296)
			(xy 42.778724 -301.80264) (xy 42.743231 -301.836732) (xy 42.702728 -301.864688) (xy 42.658266 -301.885786)
			(xy 42.610995 -301.899478) (xy 42.56214 -301.90541) (xy 42.512965 -301.903429) (xy 42.464746 -301.893585)
			(xy 42.41873 -301.876133) (xy 42.376109 -301.851526) (xy 42.337988 -301.820401) (xy 42.305353 -301.783564)
			(xy 42.27905 -301.741968) (xy 42.259759 -301.696692) (xy 42.247982 -301.648908) (xy 42.244022 -301.599854)
			(xy 41.905174 -301.599854) (xy 41.904679 -301.624461) (xy 41.896784 -301.673038) (xy 41.8812 -301.719719)
			(xy 41.858329 -301.763296) (xy 41.828764 -301.80264) (xy 41.793271 -301.836732) (xy 41.752768 -301.864688)
			(xy 41.708306 -301.885786) (xy 41.661035 -301.899478) (xy 41.61218 -301.90541) (xy 41.563005 -301.903429)
			(xy 41.514786 -301.893585) (xy 41.46877 -301.876133) (xy 41.426149 -301.851526) (xy 41.388028 -301.820401)
			(xy 41.355393 -301.783564) (xy 41.32909 -301.741968) (xy 41.309799 -301.696692) (xy 41.298022 -301.648908)
			(xy 41.294062 -301.599854) (xy 40.005254 -301.599854) (xy 40.004759 -301.624461) (xy 39.996864 -301.673038)
			(xy 39.98128 -301.719719) (xy 39.958409 -301.763296) (xy 39.928844 -301.80264) (xy 39.893351 -301.836732)
			(xy 39.852848 -301.864688) (xy 39.808386 -301.885786) (xy 39.761115 -301.899478) (xy 39.71226 -301.90541)
			(xy 39.663085 -301.903429) (xy 39.614866 -301.893585) (xy 39.56885 -301.876133) (xy 39.526229 -301.851526)
			(xy 39.488108 -301.820401) (xy 39.455473 -301.783564) (xy 39.42917 -301.741968) (xy 39.409879 -301.696692)
			(xy 39.398102 -301.648908) (xy 39.394142 -301.599854) (xy 39.055294 -301.599854) (xy 39.054799 -301.624461)
			(xy 39.046904 -301.673038) (xy 39.03132 -301.719719) (xy 39.008449 -301.763296) (xy 38.978884 -301.80264)
			(xy 38.943391 -301.836732) (xy 38.902888 -301.864688) (xy 38.858426 -301.885786) (xy 38.811155 -301.899478)
			(xy 38.7623 -301.90541) (xy 38.713125 -301.903429) (xy 38.664906 -301.893585) (xy 38.61889 -301.876133)
			(xy 38.576269 -301.851526) (xy 38.538148 -301.820401) (xy 38.505513 -301.783564) (xy 38.47921 -301.741968)
			(xy 38.459919 -301.696692) (xy 38.448142 -301.648908) (xy 38.444182 -301.599854) (xy 0.508 -301.599854)
			(xy 0.508 -302.549814) (xy 36.544008 -302.549814) (xy 36.547968 -302.50076) (xy 36.559745 -302.452976)
			(xy 36.579036 -302.4077) (xy 36.605339 -302.366104) (xy 36.637974 -302.329267) (xy 36.676095 -302.298142)
			(xy 36.718716 -302.273535) (xy 36.764732 -302.256083) (xy 36.812951 -302.246239) (xy 36.862126 -302.244258)
			(xy 36.910981 -302.25019) (xy 36.958252 -302.263882) (xy 37.002714 -302.28498) (xy 37.043217 -302.312936)
			(xy 37.07871 -302.347028) (xy 37.108275 -302.386372) (xy 37.131146 -302.429949) (xy 37.14673 -302.47663)
			(xy 37.154625 -302.525207) (xy 37.15512 -302.549814) (xy 37.493968 -302.549814) (xy 37.497928 -302.50076)
			(xy 37.509705 -302.452976) (xy 37.528996 -302.4077) (xy 37.555299 -302.366104) (xy 37.587934 -302.329267)
			(xy 37.626055 -302.298142) (xy 37.668676 -302.273535) (xy 37.714692 -302.256083) (xy 37.762911 -302.246239)
			(xy 37.812086 -302.244258) (xy 37.860941 -302.25019) (xy 37.908212 -302.263882) (xy 37.952674 -302.28498)
			(xy 37.993177 -302.312936) (xy 38.02867 -302.347028) (xy 38.058235 -302.386372) (xy 38.081106 -302.429949)
			(xy 38.09669 -302.47663) (xy 38.104585 -302.525207) (xy 38.10508 -302.549814) (xy 43.193982 -302.549814)
			(xy 43.197942 -302.50076) (xy 43.209719 -302.452976) (xy 43.22901 -302.4077) (xy 43.255313 -302.366104)
			(xy 43.287948 -302.329267) (xy 43.326069 -302.298142) (xy 43.36869 -302.273535) (xy 43.414706 -302.256083)
			(xy 43.462925 -302.246239) (xy 43.5121 -302.244258) (xy 43.560955 -302.25019) (xy 43.608226 -302.263882)
			(xy 43.652688 -302.28498) (xy 43.693191 -302.312936) (xy 43.728684 -302.347028) (xy 43.758249 -302.386372)
			(xy 43.78112 -302.429949) (xy 43.796704 -302.47663) (xy 43.804599 -302.525207) (xy 43.805094 -302.549814)
			(xy 44.143942 -302.549814) (xy 44.147902 -302.50076) (xy 44.159679 -302.452976) (xy 44.17897 -302.4077)
			(xy 44.205273 -302.366104) (xy 44.237908 -302.329267) (xy 44.276029 -302.298142) (xy 44.31865 -302.273535)
			(xy 44.364666 -302.256083) (xy 44.412885 -302.246239) (xy 44.46206 -302.244258) (xy 44.510915 -302.25019)
			(xy 44.558186 -302.263882) (xy 44.602648 -302.28498) (xy 44.643151 -302.312936) (xy 44.678644 -302.347028)
			(xy 44.708209 -302.386372) (xy 44.73108 -302.429949) (xy 44.746664 -302.47663) (xy 44.754559 -302.525207)
			(xy 44.755054 -302.549814) (xy 152.644106 -302.549814) (xy 152.648066 -302.50076) (xy 152.659843 -302.452976)
			(xy 152.679134 -302.4077) (xy 152.705437 -302.366104) (xy 152.738072 -302.329267) (xy 152.776193 -302.298142)
			(xy 152.818814 -302.273535) (xy 152.86483 -302.256083) (xy 152.913049 -302.246239) (xy 152.962224 -302.244258)
			(xy 153.011079 -302.25019) (xy 153.05835 -302.263882) (xy 153.102812 -302.28498) (xy 153.143315 -302.312936)
			(xy 153.178808 -302.347028) (xy 153.208373 -302.386372) (xy 153.231244 -302.429949) (xy 153.246828 -302.47663)
			(xy 153.254723 -302.525207) (xy 153.255218 -302.549814) (xy 153.594066 -302.549814) (xy 153.598026 -302.50076)
			(xy 153.609803 -302.452976) (xy 153.629094 -302.4077) (xy 153.655397 -302.366104) (xy 153.688032 -302.329267)
			(xy 153.726153 -302.298142) (xy 153.768774 -302.273535) (xy 153.81479 -302.256083) (xy 153.863009 -302.246239)
			(xy 153.912184 -302.244258) (xy 153.961039 -302.25019) (xy 154.00831 -302.263882) (xy 154.052772 -302.28498)
			(xy 154.093275 -302.312936) (xy 154.128768 -302.347028) (xy 154.158333 -302.386372) (xy 154.181204 -302.429949)
			(xy 154.196788 -302.47663) (xy 154.204683 -302.525207) (xy 154.205178 -302.549814) (xy 159.29408 -302.549814)
			(xy 159.29804 -302.50076) (xy 159.309817 -302.452976) (xy 159.329108 -302.4077) (xy 159.355411 -302.366104)
			(xy 159.388046 -302.329267) (xy 159.426167 -302.298142) (xy 159.468788 -302.273535) (xy 159.514804 -302.256083)
			(xy 159.563023 -302.246239) (xy 159.612198 -302.244258) (xy 159.661053 -302.25019) (xy 159.708324 -302.263882)
			(xy 159.752786 -302.28498) (xy 159.793289 -302.312936) (xy 159.828782 -302.347028) (xy 159.858347 -302.386372)
			(xy 159.881218 -302.429949) (xy 159.896802 -302.47663) (xy 159.904697 -302.525207) (xy 159.905192 -302.549814)
			(xy 160.24404 -302.549814) (xy 160.248 -302.50076) (xy 160.259777 -302.452976) (xy 160.279068 -302.4077)
			(xy 160.305371 -302.366104) (xy 160.338006 -302.329267) (xy 160.376127 -302.298142) (xy 160.418748 -302.273535)
			(xy 160.464764 -302.256083) (xy 160.512983 -302.246239) (xy 160.562158 -302.244258) (xy 160.611013 -302.25019)
			(xy 160.658284 -302.263882) (xy 160.702746 -302.28498) (xy 160.743249 -302.312936) (xy 160.778742 -302.347028)
			(xy 160.808307 -302.386372) (xy 160.831178 -302.429949) (xy 160.846762 -302.47663) (xy 160.854657 -302.525207)
			(xy 160.855152 -302.549814) (xy 268.74395 -302.549814) (xy 268.74791 -302.50076) (xy 268.759687 -302.452976)
			(xy 268.778978 -302.4077) (xy 268.805281 -302.366104) (xy 268.837916 -302.329267) (xy 268.876037 -302.298142)
			(xy 268.918658 -302.273535) (xy 268.964674 -302.256083) (xy 269.012893 -302.246239) (xy 269.062068 -302.244258)
			(xy 269.110923 -302.25019) (xy 269.158194 -302.263882) (xy 269.202656 -302.28498) (xy 269.243159 -302.312936)
			(xy 269.278652 -302.347028) (xy 269.308217 -302.386372) (xy 269.331088 -302.429949) (xy 269.346672 -302.47663)
			(xy 269.354567 -302.525207) (xy 269.355062 -302.549814) (xy 269.69391 -302.549814) (xy 269.69787 -302.50076)
			(xy 269.709647 -302.452976) (xy 269.728938 -302.4077) (xy 269.755241 -302.366104) (xy 269.787876 -302.329267)
			(xy 269.825997 -302.298142) (xy 269.868618 -302.273535) (xy 269.914634 -302.256083) (xy 269.962853 -302.246239)
			(xy 270.012028 -302.244258) (xy 270.060883 -302.25019) (xy 270.108154 -302.263882) (xy 270.152616 -302.28498)
			(xy 270.193119 -302.312936) (xy 270.228612 -302.347028) (xy 270.258177 -302.386372) (xy 270.281048 -302.429949)
			(xy 270.296632 -302.47663) (xy 270.304527 -302.525207) (xy 270.305022 -302.549814) (xy 275.393924 -302.549814)
			(xy 275.397884 -302.50076) (xy 275.409661 -302.452976) (xy 275.428952 -302.4077) (xy 275.455255 -302.366104)
			(xy 275.48789 -302.329267) (xy 275.526011 -302.298142) (xy 275.568632 -302.273535) (xy 275.614648 -302.256083)
			(xy 275.662867 -302.246239) (xy 275.712042 -302.244258) (xy 275.760897 -302.25019) (xy 275.808168 -302.263882)
			(xy 275.85263 -302.28498) (xy 275.893133 -302.312936) (xy 275.928626 -302.347028) (xy 275.958191 -302.386372)
			(xy 275.981062 -302.429949) (xy 275.996646 -302.47663) (xy 276.004541 -302.525207) (xy 276.005036 -302.549814)
			(xy 276.343884 -302.549814) (xy 276.347844 -302.50076) (xy 276.359621 -302.452976) (xy 276.378912 -302.4077)
			(xy 276.405215 -302.366104) (xy 276.43785 -302.329267) (xy 276.475971 -302.298142) (xy 276.518592 -302.273535)
			(xy 276.564608 -302.256083) (xy 276.612827 -302.246239) (xy 276.662002 -302.244258) (xy 276.710857 -302.25019)
			(xy 276.758128 -302.263882) (xy 276.80259 -302.28498) (xy 276.843093 -302.312936) (xy 276.878586 -302.347028)
			(xy 276.908151 -302.386372) (xy 276.931022 -302.429949) (xy 276.946606 -302.47663) (xy 276.954501 -302.525207)
			(xy 276.954996 -302.549814) (xy 384.844048 -302.549814) (xy 384.848008 -302.50076) (xy 384.859785 -302.452976)
			(xy 384.879076 -302.4077) (xy 384.905379 -302.366104) (xy 384.938014 -302.329267) (xy 384.976135 -302.298142)
			(xy 385.018756 -302.273535) (xy 385.064772 -302.256083) (xy 385.112991 -302.246239) (xy 385.162166 -302.244258)
			(xy 385.211021 -302.25019) (xy 385.258292 -302.263882) (xy 385.302754 -302.28498) (xy 385.343257 -302.312936)
			(xy 385.37875 -302.347028) (xy 385.408315 -302.386372) (xy 385.431186 -302.429949) (xy 385.44677 -302.47663)
			(xy 385.454665 -302.525207) (xy 385.45516 -302.549814) (xy 385.794008 -302.549814) (xy 385.797968 -302.50076)
			(xy 385.809745 -302.452976) (xy 385.829036 -302.4077) (xy 385.855339 -302.366104) (xy 385.887974 -302.329267)
			(xy 385.926095 -302.298142) (xy 385.968716 -302.273535) (xy 386.014732 -302.256083) (xy 386.062951 -302.246239)
			(xy 386.112126 -302.244258) (xy 386.160981 -302.25019) (xy 386.208252 -302.263882) (xy 386.252714 -302.28498)
			(xy 386.293217 -302.312936) (xy 386.32871 -302.347028) (xy 386.358275 -302.386372) (xy 386.381146 -302.429949)
			(xy 386.39673 -302.47663) (xy 386.404625 -302.525207) (xy 386.40512 -302.549814) (xy 391.494022 -302.549814)
			(xy 391.497982 -302.50076) (xy 391.509759 -302.452976) (xy 391.52905 -302.4077) (xy 391.555353 -302.366104)
			(xy 391.587988 -302.329267) (xy 391.626109 -302.298142) (xy 391.66873 -302.273535) (xy 391.714746 -302.256083)
			(xy 391.762965 -302.246239) (xy 391.81214 -302.244258) (xy 391.860995 -302.25019) (xy 391.908266 -302.263882)
			(xy 391.952728 -302.28498) (xy 391.993231 -302.312936) (xy 392.028724 -302.347028) (xy 392.058289 -302.386372)
			(xy 392.08116 -302.429949) (xy 392.096744 -302.47663) (xy 392.104639 -302.525207) (xy 392.105134 -302.549814)
			(xy 392.443982 -302.549814) (xy 392.447942 -302.50076) (xy 392.459719 -302.452976) (xy 392.47901 -302.4077)
			(xy 392.505313 -302.366104) (xy 392.537948 -302.329267) (xy 392.576069 -302.298142) (xy 392.61869 -302.273535)
			(xy 392.664706 -302.256083) (xy 392.712925 -302.246239) (xy 392.7621 -302.244258) (xy 392.810955 -302.25019)
			(xy 392.858226 -302.263882) (xy 392.902688 -302.28498) (xy 392.943191 -302.312936) (xy 392.978684 -302.347028)
			(xy 393.008249 -302.386372) (xy 393.03112 -302.429949) (xy 393.046704 -302.47663) (xy 393.054599 -302.525207)
			(xy 393.055094 -302.549814) (xy 393.054599 -302.574421) (xy 393.046704 -302.622998) (xy 393.03112 -302.669679)
			(xy 393.008249 -302.713256) (xy 392.978684 -302.7526) (xy 392.943191 -302.786692) (xy 392.902688 -302.814648)
			(xy 392.858226 -302.835746) (xy 392.810955 -302.849438) (xy 392.7621 -302.85537) (xy 392.712925 -302.853389)
			(xy 392.664706 -302.843545) (xy 392.61869 -302.826093) (xy 392.576069 -302.801486) (xy 392.537948 -302.770361)
			(xy 392.505313 -302.733524) (xy 392.47901 -302.691928) (xy 392.459719 -302.646652) (xy 392.447942 -302.598868)
			(xy 392.443982 -302.549814) (xy 392.105134 -302.549814) (xy 392.104639 -302.574421) (xy 392.096744 -302.622998)
			(xy 392.08116 -302.669679) (xy 392.058289 -302.713256) (xy 392.028724 -302.7526) (xy 391.993231 -302.786692)
			(xy 391.952728 -302.814648) (xy 391.908266 -302.835746) (xy 391.860995 -302.849438) (xy 391.81214 -302.85537)
			(xy 391.762965 -302.853389) (xy 391.714746 -302.843545) (xy 391.66873 -302.826093) (xy 391.626109 -302.801486)
			(xy 391.587988 -302.770361) (xy 391.555353 -302.733524) (xy 391.52905 -302.691928) (xy 391.509759 -302.646652)
			(xy 391.497982 -302.598868) (xy 391.494022 -302.549814) (xy 386.40512 -302.549814) (xy 386.404625 -302.574421)
			(xy 386.39673 -302.622998) (xy 386.381146 -302.669679) (xy 386.358275 -302.713256) (xy 386.32871 -302.7526)
			(xy 386.293217 -302.786692) (xy 386.252714 -302.814648) (xy 386.208252 -302.835746) (xy 386.160981 -302.849438)
			(xy 386.112126 -302.85537) (xy 386.062951 -302.853389) (xy 386.014732 -302.843545) (xy 385.968716 -302.826093)
			(xy 385.926095 -302.801486) (xy 385.887974 -302.770361) (xy 385.855339 -302.733524) (xy 385.829036 -302.691928)
			(xy 385.809745 -302.646652) (xy 385.797968 -302.598868) (xy 385.794008 -302.549814) (xy 385.45516 -302.549814)
			(xy 385.454665 -302.574421) (xy 385.44677 -302.622998) (xy 385.431186 -302.669679) (xy 385.408315 -302.713256)
			(xy 385.37875 -302.7526) (xy 385.343257 -302.786692) (xy 385.302754 -302.814648) (xy 385.258292 -302.835746)
			(xy 385.211021 -302.849438) (xy 385.162166 -302.85537) (xy 385.112991 -302.853389) (xy 385.064772 -302.843545)
			(xy 385.018756 -302.826093) (xy 384.976135 -302.801486) (xy 384.938014 -302.770361) (xy 384.905379 -302.733524)
			(xy 384.879076 -302.691928) (xy 384.859785 -302.646652) (xy 384.848008 -302.598868) (xy 384.844048 -302.549814)
			(xy 276.954996 -302.549814) (xy 276.954501 -302.574421) (xy 276.946606 -302.622998) (xy 276.931022 -302.669679)
			(xy 276.908151 -302.713256) (xy 276.878586 -302.7526) (xy 276.843093 -302.786692) (xy 276.80259 -302.814648)
			(xy 276.758128 -302.835746) (xy 276.710857 -302.849438) (xy 276.662002 -302.85537) (xy 276.612827 -302.853389)
			(xy 276.564608 -302.843545) (xy 276.518592 -302.826093) (xy 276.475971 -302.801486) (xy 276.43785 -302.770361)
			(xy 276.405215 -302.733524) (xy 276.378912 -302.691928) (xy 276.359621 -302.646652) (xy 276.347844 -302.598868)
			(xy 276.343884 -302.549814) (xy 276.005036 -302.549814) (xy 276.004541 -302.574421) (xy 275.996646 -302.622998)
			(xy 275.981062 -302.669679) (xy 275.958191 -302.713256) (xy 275.928626 -302.7526) (xy 275.893133 -302.786692)
			(xy 275.85263 -302.814648) (xy 275.808168 -302.835746) (xy 275.760897 -302.849438) (xy 275.712042 -302.85537)
			(xy 275.662867 -302.853389) (xy 275.614648 -302.843545) (xy 275.568632 -302.826093) (xy 275.526011 -302.801486)
			(xy 275.48789 -302.770361) (xy 275.455255 -302.733524) (xy 275.428952 -302.691928) (xy 275.409661 -302.646652)
			(xy 275.397884 -302.598868) (xy 275.393924 -302.549814) (xy 270.305022 -302.549814) (xy 270.304527 -302.574421)
			(xy 270.296632 -302.622998) (xy 270.281048 -302.669679) (xy 270.258177 -302.713256) (xy 270.228612 -302.7526)
			(xy 270.193119 -302.786692) (xy 270.152616 -302.814648) (xy 270.108154 -302.835746) (xy 270.060883 -302.849438)
			(xy 270.012028 -302.85537) (xy 269.962853 -302.853389) (xy 269.914634 -302.843545) (xy 269.868618 -302.826093)
			(xy 269.825997 -302.801486) (xy 269.787876 -302.770361) (xy 269.755241 -302.733524) (xy 269.728938 -302.691928)
			(xy 269.709647 -302.646652) (xy 269.69787 -302.598868) (xy 269.69391 -302.549814) (xy 269.355062 -302.549814)
			(xy 269.354567 -302.574421) (xy 269.346672 -302.622998) (xy 269.331088 -302.669679) (xy 269.308217 -302.713256)
			(xy 269.278652 -302.7526) (xy 269.243159 -302.786692) (xy 269.202656 -302.814648) (xy 269.158194 -302.835746)
			(xy 269.110923 -302.849438) (xy 269.062068 -302.85537) (xy 269.012893 -302.853389) (xy 268.964674 -302.843545)
			(xy 268.918658 -302.826093) (xy 268.876037 -302.801486) (xy 268.837916 -302.770361) (xy 268.805281 -302.733524)
			(xy 268.778978 -302.691928) (xy 268.759687 -302.646652) (xy 268.74791 -302.598868) (xy 268.74395 -302.549814)
			(xy 160.855152 -302.549814) (xy 160.854657 -302.574421) (xy 160.846762 -302.622998) (xy 160.831178 -302.669679)
			(xy 160.808307 -302.713256) (xy 160.778742 -302.7526) (xy 160.743249 -302.786692) (xy 160.702746 -302.814648)
			(xy 160.658284 -302.835746) (xy 160.611013 -302.849438) (xy 160.562158 -302.85537) (xy 160.512983 -302.853389)
			(xy 160.464764 -302.843545) (xy 160.418748 -302.826093) (xy 160.376127 -302.801486) (xy 160.338006 -302.770361)
			(xy 160.305371 -302.733524) (xy 160.279068 -302.691928) (xy 160.259777 -302.646652) (xy 160.248 -302.598868)
			(xy 160.24404 -302.549814) (xy 159.905192 -302.549814) (xy 159.904697 -302.574421) (xy 159.896802 -302.622998)
			(xy 159.881218 -302.669679) (xy 159.858347 -302.713256) (xy 159.828782 -302.7526) (xy 159.793289 -302.786692)
			(xy 159.752786 -302.814648) (xy 159.708324 -302.835746) (xy 159.661053 -302.849438) (xy 159.612198 -302.85537)
			(xy 159.563023 -302.853389) (xy 159.514804 -302.843545) (xy 159.468788 -302.826093) (xy 159.426167 -302.801486)
			(xy 159.388046 -302.770361) (xy 159.355411 -302.733524) (xy 159.329108 -302.691928) (xy 159.309817 -302.646652)
			(xy 159.29804 -302.598868) (xy 159.29408 -302.549814) (xy 154.205178 -302.549814) (xy 154.204683 -302.574421)
			(xy 154.196788 -302.622998) (xy 154.181204 -302.669679) (xy 154.158333 -302.713256) (xy 154.128768 -302.7526)
			(xy 154.093275 -302.786692) (xy 154.052772 -302.814648) (xy 154.00831 -302.835746) (xy 153.961039 -302.849438)
			(xy 153.912184 -302.85537) (xy 153.863009 -302.853389) (xy 153.81479 -302.843545) (xy 153.768774 -302.826093)
			(xy 153.726153 -302.801486) (xy 153.688032 -302.770361) (xy 153.655397 -302.733524) (xy 153.629094 -302.691928)
			(xy 153.609803 -302.646652) (xy 153.598026 -302.598868) (xy 153.594066 -302.549814) (xy 153.255218 -302.549814)
			(xy 153.254723 -302.574421) (xy 153.246828 -302.622998) (xy 153.231244 -302.669679) (xy 153.208373 -302.713256)
			(xy 153.178808 -302.7526) (xy 153.143315 -302.786692) (xy 153.102812 -302.814648) (xy 153.05835 -302.835746)
			(xy 153.011079 -302.849438) (xy 152.962224 -302.85537) (xy 152.913049 -302.853389) (xy 152.86483 -302.843545)
			(xy 152.818814 -302.826093) (xy 152.776193 -302.801486) (xy 152.738072 -302.770361) (xy 152.705437 -302.733524)
			(xy 152.679134 -302.691928) (xy 152.659843 -302.646652) (xy 152.648066 -302.598868) (xy 152.644106 -302.549814)
			(xy 44.755054 -302.549814) (xy 44.754559 -302.574421) (xy 44.746664 -302.622998) (xy 44.73108 -302.669679)
			(xy 44.708209 -302.713256) (xy 44.678644 -302.7526) (xy 44.643151 -302.786692) (xy 44.602648 -302.814648)
			(xy 44.558186 -302.835746) (xy 44.510915 -302.849438) (xy 44.46206 -302.85537) (xy 44.412885 -302.853389)
			(xy 44.364666 -302.843545) (xy 44.31865 -302.826093) (xy 44.276029 -302.801486) (xy 44.237908 -302.770361)
			(xy 44.205273 -302.733524) (xy 44.17897 -302.691928) (xy 44.159679 -302.646652) (xy 44.147902 -302.598868)
			(xy 44.143942 -302.549814) (xy 43.805094 -302.549814) (xy 43.804599 -302.574421) (xy 43.796704 -302.622998)
			(xy 43.78112 -302.669679) (xy 43.758249 -302.713256) (xy 43.728684 -302.7526) (xy 43.693191 -302.786692)
			(xy 43.652688 -302.814648) (xy 43.608226 -302.835746) (xy 43.560955 -302.849438) (xy 43.5121 -302.85537)
			(xy 43.462925 -302.853389) (xy 43.414706 -302.843545) (xy 43.36869 -302.826093) (xy 43.326069 -302.801486)
			(xy 43.287948 -302.770361) (xy 43.255313 -302.733524) (xy 43.22901 -302.691928) (xy 43.209719 -302.646652)
			(xy 43.197942 -302.598868) (xy 43.193982 -302.549814) (xy 38.10508 -302.549814) (xy 38.104585 -302.574421)
			(xy 38.09669 -302.622998) (xy 38.081106 -302.669679) (xy 38.058235 -302.713256) (xy 38.02867 -302.7526)
			(xy 37.993177 -302.786692) (xy 37.952674 -302.814648) (xy 37.908212 -302.835746) (xy 37.860941 -302.849438)
			(xy 37.812086 -302.85537) (xy 37.762911 -302.853389) (xy 37.714692 -302.843545) (xy 37.668676 -302.826093)
			(xy 37.626055 -302.801486) (xy 37.587934 -302.770361) (xy 37.555299 -302.733524) (xy 37.528996 -302.691928)
			(xy 37.509705 -302.646652) (xy 37.497928 -302.598868) (xy 37.493968 -302.549814) (xy 37.15512 -302.549814)
			(xy 37.154625 -302.574421) (xy 37.14673 -302.622998) (xy 37.131146 -302.669679) (xy 37.108275 -302.713256)
			(xy 37.07871 -302.7526) (xy 37.043217 -302.786692) (xy 37.002714 -302.814648) (xy 36.958252 -302.835746)
			(xy 36.910981 -302.849438) (xy 36.862126 -302.85537) (xy 36.812951 -302.853389) (xy 36.764732 -302.843545)
			(xy 36.718716 -302.826093) (xy 36.676095 -302.801486) (xy 36.637974 -302.770361) (xy 36.605339 -302.733524)
			(xy 36.579036 -302.691928) (xy 36.559745 -302.646652) (xy 36.547968 -302.598868) (xy 36.544008 -302.549814)
			(xy 0.508 -302.549814) (xy 0.508 -303.499774) (xy 38.444182 -303.499774) (xy 38.448142 -303.45072)
			(xy 38.459919 -303.402936) (xy 38.47921 -303.35766) (xy 38.505513 -303.316064) (xy 38.538148 -303.279227)
			(xy 38.576269 -303.248102) (xy 38.61889 -303.223495) (xy 38.664906 -303.206043) (xy 38.713125 -303.196199)
			(xy 38.7623 -303.194218) (xy 38.811155 -303.20015) (xy 38.858426 -303.213842) (xy 38.902888 -303.23494)
			(xy 38.943391 -303.262896) (xy 38.978884 -303.296988) (xy 39.008449 -303.336332) (xy 39.03132 -303.379909)
			(xy 39.046904 -303.42659) (xy 39.054799 -303.475167) (xy 39.055294 -303.499774) (xy 39.394142 -303.499774)
			(xy 39.398102 -303.45072) (xy 39.409879 -303.402936) (xy 39.42917 -303.35766) (xy 39.455473 -303.316064)
			(xy 39.488108 -303.279227) (xy 39.526229 -303.248102) (xy 39.56885 -303.223495) (xy 39.614866 -303.206043)
			(xy 39.663085 -303.196199) (xy 39.71226 -303.194218) (xy 39.761115 -303.20015) (xy 39.808386 -303.213842)
			(xy 39.852848 -303.23494) (xy 39.893351 -303.262896) (xy 39.928844 -303.296988) (xy 39.958409 -303.336332)
			(xy 39.98128 -303.379909) (xy 39.996864 -303.42659) (xy 40.004759 -303.475167) (xy 40.005254 -303.499774)
			(xy 41.294062 -303.499774) (xy 41.298022 -303.45072) (xy 41.309799 -303.402936) (xy 41.32909 -303.35766)
			(xy 41.355393 -303.316064) (xy 41.388028 -303.279227) (xy 41.426149 -303.248102) (xy 41.46877 -303.223495)
			(xy 41.514786 -303.206043) (xy 41.563005 -303.196199) (xy 41.61218 -303.194218) (xy 41.661035 -303.20015)
			(xy 41.708306 -303.213842) (xy 41.752768 -303.23494) (xy 41.793271 -303.262896) (xy 41.828764 -303.296988)
			(xy 41.858329 -303.336332) (xy 41.8812 -303.379909) (xy 41.896784 -303.42659) (xy 41.904679 -303.475167)
			(xy 41.905174 -303.499774) (xy 42.244022 -303.499774) (xy 42.247982 -303.45072) (xy 42.259759 -303.402936)
			(xy 42.27905 -303.35766) (xy 42.305353 -303.316064) (xy 42.337988 -303.279227) (xy 42.376109 -303.248102)
			(xy 42.41873 -303.223495) (xy 42.464746 -303.206043) (xy 42.512965 -303.196199) (xy 42.56214 -303.194218)
			(xy 42.610995 -303.20015) (xy 42.658266 -303.213842) (xy 42.702728 -303.23494) (xy 42.743231 -303.262896)
			(xy 42.778724 -303.296988) (xy 42.808289 -303.336332) (xy 42.83116 -303.379909) (xy 42.846744 -303.42659)
			(xy 42.854639 -303.475167) (xy 42.855134 -303.499774) (xy 154.54428 -303.499774) (xy 154.54824 -303.45072)
			(xy 154.560017 -303.402936) (xy 154.579308 -303.35766) (xy 154.605611 -303.316064) (xy 154.638246 -303.279227)
			(xy 154.676367 -303.248102) (xy 154.718988 -303.223495) (xy 154.765004 -303.206043) (xy 154.813223 -303.196199)
			(xy 154.862398 -303.194218) (xy 154.911253 -303.20015) (xy 154.958524 -303.213842) (xy 155.002986 -303.23494)
			(xy 155.043489 -303.262896) (xy 155.078982 -303.296988) (xy 155.108547 -303.336332) (xy 155.131418 -303.379909)
			(xy 155.147002 -303.42659) (xy 155.154897 -303.475167) (xy 155.155392 -303.499774) (xy 155.49424 -303.499774)
			(xy 155.4982 -303.45072) (xy 155.509977 -303.402936) (xy 155.529268 -303.35766) (xy 155.555571 -303.316064)
			(xy 155.588206 -303.279227) (xy 155.626327 -303.248102) (xy 155.668948 -303.223495) (xy 155.714964 -303.206043)
			(xy 155.763183 -303.196199) (xy 155.812358 -303.194218) (xy 155.861213 -303.20015) (xy 155.908484 -303.213842)
			(xy 155.952946 -303.23494) (xy 155.993449 -303.262896) (xy 156.028942 -303.296988) (xy 156.058507 -303.336332)
			(xy 156.081378 -303.379909) (xy 156.096962 -303.42659) (xy 156.104857 -303.475167) (xy 156.105352 -303.499774)
			(xy 157.39416 -303.499774) (xy 157.39812 -303.45072) (xy 157.409897 -303.402936) (xy 157.429188 -303.35766)
			(xy 157.455491 -303.316064) (xy 157.488126 -303.279227) (xy 157.526247 -303.248102) (xy 157.568868 -303.223495)
			(xy 157.614884 -303.206043) (xy 157.663103 -303.196199) (xy 157.712278 -303.194218) (xy 157.761133 -303.20015)
			(xy 157.808404 -303.213842) (xy 157.852866 -303.23494) (xy 157.893369 -303.262896) (xy 157.928862 -303.296988)
			(xy 157.958427 -303.336332) (xy 157.981298 -303.379909) (xy 157.996882 -303.42659) (xy 158.004777 -303.475167)
			(xy 158.005272 -303.499774) (xy 158.34412 -303.499774) (xy 158.34808 -303.45072) (xy 158.359857 -303.402936)
			(xy 158.379148 -303.35766) (xy 158.405451 -303.316064) (xy 158.438086 -303.279227) (xy 158.476207 -303.248102)
			(xy 158.518828 -303.223495) (xy 158.564844 -303.206043) (xy 158.613063 -303.196199) (xy 158.662238 -303.194218)
			(xy 158.711093 -303.20015) (xy 158.758364 -303.213842) (xy 158.802826 -303.23494) (xy 158.843329 -303.262896)
			(xy 158.878822 -303.296988) (xy 158.908387 -303.336332) (xy 158.931258 -303.379909) (xy 158.946842 -303.42659)
			(xy 158.954737 -303.475167) (xy 158.955232 -303.499774) (xy 270.644124 -303.499774) (xy 270.648084 -303.45072)
			(xy 270.659861 -303.402936) (xy 270.679152 -303.35766) (xy 270.705455 -303.316064) (xy 270.73809 -303.279227)
			(xy 270.776211 -303.248102) (xy 270.818832 -303.223495) (xy 270.864848 -303.206043) (xy 270.913067 -303.196199)
			(xy 270.962242 -303.194218) (xy 271.011097 -303.20015) (xy 271.058368 -303.213842) (xy 271.10283 -303.23494)
			(xy 271.143333 -303.262896) (xy 271.178826 -303.296988) (xy 271.208391 -303.336332) (xy 271.231262 -303.379909)
			(xy 271.246846 -303.42659) (xy 271.254741 -303.475167) (xy 271.255236 -303.499774) (xy 271.594084 -303.499774)
			(xy 271.598044 -303.45072) (xy 271.609821 -303.402936) (xy 271.629112 -303.35766) (xy 271.655415 -303.316064)
			(xy 271.68805 -303.279227) (xy 271.726171 -303.248102) (xy 271.768792 -303.223495) (xy 271.814808 -303.206043)
			(xy 271.863027 -303.196199) (xy 271.912202 -303.194218) (xy 271.961057 -303.20015) (xy 272.008328 -303.213842)
			(xy 272.05279 -303.23494) (xy 272.093293 -303.262896) (xy 272.128786 -303.296988) (xy 272.158351 -303.336332)
			(xy 272.181222 -303.379909) (xy 272.196806 -303.42659) (xy 272.204701 -303.475167) (xy 272.205196 -303.499774)
			(xy 273.494004 -303.499774) (xy 273.497964 -303.45072) (xy 273.509741 -303.402936) (xy 273.529032 -303.35766)
			(xy 273.555335 -303.316064) (xy 273.58797 -303.279227) (xy 273.626091 -303.248102) (xy 273.668712 -303.223495)
			(xy 273.714728 -303.206043) (xy 273.762947 -303.196199) (xy 273.812122 -303.194218) (xy 273.860977 -303.20015)
			(xy 273.908248 -303.213842) (xy 273.95271 -303.23494) (xy 273.993213 -303.262896) (xy 274.028706 -303.296988)
			(xy 274.058271 -303.336332) (xy 274.081142 -303.379909) (xy 274.096726 -303.42659) (xy 274.104621 -303.475167)
			(xy 274.105116 -303.499774) (xy 274.443964 -303.499774) (xy 274.447924 -303.45072) (xy 274.459701 -303.402936)
			(xy 274.478992 -303.35766) (xy 274.505295 -303.316064) (xy 274.53793 -303.279227) (xy 274.576051 -303.248102)
			(xy 274.618672 -303.223495) (xy 274.664688 -303.206043) (xy 274.712907 -303.196199) (xy 274.762082 -303.194218)
			(xy 274.810937 -303.20015) (xy 274.858208 -303.213842) (xy 274.90267 -303.23494) (xy 274.943173 -303.262896)
			(xy 274.978666 -303.296988) (xy 275.008231 -303.336332) (xy 275.031102 -303.379909) (xy 275.046686 -303.42659)
			(xy 275.054581 -303.475167) (xy 275.055076 -303.499774) (xy 386.744222 -303.499774) (xy 386.748182 -303.45072)
			(xy 386.759959 -303.402936) (xy 386.77925 -303.35766) (xy 386.805553 -303.316064) (xy 386.838188 -303.279227)
			(xy 386.876309 -303.248102) (xy 386.91893 -303.223495) (xy 386.964946 -303.206043) (xy 387.013165 -303.196199)
			(xy 387.06234 -303.194218) (xy 387.111195 -303.20015) (xy 387.158466 -303.213842) (xy 387.202928 -303.23494)
			(xy 387.243431 -303.262896) (xy 387.278924 -303.296988) (xy 387.308489 -303.336332) (xy 387.33136 -303.379909)
			(xy 387.346944 -303.42659) (xy 387.354839 -303.475167) (xy 387.355334 -303.499774) (xy 387.694182 -303.499774)
			(xy 387.698142 -303.45072) (xy 387.709919 -303.402936) (xy 387.72921 -303.35766) (xy 387.755513 -303.316064)
			(xy 387.788148 -303.279227) (xy 387.826269 -303.248102) (xy 387.86889 -303.223495) (xy 387.914906 -303.206043)
			(xy 387.963125 -303.196199) (xy 388.0123 -303.194218) (xy 388.061155 -303.20015) (xy 388.108426 -303.213842)
			(xy 388.152888 -303.23494) (xy 388.193391 -303.262896) (xy 388.228884 -303.296988) (xy 388.258449 -303.336332)
			(xy 388.28132 -303.379909) (xy 388.296904 -303.42659) (xy 388.304799 -303.475167) (xy 388.305294 -303.499774)
			(xy 389.594102 -303.499774) (xy 389.598062 -303.45072) (xy 389.609839 -303.402936) (xy 389.62913 -303.35766)
			(xy 389.655433 -303.316064) (xy 389.688068 -303.279227) (xy 389.726189 -303.248102) (xy 389.76881 -303.223495)
			(xy 389.814826 -303.206043) (xy 389.863045 -303.196199) (xy 389.91222 -303.194218) (xy 389.961075 -303.20015)
			(xy 390.008346 -303.213842) (xy 390.052808 -303.23494) (xy 390.093311 -303.262896) (xy 390.128804 -303.296988)
			(xy 390.158369 -303.336332) (xy 390.18124 -303.379909) (xy 390.196824 -303.42659) (xy 390.204719 -303.475167)
			(xy 390.205214 -303.499774) (xy 390.544062 -303.499774) (xy 390.548022 -303.45072) (xy 390.559799 -303.402936)
			(xy 390.57909 -303.35766) (xy 390.605393 -303.316064) (xy 390.638028 -303.279227) (xy 390.676149 -303.248102)
			(xy 390.71877 -303.223495) (xy 390.764786 -303.206043) (xy 390.813005 -303.196199) (xy 390.86218 -303.194218)
			(xy 390.911035 -303.20015) (xy 390.958306 -303.213842) (xy 391.002768 -303.23494) (xy 391.043271 -303.262896)
			(xy 391.078764 -303.296988) (xy 391.108329 -303.336332) (xy 391.1312 -303.379909) (xy 391.146784 -303.42659)
			(xy 391.154679 -303.475167) (xy 391.155174 -303.499774) (xy 391.154679 -303.524381) (xy 391.146784 -303.572958)
			(xy 391.1312 -303.619639) (xy 391.108329 -303.663216) (xy 391.078764 -303.70256) (xy 391.043271 -303.736652)
			(xy 391.002768 -303.764608) (xy 390.958306 -303.785706) (xy 390.911035 -303.799398) (xy 390.86218 -303.80533)
			(xy 390.813005 -303.803349) (xy 390.764786 -303.793505) (xy 390.71877 -303.776053) (xy 390.676149 -303.751446)
			(xy 390.638028 -303.720321) (xy 390.605393 -303.683484) (xy 390.57909 -303.641888) (xy 390.559799 -303.596612)
			(xy 390.548022 -303.548828) (xy 390.544062 -303.499774) (xy 390.205214 -303.499774) (xy 390.204719 -303.524381)
			(xy 390.196824 -303.572958) (xy 390.18124 -303.619639) (xy 390.158369 -303.663216) (xy 390.128804 -303.70256)
			(xy 390.093311 -303.736652) (xy 390.052808 -303.764608) (xy 390.008346 -303.785706) (xy 389.961075 -303.799398)
			(xy 389.91222 -303.80533) (xy 389.863045 -303.803349) (xy 389.814826 -303.793505) (xy 389.76881 -303.776053)
			(xy 389.726189 -303.751446) (xy 389.688068 -303.720321) (xy 389.655433 -303.683484) (xy 389.62913 -303.641888)
			(xy 389.609839 -303.596612) (xy 389.598062 -303.548828) (xy 389.594102 -303.499774) (xy 388.305294 -303.499774)
			(xy 388.304799 -303.524381) (xy 388.296904 -303.572958) (xy 388.28132 -303.619639) (xy 388.258449 -303.663216)
			(xy 388.228884 -303.70256) (xy 388.193391 -303.736652) (xy 388.152888 -303.764608) (xy 388.108426 -303.785706)
			(xy 388.061155 -303.799398) (xy 388.0123 -303.80533) (xy 387.963125 -303.803349) (xy 387.914906 -303.793505)
			(xy 387.86889 -303.776053) (xy 387.826269 -303.751446) (xy 387.788148 -303.720321) (xy 387.755513 -303.683484)
			(xy 387.72921 -303.641888) (xy 387.709919 -303.596612) (xy 387.698142 -303.548828) (xy 387.694182 -303.499774)
			(xy 387.355334 -303.499774) (xy 387.354839 -303.524381) (xy 387.346944 -303.572958) (xy 387.33136 -303.619639)
			(xy 387.308489 -303.663216) (xy 387.278924 -303.70256) (xy 387.243431 -303.736652) (xy 387.202928 -303.764608)
			(xy 387.158466 -303.785706) (xy 387.111195 -303.799398) (xy 387.06234 -303.80533) (xy 387.013165 -303.803349)
			(xy 386.964946 -303.793505) (xy 386.91893 -303.776053) (xy 386.876309 -303.751446) (xy 386.838188 -303.720321)
			(xy 386.805553 -303.683484) (xy 386.77925 -303.641888) (xy 386.759959 -303.596612) (xy 386.748182 -303.548828)
			(xy 386.744222 -303.499774) (xy 275.055076 -303.499774) (xy 275.054581 -303.524381) (xy 275.046686 -303.572958)
			(xy 275.031102 -303.619639) (xy 275.008231 -303.663216) (xy 274.978666 -303.70256) (xy 274.943173 -303.736652)
			(xy 274.90267 -303.764608) (xy 274.858208 -303.785706) (xy 274.810937 -303.799398) (xy 274.762082 -303.80533)
			(xy 274.712907 -303.803349) (xy 274.664688 -303.793505) (xy 274.618672 -303.776053) (xy 274.576051 -303.751446)
			(xy 274.53793 -303.720321) (xy 274.505295 -303.683484) (xy 274.478992 -303.641888) (xy 274.459701 -303.596612)
			(xy 274.447924 -303.548828) (xy 274.443964 -303.499774) (xy 274.105116 -303.499774) (xy 274.104621 -303.524381)
			(xy 274.096726 -303.572958) (xy 274.081142 -303.619639) (xy 274.058271 -303.663216) (xy 274.028706 -303.70256)
			(xy 273.993213 -303.736652) (xy 273.95271 -303.764608) (xy 273.908248 -303.785706) (xy 273.860977 -303.799398)
			(xy 273.812122 -303.80533) (xy 273.762947 -303.803349) (xy 273.714728 -303.793505) (xy 273.668712 -303.776053)
			(xy 273.626091 -303.751446) (xy 273.58797 -303.720321) (xy 273.555335 -303.683484) (xy 273.529032 -303.641888)
			(xy 273.509741 -303.596612) (xy 273.497964 -303.548828) (xy 273.494004 -303.499774) (xy 272.205196 -303.499774)
			(xy 272.204701 -303.524381) (xy 272.196806 -303.572958) (xy 272.181222 -303.619639) (xy 272.158351 -303.663216)
			(xy 272.128786 -303.70256) (xy 272.093293 -303.736652) (xy 272.05279 -303.764608) (xy 272.008328 -303.785706)
			(xy 271.961057 -303.799398) (xy 271.912202 -303.80533) (xy 271.863027 -303.803349) (xy 271.814808 -303.793505)
			(xy 271.768792 -303.776053) (xy 271.726171 -303.751446) (xy 271.68805 -303.720321) (xy 271.655415 -303.683484)
			(xy 271.629112 -303.641888) (xy 271.609821 -303.596612) (xy 271.598044 -303.548828) (xy 271.594084 -303.499774)
			(xy 271.255236 -303.499774) (xy 271.254741 -303.524381) (xy 271.246846 -303.572958) (xy 271.231262 -303.619639)
			(xy 271.208391 -303.663216) (xy 271.178826 -303.70256) (xy 271.143333 -303.736652) (xy 271.10283 -303.764608)
			(xy 271.058368 -303.785706) (xy 271.011097 -303.799398) (xy 270.962242 -303.80533) (xy 270.913067 -303.803349)
			(xy 270.864848 -303.793505) (xy 270.818832 -303.776053) (xy 270.776211 -303.751446) (xy 270.73809 -303.720321)
			(xy 270.705455 -303.683484) (xy 270.679152 -303.641888) (xy 270.659861 -303.596612) (xy 270.648084 -303.548828)
			(xy 270.644124 -303.499774) (xy 158.955232 -303.499774) (xy 158.954737 -303.524381) (xy 158.946842 -303.572958)
			(xy 158.931258 -303.619639) (xy 158.908387 -303.663216) (xy 158.878822 -303.70256) (xy 158.843329 -303.736652)
			(xy 158.802826 -303.764608) (xy 158.758364 -303.785706) (xy 158.711093 -303.799398) (xy 158.662238 -303.80533)
			(xy 158.613063 -303.803349) (xy 158.564844 -303.793505) (xy 158.518828 -303.776053) (xy 158.476207 -303.751446)
			(xy 158.438086 -303.720321) (xy 158.405451 -303.683484) (xy 158.379148 -303.641888) (xy 158.359857 -303.596612)
			(xy 158.34808 -303.548828) (xy 158.34412 -303.499774) (xy 158.005272 -303.499774) (xy 158.004777 -303.524381)
			(xy 157.996882 -303.572958) (xy 157.981298 -303.619639) (xy 157.958427 -303.663216) (xy 157.928862 -303.70256)
			(xy 157.893369 -303.736652) (xy 157.852866 -303.764608) (xy 157.808404 -303.785706) (xy 157.761133 -303.799398)
			(xy 157.712278 -303.80533) (xy 157.663103 -303.803349) (xy 157.614884 -303.793505) (xy 157.568868 -303.776053)
			(xy 157.526247 -303.751446) (xy 157.488126 -303.720321) (xy 157.455491 -303.683484) (xy 157.429188 -303.641888)
			(xy 157.409897 -303.596612) (xy 157.39812 -303.548828) (xy 157.39416 -303.499774) (xy 156.105352 -303.499774)
			(xy 156.104857 -303.524381) (xy 156.096962 -303.572958) (xy 156.081378 -303.619639) (xy 156.058507 -303.663216)
			(xy 156.028942 -303.70256) (xy 155.993449 -303.736652) (xy 155.952946 -303.764608) (xy 155.908484 -303.785706)
			(xy 155.861213 -303.799398) (xy 155.812358 -303.80533) (xy 155.763183 -303.803349) (xy 155.714964 -303.793505)
			(xy 155.668948 -303.776053) (xy 155.626327 -303.751446) (xy 155.588206 -303.720321) (xy 155.555571 -303.683484)
			(xy 155.529268 -303.641888) (xy 155.509977 -303.596612) (xy 155.4982 -303.548828) (xy 155.49424 -303.499774)
			(xy 155.155392 -303.499774) (xy 155.154897 -303.524381) (xy 155.147002 -303.572958) (xy 155.131418 -303.619639)
			(xy 155.108547 -303.663216) (xy 155.078982 -303.70256) (xy 155.043489 -303.736652) (xy 155.002986 -303.764608)
			(xy 154.958524 -303.785706) (xy 154.911253 -303.799398) (xy 154.862398 -303.80533) (xy 154.813223 -303.803349)
			(xy 154.765004 -303.793505) (xy 154.718988 -303.776053) (xy 154.676367 -303.751446) (xy 154.638246 -303.720321)
			(xy 154.605611 -303.683484) (xy 154.579308 -303.641888) (xy 154.560017 -303.596612) (xy 154.54824 -303.548828)
			(xy 154.54428 -303.499774) (xy 42.855134 -303.499774) (xy 42.854639 -303.524381) (xy 42.846744 -303.572958)
			(xy 42.83116 -303.619639) (xy 42.808289 -303.663216) (xy 42.778724 -303.70256) (xy 42.743231 -303.736652)
			(xy 42.702728 -303.764608) (xy 42.658266 -303.785706) (xy 42.610995 -303.799398) (xy 42.56214 -303.80533)
			(xy 42.512965 -303.803349) (xy 42.464746 -303.793505) (xy 42.41873 -303.776053) (xy 42.376109 -303.751446)
			(xy 42.337988 -303.720321) (xy 42.305353 -303.683484) (xy 42.27905 -303.641888) (xy 42.259759 -303.596612)
			(xy 42.247982 -303.548828) (xy 42.244022 -303.499774) (xy 41.905174 -303.499774) (xy 41.904679 -303.524381)
			(xy 41.896784 -303.572958) (xy 41.8812 -303.619639) (xy 41.858329 -303.663216) (xy 41.828764 -303.70256)
			(xy 41.793271 -303.736652) (xy 41.752768 -303.764608) (xy 41.708306 -303.785706) (xy 41.661035 -303.799398)
			(xy 41.61218 -303.80533) (xy 41.563005 -303.803349) (xy 41.514786 -303.793505) (xy 41.46877 -303.776053)
			(xy 41.426149 -303.751446) (xy 41.388028 -303.720321) (xy 41.355393 -303.683484) (xy 41.32909 -303.641888)
			(xy 41.309799 -303.596612) (xy 41.298022 -303.548828) (xy 41.294062 -303.499774) (xy 40.005254 -303.499774)
			(xy 40.004759 -303.524381) (xy 39.996864 -303.572958) (xy 39.98128 -303.619639) (xy 39.958409 -303.663216)
			(xy 39.928844 -303.70256) (xy 39.893351 -303.736652) (xy 39.852848 -303.764608) (xy 39.808386 -303.785706)
			(xy 39.761115 -303.799398) (xy 39.71226 -303.80533) (xy 39.663085 -303.803349) (xy 39.614866 -303.793505)
			(xy 39.56885 -303.776053) (xy 39.526229 -303.751446) (xy 39.488108 -303.720321) (xy 39.455473 -303.683484)
			(xy 39.42917 -303.641888) (xy 39.409879 -303.596612) (xy 39.398102 -303.548828) (xy 39.394142 -303.499774)
			(xy 39.055294 -303.499774) (xy 39.054799 -303.524381) (xy 39.046904 -303.572958) (xy 39.03132 -303.619639)
			(xy 39.008449 -303.663216) (xy 38.978884 -303.70256) (xy 38.943391 -303.736652) (xy 38.902888 -303.764608)
			(xy 38.858426 -303.785706) (xy 38.811155 -303.799398) (xy 38.7623 -303.80533) (xy 38.713125 -303.803349)
			(xy 38.664906 -303.793505) (xy 38.61889 -303.776053) (xy 38.576269 -303.751446) (xy 38.538148 -303.720321)
			(xy 38.505513 -303.683484) (xy 38.47921 -303.641888) (xy 38.459919 -303.596612) (xy 38.448142 -303.548828)
			(xy 38.444182 -303.499774) (xy 0.508 -303.499774) (xy 0.508 -304.449734) (xy 36.544008 -304.449734)
			(xy 36.547968 -304.40068) (xy 36.559745 -304.352896) (xy 36.579036 -304.30762) (xy 36.605339 -304.266024)
			(xy 36.637974 -304.229187) (xy 36.676095 -304.198062) (xy 36.718716 -304.173455) (xy 36.764732 -304.156003)
			(xy 36.812951 -304.146159) (xy 36.862126 -304.144178) (xy 36.910981 -304.15011) (xy 36.958252 -304.163802)
			(xy 37.002714 -304.1849) (xy 37.043217 -304.212856) (xy 37.07871 -304.246948) (xy 37.108275 -304.286292)
			(xy 37.131146 -304.329869) (xy 37.14673 -304.37655) (xy 37.154625 -304.425127) (xy 37.15512 -304.449734)
			(xy 37.493968 -304.449734) (xy 37.497928 -304.40068) (xy 37.509705 -304.352896) (xy 37.528996 -304.30762)
			(xy 37.555299 -304.266024) (xy 37.587934 -304.229187) (xy 37.626055 -304.198062) (xy 37.668676 -304.173455)
			(xy 37.714692 -304.156003) (xy 37.762911 -304.146159) (xy 37.812086 -304.144178) (xy 37.860941 -304.15011)
			(xy 37.908212 -304.163802) (xy 37.952674 -304.1849) (xy 37.993177 -304.212856) (xy 38.02867 -304.246948)
			(xy 38.058235 -304.286292) (xy 38.081106 -304.329869) (xy 38.09669 -304.37655) (xy 38.104585 -304.425127)
			(xy 38.10508 -304.449734) (xy 43.193982 -304.449734) (xy 43.197942 -304.40068) (xy 43.209719 -304.352896)
			(xy 43.22901 -304.30762) (xy 43.255313 -304.266024) (xy 43.287948 -304.229187) (xy 43.326069 -304.198062)
			(xy 43.36869 -304.173455) (xy 43.414706 -304.156003) (xy 43.462925 -304.146159) (xy 43.5121 -304.144178)
			(xy 43.560955 -304.15011) (xy 43.608226 -304.163802) (xy 43.652688 -304.1849) (xy 43.693191 -304.212856)
			(xy 43.728684 -304.246948) (xy 43.758249 -304.286292) (xy 43.78112 -304.329869) (xy 43.796704 -304.37655)
			(xy 43.804599 -304.425127) (xy 43.805094 -304.449734) (xy 44.143942 -304.449734) (xy 44.147902 -304.40068)
			(xy 44.159679 -304.352896) (xy 44.17897 -304.30762) (xy 44.205273 -304.266024) (xy 44.237908 -304.229187)
			(xy 44.276029 -304.198062) (xy 44.31865 -304.173455) (xy 44.364666 -304.156003) (xy 44.412885 -304.146159)
			(xy 44.46206 -304.144178) (xy 44.510915 -304.15011) (xy 44.558186 -304.163802) (xy 44.602648 -304.1849)
			(xy 44.643151 -304.212856) (xy 44.678644 -304.246948) (xy 44.708209 -304.286292) (xy 44.73108 -304.329869)
			(xy 44.746664 -304.37655) (xy 44.754559 -304.425127) (xy 44.755054 -304.449734) (xy 74.544186 -304.449734)
			(xy 74.548146 -304.40068) (xy 74.559923 -304.352896) (xy 74.579214 -304.30762) (xy 74.605517 -304.266024)
			(xy 74.638152 -304.229187) (xy 74.676273 -304.198062) (xy 74.718894 -304.173455) (xy 74.76491 -304.156003)
			(xy 74.813129 -304.146159) (xy 74.862304 -304.144178) (xy 74.911159 -304.15011) (xy 74.95843 -304.163802)
			(xy 75.002892 -304.1849) (xy 75.043395 -304.212856) (xy 75.078888 -304.246948) (xy 75.108453 -304.286292)
			(xy 75.131324 -304.329869) (xy 75.146908 -304.37655) (xy 75.154803 -304.425127) (xy 75.155298 -304.449734)
			(xy 75.494146 -304.449734) (xy 75.498106 -304.40068) (xy 75.509883 -304.352896) (xy 75.529174 -304.30762)
			(xy 75.555477 -304.266024) (xy 75.588112 -304.229187) (xy 75.626233 -304.198062) (xy 75.668854 -304.173455)
			(xy 75.71487 -304.156003) (xy 75.763089 -304.146159) (xy 75.812264 -304.144178) (xy 75.861119 -304.15011)
			(xy 75.90839 -304.163802) (xy 75.952852 -304.1849) (xy 75.993355 -304.212856) (xy 76.028848 -304.246948)
			(xy 76.058413 -304.286292) (xy 76.081284 -304.329869) (xy 76.096868 -304.37655) (xy 76.104763 -304.425127)
			(xy 76.105258 -304.449734) (xy 81.19416 -304.449734) (xy 81.19812 -304.40068) (xy 81.209897 -304.352896)
			(xy 81.229188 -304.30762) (xy 81.255491 -304.266024) (xy 81.288126 -304.229187) (xy 81.326247 -304.198062)
			(xy 81.368868 -304.173455) (xy 81.414884 -304.156003) (xy 81.463103 -304.146159) (xy 81.512278 -304.144178)
			(xy 81.561133 -304.15011) (xy 81.608404 -304.163802) (xy 81.652866 -304.1849) (xy 81.693369 -304.212856)
			(xy 81.728862 -304.246948) (xy 81.758427 -304.286292) (xy 81.781298 -304.329869) (xy 81.796882 -304.37655)
			(xy 81.804777 -304.425127) (xy 81.805272 -304.449734) (xy 82.14412 -304.449734) (xy 82.14808 -304.40068)
			(xy 82.159857 -304.352896) (xy 82.179148 -304.30762) (xy 82.205451 -304.266024) (xy 82.238086 -304.229187)
			(xy 82.276207 -304.198062) (xy 82.318828 -304.173455) (xy 82.364844 -304.156003) (xy 82.413063 -304.146159)
			(xy 82.462238 -304.144178) (xy 82.511093 -304.15011) (xy 82.558364 -304.163802) (xy 82.602826 -304.1849)
			(xy 82.643329 -304.212856) (xy 82.678822 -304.246948) (xy 82.708387 -304.286292) (xy 82.731258 -304.329869)
			(xy 82.746842 -304.37655) (xy 82.754737 -304.425127) (xy 82.755232 -304.449734) (xy 152.644106 -304.449734)
			(xy 152.648066 -304.40068) (xy 152.659843 -304.352896) (xy 152.679134 -304.30762) (xy 152.705437 -304.266024)
			(xy 152.738072 -304.229187) (xy 152.776193 -304.198062) (xy 152.818814 -304.173455) (xy 152.86483 -304.156003)
			(xy 152.913049 -304.146159) (xy 152.962224 -304.144178) (xy 153.011079 -304.15011) (xy 153.05835 -304.163802)
			(xy 153.102812 -304.1849) (xy 153.143315 -304.212856) (xy 153.178808 -304.246948) (xy 153.208373 -304.286292)
			(xy 153.231244 -304.329869) (xy 153.246828 -304.37655) (xy 153.254723 -304.425127) (xy 153.255218 -304.449734)
			(xy 153.594066 -304.449734) (xy 153.598026 -304.40068) (xy 153.609803 -304.352896) (xy 153.629094 -304.30762)
			(xy 153.655397 -304.266024) (xy 153.688032 -304.229187) (xy 153.726153 -304.198062) (xy 153.768774 -304.173455)
			(xy 153.81479 -304.156003) (xy 153.863009 -304.146159) (xy 153.912184 -304.144178) (xy 153.961039 -304.15011)
			(xy 154.00831 -304.163802) (xy 154.052772 -304.1849) (xy 154.093275 -304.212856) (xy 154.128768 -304.246948)
			(xy 154.158333 -304.286292) (xy 154.181204 -304.329869) (xy 154.196788 -304.37655) (xy 154.204683 -304.425127)
			(xy 154.205178 -304.449734) (xy 159.29408 -304.449734) (xy 159.29804 -304.40068) (xy 159.309817 -304.352896)
			(xy 159.329108 -304.30762) (xy 159.355411 -304.266024) (xy 159.388046 -304.229187) (xy 159.426167 -304.198062)
			(xy 159.468788 -304.173455) (xy 159.514804 -304.156003) (xy 159.563023 -304.146159) (xy 159.612198 -304.144178)
			(xy 159.661053 -304.15011) (xy 159.708324 -304.163802) (xy 159.752786 -304.1849) (xy 159.793289 -304.212856)
			(xy 159.828782 -304.246948) (xy 159.858347 -304.286292) (xy 159.881218 -304.329869) (xy 159.896802 -304.37655)
			(xy 159.904697 -304.425127) (xy 159.905192 -304.449734) (xy 160.24404 -304.449734) (xy 160.248 -304.40068)
			(xy 160.259777 -304.352896) (xy 160.279068 -304.30762) (xy 160.305371 -304.266024) (xy 160.338006 -304.229187)
			(xy 160.376127 -304.198062) (xy 160.418748 -304.173455) (xy 160.464764 -304.156003) (xy 160.512983 -304.146159)
			(xy 160.562158 -304.144178) (xy 160.611013 -304.15011) (xy 160.658284 -304.163802) (xy 160.702746 -304.1849)
			(xy 160.743249 -304.212856) (xy 160.778742 -304.246948) (xy 160.808307 -304.286292) (xy 160.831178 -304.329869)
			(xy 160.846762 -304.37655) (xy 160.854657 -304.425127) (xy 160.855152 -304.449734) (xy 190.644284 -304.449734)
			(xy 190.648244 -304.40068) (xy 190.660021 -304.352896) (xy 190.679312 -304.30762) (xy 190.705615 -304.266024)
			(xy 190.73825 -304.229187) (xy 190.776371 -304.198062) (xy 190.818992 -304.173455) (xy 190.865008 -304.156003)
			(xy 190.913227 -304.146159) (xy 190.962402 -304.144178) (xy 191.011257 -304.15011) (xy 191.058528 -304.163802)
			(xy 191.10299 -304.1849) (xy 191.143493 -304.212856) (xy 191.178986 -304.246948) (xy 191.208551 -304.286292)
			(xy 191.231422 -304.329869) (xy 191.247006 -304.37655) (xy 191.254901 -304.425127) (xy 191.255396 -304.449734)
			(xy 191.594244 -304.449734) (xy 191.598204 -304.40068) (xy 191.609981 -304.352896) (xy 191.629272 -304.30762)
			(xy 191.655575 -304.266024) (xy 191.68821 -304.229187) (xy 191.726331 -304.198062) (xy 191.768952 -304.173455)
			(xy 191.814968 -304.156003) (xy 191.863187 -304.146159) (xy 191.912362 -304.144178) (xy 191.961217 -304.15011)
			(xy 192.008488 -304.163802) (xy 192.05295 -304.1849) (xy 192.093453 -304.212856) (xy 192.128946 -304.246948)
			(xy 192.158511 -304.286292) (xy 192.181382 -304.329869) (xy 192.196966 -304.37655) (xy 192.204861 -304.425127)
			(xy 192.205356 -304.449734) (xy 197.294258 -304.449734) (xy 197.298218 -304.40068) (xy 197.309995 -304.352896)
			(xy 197.329286 -304.30762) (xy 197.355589 -304.266024) (xy 197.388224 -304.229187) (xy 197.426345 -304.198062)
			(xy 197.468966 -304.173455) (xy 197.514982 -304.156003) (xy 197.563201 -304.146159) (xy 197.612376 -304.144178)
			(xy 197.661231 -304.15011) (xy 197.708502 -304.163802) (xy 197.752964 -304.1849) (xy 197.793467 -304.212856)
			(xy 197.82896 -304.246948) (xy 197.858525 -304.286292) (xy 197.881396 -304.329869) (xy 197.89698 -304.37655)
			(xy 197.904875 -304.425127) (xy 197.90537 -304.449734) (xy 198.244218 -304.449734) (xy 198.248178 -304.40068)
			(xy 198.259955 -304.352896) (xy 198.279246 -304.30762) (xy 198.305549 -304.266024) (xy 198.338184 -304.229187)
			(xy 198.376305 -304.198062) (xy 198.418926 -304.173455) (xy 198.464942 -304.156003) (xy 198.513161 -304.146159)
			(xy 198.562336 -304.144178) (xy 198.611191 -304.15011) (xy 198.658462 -304.163802) (xy 198.702924 -304.1849)
			(xy 198.743427 -304.212856) (xy 198.77892 -304.246948) (xy 198.808485 -304.286292) (xy 198.831356 -304.329869)
			(xy 198.84694 -304.37655) (xy 198.854835 -304.425127) (xy 198.85533 -304.449734) (xy 268.74395 -304.449734)
			(xy 268.74791 -304.40068) (xy 268.759687 -304.352896) (xy 268.778978 -304.30762) (xy 268.805281 -304.266024)
			(xy 268.837916 -304.229187) (xy 268.876037 -304.198062) (xy 268.918658 -304.173455) (xy 268.964674 -304.156003)
			(xy 269.012893 -304.146159) (xy 269.062068 -304.144178) (xy 269.110923 -304.15011) (xy 269.158194 -304.163802)
			(xy 269.202656 -304.1849) (xy 269.243159 -304.212856) (xy 269.278652 -304.246948) (xy 269.308217 -304.286292)
			(xy 269.331088 -304.329869) (xy 269.346672 -304.37655) (xy 269.354567 -304.425127) (xy 269.355062 -304.449734)
			(xy 269.69391 -304.449734) (xy 269.69787 -304.40068) (xy 269.709647 -304.352896) (xy 269.728938 -304.30762)
			(xy 269.755241 -304.266024) (xy 269.787876 -304.229187) (xy 269.825997 -304.198062) (xy 269.868618 -304.173455)
			(xy 269.914634 -304.156003) (xy 269.962853 -304.146159) (xy 270.012028 -304.144178) (xy 270.060883 -304.15011)
			(xy 270.108154 -304.163802) (xy 270.152616 -304.1849) (xy 270.193119 -304.212856) (xy 270.228612 -304.246948)
			(xy 270.258177 -304.286292) (xy 270.281048 -304.329869) (xy 270.296632 -304.37655) (xy 270.304527 -304.425127)
			(xy 270.305022 -304.449734) (xy 275.393924 -304.449734) (xy 275.397884 -304.40068) (xy 275.409661 -304.352896)
			(xy 275.428952 -304.30762) (xy 275.455255 -304.266024) (xy 275.48789 -304.229187) (xy 275.526011 -304.198062)
			(xy 275.568632 -304.173455) (xy 275.614648 -304.156003) (xy 275.662867 -304.146159) (xy 275.712042 -304.144178)
			(xy 275.760897 -304.15011) (xy 275.808168 -304.163802) (xy 275.85263 -304.1849) (xy 275.893133 -304.212856)
			(xy 275.928626 -304.246948) (xy 275.958191 -304.286292) (xy 275.981062 -304.329869) (xy 275.996646 -304.37655)
			(xy 276.004541 -304.425127) (xy 276.005036 -304.449734) (xy 276.343884 -304.449734) (xy 276.347844 -304.40068)
			(xy 276.359621 -304.352896) (xy 276.378912 -304.30762) (xy 276.405215 -304.266024) (xy 276.43785 -304.229187)
			(xy 276.475971 -304.198062) (xy 276.518592 -304.173455) (xy 276.564608 -304.156003) (xy 276.612827 -304.146159)
			(xy 276.662002 -304.144178) (xy 276.710857 -304.15011) (xy 276.758128 -304.163802) (xy 276.80259 -304.1849)
			(xy 276.843093 -304.212856) (xy 276.878586 -304.246948) (xy 276.908151 -304.286292) (xy 276.931022 -304.329869)
			(xy 276.946606 -304.37655) (xy 276.954501 -304.425127) (xy 276.954996 -304.449734) (xy 306.744128 -304.449734)
			(xy 306.748088 -304.40068) (xy 306.759865 -304.352896) (xy 306.779156 -304.30762) (xy 306.805459 -304.266024)
			(xy 306.838094 -304.229187) (xy 306.876215 -304.198062) (xy 306.918836 -304.173455) (xy 306.964852 -304.156003)
			(xy 307.013071 -304.146159) (xy 307.062246 -304.144178) (xy 307.111101 -304.15011) (xy 307.158372 -304.163802)
			(xy 307.202834 -304.1849) (xy 307.243337 -304.212856) (xy 307.27883 -304.246948) (xy 307.308395 -304.286292)
			(xy 307.331266 -304.329869) (xy 307.34685 -304.37655) (xy 307.354745 -304.425127) (xy 307.35524 -304.449734)
			(xy 307.694088 -304.449734) (xy 307.698048 -304.40068) (xy 307.709825 -304.352896) (xy 307.729116 -304.30762)
			(xy 307.755419 -304.266024) (xy 307.788054 -304.229187) (xy 307.826175 -304.198062) (xy 307.868796 -304.173455)
			(xy 307.914812 -304.156003) (xy 307.963031 -304.146159) (xy 308.012206 -304.144178) (xy 308.061061 -304.15011)
			(xy 308.108332 -304.163802) (xy 308.152794 -304.1849) (xy 308.193297 -304.212856) (xy 308.22879 -304.246948)
			(xy 308.258355 -304.286292) (xy 308.281226 -304.329869) (xy 308.29681 -304.37655) (xy 308.304705 -304.425127)
			(xy 308.3052 -304.449734) (xy 313.394102 -304.449734) (xy 313.398062 -304.40068) (xy 313.409839 -304.352896)
			(xy 313.42913 -304.30762) (xy 313.455433 -304.266024) (xy 313.488068 -304.229187) (xy 313.526189 -304.198062)
			(xy 313.56881 -304.173455) (xy 313.614826 -304.156003) (xy 313.663045 -304.146159) (xy 313.71222 -304.144178)
			(xy 313.761075 -304.15011) (xy 313.808346 -304.163802) (xy 313.852808 -304.1849) (xy 313.893311 -304.212856)
			(xy 313.928804 -304.246948) (xy 313.958369 -304.286292) (xy 313.98124 -304.329869) (xy 313.996824 -304.37655)
			(xy 314.004719 -304.425127) (xy 314.005214 -304.449734) (xy 314.344062 -304.449734) (xy 314.348022 -304.40068)
			(xy 314.359799 -304.352896) (xy 314.37909 -304.30762) (xy 314.405393 -304.266024) (xy 314.438028 -304.229187)
			(xy 314.476149 -304.198062) (xy 314.51877 -304.173455) (xy 314.564786 -304.156003) (xy 314.613005 -304.146159)
			(xy 314.66218 -304.144178) (xy 314.711035 -304.15011) (xy 314.758306 -304.163802) (xy 314.802768 -304.1849)
			(xy 314.843271 -304.212856) (xy 314.878764 -304.246948) (xy 314.908329 -304.286292) (xy 314.9312 -304.329869)
			(xy 314.946784 -304.37655) (xy 314.954679 -304.425127) (xy 314.955174 -304.449734) (xy 384.844048 -304.449734)
			(xy 384.848008 -304.40068) (xy 384.859785 -304.352896) (xy 384.879076 -304.30762) (xy 384.905379 -304.266024)
			(xy 384.938014 -304.229187) (xy 384.976135 -304.198062) (xy 385.018756 -304.173455) (xy 385.064772 -304.156003)
			(xy 385.112991 -304.146159) (xy 385.162166 -304.144178) (xy 385.211021 -304.15011) (xy 385.258292 -304.163802)
			(xy 385.302754 -304.1849) (xy 385.343257 -304.212856) (xy 385.37875 -304.246948) (xy 385.408315 -304.286292)
			(xy 385.431186 -304.329869) (xy 385.44677 -304.37655) (xy 385.454665 -304.425127) (xy 385.45516 -304.449734)
			(xy 385.794008 -304.449734) (xy 385.797968 -304.40068) (xy 385.809745 -304.352896) (xy 385.829036 -304.30762)
			(xy 385.855339 -304.266024) (xy 385.887974 -304.229187) (xy 385.926095 -304.198062) (xy 385.968716 -304.173455)
			(xy 386.014732 -304.156003) (xy 386.062951 -304.146159) (xy 386.112126 -304.144178) (xy 386.160981 -304.15011)
			(xy 386.208252 -304.163802) (xy 386.252714 -304.1849) (xy 386.293217 -304.212856) (xy 386.32871 -304.246948)
			(xy 386.358275 -304.286292) (xy 386.381146 -304.329869) (xy 386.39673 -304.37655) (xy 386.404625 -304.425127)
			(xy 386.40512 -304.449734) (xy 391.494022 -304.449734) (xy 391.497982 -304.40068) (xy 391.509759 -304.352896)
			(xy 391.52905 -304.30762) (xy 391.555353 -304.266024) (xy 391.587988 -304.229187) (xy 391.626109 -304.198062)
			(xy 391.66873 -304.173455) (xy 391.714746 -304.156003) (xy 391.762965 -304.146159) (xy 391.81214 -304.144178)
			(xy 391.860995 -304.15011) (xy 391.908266 -304.163802) (xy 391.952728 -304.1849) (xy 391.993231 -304.212856)
			(xy 392.028724 -304.246948) (xy 392.058289 -304.286292) (xy 392.08116 -304.329869) (xy 392.096744 -304.37655)
			(xy 392.104639 -304.425127) (xy 392.105134 -304.449734) (xy 392.443982 -304.449734) (xy 392.447942 -304.40068)
			(xy 392.459719 -304.352896) (xy 392.47901 -304.30762) (xy 392.505313 -304.266024) (xy 392.537948 -304.229187)
			(xy 392.576069 -304.198062) (xy 392.61869 -304.173455) (xy 392.664706 -304.156003) (xy 392.712925 -304.146159)
			(xy 392.7621 -304.144178) (xy 392.810955 -304.15011) (xy 392.858226 -304.163802) (xy 392.902688 -304.1849)
			(xy 392.943191 -304.212856) (xy 392.978684 -304.246948) (xy 393.008249 -304.286292) (xy 393.03112 -304.329869)
			(xy 393.046704 -304.37655) (xy 393.054599 -304.425127) (xy 393.055094 -304.449734) (xy 422.844226 -304.449734)
			(xy 422.848186 -304.40068) (xy 422.859963 -304.352896) (xy 422.879254 -304.30762) (xy 422.905557 -304.266024)
			(xy 422.938192 -304.229187) (xy 422.976313 -304.198062) (xy 423.018934 -304.173455) (xy 423.06495 -304.156003)
			(xy 423.113169 -304.146159) (xy 423.162344 -304.144178) (xy 423.211199 -304.15011) (xy 423.25847 -304.163802)
			(xy 423.302932 -304.1849) (xy 423.343435 -304.212856) (xy 423.378928 -304.246948) (xy 423.408493 -304.286292)
			(xy 423.431364 -304.329869) (xy 423.446948 -304.37655) (xy 423.454843 -304.425127) (xy 423.455338 -304.449734)
			(xy 423.794186 -304.449734) (xy 423.798146 -304.40068) (xy 423.809923 -304.352896) (xy 423.829214 -304.30762)
			(xy 423.855517 -304.266024) (xy 423.888152 -304.229187) (xy 423.926273 -304.198062) (xy 423.968894 -304.173455)
			(xy 424.01491 -304.156003) (xy 424.063129 -304.146159) (xy 424.112304 -304.144178) (xy 424.161159 -304.15011)
			(xy 424.20843 -304.163802) (xy 424.252892 -304.1849) (xy 424.293395 -304.212856) (xy 424.328888 -304.246948)
			(xy 424.358453 -304.286292) (xy 424.381324 -304.329869) (xy 424.396908 -304.37655) (xy 424.404803 -304.425127)
			(xy 424.405298 -304.449734) (xy 429.4942 -304.449734) (xy 429.49816 -304.40068) (xy 429.509937 -304.352896)
			(xy 429.529228 -304.30762) (xy 429.555531 -304.266024) (xy 429.588166 -304.229187) (xy 429.626287 -304.198062)
			(xy 429.668908 -304.173455) (xy 429.714924 -304.156003) (xy 429.763143 -304.146159) (xy 429.812318 -304.144178)
			(xy 429.861173 -304.15011) (xy 429.908444 -304.163802) (xy 429.952906 -304.1849) (xy 429.993409 -304.212856)
			(xy 430.028902 -304.246948) (xy 430.058467 -304.286292) (xy 430.081338 -304.329869) (xy 430.096922 -304.37655)
			(xy 430.104817 -304.425127) (xy 430.105312 -304.449734) (xy 430.44416 -304.449734) (xy 430.44812 -304.40068)
			(xy 430.459897 -304.352896) (xy 430.479188 -304.30762) (xy 430.505491 -304.266024) (xy 430.538126 -304.229187)
			(xy 430.576247 -304.198062) (xy 430.618868 -304.173455) (xy 430.664884 -304.156003) (xy 430.713103 -304.146159)
			(xy 430.762278 -304.144178) (xy 430.811133 -304.15011) (xy 430.858404 -304.163802) (xy 430.902866 -304.1849)
			(xy 430.943369 -304.212856) (xy 430.978862 -304.246948) (xy 431.008427 -304.286292) (xy 431.031298 -304.329869)
			(xy 431.046882 -304.37655) (xy 431.054777 -304.425127) (xy 431.055272 -304.449734) (xy 431.054777 -304.474341)
			(xy 431.046882 -304.522918) (xy 431.031298 -304.569599) (xy 431.008427 -304.613176) (xy 430.978862 -304.65252)
			(xy 430.943369 -304.686612) (xy 430.902866 -304.714568) (xy 430.858404 -304.735666) (xy 430.811133 -304.749358)
			(xy 430.762278 -304.75529) (xy 430.713103 -304.753309) (xy 430.664884 -304.743465) (xy 430.618868 -304.726013)
			(xy 430.576247 -304.701406) (xy 430.538126 -304.670281) (xy 430.505491 -304.633444) (xy 430.479188 -304.591848)
			(xy 430.459897 -304.546572) (xy 430.44812 -304.498788) (xy 430.44416 -304.449734) (xy 430.105312 -304.449734)
			(xy 430.104817 -304.474341) (xy 430.096922 -304.522918) (xy 430.081338 -304.569599) (xy 430.058467 -304.613176)
			(xy 430.028902 -304.65252) (xy 429.993409 -304.686612) (xy 429.952906 -304.714568) (xy 429.908444 -304.735666)
			(xy 429.861173 -304.749358) (xy 429.812318 -304.75529) (xy 429.763143 -304.753309) (xy 429.714924 -304.743465)
			(xy 429.668908 -304.726013) (xy 429.626287 -304.701406) (xy 429.588166 -304.670281) (xy 429.555531 -304.633444)
			(xy 429.529228 -304.591848) (xy 429.509937 -304.546572) (xy 429.49816 -304.498788) (xy 429.4942 -304.449734)
			(xy 424.405298 -304.449734) (xy 424.404803 -304.474341) (xy 424.396908 -304.522918) (xy 424.381324 -304.569599)
			(xy 424.358453 -304.613176) (xy 424.328888 -304.65252) (xy 424.293395 -304.686612) (xy 424.252892 -304.714568)
			(xy 424.20843 -304.735666) (xy 424.161159 -304.749358) (xy 424.112304 -304.75529) (xy 424.063129 -304.753309)
			(xy 424.01491 -304.743465) (xy 423.968894 -304.726013) (xy 423.926273 -304.701406) (xy 423.888152 -304.670281)
			(xy 423.855517 -304.633444) (xy 423.829214 -304.591848) (xy 423.809923 -304.546572) (xy 423.798146 -304.498788)
			(xy 423.794186 -304.449734) (xy 423.455338 -304.449734) (xy 423.454843 -304.474341) (xy 423.446948 -304.522918)
			(xy 423.431364 -304.569599) (xy 423.408493 -304.613176) (xy 423.378928 -304.65252) (xy 423.343435 -304.686612)
			(xy 423.302932 -304.714568) (xy 423.25847 -304.735666) (xy 423.211199 -304.749358) (xy 423.162344 -304.75529)
			(xy 423.113169 -304.753309) (xy 423.06495 -304.743465) (xy 423.018934 -304.726013) (xy 422.976313 -304.701406)
			(xy 422.938192 -304.670281) (xy 422.905557 -304.633444) (xy 422.879254 -304.591848) (xy 422.859963 -304.546572)
			(xy 422.848186 -304.498788) (xy 422.844226 -304.449734) (xy 393.055094 -304.449734) (xy 393.054599 -304.474341)
			(xy 393.046704 -304.522918) (xy 393.03112 -304.569599) (xy 393.008249 -304.613176) (xy 392.978684 -304.65252)
			(xy 392.943191 -304.686612) (xy 392.902688 -304.714568) (xy 392.858226 -304.735666) (xy 392.810955 -304.749358)
			(xy 392.7621 -304.75529) (xy 392.712925 -304.753309) (xy 392.664706 -304.743465) (xy 392.61869 -304.726013)
			(xy 392.576069 -304.701406) (xy 392.537948 -304.670281) (xy 392.505313 -304.633444) (xy 392.47901 -304.591848)
			(xy 392.459719 -304.546572) (xy 392.447942 -304.498788) (xy 392.443982 -304.449734) (xy 392.105134 -304.449734)
			(xy 392.104639 -304.474341) (xy 392.096744 -304.522918) (xy 392.08116 -304.569599) (xy 392.058289 -304.613176)
			(xy 392.028724 -304.65252) (xy 391.993231 -304.686612) (xy 391.952728 -304.714568) (xy 391.908266 -304.735666)
			(xy 391.860995 -304.749358) (xy 391.81214 -304.75529) (xy 391.762965 -304.753309) (xy 391.714746 -304.743465)
			(xy 391.66873 -304.726013) (xy 391.626109 -304.701406) (xy 391.587988 -304.670281) (xy 391.555353 -304.633444)
			(xy 391.52905 -304.591848) (xy 391.509759 -304.546572) (xy 391.497982 -304.498788) (xy 391.494022 -304.449734)
			(xy 386.40512 -304.449734) (xy 386.404625 -304.474341) (xy 386.39673 -304.522918) (xy 386.381146 -304.569599)
			(xy 386.358275 -304.613176) (xy 386.32871 -304.65252) (xy 386.293217 -304.686612) (xy 386.252714 -304.714568)
			(xy 386.208252 -304.735666) (xy 386.160981 -304.749358) (xy 386.112126 -304.75529) (xy 386.062951 -304.753309)
			(xy 386.014732 -304.743465) (xy 385.968716 -304.726013) (xy 385.926095 -304.701406) (xy 385.887974 -304.670281)
			(xy 385.855339 -304.633444) (xy 385.829036 -304.591848) (xy 385.809745 -304.546572) (xy 385.797968 -304.498788)
			(xy 385.794008 -304.449734) (xy 385.45516 -304.449734) (xy 385.454665 -304.474341) (xy 385.44677 -304.522918)
			(xy 385.431186 -304.569599) (xy 385.408315 -304.613176) (xy 385.37875 -304.65252) (xy 385.343257 -304.686612)
			(xy 385.302754 -304.714568) (xy 385.258292 -304.735666) (xy 385.211021 -304.749358) (xy 385.162166 -304.75529)
			(xy 385.112991 -304.753309) (xy 385.064772 -304.743465) (xy 385.018756 -304.726013) (xy 384.976135 -304.701406)
			(xy 384.938014 -304.670281) (xy 384.905379 -304.633444) (xy 384.879076 -304.591848) (xy 384.859785 -304.546572)
			(xy 384.848008 -304.498788) (xy 384.844048 -304.449734) (xy 314.955174 -304.449734) (xy 314.954679 -304.474341)
			(xy 314.946784 -304.522918) (xy 314.9312 -304.569599) (xy 314.908329 -304.613176) (xy 314.878764 -304.65252)
			(xy 314.843271 -304.686612) (xy 314.802768 -304.714568) (xy 314.758306 -304.735666) (xy 314.711035 -304.749358)
			(xy 314.66218 -304.75529) (xy 314.613005 -304.753309) (xy 314.564786 -304.743465) (xy 314.51877 -304.726013)
			(xy 314.476149 -304.701406) (xy 314.438028 -304.670281) (xy 314.405393 -304.633444) (xy 314.37909 -304.591848)
			(xy 314.359799 -304.546572) (xy 314.348022 -304.498788) (xy 314.344062 -304.449734) (xy 314.005214 -304.449734)
			(xy 314.004719 -304.474341) (xy 313.996824 -304.522918) (xy 313.98124 -304.569599) (xy 313.958369 -304.613176)
			(xy 313.928804 -304.65252) (xy 313.893311 -304.686612) (xy 313.852808 -304.714568) (xy 313.808346 -304.735666)
			(xy 313.761075 -304.749358) (xy 313.71222 -304.75529) (xy 313.663045 -304.753309) (xy 313.614826 -304.743465)
			(xy 313.56881 -304.726013) (xy 313.526189 -304.701406) (xy 313.488068 -304.670281) (xy 313.455433 -304.633444)
			(xy 313.42913 -304.591848) (xy 313.409839 -304.546572) (xy 313.398062 -304.498788) (xy 313.394102 -304.449734)
			(xy 308.3052 -304.449734) (xy 308.304705 -304.474341) (xy 308.29681 -304.522918) (xy 308.281226 -304.569599)
			(xy 308.258355 -304.613176) (xy 308.22879 -304.65252) (xy 308.193297 -304.686612) (xy 308.152794 -304.714568)
			(xy 308.108332 -304.735666) (xy 308.061061 -304.749358) (xy 308.012206 -304.75529) (xy 307.963031 -304.753309)
			(xy 307.914812 -304.743465) (xy 307.868796 -304.726013) (xy 307.826175 -304.701406) (xy 307.788054 -304.670281)
			(xy 307.755419 -304.633444) (xy 307.729116 -304.591848) (xy 307.709825 -304.546572) (xy 307.698048 -304.498788)
			(xy 307.694088 -304.449734) (xy 307.35524 -304.449734) (xy 307.354745 -304.474341) (xy 307.34685 -304.522918)
			(xy 307.331266 -304.569599) (xy 307.308395 -304.613176) (xy 307.27883 -304.65252) (xy 307.243337 -304.686612)
			(xy 307.202834 -304.714568) (xy 307.158372 -304.735666) (xy 307.111101 -304.749358) (xy 307.062246 -304.75529)
			(xy 307.013071 -304.753309) (xy 306.964852 -304.743465) (xy 306.918836 -304.726013) (xy 306.876215 -304.701406)
			(xy 306.838094 -304.670281) (xy 306.805459 -304.633444) (xy 306.779156 -304.591848) (xy 306.759865 -304.546572)
			(xy 306.748088 -304.498788) (xy 306.744128 -304.449734) (xy 276.954996 -304.449734) (xy 276.954501 -304.474341)
			(xy 276.946606 -304.522918) (xy 276.931022 -304.569599) (xy 276.908151 -304.613176) (xy 276.878586 -304.65252)
			(xy 276.843093 -304.686612) (xy 276.80259 -304.714568) (xy 276.758128 -304.735666) (xy 276.710857 -304.749358)
			(xy 276.662002 -304.75529) (xy 276.612827 -304.753309) (xy 276.564608 -304.743465) (xy 276.518592 -304.726013)
			(xy 276.475971 -304.701406) (xy 276.43785 -304.670281) (xy 276.405215 -304.633444) (xy 276.378912 -304.591848)
			(xy 276.359621 -304.546572) (xy 276.347844 -304.498788) (xy 276.343884 -304.449734) (xy 276.005036 -304.449734)
			(xy 276.004541 -304.474341) (xy 275.996646 -304.522918) (xy 275.981062 -304.569599) (xy 275.958191 -304.613176)
			(xy 275.928626 -304.65252) (xy 275.893133 -304.686612) (xy 275.85263 -304.714568) (xy 275.808168 -304.735666)
			(xy 275.760897 -304.749358) (xy 275.712042 -304.75529) (xy 275.662867 -304.753309) (xy 275.614648 -304.743465)
			(xy 275.568632 -304.726013) (xy 275.526011 -304.701406) (xy 275.48789 -304.670281) (xy 275.455255 -304.633444)
			(xy 275.428952 -304.591848) (xy 275.409661 -304.546572) (xy 275.397884 -304.498788) (xy 275.393924 -304.449734)
			(xy 270.305022 -304.449734) (xy 270.304527 -304.474341) (xy 270.296632 -304.522918) (xy 270.281048 -304.569599)
			(xy 270.258177 -304.613176) (xy 270.228612 -304.65252) (xy 270.193119 -304.686612) (xy 270.152616 -304.714568)
			(xy 270.108154 -304.735666) (xy 270.060883 -304.749358) (xy 270.012028 -304.75529) (xy 269.962853 -304.753309)
			(xy 269.914634 -304.743465) (xy 269.868618 -304.726013) (xy 269.825997 -304.701406) (xy 269.787876 -304.670281)
			(xy 269.755241 -304.633444) (xy 269.728938 -304.591848) (xy 269.709647 -304.546572) (xy 269.69787 -304.498788)
			(xy 269.69391 -304.449734) (xy 269.355062 -304.449734) (xy 269.354567 -304.474341) (xy 269.346672 -304.522918)
			(xy 269.331088 -304.569599) (xy 269.308217 -304.613176) (xy 269.278652 -304.65252) (xy 269.243159 -304.686612)
			(xy 269.202656 -304.714568) (xy 269.158194 -304.735666) (xy 269.110923 -304.749358) (xy 269.062068 -304.75529)
			(xy 269.012893 -304.753309) (xy 268.964674 -304.743465) (xy 268.918658 -304.726013) (xy 268.876037 -304.701406)
			(xy 268.837916 -304.670281) (xy 268.805281 -304.633444) (xy 268.778978 -304.591848) (xy 268.759687 -304.546572)
			(xy 268.74791 -304.498788) (xy 268.74395 -304.449734) (xy 198.85533 -304.449734) (xy 198.854835 -304.474341)
			(xy 198.84694 -304.522918) (xy 198.831356 -304.569599) (xy 198.808485 -304.613176) (xy 198.77892 -304.65252)
			(xy 198.743427 -304.686612) (xy 198.702924 -304.714568) (xy 198.658462 -304.735666) (xy 198.611191 -304.749358)
			(xy 198.562336 -304.75529) (xy 198.513161 -304.753309) (xy 198.464942 -304.743465) (xy 198.418926 -304.726013)
			(xy 198.376305 -304.701406) (xy 198.338184 -304.670281) (xy 198.305549 -304.633444) (xy 198.279246 -304.591848)
			(xy 198.259955 -304.546572) (xy 198.248178 -304.498788) (xy 198.244218 -304.449734) (xy 197.90537 -304.449734)
			(xy 197.904875 -304.474341) (xy 197.89698 -304.522918) (xy 197.881396 -304.569599) (xy 197.858525 -304.613176)
			(xy 197.82896 -304.65252) (xy 197.793467 -304.686612) (xy 197.752964 -304.714568) (xy 197.708502 -304.735666)
			(xy 197.661231 -304.749358) (xy 197.612376 -304.75529) (xy 197.563201 -304.753309) (xy 197.514982 -304.743465)
			(xy 197.468966 -304.726013) (xy 197.426345 -304.701406) (xy 197.388224 -304.670281) (xy 197.355589 -304.633444)
			(xy 197.329286 -304.591848) (xy 197.309995 -304.546572) (xy 197.298218 -304.498788) (xy 197.294258 -304.449734)
			(xy 192.205356 -304.449734) (xy 192.204861 -304.474341) (xy 192.196966 -304.522918) (xy 192.181382 -304.569599)
			(xy 192.158511 -304.613176) (xy 192.128946 -304.65252) (xy 192.093453 -304.686612) (xy 192.05295 -304.714568)
			(xy 192.008488 -304.735666) (xy 191.961217 -304.749358) (xy 191.912362 -304.75529) (xy 191.863187 -304.753309)
			(xy 191.814968 -304.743465) (xy 191.768952 -304.726013) (xy 191.726331 -304.701406) (xy 191.68821 -304.670281)
			(xy 191.655575 -304.633444) (xy 191.629272 -304.591848) (xy 191.609981 -304.546572) (xy 191.598204 -304.498788)
			(xy 191.594244 -304.449734) (xy 191.255396 -304.449734) (xy 191.254901 -304.474341) (xy 191.247006 -304.522918)
			(xy 191.231422 -304.569599) (xy 191.208551 -304.613176) (xy 191.178986 -304.65252) (xy 191.143493 -304.686612)
			(xy 191.10299 -304.714568) (xy 191.058528 -304.735666) (xy 191.011257 -304.749358) (xy 190.962402 -304.75529)
			(xy 190.913227 -304.753309) (xy 190.865008 -304.743465) (xy 190.818992 -304.726013) (xy 190.776371 -304.701406)
			(xy 190.73825 -304.670281) (xy 190.705615 -304.633444) (xy 190.679312 -304.591848) (xy 190.660021 -304.546572)
			(xy 190.648244 -304.498788) (xy 190.644284 -304.449734) (xy 160.855152 -304.449734) (xy 160.854657 -304.474341)
			(xy 160.846762 -304.522918) (xy 160.831178 -304.569599) (xy 160.808307 -304.613176) (xy 160.778742 -304.65252)
			(xy 160.743249 -304.686612) (xy 160.702746 -304.714568) (xy 160.658284 -304.735666) (xy 160.611013 -304.749358)
			(xy 160.562158 -304.75529) (xy 160.512983 -304.753309) (xy 160.464764 -304.743465) (xy 160.418748 -304.726013)
			(xy 160.376127 -304.701406) (xy 160.338006 -304.670281) (xy 160.305371 -304.633444) (xy 160.279068 -304.591848)
			(xy 160.259777 -304.546572) (xy 160.248 -304.498788) (xy 160.24404 -304.449734) (xy 159.905192 -304.449734)
			(xy 159.904697 -304.474341) (xy 159.896802 -304.522918) (xy 159.881218 -304.569599) (xy 159.858347 -304.613176)
			(xy 159.828782 -304.65252) (xy 159.793289 -304.686612) (xy 159.752786 -304.714568) (xy 159.708324 -304.735666)
			(xy 159.661053 -304.749358) (xy 159.612198 -304.75529) (xy 159.563023 -304.753309) (xy 159.514804 -304.743465)
			(xy 159.468788 -304.726013) (xy 159.426167 -304.701406) (xy 159.388046 -304.670281) (xy 159.355411 -304.633444)
			(xy 159.329108 -304.591848) (xy 159.309817 -304.546572) (xy 159.29804 -304.498788) (xy 159.29408 -304.449734)
			(xy 154.205178 -304.449734) (xy 154.204683 -304.474341) (xy 154.196788 -304.522918) (xy 154.181204 -304.569599)
			(xy 154.158333 -304.613176) (xy 154.128768 -304.65252) (xy 154.093275 -304.686612) (xy 154.052772 -304.714568)
			(xy 154.00831 -304.735666) (xy 153.961039 -304.749358) (xy 153.912184 -304.75529) (xy 153.863009 -304.753309)
			(xy 153.81479 -304.743465) (xy 153.768774 -304.726013) (xy 153.726153 -304.701406) (xy 153.688032 -304.670281)
			(xy 153.655397 -304.633444) (xy 153.629094 -304.591848) (xy 153.609803 -304.546572) (xy 153.598026 -304.498788)
			(xy 153.594066 -304.449734) (xy 153.255218 -304.449734) (xy 153.254723 -304.474341) (xy 153.246828 -304.522918)
			(xy 153.231244 -304.569599) (xy 153.208373 -304.613176) (xy 153.178808 -304.65252) (xy 153.143315 -304.686612)
			(xy 153.102812 -304.714568) (xy 153.05835 -304.735666) (xy 153.011079 -304.749358) (xy 152.962224 -304.75529)
			(xy 152.913049 -304.753309) (xy 152.86483 -304.743465) (xy 152.818814 -304.726013) (xy 152.776193 -304.701406)
			(xy 152.738072 -304.670281) (xy 152.705437 -304.633444) (xy 152.679134 -304.591848) (xy 152.659843 -304.546572)
			(xy 152.648066 -304.498788) (xy 152.644106 -304.449734) (xy 82.755232 -304.449734) (xy 82.754737 -304.474341)
			(xy 82.746842 -304.522918) (xy 82.731258 -304.569599) (xy 82.708387 -304.613176) (xy 82.678822 -304.65252)
			(xy 82.643329 -304.686612) (xy 82.602826 -304.714568) (xy 82.558364 -304.735666) (xy 82.511093 -304.749358)
			(xy 82.462238 -304.75529) (xy 82.413063 -304.753309) (xy 82.364844 -304.743465) (xy 82.318828 -304.726013)
			(xy 82.276207 -304.701406) (xy 82.238086 -304.670281) (xy 82.205451 -304.633444) (xy 82.179148 -304.591848)
			(xy 82.159857 -304.546572) (xy 82.14808 -304.498788) (xy 82.14412 -304.449734) (xy 81.805272 -304.449734)
			(xy 81.804777 -304.474341) (xy 81.796882 -304.522918) (xy 81.781298 -304.569599) (xy 81.758427 -304.613176)
			(xy 81.728862 -304.65252) (xy 81.693369 -304.686612) (xy 81.652866 -304.714568) (xy 81.608404 -304.735666)
			(xy 81.561133 -304.749358) (xy 81.512278 -304.75529) (xy 81.463103 -304.753309) (xy 81.414884 -304.743465)
			(xy 81.368868 -304.726013) (xy 81.326247 -304.701406) (xy 81.288126 -304.670281) (xy 81.255491 -304.633444)
			(xy 81.229188 -304.591848) (xy 81.209897 -304.546572) (xy 81.19812 -304.498788) (xy 81.19416 -304.449734)
			(xy 76.105258 -304.449734) (xy 76.104763 -304.474341) (xy 76.096868 -304.522918) (xy 76.081284 -304.569599)
			(xy 76.058413 -304.613176) (xy 76.028848 -304.65252) (xy 75.993355 -304.686612) (xy 75.952852 -304.714568)
			(xy 75.90839 -304.735666) (xy 75.861119 -304.749358) (xy 75.812264 -304.75529) (xy 75.763089 -304.753309)
			(xy 75.71487 -304.743465) (xy 75.668854 -304.726013) (xy 75.626233 -304.701406) (xy 75.588112 -304.670281)
			(xy 75.555477 -304.633444) (xy 75.529174 -304.591848) (xy 75.509883 -304.546572) (xy 75.498106 -304.498788)
			(xy 75.494146 -304.449734) (xy 75.155298 -304.449734) (xy 75.154803 -304.474341) (xy 75.146908 -304.522918)
			(xy 75.131324 -304.569599) (xy 75.108453 -304.613176) (xy 75.078888 -304.65252) (xy 75.043395 -304.686612)
			(xy 75.002892 -304.714568) (xy 74.95843 -304.735666) (xy 74.911159 -304.749358) (xy 74.862304 -304.75529)
			(xy 74.813129 -304.753309) (xy 74.76491 -304.743465) (xy 74.718894 -304.726013) (xy 74.676273 -304.701406)
			(xy 74.638152 -304.670281) (xy 74.605517 -304.633444) (xy 74.579214 -304.591848) (xy 74.559923 -304.546572)
			(xy 74.548146 -304.498788) (xy 74.544186 -304.449734) (xy 44.755054 -304.449734) (xy 44.754559 -304.474341)
			(xy 44.746664 -304.522918) (xy 44.73108 -304.569599) (xy 44.708209 -304.613176) (xy 44.678644 -304.65252)
			(xy 44.643151 -304.686612) (xy 44.602648 -304.714568) (xy 44.558186 -304.735666) (xy 44.510915 -304.749358)
			(xy 44.46206 -304.75529) (xy 44.412885 -304.753309) (xy 44.364666 -304.743465) (xy 44.31865 -304.726013)
			(xy 44.276029 -304.701406) (xy 44.237908 -304.670281) (xy 44.205273 -304.633444) (xy 44.17897 -304.591848)
			(xy 44.159679 -304.546572) (xy 44.147902 -304.498788) (xy 44.143942 -304.449734) (xy 43.805094 -304.449734)
			(xy 43.804599 -304.474341) (xy 43.796704 -304.522918) (xy 43.78112 -304.569599) (xy 43.758249 -304.613176)
			(xy 43.728684 -304.65252) (xy 43.693191 -304.686612) (xy 43.652688 -304.714568) (xy 43.608226 -304.735666)
			(xy 43.560955 -304.749358) (xy 43.5121 -304.75529) (xy 43.462925 -304.753309) (xy 43.414706 -304.743465)
			(xy 43.36869 -304.726013) (xy 43.326069 -304.701406) (xy 43.287948 -304.670281) (xy 43.255313 -304.633444)
			(xy 43.22901 -304.591848) (xy 43.209719 -304.546572) (xy 43.197942 -304.498788) (xy 43.193982 -304.449734)
			(xy 38.10508 -304.449734) (xy 38.104585 -304.474341) (xy 38.09669 -304.522918) (xy 38.081106 -304.569599)
			(xy 38.058235 -304.613176) (xy 38.02867 -304.65252) (xy 37.993177 -304.686612) (xy 37.952674 -304.714568)
			(xy 37.908212 -304.735666) (xy 37.860941 -304.749358) (xy 37.812086 -304.75529) (xy 37.762911 -304.753309)
			(xy 37.714692 -304.743465) (xy 37.668676 -304.726013) (xy 37.626055 -304.701406) (xy 37.587934 -304.670281)
			(xy 37.555299 -304.633444) (xy 37.528996 -304.591848) (xy 37.509705 -304.546572) (xy 37.497928 -304.498788)
			(xy 37.493968 -304.449734) (xy 37.15512 -304.449734) (xy 37.154625 -304.474341) (xy 37.14673 -304.522918)
			(xy 37.131146 -304.569599) (xy 37.108275 -304.613176) (xy 37.07871 -304.65252) (xy 37.043217 -304.686612)
			(xy 37.002714 -304.714568) (xy 36.958252 -304.735666) (xy 36.910981 -304.749358) (xy 36.862126 -304.75529)
			(xy 36.812951 -304.753309) (xy 36.764732 -304.743465) (xy 36.718716 -304.726013) (xy 36.676095 -304.701406)
			(xy 36.637974 -304.670281) (xy 36.605339 -304.633444) (xy 36.579036 -304.591848) (xy 36.559745 -304.546572)
			(xy 36.547968 -304.498788) (xy 36.544008 -304.449734) (xy 0.508 -304.449734) (xy 0.508 -305.19751)
			(xy 17.638266 -305.19751) (xy 17.642339 -305.141851) (xy 17.654474 -305.087378) (xy 17.67441 -305.035252)
			(xy 17.701724 -304.986584) (xy 17.735832 -304.942412) (xy 17.776009 -304.903677) (xy 17.821397 -304.871205)
			(xy 17.871029 -304.845687) (xy 17.923849 -304.827668) (xy 17.978728 -304.817531) (xy 18.034499 -304.815493)
			(xy 18.089973 -304.821596) (xy 18.143966 -304.835712) (xy 18.195329 -304.857539) (xy 18.242967 -304.886612)
			(xy 18.285863 -304.922311) (xy 18.323105 -304.963875) (xy 18.353899 -305.010419) (xy 18.377587 -305.06095)
			(xy 18.393665 -305.114392) (xy 18.401791 -305.169606) (xy 18.4023 -305.19751) (xy 18.401791 -305.225414)
			(xy 18.393665 -305.280628) (xy 18.377587 -305.33407) (xy 18.353899 -305.384601) (xy 18.343745 -305.399948)
			(xy 38.444182 -305.399948) (xy 38.448142 -305.350894) (xy 38.459919 -305.30311) (xy 38.47921 -305.257834)
			(xy 38.505513 -305.216238) (xy 38.538148 -305.179401) (xy 38.576269 -305.148276) (xy 38.61889 -305.123669)
			(xy 38.664906 -305.106217) (xy 38.713125 -305.096373) (xy 38.7623 -305.094392) (xy 38.811155 -305.100324)
			(xy 38.858426 -305.114016) (xy 38.902888 -305.135114) (xy 38.943391 -305.16307) (xy 38.978884 -305.197162)
			(xy 39.008449 -305.236506) (xy 39.03132 -305.280083) (xy 39.046904 -305.326764) (xy 39.054799 -305.375341)
			(xy 39.055294 -305.399948) (xy 39.394142 -305.399948) (xy 39.398102 -305.350894) (xy 39.409879 -305.30311)
			(xy 39.42917 -305.257834) (xy 39.455473 -305.216238) (xy 39.488108 -305.179401) (xy 39.526229 -305.148276)
			(xy 39.56885 -305.123669) (xy 39.614866 -305.106217) (xy 39.663085 -305.096373) (xy 39.71226 -305.094392)
			(xy 39.761115 -305.100324) (xy 39.808386 -305.114016) (xy 39.852848 -305.135114) (xy 39.893351 -305.16307)
			(xy 39.928844 -305.197162) (xy 39.958409 -305.236506) (xy 39.98128 -305.280083) (xy 39.996864 -305.326764)
			(xy 40.004759 -305.375341) (xy 40.005254 -305.399948) (xy 41.294062 -305.399948) (xy 41.298022 -305.350894)
			(xy 41.309799 -305.30311) (xy 41.32909 -305.257834) (xy 41.355393 -305.216238) (xy 41.388028 -305.179401)
			(xy 41.426149 -305.148276) (xy 41.46877 -305.123669) (xy 41.514786 -305.106217) (xy 41.563005 -305.096373)
			(xy 41.61218 -305.094392) (xy 41.661035 -305.100324) (xy 41.708306 -305.114016) (xy 41.752768 -305.135114)
			(xy 41.793271 -305.16307) (xy 41.828764 -305.197162) (xy 41.858329 -305.236506) (xy 41.8812 -305.280083)
			(xy 41.896784 -305.326764) (xy 41.904679 -305.375341) (xy 41.905174 -305.399948) (xy 42.244022 -305.399948)
			(xy 42.247982 -305.350894) (xy 42.259759 -305.30311) (xy 42.27905 -305.257834) (xy 42.305353 -305.216238)
			(xy 42.337988 -305.179401) (xy 42.376109 -305.148276) (xy 42.41873 -305.123669) (xy 42.464746 -305.106217)
			(xy 42.512965 -305.096373) (xy 42.56214 -305.094392) (xy 42.610995 -305.100324) (xy 42.658266 -305.114016)
			(xy 42.702728 -305.135114) (xy 42.743231 -305.16307) (xy 42.778724 -305.197162) (xy 42.808289 -305.236506)
			(xy 42.83116 -305.280083) (xy 42.846744 -305.326764) (xy 42.854639 -305.375341) (xy 42.855134 -305.399948)
			(xy 76.444106 -305.399948) (xy 76.448066 -305.350894) (xy 76.459843 -305.30311) (xy 76.479134 -305.257834)
			(xy 76.505437 -305.216238) (xy 76.538072 -305.179401) (xy 76.576193 -305.148276) (xy 76.618814 -305.123669)
			(xy 76.66483 -305.106217) (xy 76.713049 -305.096373) (xy 76.762224 -305.094392) (xy 76.811079 -305.100324)
			(xy 76.85835 -305.114016) (xy 76.902812 -305.135114) (xy 76.943315 -305.16307) (xy 76.978808 -305.197162)
			(xy 77.008373 -305.236506) (xy 77.031244 -305.280083) (xy 77.046828 -305.326764) (xy 77.054723 -305.375341)
			(xy 77.055218 -305.399948) (xy 77.394066 -305.399948) (xy 77.398026 -305.350894) (xy 77.409803 -305.30311)
			(xy 77.429094 -305.257834) (xy 77.455397 -305.216238) (xy 77.488032 -305.179401) (xy 77.526153 -305.148276)
			(xy 77.568774 -305.123669) (xy 77.61479 -305.106217) (xy 77.663009 -305.096373) (xy 77.712184 -305.094392)
			(xy 77.761039 -305.100324) (xy 77.80831 -305.114016) (xy 77.852772 -305.135114) (xy 77.893275 -305.16307)
			(xy 77.928768 -305.197162) (xy 77.958333 -305.236506) (xy 77.981204 -305.280083) (xy 77.996788 -305.326764)
			(xy 78.004683 -305.375341) (xy 78.005178 -305.399948) (xy 79.293986 -305.399948) (xy 79.297946 -305.350894)
			(xy 79.309723 -305.30311) (xy 79.329014 -305.257834) (xy 79.355317 -305.216238) (xy 79.387952 -305.179401)
			(xy 79.426073 -305.148276) (xy 79.468694 -305.123669) (xy 79.51471 -305.106217) (xy 79.562929 -305.096373)
			(xy 79.612104 -305.094392) (xy 79.660959 -305.100324) (xy 79.70823 -305.114016) (xy 79.752692 -305.135114)
			(xy 79.793195 -305.16307) (xy 79.828688 -305.197162) (xy 79.858253 -305.236506) (xy 79.881124 -305.280083)
			(xy 79.896708 -305.326764) (xy 79.904603 -305.375341) (xy 79.905098 -305.399948) (xy 80.243946 -305.399948)
			(xy 80.247906 -305.350894) (xy 80.259683 -305.30311) (xy 80.278974 -305.257834) (xy 80.305277 -305.216238)
			(xy 80.337912 -305.179401) (xy 80.376033 -305.148276) (xy 80.418654 -305.123669) (xy 80.46467 -305.106217)
			(xy 80.512889 -305.096373) (xy 80.562064 -305.094392) (xy 80.610919 -305.100324) (xy 80.65819 -305.114016)
			(xy 80.702652 -305.135114) (xy 80.743155 -305.16307) (xy 80.778648 -305.197162) (xy 80.808213 -305.236506)
			(xy 80.831084 -305.280083) (xy 80.846668 -305.326764) (xy 80.854563 -305.375341) (xy 80.855058 -305.399948)
			(xy 154.54428 -305.399948) (xy 154.54824 -305.350894) (xy 154.560017 -305.30311) (xy 154.579308 -305.257834)
			(xy 154.605611 -305.216238) (xy 154.638246 -305.179401) (xy 154.676367 -305.148276) (xy 154.718988 -305.123669)
			(xy 154.765004 -305.106217) (xy 154.813223 -305.096373) (xy 154.862398 -305.094392) (xy 154.911253 -305.100324)
			(xy 154.958524 -305.114016) (xy 155.002986 -305.135114) (xy 155.043489 -305.16307) (xy 155.078982 -305.197162)
			(xy 155.108547 -305.236506) (xy 155.131418 -305.280083) (xy 155.147002 -305.326764) (xy 155.154897 -305.375341)
			(xy 155.155392 -305.399948) (xy 155.49424 -305.399948) (xy 155.4982 -305.350894) (xy 155.509977 -305.30311)
			(xy 155.529268 -305.257834) (xy 155.555571 -305.216238) (xy 155.588206 -305.179401) (xy 155.626327 -305.148276)
			(xy 155.668948 -305.123669) (xy 155.714964 -305.106217) (xy 155.763183 -305.096373) (xy 155.812358 -305.094392)
			(xy 155.861213 -305.100324) (xy 155.908484 -305.114016) (xy 155.952946 -305.135114) (xy 155.993449 -305.16307)
			(xy 156.028942 -305.197162) (xy 156.058507 -305.236506) (xy 156.081378 -305.280083) (xy 156.096962 -305.326764)
			(xy 156.104857 -305.375341) (xy 156.105352 -305.399948) (xy 157.39416 -305.399948) (xy 157.39812 -305.350894)
			(xy 157.409897 -305.30311) (xy 157.429188 -305.257834) (xy 157.455491 -305.216238) (xy 157.488126 -305.179401)
			(xy 157.526247 -305.148276) (xy 157.568868 -305.123669) (xy 157.614884 -305.106217) (xy 157.663103 -305.096373)
			(xy 157.712278 -305.094392) (xy 157.761133 -305.100324) (xy 157.808404 -305.114016) (xy 157.852866 -305.135114)
			(xy 157.893369 -305.16307) (xy 157.928862 -305.197162) (xy 157.958427 -305.236506) (xy 157.981298 -305.280083)
			(xy 157.996882 -305.326764) (xy 158.004777 -305.375341) (xy 158.005272 -305.399948) (xy 158.34412 -305.399948)
			(xy 158.34808 -305.350894) (xy 158.359857 -305.30311) (xy 158.379148 -305.257834) (xy 158.405451 -305.216238)
			(xy 158.438086 -305.179401) (xy 158.476207 -305.148276) (xy 158.518828 -305.123669) (xy 158.564844 -305.106217)
			(xy 158.613063 -305.096373) (xy 158.662238 -305.094392) (xy 158.711093 -305.100324) (xy 158.758364 -305.114016)
			(xy 158.802826 -305.135114) (xy 158.843329 -305.16307) (xy 158.878822 -305.197162) (xy 158.908387 -305.236506)
			(xy 158.931258 -305.280083) (xy 158.946842 -305.326764) (xy 158.954737 -305.375341) (xy 158.955232 -305.399948)
			(xy 192.544204 -305.399948) (xy 192.548164 -305.350894) (xy 192.559941 -305.30311) (xy 192.579232 -305.257834)
			(xy 192.605535 -305.216238) (xy 192.63817 -305.179401) (xy 192.676291 -305.148276) (xy 192.718912 -305.123669)
			(xy 192.764928 -305.106217) (xy 192.813147 -305.096373) (xy 192.862322 -305.094392) (xy 192.911177 -305.100324)
			(xy 192.958448 -305.114016) (xy 193.00291 -305.135114) (xy 193.043413 -305.16307) (xy 193.078906 -305.197162)
			(xy 193.108471 -305.236506) (xy 193.131342 -305.280083) (xy 193.146926 -305.326764) (xy 193.154821 -305.375341)
			(xy 193.155316 -305.399948) (xy 193.494164 -305.399948) (xy 193.498124 -305.350894) (xy 193.509901 -305.30311)
			(xy 193.529192 -305.257834) (xy 193.555495 -305.216238) (xy 193.58813 -305.179401) (xy 193.626251 -305.148276)
			(xy 193.668872 -305.123669) (xy 193.714888 -305.106217) (xy 193.763107 -305.096373) (xy 193.812282 -305.094392)
			(xy 193.861137 -305.100324) (xy 193.908408 -305.114016) (xy 193.95287 -305.135114) (xy 193.993373 -305.16307)
			(xy 194.028866 -305.197162) (xy 194.058431 -305.236506) (xy 194.081302 -305.280083) (xy 194.096886 -305.326764)
			(xy 194.104781 -305.375341) (xy 194.105276 -305.399948) (xy 195.394084 -305.399948) (xy 195.398044 -305.350894)
			(xy 195.409821 -305.30311) (xy 195.429112 -305.257834) (xy 195.455415 -305.216238) (xy 195.48805 -305.179401)
			(xy 195.526171 -305.148276) (xy 195.568792 -305.123669) (xy 195.614808 -305.106217) (xy 195.663027 -305.096373)
			(xy 195.712202 -305.094392) (xy 195.761057 -305.100324) (xy 195.808328 -305.114016) (xy 195.85279 -305.135114)
			(xy 195.893293 -305.16307) (xy 195.928786 -305.197162) (xy 195.958351 -305.236506) (xy 195.981222 -305.280083)
			(xy 195.996806 -305.326764) (xy 196.004701 -305.375341) (xy 196.005196 -305.399948) (xy 196.344044 -305.399948)
			(xy 196.348004 -305.350894) (xy 196.359781 -305.30311) (xy 196.379072 -305.257834) (xy 196.405375 -305.216238)
			(xy 196.43801 -305.179401) (xy 196.476131 -305.148276) (xy 196.518752 -305.123669) (xy 196.564768 -305.106217)
			(xy 196.612987 -305.096373) (xy 196.662162 -305.094392) (xy 196.711017 -305.100324) (xy 196.758288 -305.114016)
			(xy 196.80275 -305.135114) (xy 196.843253 -305.16307) (xy 196.878746 -305.197162) (xy 196.908311 -305.236506)
			(xy 196.931182 -305.280083) (xy 196.946766 -305.326764) (xy 196.954661 -305.375341) (xy 196.955156 -305.399948)
			(xy 270.644124 -305.399948) (xy 270.648084 -305.350894) (xy 270.659861 -305.30311) (xy 270.679152 -305.257834)
			(xy 270.705455 -305.216238) (xy 270.73809 -305.179401) (xy 270.776211 -305.148276) (xy 270.818832 -305.123669)
			(xy 270.864848 -305.106217) (xy 270.913067 -305.096373) (xy 270.962242 -305.094392) (xy 271.011097 -305.100324)
			(xy 271.058368 -305.114016) (xy 271.10283 -305.135114) (xy 271.143333 -305.16307) (xy 271.178826 -305.197162)
			(xy 271.208391 -305.236506) (xy 271.231262 -305.280083) (xy 271.246846 -305.326764) (xy 271.254741 -305.375341)
			(xy 271.255236 -305.399948) (xy 271.594084 -305.399948) (xy 271.598044 -305.350894) (xy 271.609821 -305.30311)
			(xy 271.629112 -305.257834) (xy 271.655415 -305.216238) (xy 271.68805 -305.179401) (xy 271.726171 -305.148276)
			(xy 271.768792 -305.123669) (xy 271.814808 -305.106217) (xy 271.863027 -305.096373) (xy 271.912202 -305.094392)
			(xy 271.961057 -305.100324) (xy 272.008328 -305.114016) (xy 272.05279 -305.135114) (xy 272.093293 -305.16307)
			(xy 272.128786 -305.197162) (xy 272.158351 -305.236506) (xy 272.181222 -305.280083) (xy 272.196806 -305.326764)
			(xy 272.204701 -305.375341) (xy 272.205196 -305.399948) (xy 273.494004 -305.399948) (xy 273.497964 -305.350894)
			(xy 273.509741 -305.30311) (xy 273.529032 -305.257834) (xy 273.555335 -305.216238) (xy 273.58797 -305.179401)
			(xy 273.626091 -305.148276) (xy 273.668712 -305.123669) (xy 273.714728 -305.106217) (xy 273.762947 -305.096373)
			(xy 273.812122 -305.094392) (xy 273.860977 -305.100324) (xy 273.908248 -305.114016) (xy 273.95271 -305.135114)
			(xy 273.993213 -305.16307) (xy 274.028706 -305.197162) (xy 274.058271 -305.236506) (xy 274.081142 -305.280083)
			(xy 274.096726 -305.326764) (xy 274.104621 -305.375341) (xy 274.105116 -305.399948) (xy 274.443964 -305.399948)
			(xy 274.447924 -305.350894) (xy 274.459701 -305.30311) (xy 274.478992 -305.257834) (xy 274.505295 -305.216238)
			(xy 274.53793 -305.179401) (xy 274.576051 -305.148276) (xy 274.618672 -305.123669) (xy 274.664688 -305.106217)
			(xy 274.712907 -305.096373) (xy 274.762082 -305.094392) (xy 274.810937 -305.100324) (xy 274.858208 -305.114016)
			(xy 274.90267 -305.135114) (xy 274.943173 -305.16307) (xy 274.978666 -305.197162) (xy 275.008231 -305.236506)
			(xy 275.031102 -305.280083) (xy 275.046686 -305.326764) (xy 275.054581 -305.375341) (xy 275.055076 -305.399948)
			(xy 308.644048 -305.399948) (xy 308.648008 -305.350894) (xy 308.659785 -305.30311) (xy 308.679076 -305.257834)
			(xy 308.705379 -305.216238) (xy 308.738014 -305.179401) (xy 308.776135 -305.148276) (xy 308.818756 -305.123669)
			(xy 308.864772 -305.106217) (xy 308.912991 -305.096373) (xy 308.962166 -305.094392) (xy 309.011021 -305.100324)
			(xy 309.058292 -305.114016) (xy 309.102754 -305.135114) (xy 309.143257 -305.16307) (xy 309.17875 -305.197162)
			(xy 309.208315 -305.236506) (xy 309.231186 -305.280083) (xy 309.24677 -305.326764) (xy 309.254665 -305.375341)
			(xy 309.25516 -305.399948) (xy 309.594008 -305.399948) (xy 309.597968 -305.350894) (xy 309.609745 -305.30311)
			(xy 309.629036 -305.257834) (xy 309.655339 -305.216238) (xy 309.687974 -305.179401) (xy 309.726095 -305.148276)
			(xy 309.768716 -305.123669) (xy 309.814732 -305.106217) (xy 309.862951 -305.096373) (xy 309.912126 -305.094392)
			(xy 309.960981 -305.100324) (xy 310.008252 -305.114016) (xy 310.052714 -305.135114) (xy 310.093217 -305.16307)
			(xy 310.12871 -305.197162) (xy 310.158275 -305.236506) (xy 310.181146 -305.280083) (xy 310.19673 -305.326764)
			(xy 310.204625 -305.375341) (xy 310.20512 -305.399948) (xy 311.493928 -305.399948) (xy 311.497888 -305.350894)
			(xy 311.509665 -305.30311) (xy 311.528956 -305.257834) (xy 311.555259 -305.216238) (xy 311.587894 -305.179401)
			(xy 311.626015 -305.148276) (xy 311.668636 -305.123669) (xy 311.714652 -305.106217) (xy 311.762871 -305.096373)
			(xy 311.812046 -305.094392) (xy 311.860901 -305.100324) (xy 311.908172 -305.114016) (xy 311.952634 -305.135114)
			(xy 311.993137 -305.16307) (xy 312.02863 -305.197162) (xy 312.058195 -305.236506) (xy 312.081066 -305.280083)
			(xy 312.09665 -305.326764) (xy 312.104545 -305.375341) (xy 312.10504 -305.399948) (xy 312.443888 -305.399948)
			(xy 312.447848 -305.350894) (xy 312.459625 -305.30311) (xy 312.478916 -305.257834) (xy 312.505219 -305.216238)
			(xy 312.537854 -305.179401) (xy 312.575975 -305.148276) (xy 312.618596 -305.123669) (xy 312.664612 -305.106217)
			(xy 312.712831 -305.096373) (xy 312.762006 -305.094392) (xy 312.810861 -305.100324) (xy 312.858132 -305.114016)
			(xy 312.902594 -305.135114) (xy 312.943097 -305.16307) (xy 312.97859 -305.197162) (xy 313.008155 -305.236506)
			(xy 313.031026 -305.280083) (xy 313.04661 -305.326764) (xy 313.054505 -305.375341) (xy 313.055 -305.399948)
			(xy 386.744222 -305.399948) (xy 386.748182 -305.350894) (xy 386.759959 -305.30311) (xy 386.77925 -305.257834)
			(xy 386.805553 -305.216238) (xy 386.838188 -305.179401) (xy 386.876309 -305.148276) (xy 386.91893 -305.123669)
			(xy 386.964946 -305.106217) (xy 387.013165 -305.096373) (xy 387.06234 -305.094392) (xy 387.111195 -305.100324)
			(xy 387.158466 -305.114016) (xy 387.202928 -305.135114) (xy 387.243431 -305.16307) (xy 387.278924 -305.197162)
			(xy 387.308489 -305.236506) (xy 387.33136 -305.280083) (xy 387.346944 -305.326764) (xy 387.354839 -305.375341)
			(xy 387.355334 -305.399948) (xy 387.694182 -305.399948) (xy 387.698142 -305.350894) (xy 387.709919 -305.30311)
			(xy 387.72921 -305.257834) (xy 387.755513 -305.216238) (xy 387.788148 -305.179401) (xy 387.826269 -305.148276)
			(xy 387.86889 -305.123669) (xy 387.914906 -305.106217) (xy 387.963125 -305.096373) (xy 388.0123 -305.094392)
			(xy 388.061155 -305.100324) (xy 388.108426 -305.114016) (xy 388.152888 -305.135114) (xy 388.193391 -305.16307)
			(xy 388.228884 -305.197162) (xy 388.258449 -305.236506) (xy 388.28132 -305.280083) (xy 388.296904 -305.326764)
			(xy 388.304799 -305.375341) (xy 388.305294 -305.399948) (xy 389.594102 -305.399948) (xy 389.598062 -305.350894)
			(xy 389.609839 -305.30311) (xy 389.62913 -305.257834) (xy 389.655433 -305.216238) (xy 389.688068 -305.179401)
			(xy 389.726189 -305.148276) (xy 389.76881 -305.123669) (xy 389.814826 -305.106217) (xy 389.863045 -305.096373)
			(xy 389.91222 -305.094392) (xy 389.961075 -305.100324) (xy 390.008346 -305.114016) (xy 390.052808 -305.135114)
			(xy 390.093311 -305.16307) (xy 390.128804 -305.197162) (xy 390.158369 -305.236506) (xy 390.18124 -305.280083)
			(xy 390.196824 -305.326764) (xy 390.204719 -305.375341) (xy 390.205214 -305.399948) (xy 390.544062 -305.399948)
			(xy 390.548022 -305.350894) (xy 390.559799 -305.30311) (xy 390.57909 -305.257834) (xy 390.605393 -305.216238)
			(xy 390.638028 -305.179401) (xy 390.676149 -305.148276) (xy 390.71877 -305.123669) (xy 390.764786 -305.106217)
			(xy 390.813005 -305.096373) (xy 390.86218 -305.094392) (xy 390.911035 -305.100324) (xy 390.958306 -305.114016)
			(xy 391.002768 -305.135114) (xy 391.043271 -305.16307) (xy 391.078764 -305.197162) (xy 391.108329 -305.236506)
			(xy 391.1312 -305.280083) (xy 391.146784 -305.326764) (xy 391.154679 -305.375341) (xy 391.155174 -305.399948)
			(xy 424.744146 -305.399948) (xy 424.748106 -305.350894) (xy 424.759883 -305.30311) (xy 424.779174 -305.257834)
			(xy 424.805477 -305.216238) (xy 424.838112 -305.179401) (xy 424.876233 -305.148276) (xy 424.918854 -305.123669)
			(xy 424.96487 -305.106217) (xy 425.013089 -305.096373) (xy 425.062264 -305.094392) (xy 425.111119 -305.100324)
			(xy 425.15839 -305.114016) (xy 425.202852 -305.135114) (xy 425.243355 -305.16307) (xy 425.278848 -305.197162)
			(xy 425.308413 -305.236506) (xy 425.331284 -305.280083) (xy 425.346868 -305.326764) (xy 425.354763 -305.375341)
			(xy 425.355258 -305.399948) (xy 425.694106 -305.399948) (xy 425.698066 -305.350894) (xy 425.709843 -305.30311)
			(xy 425.729134 -305.257834) (xy 425.755437 -305.216238) (xy 425.788072 -305.179401) (xy 425.826193 -305.148276)
			(xy 425.868814 -305.123669) (xy 425.91483 -305.106217) (xy 425.963049 -305.096373) (xy 426.012224 -305.094392)
			(xy 426.061079 -305.100324) (xy 426.10835 -305.114016) (xy 426.152812 -305.135114) (xy 426.193315 -305.16307)
			(xy 426.228808 -305.197162) (xy 426.258373 -305.236506) (xy 426.281244 -305.280083) (xy 426.296828 -305.326764)
			(xy 426.304723 -305.375341) (xy 426.305218 -305.399948) (xy 427.594026 -305.399948) (xy 427.597986 -305.350894)
			(xy 427.609763 -305.30311) (xy 427.629054 -305.257834) (xy 427.655357 -305.216238) (xy 427.687992 -305.179401)
			(xy 427.726113 -305.148276) (xy 427.768734 -305.123669) (xy 427.81475 -305.106217) (xy 427.862969 -305.096373)
			(xy 427.912144 -305.094392) (xy 427.960999 -305.100324) (xy 428.00827 -305.114016) (xy 428.052732 -305.135114)
			(xy 428.093235 -305.16307) (xy 428.128728 -305.197162) (xy 428.158293 -305.236506) (xy 428.181164 -305.280083)
			(xy 428.196748 -305.326764) (xy 428.204643 -305.375341) (xy 428.205138 -305.399948) (xy 428.543986 -305.399948)
			(xy 428.547946 -305.350894) (xy 428.559723 -305.30311) (xy 428.579014 -305.257834) (xy 428.605317 -305.216238)
			(xy 428.637952 -305.179401) (xy 428.676073 -305.148276) (xy 428.718694 -305.123669) (xy 428.76471 -305.106217)
			(xy 428.812929 -305.096373) (xy 428.862104 -305.094392) (xy 428.910959 -305.100324) (xy 428.95823 -305.114016)
			(xy 429.002692 -305.135114) (xy 429.043195 -305.16307) (xy 429.078688 -305.197162) (xy 429.108253 -305.236506)
			(xy 429.131124 -305.280083) (xy 429.146708 -305.326764) (xy 429.154603 -305.375341) (xy 429.155098 -305.399948)
			(xy 429.154603 -305.424555) (xy 429.146708 -305.473132) (xy 429.131124 -305.519813) (xy 429.108253 -305.56339)
			(xy 429.078688 -305.602734) (xy 429.043195 -305.636826) (xy 429.002692 -305.664782) (xy 428.95823 -305.68588)
			(xy 428.910959 -305.699572) (xy 428.862104 -305.705504) (xy 428.812929 -305.703523) (xy 428.76471 -305.693679)
			(xy 428.718694 -305.676227) (xy 428.676073 -305.65162) (xy 428.637952 -305.620495) (xy 428.605317 -305.583658)
			(xy 428.579014 -305.542062) (xy 428.559723 -305.496786) (xy 428.547946 -305.449002) (xy 428.543986 -305.399948)
			(xy 428.205138 -305.399948) (xy 428.204643 -305.424555) (xy 428.196748 -305.473132) (xy 428.181164 -305.519813)
			(xy 428.158293 -305.56339) (xy 428.128728 -305.602734) (xy 428.093235 -305.636826) (xy 428.052732 -305.664782)
			(xy 428.00827 -305.68588) (xy 427.960999 -305.699572) (xy 427.912144 -305.705504) (xy 427.862969 -305.703523)
			(xy 427.81475 -305.693679) (xy 427.768734 -305.676227) (xy 427.726113 -305.65162) (xy 427.687992 -305.620495)
			(xy 427.655357 -305.583658) (xy 427.629054 -305.542062) (xy 427.609763 -305.496786) (xy 427.597986 -305.449002)
			(xy 427.594026 -305.399948) (xy 426.305218 -305.399948) (xy 426.304723 -305.424555) (xy 426.296828 -305.473132)
			(xy 426.281244 -305.519813) (xy 426.258373 -305.56339) (xy 426.228808 -305.602734) (xy 426.193315 -305.636826)
			(xy 426.152812 -305.664782) (xy 426.10835 -305.68588) (xy 426.061079 -305.699572) (xy 426.012224 -305.705504)
			(xy 425.963049 -305.703523) (xy 425.91483 -305.693679) (xy 425.868814 -305.676227) (xy 425.826193 -305.65162)
			(xy 425.788072 -305.620495) (xy 425.755437 -305.583658) (xy 425.729134 -305.542062) (xy 425.709843 -305.496786)
			(xy 425.698066 -305.449002) (xy 425.694106 -305.399948) (xy 425.355258 -305.399948) (xy 425.354763 -305.424555)
			(xy 425.346868 -305.473132) (xy 425.331284 -305.519813) (xy 425.308413 -305.56339) (xy 425.278848 -305.602734)
			(xy 425.243355 -305.636826) (xy 425.202852 -305.664782) (xy 425.15839 -305.68588) (xy 425.111119 -305.699572)
			(xy 425.062264 -305.705504) (xy 425.013089 -305.703523) (xy 424.96487 -305.693679) (xy 424.918854 -305.676227)
			(xy 424.876233 -305.65162) (xy 424.838112 -305.620495) (xy 424.805477 -305.583658) (xy 424.779174 -305.542062)
			(xy 424.759883 -305.496786) (xy 424.748106 -305.449002) (xy 424.744146 -305.399948) (xy 391.155174 -305.399948)
			(xy 391.154679 -305.424555) (xy 391.146784 -305.473132) (xy 391.1312 -305.519813) (xy 391.108329 -305.56339)
			(xy 391.078764 -305.602734) (xy 391.043271 -305.636826) (xy 391.002768 -305.664782) (xy 390.958306 -305.68588)
			(xy 390.911035 -305.699572) (xy 390.86218 -305.705504) (xy 390.813005 -305.703523) (xy 390.764786 -305.693679)
			(xy 390.71877 -305.676227) (xy 390.676149 -305.65162) (xy 390.638028 -305.620495) (xy 390.605393 -305.583658)
			(xy 390.57909 -305.542062) (xy 390.559799 -305.496786) (xy 390.548022 -305.449002) (xy 390.544062 -305.399948)
			(xy 390.205214 -305.399948) (xy 390.204719 -305.424555) (xy 390.196824 -305.473132) (xy 390.18124 -305.519813)
			(xy 390.158369 -305.56339) (xy 390.128804 -305.602734) (xy 390.093311 -305.636826) (xy 390.052808 -305.664782)
			(xy 390.008346 -305.68588) (xy 389.961075 -305.699572) (xy 389.91222 -305.705504) (xy 389.863045 -305.703523)
			(xy 389.814826 -305.693679) (xy 389.76881 -305.676227) (xy 389.726189 -305.65162) (xy 389.688068 -305.620495)
			(xy 389.655433 -305.583658) (xy 389.62913 -305.542062) (xy 389.609839 -305.496786) (xy 389.598062 -305.449002)
			(xy 389.594102 -305.399948) (xy 388.305294 -305.399948) (xy 388.304799 -305.424555) (xy 388.296904 -305.473132)
			(xy 388.28132 -305.519813) (xy 388.258449 -305.56339) (xy 388.228884 -305.602734) (xy 388.193391 -305.636826)
			(xy 388.152888 -305.664782) (xy 388.108426 -305.68588) (xy 388.061155 -305.699572) (xy 388.0123 -305.705504)
			(xy 387.963125 -305.703523) (xy 387.914906 -305.693679) (xy 387.86889 -305.676227) (xy 387.826269 -305.65162)
			(xy 387.788148 -305.620495) (xy 387.755513 -305.583658) (xy 387.72921 -305.542062) (xy 387.709919 -305.496786)
			(xy 387.698142 -305.449002) (xy 387.694182 -305.399948) (xy 387.355334 -305.399948) (xy 387.354839 -305.424555)
			(xy 387.346944 -305.473132) (xy 387.33136 -305.519813) (xy 387.308489 -305.56339) (xy 387.278924 -305.602734)
			(xy 387.243431 -305.636826) (xy 387.202928 -305.664782) (xy 387.158466 -305.68588) (xy 387.111195 -305.699572)
			(xy 387.06234 -305.705504) (xy 387.013165 -305.703523) (xy 386.964946 -305.693679) (xy 386.91893 -305.676227)
			(xy 386.876309 -305.65162) (xy 386.838188 -305.620495) (xy 386.805553 -305.583658) (xy 386.77925 -305.542062)
			(xy 386.759959 -305.496786) (xy 386.748182 -305.449002) (xy 386.744222 -305.399948) (xy 313.055 -305.399948)
			(xy 313.054505 -305.424555) (xy 313.04661 -305.473132) (xy 313.031026 -305.519813) (xy 313.008155 -305.56339)
			(xy 312.97859 -305.602734) (xy 312.943097 -305.636826) (xy 312.902594 -305.664782) (xy 312.858132 -305.68588)
			(xy 312.810861 -305.699572) (xy 312.762006 -305.705504) (xy 312.712831 -305.703523) (xy 312.664612 -305.693679)
			(xy 312.618596 -305.676227) (xy 312.575975 -305.65162) (xy 312.537854 -305.620495) (xy 312.505219 -305.583658)
			(xy 312.478916 -305.542062) (xy 312.459625 -305.496786) (xy 312.447848 -305.449002) (xy 312.443888 -305.399948)
			(xy 312.10504 -305.399948) (xy 312.104545 -305.424555) (xy 312.09665 -305.473132) (xy 312.081066 -305.519813)
			(xy 312.058195 -305.56339) (xy 312.02863 -305.602734) (xy 311.993137 -305.636826) (xy 311.952634 -305.664782)
			(xy 311.908172 -305.68588) (xy 311.860901 -305.699572) (xy 311.812046 -305.705504) (xy 311.762871 -305.703523)
			(xy 311.714652 -305.693679) (xy 311.668636 -305.676227) (xy 311.626015 -305.65162) (xy 311.587894 -305.620495)
			(xy 311.555259 -305.583658) (xy 311.528956 -305.542062) (xy 311.509665 -305.496786) (xy 311.497888 -305.449002)
			(xy 311.493928 -305.399948) (xy 310.20512 -305.399948) (xy 310.204625 -305.424555) (xy 310.19673 -305.473132)
			(xy 310.181146 -305.519813) (xy 310.158275 -305.56339) (xy 310.12871 -305.602734) (xy 310.093217 -305.636826)
			(xy 310.052714 -305.664782) (xy 310.008252 -305.68588) (xy 309.960981 -305.699572) (xy 309.912126 -305.705504)
			(xy 309.862951 -305.703523) (xy 309.814732 -305.693679) (xy 309.768716 -305.676227) (xy 309.726095 -305.65162)
			(xy 309.687974 -305.620495) (xy 309.655339 -305.583658) (xy 309.629036 -305.542062) (xy 309.609745 -305.496786)
			(xy 309.597968 -305.449002) (xy 309.594008 -305.399948) (xy 309.25516 -305.399948) (xy 309.254665 -305.424555)
			(xy 309.24677 -305.473132) (xy 309.231186 -305.519813) (xy 309.208315 -305.56339) (xy 309.17875 -305.602734)
			(xy 309.143257 -305.636826) (xy 309.102754 -305.664782) (xy 309.058292 -305.68588) (xy 309.011021 -305.699572)
			(xy 308.962166 -305.705504) (xy 308.912991 -305.703523) (xy 308.864772 -305.693679) (xy 308.818756 -305.676227)
			(xy 308.776135 -305.65162) (xy 308.738014 -305.620495) (xy 308.705379 -305.583658) (xy 308.679076 -305.542062)
			(xy 308.659785 -305.496786) (xy 308.648008 -305.449002) (xy 308.644048 -305.399948) (xy 275.055076 -305.399948)
			(xy 275.054581 -305.424555) (xy 275.046686 -305.473132) (xy 275.031102 -305.519813) (xy 275.008231 -305.56339)
			(xy 274.978666 -305.602734) (xy 274.943173 -305.636826) (xy 274.90267 -305.664782) (xy 274.858208 -305.68588)
			(xy 274.810937 -305.699572) (xy 274.762082 -305.705504) (xy 274.712907 -305.703523) (xy 274.664688 -305.693679)
			(xy 274.618672 -305.676227) (xy 274.576051 -305.65162) (xy 274.53793 -305.620495) (xy 274.505295 -305.583658)
			(xy 274.478992 -305.542062) (xy 274.459701 -305.496786) (xy 274.447924 -305.449002) (xy 274.443964 -305.399948)
			(xy 274.105116 -305.399948) (xy 274.104621 -305.424555) (xy 274.096726 -305.473132) (xy 274.081142 -305.519813)
			(xy 274.058271 -305.56339) (xy 274.028706 -305.602734) (xy 273.993213 -305.636826) (xy 273.95271 -305.664782)
			(xy 273.908248 -305.68588) (xy 273.860977 -305.699572) (xy 273.812122 -305.705504) (xy 273.762947 -305.703523)
			(xy 273.714728 -305.693679) (xy 273.668712 -305.676227) (xy 273.626091 -305.65162) (xy 273.58797 -305.620495)
			(xy 273.555335 -305.583658) (xy 273.529032 -305.542062) (xy 273.509741 -305.496786) (xy 273.497964 -305.449002)
			(xy 273.494004 -305.399948) (xy 272.205196 -305.399948) (xy 272.204701 -305.424555) (xy 272.196806 -305.473132)
			(xy 272.181222 -305.519813) (xy 272.158351 -305.56339) (xy 272.128786 -305.602734) (xy 272.093293 -305.636826)
			(xy 272.05279 -305.664782) (xy 272.008328 -305.68588) (xy 271.961057 -305.699572) (xy 271.912202 -305.705504)
			(xy 271.863027 -305.703523) (xy 271.814808 -305.693679) (xy 271.768792 -305.676227) (xy 271.726171 -305.65162)
			(xy 271.68805 -305.620495) (xy 271.655415 -305.583658) (xy 271.629112 -305.542062) (xy 271.609821 -305.496786)
			(xy 271.598044 -305.449002) (xy 271.594084 -305.399948) (xy 271.255236 -305.399948) (xy 271.254741 -305.424555)
			(xy 271.246846 -305.473132) (xy 271.231262 -305.519813) (xy 271.208391 -305.56339) (xy 271.178826 -305.602734)
			(xy 271.143333 -305.636826) (xy 271.10283 -305.664782) (xy 271.058368 -305.68588) (xy 271.011097 -305.699572)
			(xy 270.962242 -305.705504) (xy 270.913067 -305.703523) (xy 270.864848 -305.693679) (xy 270.818832 -305.676227)
			(xy 270.776211 -305.65162) (xy 270.73809 -305.620495) (xy 270.705455 -305.583658) (xy 270.679152 -305.542062)
			(xy 270.659861 -305.496786) (xy 270.648084 -305.449002) (xy 270.644124 -305.399948) (xy 196.955156 -305.399948)
			(xy 196.954661 -305.424555) (xy 196.946766 -305.473132) (xy 196.931182 -305.519813) (xy 196.908311 -305.56339)
			(xy 196.878746 -305.602734) (xy 196.843253 -305.636826) (xy 196.80275 -305.664782) (xy 196.758288 -305.68588)
			(xy 196.711017 -305.699572) (xy 196.662162 -305.705504) (xy 196.612987 -305.703523) (xy 196.564768 -305.693679)
			(xy 196.518752 -305.676227) (xy 196.476131 -305.65162) (xy 196.43801 -305.620495) (xy 196.405375 -305.583658)
			(xy 196.379072 -305.542062) (xy 196.359781 -305.496786) (xy 196.348004 -305.449002) (xy 196.344044 -305.399948)
			(xy 196.005196 -305.399948) (xy 196.004701 -305.424555) (xy 195.996806 -305.473132) (xy 195.981222 -305.519813)
			(xy 195.958351 -305.56339) (xy 195.928786 -305.602734) (xy 195.893293 -305.636826) (xy 195.85279 -305.664782)
			(xy 195.808328 -305.68588) (xy 195.761057 -305.699572) (xy 195.712202 -305.705504) (xy 195.663027 -305.703523)
			(xy 195.614808 -305.693679) (xy 195.568792 -305.676227) (xy 195.526171 -305.65162) (xy 195.48805 -305.620495)
			(xy 195.455415 -305.583658) (xy 195.429112 -305.542062) (xy 195.409821 -305.496786) (xy 195.398044 -305.449002)
			(xy 195.394084 -305.399948) (xy 194.105276 -305.399948) (xy 194.104781 -305.424555) (xy 194.096886 -305.473132)
			(xy 194.081302 -305.519813) (xy 194.058431 -305.56339) (xy 194.028866 -305.602734) (xy 193.993373 -305.636826)
			(xy 193.95287 -305.664782) (xy 193.908408 -305.68588) (xy 193.861137 -305.699572) (xy 193.812282 -305.705504)
			(xy 193.763107 -305.703523) (xy 193.714888 -305.693679) (xy 193.668872 -305.676227) (xy 193.626251 -305.65162)
			(xy 193.58813 -305.620495) (xy 193.555495 -305.583658) (xy 193.529192 -305.542062) (xy 193.509901 -305.496786)
			(xy 193.498124 -305.449002) (xy 193.494164 -305.399948) (xy 193.155316 -305.399948) (xy 193.154821 -305.424555)
			(xy 193.146926 -305.473132) (xy 193.131342 -305.519813) (xy 193.108471 -305.56339) (xy 193.078906 -305.602734)
			(xy 193.043413 -305.636826) (xy 193.00291 -305.664782) (xy 192.958448 -305.68588) (xy 192.911177 -305.699572)
			(xy 192.862322 -305.705504) (xy 192.813147 -305.703523) (xy 192.764928 -305.693679) (xy 192.718912 -305.676227)
			(xy 192.676291 -305.65162) (xy 192.63817 -305.620495) (xy 192.605535 -305.583658) (xy 192.579232 -305.542062)
			(xy 192.559941 -305.496786) (xy 192.548164 -305.449002) (xy 192.544204 -305.399948) (xy 158.955232 -305.399948)
			(xy 158.954737 -305.424555) (xy 158.946842 -305.473132) (xy 158.931258 -305.519813) (xy 158.908387 -305.56339)
			(xy 158.878822 -305.602734) (xy 158.843329 -305.636826) (xy 158.802826 -305.664782) (xy 158.758364 -305.68588)
			(xy 158.711093 -305.699572) (xy 158.662238 -305.705504) (xy 158.613063 -305.703523) (xy 158.564844 -305.693679)
			(xy 158.518828 -305.676227) (xy 158.476207 -305.65162) (xy 158.438086 -305.620495) (xy 158.405451 -305.583658)
			(xy 158.379148 -305.542062) (xy 158.359857 -305.496786) (xy 158.34808 -305.449002) (xy 158.34412 -305.399948)
			(xy 158.005272 -305.399948) (xy 158.004777 -305.424555) (xy 157.996882 -305.473132) (xy 157.981298 -305.519813)
			(xy 157.958427 -305.56339) (xy 157.928862 -305.602734) (xy 157.893369 -305.636826) (xy 157.852866 -305.664782)
			(xy 157.808404 -305.68588) (xy 157.761133 -305.699572) (xy 157.712278 -305.705504) (xy 157.663103 -305.703523)
			(xy 157.614884 -305.693679) (xy 157.568868 -305.676227) (xy 157.526247 -305.65162) (xy 157.488126 -305.620495)
			(xy 157.455491 -305.583658) (xy 157.429188 -305.542062) (xy 157.409897 -305.496786) (xy 157.39812 -305.449002)
			(xy 157.39416 -305.399948) (xy 156.105352 -305.399948) (xy 156.104857 -305.424555) (xy 156.096962 -305.473132)
			(xy 156.081378 -305.519813) (xy 156.058507 -305.56339) (xy 156.028942 -305.602734) (xy 155.993449 -305.636826)
			(xy 155.952946 -305.664782) (xy 155.908484 -305.68588) (xy 155.861213 -305.699572) (xy 155.812358 -305.705504)
			(xy 155.763183 -305.703523) (xy 155.714964 -305.693679) (xy 155.668948 -305.676227) (xy 155.626327 -305.65162)
			(xy 155.588206 -305.620495) (xy 155.555571 -305.583658) (xy 155.529268 -305.542062) (xy 155.509977 -305.496786)
			(xy 155.4982 -305.449002) (xy 155.49424 -305.399948) (xy 155.155392 -305.399948) (xy 155.154897 -305.424555)
			(xy 155.147002 -305.473132) (xy 155.131418 -305.519813) (xy 155.108547 -305.56339) (xy 155.078982 -305.602734)
			(xy 155.043489 -305.636826) (xy 155.002986 -305.664782) (xy 154.958524 -305.68588) (xy 154.911253 -305.699572)
			(xy 154.862398 -305.705504) (xy 154.813223 -305.703523) (xy 154.765004 -305.693679) (xy 154.718988 -305.676227)
			(xy 154.676367 -305.65162) (xy 154.638246 -305.620495) (xy 154.605611 -305.583658) (xy 154.579308 -305.542062)
			(xy 154.560017 -305.496786) (xy 154.54824 -305.449002) (xy 154.54428 -305.399948) (xy 80.855058 -305.399948)
			(xy 80.854563 -305.424555) (xy 80.846668 -305.473132) (xy 80.831084 -305.519813) (xy 80.808213 -305.56339)
			(xy 80.778648 -305.602734) (xy 80.743155 -305.636826) (xy 80.702652 -305.664782) (xy 80.65819 -305.68588)
			(xy 80.610919 -305.699572) (xy 80.562064 -305.705504) (xy 80.512889 -305.703523) (xy 80.46467 -305.693679)
			(xy 80.418654 -305.676227) (xy 80.376033 -305.65162) (xy 80.337912 -305.620495) (xy 80.305277 -305.583658)
			(xy 80.278974 -305.542062) (xy 80.259683 -305.496786) (xy 80.247906 -305.449002) (xy 80.243946 -305.399948)
			(xy 79.905098 -305.399948) (xy 79.904603 -305.424555) (xy 79.896708 -305.473132) (xy 79.881124 -305.519813)
			(xy 79.858253 -305.56339) (xy 79.828688 -305.602734) (xy 79.793195 -305.636826) (xy 79.752692 -305.664782)
			(xy 79.70823 -305.68588) (xy 79.660959 -305.699572) (xy 79.612104 -305.705504) (xy 79.562929 -305.703523)
			(xy 79.51471 -305.693679) (xy 79.468694 -305.676227) (xy 79.426073 -305.65162) (xy 79.387952 -305.620495)
			(xy 79.355317 -305.583658) (xy 79.329014 -305.542062) (xy 79.309723 -305.496786) (xy 79.297946 -305.449002)
			(xy 79.293986 -305.399948) (xy 78.005178 -305.399948) (xy 78.004683 -305.424555) (xy 77.996788 -305.473132)
			(xy 77.981204 -305.519813) (xy 77.958333 -305.56339) (xy 77.928768 -305.602734) (xy 77.893275 -305.636826)
			(xy 77.852772 -305.664782) (xy 77.80831 -305.68588) (xy 77.761039 -305.699572) (xy 77.712184 -305.705504)
			(xy 77.663009 -305.703523) (xy 77.61479 -305.693679) (xy 77.568774 -305.676227) (xy 77.526153 -305.65162)
			(xy 77.488032 -305.620495) (xy 77.455397 -305.583658) (xy 77.429094 -305.542062) (xy 77.409803 -305.496786)
			(xy 77.398026 -305.449002) (xy 77.394066 -305.399948) (xy 77.055218 -305.399948) (xy 77.054723 -305.424555)
			(xy 77.046828 -305.473132) (xy 77.031244 -305.519813) (xy 77.008373 -305.56339) (xy 76.978808 -305.602734)
			(xy 76.943315 -305.636826) (xy 76.902812 -305.664782) (xy 76.85835 -305.68588) (xy 76.811079 -305.699572)
			(xy 76.762224 -305.705504) (xy 76.713049 -305.703523) (xy 76.66483 -305.693679) (xy 76.618814 -305.676227)
			(xy 76.576193 -305.65162) (xy 76.538072 -305.620495) (xy 76.505437 -305.583658) (xy 76.479134 -305.542062)
			(xy 76.459843 -305.496786) (xy 76.448066 -305.449002) (xy 76.444106 -305.399948) (xy 42.855134 -305.399948)
			(xy 42.854639 -305.424555) (xy 42.846744 -305.473132) (xy 42.83116 -305.519813) (xy 42.808289 -305.56339)
			(xy 42.778724 -305.602734) (xy 42.743231 -305.636826) (xy 42.702728 -305.664782) (xy 42.658266 -305.68588)
			(xy 42.610995 -305.699572) (xy 42.56214 -305.705504) (xy 42.512965 -305.703523) (xy 42.464746 -305.693679)
			(xy 42.41873 -305.676227) (xy 42.376109 -305.65162) (xy 42.337988 -305.620495) (xy 42.305353 -305.583658)
			(xy 42.27905 -305.542062) (xy 42.259759 -305.496786) (xy 42.247982 -305.449002) (xy 42.244022 -305.399948)
			(xy 41.905174 -305.399948) (xy 41.904679 -305.424555) (xy 41.896784 -305.473132) (xy 41.8812 -305.519813)
			(xy 41.858329 -305.56339) (xy 41.828764 -305.602734) (xy 41.793271 -305.636826) (xy 41.752768 -305.664782)
			(xy 41.708306 -305.68588) (xy 41.661035 -305.699572) (xy 41.61218 -305.705504) (xy 41.563005 -305.703523)
			(xy 41.514786 -305.693679) (xy 41.46877 -305.676227) (xy 41.426149 -305.65162) (xy 41.388028 -305.620495)
			(xy 41.355393 -305.583658) (xy 41.32909 -305.542062) (xy 41.309799 -305.496786) (xy 41.298022 -305.449002)
			(xy 41.294062 -305.399948) (xy 40.005254 -305.399948) (xy 40.004759 -305.424555) (xy 39.996864 -305.473132)
			(xy 39.98128 -305.519813) (xy 39.958409 -305.56339) (xy 39.928844 -305.602734) (xy 39.893351 -305.636826)
			(xy 39.852848 -305.664782) (xy 39.808386 -305.68588) (xy 39.761115 -305.699572) (xy 39.71226 -305.705504)
			(xy 39.663085 -305.703523) (xy 39.614866 -305.693679) (xy 39.56885 -305.676227) (xy 39.526229 -305.65162)
			(xy 39.488108 -305.620495) (xy 39.455473 -305.583658) (xy 39.42917 -305.542062) (xy 39.409879 -305.496786)
			(xy 39.398102 -305.449002) (xy 39.394142 -305.399948) (xy 39.055294 -305.399948) (xy 39.054799 -305.424555)
			(xy 39.046904 -305.473132) (xy 39.03132 -305.519813) (xy 39.008449 -305.56339) (xy 38.978884 -305.602734)
			(xy 38.943391 -305.636826) (xy 38.902888 -305.664782) (xy 38.858426 -305.68588) (xy 38.811155 -305.699572)
			(xy 38.7623 -305.705504) (xy 38.713125 -305.703523) (xy 38.664906 -305.693679) (xy 38.61889 -305.676227)
			(xy 38.576269 -305.65162) (xy 38.538148 -305.620495) (xy 38.505513 -305.583658) (xy 38.47921 -305.542062)
			(xy 38.459919 -305.496786) (xy 38.448142 -305.449002) (xy 38.444182 -305.399948) (xy 18.343745 -305.399948)
			(xy 18.323105 -305.431145) (xy 18.285863 -305.472709) (xy 18.242967 -305.508408) (xy 18.195329 -305.537481)
			(xy 18.143966 -305.559308) (xy 18.089973 -305.573424) (xy 18.034499 -305.579527) (xy 17.978728 -305.577489)
			(xy 17.923849 -305.567352) (xy 17.871029 -305.549333) (xy 17.821397 -305.523815) (xy 17.776009 -305.491343)
			(xy 17.735832 -305.452608) (xy 17.701724 -305.408436) (xy 17.67441 -305.359768) (xy 17.654474 -305.307642)
			(xy 17.642339 -305.253169) (xy 17.638266 -305.19751) (xy 0.508 -305.19751) (xy 0.508 -306.28209)
			(xy 17.638266 -306.28209) (xy 17.642339 -306.226431) (xy 17.654474 -306.171958) (xy 17.67441 -306.119832)
			(xy 17.701724 -306.071164) (xy 17.735832 -306.026992) (xy 17.776009 -305.988257) (xy 17.821397 -305.955785)
			(xy 17.871029 -305.930267) (xy 17.923849 -305.912248) (xy 17.978728 -305.902111) (xy 18.034499 -305.900073)
			(xy 18.089973 -305.906176) (xy 18.143966 -305.920292) (xy 18.195329 -305.942119) (xy 18.242967 -305.971192)
			(xy 18.285863 -306.006891) (xy 18.323105 -306.048455) (xy 18.353899 -306.094999) (xy 18.377587 -306.14553)
			(xy 18.393665 -306.198972) (xy 18.401791 -306.254186) (xy 18.4023 -306.28209) (xy 18.401791 -306.309994)
			(xy 18.395917 -306.349908) (xy 36.544008 -306.349908) (xy 36.547968 -306.300854) (xy 36.559745 -306.25307)
			(xy 36.579036 -306.207794) (xy 36.605339 -306.166198) (xy 36.637974 -306.129361) (xy 36.676095 -306.098236)
			(xy 36.718716 -306.073629) (xy 36.764732 -306.056177) (xy 36.812951 -306.046333) (xy 36.862126 -306.044352)
			(xy 36.910981 -306.050284) (xy 36.958252 -306.063976) (xy 37.002714 -306.085074) (xy 37.043217 -306.11303)
			(xy 37.07871 -306.147122) (xy 37.108275 -306.186466) (xy 37.131146 -306.230043) (xy 37.14673 -306.276724)
			(xy 37.154625 -306.325301) (xy 37.15512 -306.349908) (xy 37.493968 -306.349908) (xy 37.497928 -306.300854)
			(xy 37.509705 -306.25307) (xy 37.528996 -306.207794) (xy 37.555299 -306.166198) (xy 37.587934 -306.129361)
			(xy 37.626055 -306.098236) (xy 37.668676 -306.073629) (xy 37.714692 -306.056177) (xy 37.762911 -306.046333)
			(xy 37.812086 -306.044352) (xy 37.860941 -306.050284) (xy 37.908212 -306.063976) (xy 37.952674 -306.085074)
			(xy 37.993177 -306.11303) (xy 38.02867 -306.147122) (xy 38.058235 -306.186466) (xy 38.081106 -306.230043)
			(xy 38.09669 -306.276724) (xy 38.104585 -306.325301) (xy 38.10508 -306.349908) (xy 43.193982 -306.349908)
			(xy 43.197942 -306.300854) (xy 43.209719 -306.25307) (xy 43.22901 -306.207794) (xy 43.255313 -306.166198)
			(xy 43.287948 -306.129361) (xy 43.326069 -306.098236) (xy 43.36869 -306.073629) (xy 43.414706 -306.056177)
			(xy 43.462925 -306.046333) (xy 43.5121 -306.044352) (xy 43.560955 -306.050284) (xy 43.608226 -306.063976)
			(xy 43.652688 -306.085074) (xy 43.693191 -306.11303) (xy 43.728684 -306.147122) (xy 43.758249 -306.186466)
			(xy 43.78112 -306.230043) (xy 43.796704 -306.276724) (xy 43.804599 -306.325301) (xy 43.805094 -306.349908)
			(xy 44.143942 -306.349908) (xy 44.147902 -306.300854) (xy 44.159679 -306.25307) (xy 44.17897 -306.207794)
			(xy 44.205273 -306.166198) (xy 44.237908 -306.129361) (xy 44.276029 -306.098236) (xy 44.31865 -306.073629)
			(xy 44.364666 -306.056177) (xy 44.412885 -306.046333) (xy 44.46206 -306.044352) (xy 44.510915 -306.050284)
			(xy 44.558186 -306.063976) (xy 44.602648 -306.085074) (xy 44.643151 -306.11303) (xy 44.678644 -306.147122)
			(xy 44.708209 -306.186466) (xy 44.73108 -306.230043) (xy 44.746664 -306.276724) (xy 44.754559 -306.325301)
			(xy 44.755054 -306.349908) (xy 74.544186 -306.349908) (xy 74.548146 -306.300854) (xy 74.559923 -306.25307)
			(xy 74.579214 -306.207794) (xy 74.605517 -306.166198) (xy 74.638152 -306.129361) (xy 74.676273 -306.098236)
			(xy 74.718894 -306.073629) (xy 74.76491 -306.056177) (xy 74.813129 -306.046333) (xy 74.862304 -306.044352)
			(xy 74.911159 -306.050284) (xy 74.95843 -306.063976) (xy 75.002892 -306.085074) (xy 75.043395 -306.11303)
			(xy 75.078888 -306.147122) (xy 75.108453 -306.186466) (xy 75.131324 -306.230043) (xy 75.146908 -306.276724)
			(xy 75.154803 -306.325301) (xy 75.155298 -306.349908) (xy 75.494146 -306.349908) (xy 75.498106 -306.300854)
			(xy 75.509883 -306.25307) (xy 75.529174 -306.207794) (xy 75.555477 -306.166198) (xy 75.588112 -306.129361)
			(xy 75.626233 -306.098236) (xy 75.668854 -306.073629) (xy 75.71487 -306.056177) (xy 75.763089 -306.046333)
			(xy 75.812264 -306.044352) (xy 75.861119 -306.050284) (xy 75.90839 -306.063976) (xy 75.952852 -306.085074)
			(xy 75.993355 -306.11303) (xy 76.028848 -306.147122) (xy 76.058413 -306.186466) (xy 76.081284 -306.230043)
			(xy 76.096868 -306.276724) (xy 76.104763 -306.325301) (xy 76.105258 -306.349908) (xy 81.19416 -306.349908)
			(xy 81.19812 -306.300854) (xy 81.209897 -306.25307) (xy 81.229188 -306.207794) (xy 81.255491 -306.166198)
			(xy 81.288126 -306.129361) (xy 81.326247 -306.098236) (xy 81.368868 -306.073629) (xy 81.414884 -306.056177)
			(xy 81.463103 -306.046333) (xy 81.512278 -306.044352) (xy 81.561133 -306.050284) (xy 81.608404 -306.063976)
			(xy 81.652866 -306.085074) (xy 81.693369 -306.11303) (xy 81.728862 -306.147122) (xy 81.758427 -306.186466)
			(xy 81.781298 -306.230043) (xy 81.796882 -306.276724) (xy 81.804777 -306.325301) (xy 81.805272 -306.349908)
			(xy 82.14412 -306.349908) (xy 82.14808 -306.300854) (xy 82.159857 -306.25307) (xy 82.179148 -306.207794)
			(xy 82.205451 -306.166198) (xy 82.238086 -306.129361) (xy 82.276207 -306.098236) (xy 82.318828 -306.073629)
			(xy 82.364844 -306.056177) (xy 82.413063 -306.046333) (xy 82.462238 -306.044352) (xy 82.511093 -306.050284)
			(xy 82.558364 -306.063976) (xy 82.602826 -306.085074) (xy 82.643329 -306.11303) (xy 82.678822 -306.147122)
			(xy 82.708387 -306.186466) (xy 82.731258 -306.230043) (xy 82.746842 -306.276724) (xy 82.754737 -306.325301)
			(xy 82.755232 -306.349908) (xy 152.644106 -306.349908) (xy 152.648066 -306.300854) (xy 152.659843 -306.25307)
			(xy 152.679134 -306.207794) (xy 152.705437 -306.166198) (xy 152.738072 -306.129361) (xy 152.776193 -306.098236)
			(xy 152.818814 -306.073629) (xy 152.86483 -306.056177) (xy 152.913049 -306.046333) (xy 152.962224 -306.044352)
			(xy 153.011079 -306.050284) (xy 153.05835 -306.063976) (xy 153.102812 -306.085074) (xy 153.143315 -306.11303)
			(xy 153.178808 -306.147122) (xy 153.208373 -306.186466) (xy 153.231244 -306.230043) (xy 153.246828 -306.276724)
			(xy 153.254723 -306.325301) (xy 153.255218 -306.349908) (xy 153.594066 -306.349908) (xy 153.598026 -306.300854)
			(xy 153.609803 -306.25307) (xy 153.629094 -306.207794) (xy 153.655397 -306.166198) (xy 153.688032 -306.129361)
			(xy 153.726153 -306.098236) (xy 153.768774 -306.073629) (xy 153.81479 -306.056177) (xy 153.863009 -306.046333)
			(xy 153.912184 -306.044352) (xy 153.961039 -306.050284) (xy 154.00831 -306.063976) (xy 154.052772 -306.085074)
			(xy 154.093275 -306.11303) (xy 154.128768 -306.147122) (xy 154.158333 -306.186466) (xy 154.181204 -306.230043)
			(xy 154.196788 -306.276724) (xy 154.204683 -306.325301) (xy 154.205178 -306.349908) (xy 159.29408 -306.349908)
			(xy 159.29804 -306.300854) (xy 159.309817 -306.25307) (xy 159.329108 -306.207794) (xy 159.355411 -306.166198)
			(xy 159.388046 -306.129361) (xy 159.426167 -306.098236) (xy 159.468788 -306.073629) (xy 159.514804 -306.056177)
			(xy 159.563023 -306.046333) (xy 159.612198 -306.044352) (xy 159.661053 -306.050284) (xy 159.708324 -306.063976)
			(xy 159.752786 -306.085074) (xy 159.793289 -306.11303) (xy 159.828782 -306.147122) (xy 159.858347 -306.186466)
			(xy 159.881218 -306.230043) (xy 159.896802 -306.276724) (xy 159.904697 -306.325301) (xy 159.905192 -306.349908)
			(xy 160.24404 -306.349908) (xy 160.248 -306.300854) (xy 160.259777 -306.25307) (xy 160.279068 -306.207794)
			(xy 160.305371 -306.166198) (xy 160.338006 -306.129361) (xy 160.376127 -306.098236) (xy 160.418748 -306.073629)
			(xy 160.464764 -306.056177) (xy 160.512983 -306.046333) (xy 160.562158 -306.044352) (xy 160.611013 -306.050284)
			(xy 160.658284 -306.063976) (xy 160.702746 -306.085074) (xy 160.743249 -306.11303) (xy 160.778742 -306.147122)
			(xy 160.808307 -306.186466) (xy 160.831178 -306.230043) (xy 160.846762 -306.276724) (xy 160.854657 -306.325301)
			(xy 160.855152 -306.349908) (xy 190.644284 -306.349908) (xy 190.648244 -306.300854) (xy 190.660021 -306.25307)
			(xy 190.679312 -306.207794) (xy 190.705615 -306.166198) (xy 190.73825 -306.129361) (xy 190.776371 -306.098236)
			(xy 190.818992 -306.073629) (xy 190.865008 -306.056177) (xy 190.913227 -306.046333) (xy 190.962402 -306.044352)
			(xy 191.011257 -306.050284) (xy 191.058528 -306.063976) (xy 191.10299 -306.085074) (xy 191.143493 -306.11303)
			(xy 191.178986 -306.147122) (xy 191.208551 -306.186466) (xy 191.231422 -306.230043) (xy 191.247006 -306.276724)
			(xy 191.254901 -306.325301) (xy 191.255396 -306.349908) (xy 191.594244 -306.349908) (xy 191.598204 -306.300854)
			(xy 191.609981 -306.25307) (xy 191.629272 -306.207794) (xy 191.655575 -306.166198) (xy 191.68821 -306.129361)
			(xy 191.726331 -306.098236) (xy 191.768952 -306.073629) (xy 191.814968 -306.056177) (xy 191.863187 -306.046333)
			(xy 191.912362 -306.044352) (xy 191.961217 -306.050284) (xy 192.008488 -306.063976) (xy 192.05295 -306.085074)
			(xy 192.093453 -306.11303) (xy 192.128946 -306.147122) (xy 192.158511 -306.186466) (xy 192.181382 -306.230043)
			(xy 192.196966 -306.276724) (xy 192.204861 -306.325301) (xy 192.205356 -306.349908) (xy 197.294258 -306.349908)
			(xy 197.298218 -306.300854) (xy 197.309995 -306.25307) (xy 197.329286 -306.207794) (xy 197.355589 -306.166198)
			(xy 197.388224 -306.129361) (xy 197.426345 -306.098236) (xy 197.468966 -306.073629) (xy 197.514982 -306.056177)
			(xy 197.563201 -306.046333) (xy 197.612376 -306.044352) (xy 197.661231 -306.050284) (xy 197.708502 -306.063976)
			(xy 197.752964 -306.085074) (xy 197.793467 -306.11303) (xy 197.82896 -306.147122) (xy 197.858525 -306.186466)
			(xy 197.881396 -306.230043) (xy 197.89698 -306.276724) (xy 197.904875 -306.325301) (xy 197.90537 -306.349908)
			(xy 198.244218 -306.349908) (xy 198.248178 -306.300854) (xy 198.259955 -306.25307) (xy 198.279246 -306.207794)
			(xy 198.305549 -306.166198) (xy 198.338184 -306.129361) (xy 198.376305 -306.098236) (xy 198.418926 -306.073629)
			(xy 198.464942 -306.056177) (xy 198.513161 -306.046333) (xy 198.562336 -306.044352) (xy 198.611191 -306.050284)
			(xy 198.658462 -306.063976) (xy 198.702924 -306.085074) (xy 198.743427 -306.11303) (xy 198.77892 -306.147122)
			(xy 198.808485 -306.186466) (xy 198.831356 -306.230043) (xy 198.84694 -306.276724) (xy 198.854835 -306.325301)
			(xy 198.85533 -306.349908) (xy 268.74395 -306.349908) (xy 268.74791 -306.300854) (xy 268.759687 -306.25307)
			(xy 268.778978 -306.207794) (xy 268.805281 -306.166198) (xy 268.837916 -306.129361) (xy 268.876037 -306.098236)
			(xy 268.918658 -306.073629) (xy 268.964674 -306.056177) (xy 269.012893 -306.046333) (xy 269.062068 -306.044352)
			(xy 269.110923 -306.050284) (xy 269.158194 -306.063976) (xy 269.202656 -306.085074) (xy 269.243159 -306.11303)
			(xy 269.278652 -306.147122) (xy 269.308217 -306.186466) (xy 269.331088 -306.230043) (xy 269.346672 -306.276724)
			(xy 269.354567 -306.325301) (xy 269.355062 -306.349908) (xy 269.69391 -306.349908) (xy 269.69787 -306.300854)
			(xy 269.709647 -306.25307) (xy 269.728938 -306.207794) (xy 269.755241 -306.166198) (xy 269.787876 -306.129361)
			(xy 269.825997 -306.098236) (xy 269.868618 -306.073629) (xy 269.914634 -306.056177) (xy 269.962853 -306.046333)
			(xy 270.012028 -306.044352) (xy 270.060883 -306.050284) (xy 270.108154 -306.063976) (xy 270.152616 -306.085074)
			(xy 270.193119 -306.11303) (xy 270.228612 -306.147122) (xy 270.258177 -306.186466) (xy 270.281048 -306.230043)
			(xy 270.296632 -306.276724) (xy 270.304527 -306.325301) (xy 270.305022 -306.349908) (xy 275.393924 -306.349908)
			(xy 275.397884 -306.300854) (xy 275.409661 -306.25307) (xy 275.428952 -306.207794) (xy 275.455255 -306.166198)
			(xy 275.48789 -306.129361) (xy 275.526011 -306.098236) (xy 275.568632 -306.073629) (xy 275.614648 -306.056177)
			(xy 275.662867 -306.046333) (xy 275.712042 -306.044352) (xy 275.760897 -306.050284) (xy 275.808168 -306.063976)
			(xy 275.85263 -306.085074) (xy 275.893133 -306.11303) (xy 275.928626 -306.147122) (xy 275.958191 -306.186466)
			(xy 275.981062 -306.230043) (xy 275.996646 -306.276724) (xy 276.004541 -306.325301) (xy 276.005036 -306.349908)
			(xy 276.343884 -306.349908) (xy 276.347844 -306.300854) (xy 276.359621 -306.25307) (xy 276.378912 -306.207794)
			(xy 276.405215 -306.166198) (xy 276.43785 -306.129361) (xy 276.475971 -306.098236) (xy 276.518592 -306.073629)
			(xy 276.564608 -306.056177) (xy 276.612827 -306.046333) (xy 276.662002 -306.044352) (xy 276.710857 -306.050284)
			(xy 276.758128 -306.063976) (xy 276.80259 -306.085074) (xy 276.843093 -306.11303) (xy 276.878586 -306.147122)
			(xy 276.908151 -306.186466) (xy 276.931022 -306.230043) (xy 276.946606 -306.276724) (xy 276.954501 -306.325301)
			(xy 276.954996 -306.349908) (xy 306.744128 -306.349908) (xy 306.748088 -306.300854) (xy 306.759865 -306.25307)
			(xy 306.779156 -306.207794) (xy 306.805459 -306.166198) (xy 306.838094 -306.129361) (xy 306.876215 -306.098236)
			(xy 306.918836 -306.073629) (xy 306.964852 -306.056177) (xy 307.013071 -306.046333) (xy 307.062246 -306.044352)
			(xy 307.111101 -306.050284) (xy 307.158372 -306.063976) (xy 307.202834 -306.085074) (xy 307.243337 -306.11303)
			(xy 307.27883 -306.147122) (xy 307.308395 -306.186466) (xy 307.331266 -306.230043) (xy 307.34685 -306.276724)
			(xy 307.354745 -306.325301) (xy 307.35524 -306.349908) (xy 307.694088 -306.349908) (xy 307.698048 -306.300854)
			(xy 307.709825 -306.25307) (xy 307.729116 -306.207794) (xy 307.755419 -306.166198) (xy 307.788054 -306.129361)
			(xy 307.826175 -306.098236) (xy 307.868796 -306.073629) (xy 307.914812 -306.056177) (xy 307.963031 -306.046333)
			(xy 308.012206 -306.044352) (xy 308.061061 -306.050284) (xy 308.108332 -306.063976) (xy 308.152794 -306.085074)
			(xy 308.193297 -306.11303) (xy 308.22879 -306.147122) (xy 308.258355 -306.186466) (xy 308.281226 -306.230043)
			(xy 308.29681 -306.276724) (xy 308.304705 -306.325301) (xy 308.3052 -306.349908) (xy 313.394102 -306.349908)
			(xy 313.398062 -306.300854) (xy 313.409839 -306.25307) (xy 313.42913 -306.207794) (xy 313.455433 -306.166198)
			(xy 313.488068 -306.129361) (xy 313.526189 -306.098236) (xy 313.56881 -306.073629) (xy 313.614826 -306.056177)
			(xy 313.663045 -306.046333) (xy 313.71222 -306.044352) (xy 313.761075 -306.050284) (xy 313.808346 -306.063976)
			(xy 313.852808 -306.085074) (xy 313.893311 -306.11303) (xy 313.928804 -306.147122) (xy 313.958369 -306.186466)
			(xy 313.98124 -306.230043) (xy 313.996824 -306.276724) (xy 314.004719 -306.325301) (xy 314.005214 -306.349908)
			(xy 314.344062 -306.349908) (xy 314.348022 -306.300854) (xy 314.359799 -306.25307) (xy 314.37909 -306.207794)
			(xy 314.405393 -306.166198) (xy 314.438028 -306.129361) (xy 314.476149 -306.098236) (xy 314.51877 -306.073629)
			(xy 314.564786 -306.056177) (xy 314.613005 -306.046333) (xy 314.66218 -306.044352) (xy 314.711035 -306.050284)
			(xy 314.758306 -306.063976) (xy 314.802768 -306.085074) (xy 314.843271 -306.11303) (xy 314.878764 -306.147122)
			(xy 314.908329 -306.186466) (xy 314.9312 -306.230043) (xy 314.946784 -306.276724) (xy 314.954679 -306.325301)
			(xy 314.955174 -306.349908) (xy 384.844048 -306.349908) (xy 384.848008 -306.300854) (xy 384.859785 -306.25307)
			(xy 384.879076 -306.207794) (xy 384.905379 -306.166198) (xy 384.938014 -306.129361) (xy 384.976135 -306.098236)
			(xy 385.018756 -306.073629) (xy 385.064772 -306.056177) (xy 385.112991 -306.046333) (xy 385.162166 -306.044352)
			(xy 385.211021 -306.050284) (xy 385.258292 -306.063976) (xy 385.302754 -306.085074) (xy 385.343257 -306.11303)
			(xy 385.37875 -306.147122) (xy 385.408315 -306.186466) (xy 385.431186 -306.230043) (xy 385.44677 -306.276724)
			(xy 385.454665 -306.325301) (xy 385.45516 -306.349908) (xy 385.794008 -306.349908) (xy 385.797968 -306.300854)
			(xy 385.809745 -306.25307) (xy 385.829036 -306.207794) (xy 385.855339 -306.166198) (xy 385.887974 -306.129361)
			(xy 385.926095 -306.098236) (xy 385.968716 -306.073629) (xy 386.014732 -306.056177) (xy 386.062951 -306.046333)
			(xy 386.112126 -306.044352) (xy 386.160981 -306.050284) (xy 386.208252 -306.063976) (xy 386.252714 -306.085074)
			(xy 386.293217 -306.11303) (xy 386.32871 -306.147122) (xy 386.358275 -306.186466) (xy 386.381146 -306.230043)
			(xy 386.39673 -306.276724) (xy 386.404625 -306.325301) (xy 386.40512 -306.349908) (xy 391.494022 -306.349908)
			(xy 391.497982 -306.300854) (xy 391.509759 -306.25307) (xy 391.52905 -306.207794) (xy 391.555353 -306.166198)
			(xy 391.587988 -306.129361) (xy 391.626109 -306.098236) (xy 391.66873 -306.073629) (xy 391.714746 -306.056177)
			(xy 391.762965 -306.046333) (xy 391.81214 -306.044352) (xy 391.860995 -306.050284) (xy 391.908266 -306.063976)
			(xy 391.952728 -306.085074) (xy 391.993231 -306.11303) (xy 392.028724 -306.147122) (xy 392.058289 -306.186466)
			(xy 392.08116 -306.230043) (xy 392.096744 -306.276724) (xy 392.104639 -306.325301) (xy 392.105134 -306.349908)
			(xy 392.443982 -306.349908) (xy 392.447942 -306.300854) (xy 392.459719 -306.25307) (xy 392.47901 -306.207794)
			(xy 392.505313 -306.166198) (xy 392.537948 -306.129361) (xy 392.576069 -306.098236) (xy 392.61869 -306.073629)
			(xy 392.664706 -306.056177) (xy 392.712925 -306.046333) (xy 392.7621 -306.044352) (xy 392.810955 -306.050284)
			(xy 392.858226 -306.063976) (xy 392.902688 -306.085074) (xy 392.943191 -306.11303) (xy 392.978684 -306.147122)
			(xy 393.008249 -306.186466) (xy 393.03112 -306.230043) (xy 393.046704 -306.276724) (xy 393.054599 -306.325301)
			(xy 393.055094 -306.349908) (xy 422.844226 -306.349908) (xy 422.848186 -306.300854) (xy 422.859963 -306.25307)
			(xy 422.879254 -306.207794) (xy 422.905557 -306.166198) (xy 422.938192 -306.129361) (xy 422.976313 -306.098236)
			(xy 423.018934 -306.073629) (xy 423.06495 -306.056177) (xy 423.113169 -306.046333) (xy 423.162344 -306.044352)
			(xy 423.211199 -306.050284) (xy 423.25847 -306.063976) (xy 423.302932 -306.085074) (xy 423.343435 -306.11303)
			(xy 423.378928 -306.147122) (xy 423.408493 -306.186466) (xy 423.431364 -306.230043) (xy 423.446948 -306.276724)
			(xy 423.454843 -306.325301) (xy 423.455338 -306.349908) (xy 423.794186 -306.349908) (xy 423.798146 -306.300854)
			(xy 423.809923 -306.25307) (xy 423.829214 -306.207794) (xy 423.855517 -306.166198) (xy 423.888152 -306.129361)
			(xy 423.926273 -306.098236) (xy 423.968894 -306.073629) (xy 424.01491 -306.056177) (xy 424.063129 -306.046333)
			(xy 424.112304 -306.044352) (xy 424.161159 -306.050284) (xy 424.20843 -306.063976) (xy 424.252892 -306.085074)
			(xy 424.293395 -306.11303) (xy 424.328888 -306.147122) (xy 424.358453 -306.186466) (xy 424.381324 -306.230043)
			(xy 424.396908 -306.276724) (xy 424.404803 -306.325301) (xy 424.405298 -306.349908) (xy 429.4942 -306.349908)
			(xy 429.49816 -306.300854) (xy 429.509937 -306.25307) (xy 429.529228 -306.207794) (xy 429.555531 -306.166198)
			(xy 429.588166 -306.129361) (xy 429.626287 -306.098236) (xy 429.668908 -306.073629) (xy 429.714924 -306.056177)
			(xy 429.763143 -306.046333) (xy 429.812318 -306.044352) (xy 429.861173 -306.050284) (xy 429.908444 -306.063976)
			(xy 429.952906 -306.085074) (xy 429.993409 -306.11303) (xy 430.028902 -306.147122) (xy 430.058467 -306.186466)
			(xy 430.081338 -306.230043) (xy 430.096922 -306.276724) (xy 430.104817 -306.325301) (xy 430.105312 -306.349908)
			(xy 430.44416 -306.349908) (xy 430.44812 -306.300854) (xy 430.459897 -306.25307) (xy 430.479188 -306.207794)
			(xy 430.505491 -306.166198) (xy 430.538126 -306.129361) (xy 430.576247 -306.098236) (xy 430.618868 -306.073629)
			(xy 430.664884 -306.056177) (xy 430.713103 -306.046333) (xy 430.762278 -306.044352) (xy 430.811133 -306.050284)
			(xy 430.858404 -306.063976) (xy 430.902866 -306.085074) (xy 430.943369 -306.11303) (xy 430.978862 -306.147122)
			(xy 431.008427 -306.186466) (xy 431.031298 -306.230043) (xy 431.046882 -306.276724) (xy 431.054777 -306.325301)
			(xy 431.055272 -306.349908) (xy 431.054777 -306.374515) (xy 431.046882 -306.423092) (xy 431.031298 -306.469773)
			(xy 431.008427 -306.51335) (xy 430.978862 -306.552694) (xy 430.943369 -306.586786) (xy 430.902866 -306.614742)
			(xy 430.858404 -306.63584) (xy 430.811133 -306.649532) (xy 430.762278 -306.655464) (xy 430.713103 -306.653483)
			(xy 430.664884 -306.643639) (xy 430.618868 -306.626187) (xy 430.576247 -306.60158) (xy 430.538126 -306.570455)
			(xy 430.505491 -306.533618) (xy 430.479188 -306.492022) (xy 430.459897 -306.446746) (xy 430.44812 -306.398962)
			(xy 430.44416 -306.349908) (xy 430.105312 -306.349908) (xy 430.104817 -306.374515) (xy 430.096922 -306.423092)
			(xy 430.081338 -306.469773) (xy 430.058467 -306.51335) (xy 430.028902 -306.552694) (xy 429.993409 -306.586786)
			(xy 429.952906 -306.614742) (xy 429.908444 -306.63584) (xy 429.861173 -306.649532) (xy 429.812318 -306.655464)
			(xy 429.763143 -306.653483) (xy 429.714924 -306.643639) (xy 429.668908 -306.626187) (xy 429.626287 -306.60158)
			(xy 429.588166 -306.570455) (xy 429.555531 -306.533618) (xy 429.529228 -306.492022) (xy 429.509937 -306.446746)
			(xy 429.49816 -306.398962) (xy 429.4942 -306.349908) (xy 424.405298 -306.349908) (xy 424.404803 -306.374515)
			(xy 424.396908 -306.423092) (xy 424.381324 -306.469773) (xy 424.358453 -306.51335) (xy 424.328888 -306.552694)
			(xy 424.293395 -306.586786) (xy 424.252892 -306.614742) (xy 424.20843 -306.63584) (xy 424.161159 -306.649532)
			(xy 424.112304 -306.655464) (xy 424.063129 -306.653483) (xy 424.01491 -306.643639) (xy 423.968894 -306.626187)
			(xy 423.926273 -306.60158) (xy 423.888152 -306.570455) (xy 423.855517 -306.533618) (xy 423.829214 -306.492022)
			(xy 423.809923 -306.446746) (xy 423.798146 -306.398962) (xy 423.794186 -306.349908) (xy 423.455338 -306.349908)
			(xy 423.454843 -306.374515) (xy 423.446948 -306.423092) (xy 423.431364 -306.469773) (xy 423.408493 -306.51335)
			(xy 423.378928 -306.552694) (xy 423.343435 -306.586786) (xy 423.302932 -306.614742) (xy 423.25847 -306.63584)
			(xy 423.211199 -306.649532) (xy 423.162344 -306.655464) (xy 423.113169 -306.653483) (xy 423.06495 -306.643639)
			(xy 423.018934 -306.626187) (xy 422.976313 -306.60158) (xy 422.938192 -306.570455) (xy 422.905557 -306.533618)
			(xy 422.879254 -306.492022) (xy 422.859963 -306.446746) (xy 422.848186 -306.398962) (xy 422.844226 -306.349908)
			(xy 393.055094 -306.349908) (xy 393.054599 -306.374515) (xy 393.046704 -306.423092) (xy 393.03112 -306.469773)
			(xy 393.008249 -306.51335) (xy 392.978684 -306.552694) (xy 392.943191 -306.586786) (xy 392.902688 -306.614742)
			(xy 392.858226 -306.63584) (xy 392.810955 -306.649532) (xy 392.7621 -306.655464) (xy 392.712925 -306.653483)
			(xy 392.664706 -306.643639) (xy 392.61869 -306.626187) (xy 392.576069 -306.60158) (xy 392.537948 -306.570455)
			(xy 392.505313 -306.533618) (xy 392.47901 -306.492022) (xy 392.459719 -306.446746) (xy 392.447942 -306.398962)
			(xy 392.443982 -306.349908) (xy 392.105134 -306.349908) (xy 392.104639 -306.374515) (xy 392.096744 -306.423092)
			(xy 392.08116 -306.469773) (xy 392.058289 -306.51335) (xy 392.028724 -306.552694) (xy 391.993231 -306.586786)
			(xy 391.952728 -306.614742) (xy 391.908266 -306.63584) (xy 391.860995 -306.649532) (xy 391.81214 -306.655464)
			(xy 391.762965 -306.653483) (xy 391.714746 -306.643639) (xy 391.66873 -306.626187) (xy 391.626109 -306.60158)
			(xy 391.587988 -306.570455) (xy 391.555353 -306.533618) (xy 391.52905 -306.492022) (xy 391.509759 -306.446746)
			(xy 391.497982 -306.398962) (xy 391.494022 -306.349908) (xy 386.40512 -306.349908) (xy 386.404625 -306.374515)
			(xy 386.39673 -306.423092) (xy 386.381146 -306.469773) (xy 386.358275 -306.51335) (xy 386.32871 -306.552694)
			(xy 386.293217 -306.586786) (xy 386.252714 -306.614742) (xy 386.208252 -306.63584) (xy 386.160981 -306.649532)
			(xy 386.112126 -306.655464) (xy 386.062951 -306.653483) (xy 386.014732 -306.643639) (xy 385.968716 -306.626187)
			(xy 385.926095 -306.60158) (xy 385.887974 -306.570455) (xy 385.855339 -306.533618) (xy 385.829036 -306.492022)
			(xy 385.809745 -306.446746) (xy 385.797968 -306.398962) (xy 385.794008 -306.349908) (xy 385.45516 -306.349908)
			(xy 385.454665 -306.374515) (xy 385.44677 -306.423092) (xy 385.431186 -306.469773) (xy 385.408315 -306.51335)
			(xy 385.37875 -306.552694) (xy 385.343257 -306.586786) (xy 385.302754 -306.614742) (xy 385.258292 -306.63584)
			(xy 385.211021 -306.649532) (xy 385.162166 -306.655464) (xy 385.112991 -306.653483) (xy 385.064772 -306.643639)
			(xy 385.018756 -306.626187) (xy 384.976135 -306.60158) (xy 384.938014 -306.570455) (xy 384.905379 -306.533618)
			(xy 384.879076 -306.492022) (xy 384.859785 -306.446746) (xy 384.848008 -306.398962) (xy 384.844048 -306.349908)
			(xy 314.955174 -306.349908) (xy 314.954679 -306.374515) (xy 314.946784 -306.423092) (xy 314.9312 -306.469773)
			(xy 314.908329 -306.51335) (xy 314.878764 -306.552694) (xy 314.843271 -306.586786) (xy 314.802768 -306.614742)
			(xy 314.758306 -306.63584) (xy 314.711035 -306.649532) (xy 314.66218 -306.655464) (xy 314.613005 -306.653483)
			(xy 314.564786 -306.643639) (xy 314.51877 -306.626187) (xy 314.476149 -306.60158) (xy 314.438028 -306.570455)
			(xy 314.405393 -306.533618) (xy 314.37909 -306.492022) (xy 314.359799 -306.446746) (xy 314.348022 -306.398962)
			(xy 314.344062 -306.349908) (xy 314.005214 -306.349908) (xy 314.004719 -306.374515) (xy 313.996824 -306.423092)
			(xy 313.98124 -306.469773) (xy 313.958369 -306.51335) (xy 313.928804 -306.552694) (xy 313.893311 -306.586786)
			(xy 313.852808 -306.614742) (xy 313.808346 -306.63584) (xy 313.761075 -306.649532) (xy 313.71222 -306.655464)
			(xy 313.663045 -306.653483) (xy 313.614826 -306.643639) (xy 313.56881 -306.626187) (xy 313.526189 -306.60158)
			(xy 313.488068 -306.570455) (xy 313.455433 -306.533618) (xy 313.42913 -306.492022) (xy 313.409839 -306.446746)
			(xy 313.398062 -306.398962) (xy 313.394102 -306.349908) (xy 308.3052 -306.349908) (xy 308.304705 -306.374515)
			(xy 308.29681 -306.423092) (xy 308.281226 -306.469773) (xy 308.258355 -306.51335) (xy 308.22879 -306.552694)
			(xy 308.193297 -306.586786) (xy 308.152794 -306.614742) (xy 308.108332 -306.63584) (xy 308.061061 -306.649532)
			(xy 308.012206 -306.655464) (xy 307.963031 -306.653483) (xy 307.914812 -306.643639) (xy 307.868796 -306.626187)
			(xy 307.826175 -306.60158) (xy 307.788054 -306.570455) (xy 307.755419 -306.533618) (xy 307.729116 -306.492022)
			(xy 307.709825 -306.446746) (xy 307.698048 -306.398962) (xy 307.694088 -306.349908) (xy 307.35524 -306.349908)
			(xy 307.354745 -306.374515) (xy 307.34685 -306.423092) (xy 307.331266 -306.469773) (xy 307.308395 -306.51335)
			(xy 307.27883 -306.552694) (xy 307.243337 -306.586786) (xy 307.202834 -306.614742) (xy 307.158372 -306.63584)
			(xy 307.111101 -306.649532) (xy 307.062246 -306.655464) (xy 307.013071 -306.653483) (xy 306.964852 -306.643639)
			(xy 306.918836 -306.626187) (xy 306.876215 -306.60158) (xy 306.838094 -306.570455) (xy 306.805459 -306.533618)
			(xy 306.779156 -306.492022) (xy 306.759865 -306.446746) (xy 306.748088 -306.398962) (xy 306.744128 -306.349908)
			(xy 276.954996 -306.349908) (xy 276.954501 -306.374515) (xy 276.946606 -306.423092) (xy 276.931022 -306.469773)
			(xy 276.908151 -306.51335) (xy 276.878586 -306.552694) (xy 276.843093 -306.586786) (xy 276.80259 -306.614742)
			(xy 276.758128 -306.63584) (xy 276.710857 -306.649532) (xy 276.662002 -306.655464) (xy 276.612827 -306.653483)
			(xy 276.564608 -306.643639) (xy 276.518592 -306.626187) (xy 276.475971 -306.60158) (xy 276.43785 -306.570455)
			(xy 276.405215 -306.533618) (xy 276.378912 -306.492022) (xy 276.359621 -306.446746) (xy 276.347844 -306.398962)
			(xy 276.343884 -306.349908) (xy 276.005036 -306.349908) (xy 276.004541 -306.374515) (xy 275.996646 -306.423092)
			(xy 275.981062 -306.469773) (xy 275.958191 -306.51335) (xy 275.928626 -306.552694) (xy 275.893133 -306.586786)
			(xy 275.85263 -306.614742) (xy 275.808168 -306.63584) (xy 275.760897 -306.649532) (xy 275.712042 -306.655464)
			(xy 275.662867 -306.653483) (xy 275.614648 -306.643639) (xy 275.568632 -306.626187) (xy 275.526011 -306.60158)
			(xy 275.48789 -306.570455) (xy 275.455255 -306.533618) (xy 275.428952 -306.492022) (xy 275.409661 -306.446746)
			(xy 275.397884 -306.398962) (xy 275.393924 -306.349908) (xy 270.305022 -306.349908) (xy 270.304527 -306.374515)
			(xy 270.296632 -306.423092) (xy 270.281048 -306.469773) (xy 270.258177 -306.51335) (xy 270.228612 -306.552694)
			(xy 270.193119 -306.586786) (xy 270.152616 -306.614742) (xy 270.108154 -306.63584) (xy 270.060883 -306.649532)
			(xy 270.012028 -306.655464) (xy 269.962853 -306.653483) (xy 269.914634 -306.643639) (xy 269.868618 -306.626187)
			(xy 269.825997 -306.60158) (xy 269.787876 -306.570455) (xy 269.755241 -306.533618) (xy 269.728938 -306.492022)
			(xy 269.709647 -306.446746) (xy 269.69787 -306.398962) (xy 269.69391 -306.349908) (xy 269.355062 -306.349908)
			(xy 269.354567 -306.374515) (xy 269.346672 -306.423092) (xy 269.331088 -306.469773) (xy 269.308217 -306.51335)
			(xy 269.278652 -306.552694) (xy 269.243159 -306.586786) (xy 269.202656 -306.614742) (xy 269.158194 -306.63584)
			(xy 269.110923 -306.649532) (xy 269.062068 -306.655464) (xy 269.012893 -306.653483) (xy 268.964674 -306.643639)
			(xy 268.918658 -306.626187) (xy 268.876037 -306.60158) (xy 268.837916 -306.570455) (xy 268.805281 -306.533618)
			(xy 268.778978 -306.492022) (xy 268.759687 -306.446746) (xy 268.74791 -306.398962) (xy 268.74395 -306.349908)
			(xy 198.85533 -306.349908) (xy 198.854835 -306.374515) (xy 198.84694 -306.423092) (xy 198.831356 -306.469773)
			(xy 198.808485 -306.51335) (xy 198.77892 -306.552694) (xy 198.743427 -306.586786) (xy 198.702924 -306.614742)
			(xy 198.658462 -306.63584) (xy 198.611191 -306.649532) (xy 198.562336 -306.655464) (xy 198.513161 -306.653483)
			(xy 198.464942 -306.643639) (xy 198.418926 -306.626187) (xy 198.376305 -306.60158) (xy 198.338184 -306.570455)
			(xy 198.305549 -306.533618) (xy 198.279246 -306.492022) (xy 198.259955 -306.446746) (xy 198.248178 -306.398962)
			(xy 198.244218 -306.349908) (xy 197.90537 -306.349908) (xy 197.904875 -306.374515) (xy 197.89698 -306.423092)
			(xy 197.881396 -306.469773) (xy 197.858525 -306.51335) (xy 197.82896 -306.552694) (xy 197.793467 -306.586786)
			(xy 197.752964 -306.614742) (xy 197.708502 -306.63584) (xy 197.661231 -306.649532) (xy 197.612376 -306.655464)
			(xy 197.563201 -306.653483) (xy 197.514982 -306.643639) (xy 197.468966 -306.626187) (xy 197.426345 -306.60158)
			(xy 197.388224 -306.570455) (xy 197.355589 -306.533618) (xy 197.329286 -306.492022) (xy 197.309995 -306.446746)
			(xy 197.298218 -306.398962) (xy 197.294258 -306.349908) (xy 192.205356 -306.349908) (xy 192.204861 -306.374515)
			(xy 192.196966 -306.423092) (xy 192.181382 -306.469773) (xy 192.158511 -306.51335) (xy 192.128946 -306.552694)
			(xy 192.093453 -306.586786) (xy 192.05295 -306.614742) (xy 192.008488 -306.63584) (xy 191.961217 -306.649532)
			(xy 191.912362 -306.655464) (xy 191.863187 -306.653483) (xy 191.814968 -306.643639) (xy 191.768952 -306.626187)
			(xy 191.726331 -306.60158) (xy 191.68821 -306.570455) (xy 191.655575 -306.533618) (xy 191.629272 -306.492022)
			(xy 191.609981 -306.446746) (xy 191.598204 -306.398962) (xy 191.594244 -306.349908) (xy 191.255396 -306.349908)
			(xy 191.254901 -306.374515) (xy 191.247006 -306.423092) (xy 191.231422 -306.469773) (xy 191.208551 -306.51335)
			(xy 191.178986 -306.552694) (xy 191.143493 -306.586786) (xy 191.10299 -306.614742) (xy 191.058528 -306.63584)
			(xy 191.011257 -306.649532) (xy 190.962402 -306.655464) (xy 190.913227 -306.653483) (xy 190.865008 -306.643639)
			(xy 190.818992 -306.626187) (xy 190.776371 -306.60158) (xy 190.73825 -306.570455) (xy 190.705615 -306.533618)
			(xy 190.679312 -306.492022) (xy 190.660021 -306.446746) (xy 190.648244 -306.398962) (xy 190.644284 -306.349908)
			(xy 160.855152 -306.349908) (xy 160.854657 -306.374515) (xy 160.846762 -306.423092) (xy 160.831178 -306.469773)
			(xy 160.808307 -306.51335) (xy 160.778742 -306.552694) (xy 160.743249 -306.586786) (xy 160.702746 -306.614742)
			(xy 160.658284 -306.63584) (xy 160.611013 -306.649532) (xy 160.562158 -306.655464) (xy 160.512983 -306.653483)
			(xy 160.464764 -306.643639) (xy 160.418748 -306.626187) (xy 160.376127 -306.60158) (xy 160.338006 -306.570455)
			(xy 160.305371 -306.533618) (xy 160.279068 -306.492022) (xy 160.259777 -306.446746) (xy 160.248 -306.398962)
			(xy 160.24404 -306.349908) (xy 159.905192 -306.349908) (xy 159.904697 -306.374515) (xy 159.896802 -306.423092)
			(xy 159.881218 -306.469773) (xy 159.858347 -306.51335) (xy 159.828782 -306.552694) (xy 159.793289 -306.586786)
			(xy 159.752786 -306.614742) (xy 159.708324 -306.63584) (xy 159.661053 -306.649532) (xy 159.612198 -306.655464)
			(xy 159.563023 -306.653483) (xy 159.514804 -306.643639) (xy 159.468788 -306.626187) (xy 159.426167 -306.60158)
			(xy 159.388046 -306.570455) (xy 159.355411 -306.533618) (xy 159.329108 -306.492022) (xy 159.309817 -306.446746)
			(xy 159.29804 -306.398962) (xy 159.29408 -306.349908) (xy 154.205178 -306.349908) (xy 154.204683 -306.374515)
			(xy 154.196788 -306.423092) (xy 154.181204 -306.469773) (xy 154.158333 -306.51335) (xy 154.128768 -306.552694)
			(xy 154.093275 -306.586786) (xy 154.052772 -306.614742) (xy 154.00831 -306.63584) (xy 153.961039 -306.649532)
			(xy 153.912184 -306.655464) (xy 153.863009 -306.653483) (xy 153.81479 -306.643639) (xy 153.768774 -306.626187)
			(xy 153.726153 -306.60158) (xy 153.688032 -306.570455) (xy 153.655397 -306.533618) (xy 153.629094 -306.492022)
			(xy 153.609803 -306.446746) (xy 153.598026 -306.398962) (xy 153.594066 -306.349908) (xy 153.255218 -306.349908)
			(xy 153.254723 -306.374515) (xy 153.246828 -306.423092) (xy 153.231244 -306.469773) (xy 153.208373 -306.51335)
			(xy 153.178808 -306.552694) (xy 153.143315 -306.586786) (xy 153.102812 -306.614742) (xy 153.05835 -306.63584)
			(xy 153.011079 -306.649532) (xy 152.962224 -306.655464) (xy 152.913049 -306.653483) (xy 152.86483 -306.643639)
			(xy 152.818814 -306.626187) (xy 152.776193 -306.60158) (xy 152.738072 -306.570455) (xy 152.705437 -306.533618)
			(xy 152.679134 -306.492022) (xy 152.659843 -306.446746) (xy 152.648066 -306.398962) (xy 152.644106 -306.349908)
			(xy 82.755232 -306.349908) (xy 82.754737 -306.374515) (xy 82.746842 -306.423092) (xy 82.731258 -306.469773)
			(xy 82.708387 -306.51335) (xy 82.678822 -306.552694) (xy 82.643329 -306.586786) (xy 82.602826 -306.614742)
			(xy 82.558364 -306.63584) (xy 82.511093 -306.649532) (xy 82.462238 -306.655464) (xy 82.413063 -306.653483)
			(xy 82.364844 -306.643639) (xy 82.318828 -306.626187) (xy 82.276207 -306.60158) (xy 82.238086 -306.570455)
			(xy 82.205451 -306.533618) (xy 82.179148 -306.492022) (xy 82.159857 -306.446746) (xy 82.14808 -306.398962)
			(xy 82.14412 -306.349908) (xy 81.805272 -306.349908) (xy 81.804777 -306.374515) (xy 81.796882 -306.423092)
			(xy 81.781298 -306.469773) (xy 81.758427 -306.51335) (xy 81.728862 -306.552694) (xy 81.693369 -306.586786)
			(xy 81.652866 -306.614742) (xy 81.608404 -306.63584) (xy 81.561133 -306.649532) (xy 81.512278 -306.655464)
			(xy 81.463103 -306.653483) (xy 81.414884 -306.643639) (xy 81.368868 -306.626187) (xy 81.326247 -306.60158)
			(xy 81.288126 -306.570455) (xy 81.255491 -306.533618) (xy 81.229188 -306.492022) (xy 81.209897 -306.446746)
			(xy 81.19812 -306.398962) (xy 81.19416 -306.349908) (xy 76.105258 -306.349908) (xy 76.104763 -306.374515)
			(xy 76.096868 -306.423092) (xy 76.081284 -306.469773) (xy 76.058413 -306.51335) (xy 76.028848 -306.552694)
			(xy 75.993355 -306.586786) (xy 75.952852 -306.614742) (xy 75.90839 -306.63584) (xy 75.861119 -306.649532)
			(xy 75.812264 -306.655464) (xy 75.763089 -306.653483) (xy 75.71487 -306.643639) (xy 75.668854 -306.626187)
			(xy 75.626233 -306.60158) (xy 75.588112 -306.570455) (xy 75.555477 -306.533618) (xy 75.529174 -306.492022)
			(xy 75.509883 -306.446746) (xy 75.498106 -306.398962) (xy 75.494146 -306.349908) (xy 75.155298 -306.349908)
			(xy 75.154803 -306.374515) (xy 75.146908 -306.423092) (xy 75.131324 -306.469773) (xy 75.108453 -306.51335)
			(xy 75.078888 -306.552694) (xy 75.043395 -306.586786) (xy 75.002892 -306.614742) (xy 74.95843 -306.63584)
			(xy 74.911159 -306.649532) (xy 74.862304 -306.655464) (xy 74.813129 -306.653483) (xy 74.76491 -306.643639)
			(xy 74.718894 -306.626187) (xy 74.676273 -306.60158) (xy 74.638152 -306.570455) (xy 74.605517 -306.533618)
			(xy 74.579214 -306.492022) (xy 74.559923 -306.446746) (xy 74.548146 -306.398962) (xy 74.544186 -306.349908)
			(xy 44.755054 -306.349908) (xy 44.754559 -306.374515) (xy 44.746664 -306.423092) (xy 44.73108 -306.469773)
			(xy 44.708209 -306.51335) (xy 44.678644 -306.552694) (xy 44.643151 -306.586786) (xy 44.602648 -306.614742)
			(xy 44.558186 -306.63584) (xy 44.510915 -306.649532) (xy 44.46206 -306.655464) (xy 44.412885 -306.653483)
			(xy 44.364666 -306.643639) (xy 44.31865 -306.626187) (xy 44.276029 -306.60158) (xy 44.237908 -306.570455)
			(xy 44.205273 -306.533618) (xy 44.17897 -306.492022) (xy 44.159679 -306.446746) (xy 44.147902 -306.398962)
			(xy 44.143942 -306.349908) (xy 43.805094 -306.349908) (xy 43.804599 -306.374515) (xy 43.796704 -306.423092)
			(xy 43.78112 -306.469773) (xy 43.758249 -306.51335) (xy 43.728684 -306.552694) (xy 43.693191 -306.586786)
			(xy 43.652688 -306.614742) (xy 43.608226 -306.63584) (xy 43.560955 -306.649532) (xy 43.5121 -306.655464)
			(xy 43.462925 -306.653483) (xy 43.414706 -306.643639) (xy 43.36869 -306.626187) (xy 43.326069 -306.60158)
			(xy 43.287948 -306.570455) (xy 43.255313 -306.533618) (xy 43.22901 -306.492022) (xy 43.209719 -306.446746)
			(xy 43.197942 -306.398962) (xy 43.193982 -306.349908) (xy 38.10508 -306.349908) (xy 38.104585 -306.374515)
			(xy 38.09669 -306.423092) (xy 38.081106 -306.469773) (xy 38.058235 -306.51335) (xy 38.02867 -306.552694)
			(xy 37.993177 -306.586786) (xy 37.952674 -306.614742) (xy 37.908212 -306.63584) (xy 37.860941 -306.649532)
			(xy 37.812086 -306.655464) (xy 37.762911 -306.653483) (xy 37.714692 -306.643639) (xy 37.668676 -306.626187)
			(xy 37.626055 -306.60158) (xy 37.587934 -306.570455) (xy 37.555299 -306.533618) (xy 37.528996 -306.492022)
			(xy 37.509705 -306.446746) (xy 37.497928 -306.398962) (xy 37.493968 -306.349908) (xy 37.15512 -306.349908)
			(xy 37.154625 -306.374515) (xy 37.14673 -306.423092) (xy 37.131146 -306.469773) (xy 37.108275 -306.51335)
			(xy 37.07871 -306.552694) (xy 37.043217 -306.586786) (xy 37.002714 -306.614742) (xy 36.958252 -306.63584)
			(xy 36.910981 -306.649532) (xy 36.862126 -306.655464) (xy 36.812951 -306.653483) (xy 36.764732 -306.643639)
			(xy 36.718716 -306.626187) (xy 36.676095 -306.60158) (xy 36.637974 -306.570455) (xy 36.605339 -306.533618)
			(xy 36.579036 -306.492022) (xy 36.559745 -306.446746) (xy 36.547968 -306.398962) (xy 36.544008 -306.349908)
			(xy 18.395917 -306.349908) (xy 18.393665 -306.365208) (xy 18.377587 -306.41865) (xy 18.353899 -306.469181)
			(xy 18.323105 -306.515725) (xy 18.285863 -306.557289) (xy 18.242967 -306.592988) (xy 18.195329 -306.622061)
			(xy 18.143966 -306.643888) (xy 18.089973 -306.658004) (xy 18.034499 -306.664107) (xy 17.978728 -306.662069)
			(xy 17.923849 -306.651932) (xy 17.871029 -306.633913) (xy 17.821397 -306.608395) (xy 17.776009 -306.575923)
			(xy 17.735832 -306.537188) (xy 17.701724 -306.493016) (xy 17.67441 -306.444348) (xy 17.654474 -306.392222)
			(xy 17.642339 -306.337749) (xy 17.638266 -306.28209) (xy 0.508 -306.28209) (xy 0.508 -307.299868)
			(xy 38.444182 -307.299868) (xy 38.448142 -307.250814) (xy 38.459919 -307.20303) (xy 38.47921 -307.157754)
			(xy 38.505513 -307.116158) (xy 38.538148 -307.079321) (xy 38.576269 -307.048196) (xy 38.61889 -307.023589)
			(xy 38.664906 -307.006137) (xy 38.713125 -306.996293) (xy 38.7623 -306.994312) (xy 38.811155 -307.000244)
			(xy 38.858426 -307.013936) (xy 38.902888 -307.035034) (xy 38.943391 -307.06299) (xy 38.978884 -307.097082)
			(xy 39.008449 -307.136426) (xy 39.03132 -307.180003) (xy 39.046904 -307.226684) (xy 39.054799 -307.275261)
			(xy 39.055294 -307.299868) (xy 39.394142 -307.299868) (xy 39.398102 -307.250814) (xy 39.409879 -307.20303)
			(xy 39.42917 -307.157754) (xy 39.455473 -307.116158) (xy 39.488108 -307.079321) (xy 39.526229 -307.048196)
			(xy 39.56885 -307.023589) (xy 39.614866 -307.006137) (xy 39.663085 -306.996293) (xy 39.71226 -306.994312)
			(xy 39.761115 -307.000244) (xy 39.808386 -307.013936) (xy 39.852848 -307.035034) (xy 39.893351 -307.06299)
			(xy 39.928844 -307.097082) (xy 39.958409 -307.136426) (xy 39.98128 -307.180003) (xy 39.996864 -307.226684)
			(xy 40.004759 -307.275261) (xy 40.005254 -307.299868) (xy 41.294062 -307.299868) (xy 41.298022 -307.250814)
			(xy 41.309799 -307.20303) (xy 41.32909 -307.157754) (xy 41.355393 -307.116158) (xy 41.388028 -307.079321)
			(xy 41.426149 -307.048196) (xy 41.46877 -307.023589) (xy 41.514786 -307.006137) (xy 41.563005 -306.996293)
			(xy 41.61218 -306.994312) (xy 41.661035 -307.000244) (xy 41.708306 -307.013936) (xy 41.752768 -307.035034)
			(xy 41.793271 -307.06299) (xy 41.828764 -307.097082) (xy 41.858329 -307.136426) (xy 41.8812 -307.180003)
			(xy 41.896784 -307.226684) (xy 41.904679 -307.275261) (xy 41.905174 -307.299868) (xy 42.244022 -307.299868)
			(xy 42.247982 -307.250814) (xy 42.259759 -307.20303) (xy 42.27905 -307.157754) (xy 42.305353 -307.116158)
			(xy 42.337988 -307.079321) (xy 42.376109 -307.048196) (xy 42.41873 -307.023589) (xy 42.464746 -307.006137)
			(xy 42.512965 -306.996293) (xy 42.56214 -306.994312) (xy 42.610995 -307.000244) (xy 42.658266 -307.013936)
			(xy 42.702728 -307.035034) (xy 42.743231 -307.06299) (xy 42.778724 -307.097082) (xy 42.808289 -307.136426)
			(xy 42.83116 -307.180003) (xy 42.846744 -307.226684) (xy 42.854639 -307.275261) (xy 42.855134 -307.299868)
			(xy 76.444106 -307.299868) (xy 76.448066 -307.250814) (xy 76.459843 -307.20303) (xy 76.479134 -307.157754)
			(xy 76.505437 -307.116158) (xy 76.538072 -307.079321) (xy 76.576193 -307.048196) (xy 76.618814 -307.023589)
			(xy 76.66483 -307.006137) (xy 76.713049 -306.996293) (xy 76.762224 -306.994312) (xy 76.811079 -307.000244)
			(xy 76.85835 -307.013936) (xy 76.902812 -307.035034) (xy 76.943315 -307.06299) (xy 76.978808 -307.097082)
			(xy 77.008373 -307.136426) (xy 77.031244 -307.180003) (xy 77.046828 -307.226684) (xy 77.054723 -307.275261)
			(xy 77.055218 -307.299868) (xy 77.394066 -307.299868) (xy 77.398026 -307.250814) (xy 77.409803 -307.20303)
			(xy 77.429094 -307.157754) (xy 77.455397 -307.116158) (xy 77.488032 -307.079321) (xy 77.526153 -307.048196)
			(xy 77.568774 -307.023589) (xy 77.61479 -307.006137) (xy 77.663009 -306.996293) (xy 77.712184 -306.994312)
			(xy 77.761039 -307.000244) (xy 77.80831 -307.013936) (xy 77.852772 -307.035034) (xy 77.893275 -307.06299)
			(xy 77.928768 -307.097082) (xy 77.958333 -307.136426) (xy 77.981204 -307.180003) (xy 77.996788 -307.226684)
			(xy 78.004683 -307.275261) (xy 78.005178 -307.299868) (xy 79.293986 -307.299868) (xy 79.297946 -307.250814)
			(xy 79.309723 -307.20303) (xy 79.329014 -307.157754) (xy 79.355317 -307.116158) (xy 79.387952 -307.079321)
			(xy 79.426073 -307.048196) (xy 79.468694 -307.023589) (xy 79.51471 -307.006137) (xy 79.562929 -306.996293)
			(xy 79.612104 -306.994312) (xy 79.660959 -307.000244) (xy 79.70823 -307.013936) (xy 79.752692 -307.035034)
			(xy 79.793195 -307.06299) (xy 79.828688 -307.097082) (xy 79.858253 -307.136426) (xy 79.881124 -307.180003)
			(xy 79.896708 -307.226684) (xy 79.904603 -307.275261) (xy 79.905098 -307.299868) (xy 80.243946 -307.299868)
			(xy 80.247906 -307.250814) (xy 80.259683 -307.20303) (xy 80.278974 -307.157754) (xy 80.305277 -307.116158)
			(xy 80.337912 -307.079321) (xy 80.376033 -307.048196) (xy 80.418654 -307.023589) (xy 80.46467 -307.006137)
			(xy 80.512889 -306.996293) (xy 80.562064 -306.994312) (xy 80.610919 -307.000244) (xy 80.65819 -307.013936)
			(xy 80.702652 -307.035034) (xy 80.743155 -307.06299) (xy 80.778648 -307.097082) (xy 80.808213 -307.136426)
			(xy 80.831084 -307.180003) (xy 80.846668 -307.226684) (xy 80.854563 -307.275261) (xy 80.855058 -307.299868)
			(xy 154.54428 -307.299868) (xy 154.54824 -307.250814) (xy 154.560017 -307.20303) (xy 154.579308 -307.157754)
			(xy 154.605611 -307.116158) (xy 154.638246 -307.079321) (xy 154.676367 -307.048196) (xy 154.718988 -307.023589)
			(xy 154.765004 -307.006137) (xy 154.813223 -306.996293) (xy 154.862398 -306.994312) (xy 154.911253 -307.000244)
			(xy 154.958524 -307.013936) (xy 155.002986 -307.035034) (xy 155.043489 -307.06299) (xy 155.078982 -307.097082)
			(xy 155.108547 -307.136426) (xy 155.131418 -307.180003) (xy 155.147002 -307.226684) (xy 155.154897 -307.275261)
			(xy 155.155392 -307.299868) (xy 155.49424 -307.299868) (xy 155.4982 -307.250814) (xy 155.509977 -307.20303)
			(xy 155.529268 -307.157754) (xy 155.555571 -307.116158) (xy 155.588206 -307.079321) (xy 155.626327 -307.048196)
			(xy 155.668948 -307.023589) (xy 155.714964 -307.006137) (xy 155.763183 -306.996293) (xy 155.812358 -306.994312)
			(xy 155.861213 -307.000244) (xy 155.908484 -307.013936) (xy 155.952946 -307.035034) (xy 155.993449 -307.06299)
			(xy 156.028942 -307.097082) (xy 156.058507 -307.136426) (xy 156.081378 -307.180003) (xy 156.096962 -307.226684)
			(xy 156.104857 -307.275261) (xy 156.105352 -307.299868) (xy 157.39416 -307.299868) (xy 157.39812 -307.250814)
			(xy 157.409897 -307.20303) (xy 157.429188 -307.157754) (xy 157.455491 -307.116158) (xy 157.488126 -307.079321)
			(xy 157.526247 -307.048196) (xy 157.568868 -307.023589) (xy 157.614884 -307.006137) (xy 157.663103 -306.996293)
			(xy 157.712278 -306.994312) (xy 157.761133 -307.000244) (xy 157.808404 -307.013936) (xy 157.852866 -307.035034)
			(xy 157.893369 -307.06299) (xy 157.928862 -307.097082) (xy 157.958427 -307.136426) (xy 157.981298 -307.180003)
			(xy 157.996882 -307.226684) (xy 158.004777 -307.275261) (xy 158.005272 -307.299868) (xy 158.34412 -307.299868)
			(xy 158.34808 -307.250814) (xy 158.359857 -307.20303) (xy 158.379148 -307.157754) (xy 158.405451 -307.116158)
			(xy 158.438086 -307.079321) (xy 158.476207 -307.048196) (xy 158.518828 -307.023589) (xy 158.564844 -307.006137)
			(xy 158.613063 -306.996293) (xy 158.662238 -306.994312) (xy 158.711093 -307.000244) (xy 158.758364 -307.013936)
			(xy 158.802826 -307.035034) (xy 158.843329 -307.06299) (xy 158.878822 -307.097082) (xy 158.908387 -307.136426)
			(xy 158.931258 -307.180003) (xy 158.946842 -307.226684) (xy 158.954737 -307.275261) (xy 158.955232 -307.299868)
			(xy 192.544204 -307.299868) (xy 192.548164 -307.250814) (xy 192.559941 -307.20303) (xy 192.579232 -307.157754)
			(xy 192.605535 -307.116158) (xy 192.63817 -307.079321) (xy 192.676291 -307.048196) (xy 192.718912 -307.023589)
			(xy 192.764928 -307.006137) (xy 192.813147 -306.996293) (xy 192.862322 -306.994312) (xy 192.911177 -307.000244)
			(xy 192.958448 -307.013936) (xy 193.00291 -307.035034) (xy 193.043413 -307.06299) (xy 193.078906 -307.097082)
			(xy 193.108471 -307.136426) (xy 193.131342 -307.180003) (xy 193.146926 -307.226684) (xy 193.154821 -307.275261)
			(xy 193.155316 -307.299868) (xy 193.494164 -307.299868) (xy 193.498124 -307.250814) (xy 193.509901 -307.20303)
			(xy 193.529192 -307.157754) (xy 193.555495 -307.116158) (xy 193.58813 -307.079321) (xy 193.626251 -307.048196)
			(xy 193.668872 -307.023589) (xy 193.714888 -307.006137) (xy 193.763107 -306.996293) (xy 193.812282 -306.994312)
			(xy 193.861137 -307.000244) (xy 193.908408 -307.013936) (xy 193.95287 -307.035034) (xy 193.993373 -307.06299)
			(xy 194.028866 -307.097082) (xy 194.058431 -307.136426) (xy 194.081302 -307.180003) (xy 194.096886 -307.226684)
			(xy 194.104781 -307.275261) (xy 194.105276 -307.299868) (xy 195.394084 -307.299868) (xy 195.398044 -307.250814)
			(xy 195.409821 -307.20303) (xy 195.429112 -307.157754) (xy 195.455415 -307.116158) (xy 195.48805 -307.079321)
			(xy 195.526171 -307.048196) (xy 195.568792 -307.023589) (xy 195.614808 -307.006137) (xy 195.663027 -306.996293)
			(xy 195.712202 -306.994312) (xy 195.761057 -307.000244) (xy 195.808328 -307.013936) (xy 195.85279 -307.035034)
			(xy 195.893293 -307.06299) (xy 195.928786 -307.097082) (xy 195.958351 -307.136426) (xy 195.981222 -307.180003)
			(xy 195.996806 -307.226684) (xy 196.004701 -307.275261) (xy 196.005196 -307.299868) (xy 196.344044 -307.299868)
			(xy 196.348004 -307.250814) (xy 196.359781 -307.20303) (xy 196.379072 -307.157754) (xy 196.405375 -307.116158)
			(xy 196.43801 -307.079321) (xy 196.476131 -307.048196) (xy 196.518752 -307.023589) (xy 196.564768 -307.006137)
			(xy 196.612987 -306.996293) (xy 196.662162 -306.994312) (xy 196.711017 -307.000244) (xy 196.758288 -307.013936)
			(xy 196.80275 -307.035034) (xy 196.843253 -307.06299) (xy 196.878746 -307.097082) (xy 196.908311 -307.136426)
			(xy 196.931182 -307.180003) (xy 196.946766 -307.226684) (xy 196.954661 -307.275261) (xy 196.955156 -307.299868)
			(xy 196.954661 -307.324475) (xy 196.946766 -307.373052) (xy 196.931182 -307.419733) (xy 196.908311 -307.46331)
			(xy 196.892559 -307.484272) (xy 231.935526 -307.484272) (xy 231.939599 -307.428613) (xy 231.951734 -307.37414)
			(xy 231.97167 -307.322014) (xy 231.998984 -307.273346) (xy 232.033092 -307.229174) (xy 232.073269 -307.190439)
			(xy 232.118657 -307.157967) (xy 232.168289 -307.132449) (xy 232.221109 -307.11443) (xy 232.275988 -307.104293)
			(xy 232.331759 -307.102255) (xy 232.387233 -307.108358) (xy 232.441226 -307.122474) (xy 232.492589 -307.144301)
			(xy 232.540227 -307.173374) (xy 232.583123 -307.209073) (xy 232.620365 -307.250637) (xy 232.651159 -307.297181)
			(xy 232.674847 -307.347712) (xy 232.690925 -307.401154) (xy 232.699051 -307.456368) (xy 232.69956 -307.484272)
			(xy 248.185684 -307.484272) (xy 248.189757 -307.428613) (xy 248.201892 -307.37414) (xy 248.221828 -307.322014)
			(xy 248.249142 -307.273346) (xy 248.28325 -307.229174) (xy 248.323427 -307.190439) (xy 248.368815 -307.157967)
			(xy 248.418447 -307.132449) (xy 248.471267 -307.11443) (xy 248.526146 -307.104293) (xy 248.581917 -307.102255)
			(xy 248.637391 -307.108358) (xy 248.691384 -307.122474) (xy 248.742747 -307.144301) (xy 248.790385 -307.173374)
			(xy 248.833281 -307.209073) (xy 248.870523 -307.250637) (xy 248.901317 -307.297181) (xy 248.902577 -307.299868)
			(xy 270.644124 -307.299868) (xy 270.648084 -307.250814) (xy 270.659861 -307.20303) (xy 270.679152 -307.157754)
			(xy 270.705455 -307.116158) (xy 270.73809 -307.079321) (xy 270.776211 -307.048196) (xy 270.818832 -307.023589)
			(xy 270.864848 -307.006137) (xy 270.913067 -306.996293) (xy 270.962242 -306.994312) (xy 271.011097 -307.000244)
			(xy 271.058368 -307.013936) (xy 271.10283 -307.035034) (xy 271.143333 -307.06299) (xy 271.178826 -307.097082)
			(xy 271.208391 -307.136426) (xy 271.231262 -307.180003) (xy 271.246846 -307.226684) (xy 271.254741 -307.275261)
			(xy 271.255236 -307.299868) (xy 271.594084 -307.299868) (xy 271.598044 -307.250814) (xy 271.609821 -307.20303)
			(xy 271.629112 -307.157754) (xy 271.655415 -307.116158) (xy 271.68805 -307.079321) (xy 271.726171 -307.048196)
			(xy 271.768792 -307.023589) (xy 271.814808 -307.006137) (xy 271.863027 -306.996293) (xy 271.912202 -306.994312)
			(xy 271.961057 -307.000244) (xy 272.008328 -307.013936) (xy 272.05279 -307.035034) (xy 272.093293 -307.06299)
			(xy 272.128786 -307.097082) (xy 272.158351 -307.136426) (xy 272.181222 -307.180003) (xy 272.196806 -307.226684)
			(xy 272.204701 -307.275261) (xy 272.205196 -307.299868) (xy 273.494004 -307.299868) (xy 273.497964 -307.250814)
			(xy 273.509741 -307.20303) (xy 273.529032 -307.157754) (xy 273.555335 -307.116158) (xy 273.58797 -307.079321)
			(xy 273.626091 -307.048196) (xy 273.668712 -307.023589) (xy 273.714728 -307.006137) (xy 273.762947 -306.996293)
			(xy 273.812122 -306.994312) (xy 273.860977 -307.000244) (xy 273.908248 -307.013936) (xy 273.95271 -307.035034)
			(xy 273.993213 -307.06299) (xy 274.028706 -307.097082) (xy 274.058271 -307.136426) (xy 274.081142 -307.180003)
			(xy 274.096726 -307.226684) (xy 274.104621 -307.275261) (xy 274.105116 -307.299868) (xy 274.443964 -307.299868)
			(xy 274.447924 -307.250814) (xy 274.459701 -307.20303) (xy 274.478992 -307.157754) (xy 274.505295 -307.116158)
			(xy 274.53793 -307.079321) (xy 274.576051 -307.048196) (xy 274.618672 -307.023589) (xy 274.664688 -307.006137)
			(xy 274.712907 -306.996293) (xy 274.762082 -306.994312) (xy 274.810937 -307.000244) (xy 274.858208 -307.013936)
			(xy 274.90267 -307.035034) (xy 274.943173 -307.06299) (xy 274.978666 -307.097082) (xy 275.008231 -307.136426)
			(xy 275.031102 -307.180003) (xy 275.046686 -307.226684) (xy 275.054581 -307.275261) (xy 275.055076 -307.299868)
			(xy 308.644048 -307.299868) (xy 308.648008 -307.250814) (xy 308.659785 -307.20303) (xy 308.679076 -307.157754)
			(xy 308.705379 -307.116158) (xy 308.738014 -307.079321) (xy 308.776135 -307.048196) (xy 308.818756 -307.023589)
			(xy 308.864772 -307.006137) (xy 308.912991 -306.996293) (xy 308.962166 -306.994312) (xy 309.011021 -307.000244)
			(xy 309.058292 -307.013936) (xy 309.102754 -307.035034) (xy 309.143257 -307.06299) (xy 309.17875 -307.097082)
			(xy 309.208315 -307.136426) (xy 309.231186 -307.180003) (xy 309.24677 -307.226684) (xy 309.254665 -307.275261)
			(xy 309.25516 -307.299868) (xy 309.594008 -307.299868) (xy 309.597968 -307.250814) (xy 309.609745 -307.20303)
			(xy 309.629036 -307.157754) (xy 309.655339 -307.116158) (xy 309.687974 -307.079321) (xy 309.726095 -307.048196)
			(xy 309.768716 -307.023589) (xy 309.814732 -307.006137) (xy 309.862951 -306.996293) (xy 309.912126 -306.994312)
			(xy 309.960981 -307.000244) (xy 310.008252 -307.013936) (xy 310.052714 -307.035034) (xy 310.093217 -307.06299)
			(xy 310.12871 -307.097082) (xy 310.158275 -307.136426) (xy 310.181146 -307.180003) (xy 310.19673 -307.226684)
			(xy 310.204625 -307.275261) (xy 310.20512 -307.299868) (xy 311.493928 -307.299868) (xy 311.497888 -307.250814)
			(xy 311.509665 -307.20303) (xy 311.528956 -307.157754) (xy 311.555259 -307.116158) (xy 311.587894 -307.079321)
			(xy 311.626015 -307.048196) (xy 311.668636 -307.023589) (xy 311.714652 -307.006137) (xy 311.762871 -306.996293)
			(xy 311.812046 -306.994312) (xy 311.860901 -307.000244) (xy 311.908172 -307.013936) (xy 311.952634 -307.035034)
			(xy 311.993137 -307.06299) (xy 312.02863 -307.097082) (xy 312.058195 -307.136426) (xy 312.081066 -307.180003)
			(xy 312.09665 -307.226684) (xy 312.104545 -307.275261) (xy 312.10504 -307.299868) (xy 312.443888 -307.299868)
			(xy 312.447848 -307.250814) (xy 312.459625 -307.20303) (xy 312.478916 -307.157754) (xy 312.505219 -307.116158)
			(xy 312.537854 -307.079321) (xy 312.575975 -307.048196) (xy 312.618596 -307.023589) (xy 312.664612 -307.006137)
			(xy 312.712831 -306.996293) (xy 312.762006 -306.994312) (xy 312.810861 -307.000244) (xy 312.858132 -307.013936)
			(xy 312.902594 -307.035034) (xy 312.943097 -307.06299) (xy 312.97859 -307.097082) (xy 313.008155 -307.136426)
			(xy 313.031026 -307.180003) (xy 313.04661 -307.226684) (xy 313.054505 -307.275261) (xy 313.055 -307.299868)
			(xy 386.744222 -307.299868) (xy 386.748182 -307.250814) (xy 386.759959 -307.20303) (xy 386.77925 -307.157754)
			(xy 386.805553 -307.116158) (xy 386.838188 -307.079321) (xy 386.876309 -307.048196) (xy 386.91893 -307.023589)
			(xy 386.964946 -307.006137) (xy 387.013165 -306.996293) (xy 387.06234 -306.994312) (xy 387.111195 -307.000244)
			(xy 387.158466 -307.013936) (xy 387.202928 -307.035034) (xy 387.243431 -307.06299) (xy 387.278924 -307.097082)
			(xy 387.308489 -307.136426) (xy 387.33136 -307.180003) (xy 387.346944 -307.226684) (xy 387.354839 -307.275261)
			(xy 387.355334 -307.299868) (xy 387.694182 -307.299868) (xy 387.698142 -307.250814) (xy 387.709919 -307.20303)
			(xy 387.72921 -307.157754) (xy 387.755513 -307.116158) (xy 387.788148 -307.079321) (xy 387.826269 -307.048196)
			(xy 387.86889 -307.023589) (xy 387.914906 -307.006137) (xy 387.963125 -306.996293) (xy 388.0123 -306.994312)
			(xy 388.061155 -307.000244) (xy 388.108426 -307.013936) (xy 388.152888 -307.035034) (xy 388.193391 -307.06299)
			(xy 388.228884 -307.097082) (xy 388.258449 -307.136426) (xy 388.28132 -307.180003) (xy 388.296904 -307.226684)
			(xy 388.304799 -307.275261) (xy 388.305294 -307.299868) (xy 389.594102 -307.299868) (xy 389.598062 -307.250814)
			(xy 389.609839 -307.20303) (xy 389.62913 -307.157754) (xy 389.655433 -307.116158) (xy 389.688068 -307.079321)
			(xy 389.726189 -307.048196) (xy 389.76881 -307.023589) (xy 389.814826 -307.006137) (xy 389.863045 -306.996293)
			(xy 389.91222 -306.994312) (xy 389.961075 -307.000244) (xy 390.008346 -307.013936) (xy 390.052808 -307.035034)
			(xy 390.093311 -307.06299) (xy 390.128804 -307.097082) (xy 390.158369 -307.136426) (xy 390.18124 -307.180003)
			(xy 390.196824 -307.226684) (xy 390.204719 -307.275261) (xy 390.205214 -307.299868) (xy 390.544062 -307.299868)
			(xy 390.548022 -307.250814) (xy 390.559799 -307.20303) (xy 390.57909 -307.157754) (xy 390.605393 -307.116158)
			(xy 390.638028 -307.079321) (xy 390.676149 -307.048196) (xy 390.71877 -307.023589) (xy 390.764786 -307.006137)
			(xy 390.813005 -306.996293) (xy 390.86218 -306.994312) (xy 390.911035 -307.000244) (xy 390.958306 -307.013936)
			(xy 391.002768 -307.035034) (xy 391.043271 -307.06299) (xy 391.078764 -307.097082) (xy 391.108329 -307.136426)
			(xy 391.1312 -307.180003) (xy 391.146784 -307.226684) (xy 391.154679 -307.275261) (xy 391.155174 -307.299868)
			(xy 424.744146 -307.299868) (xy 424.748106 -307.250814) (xy 424.759883 -307.20303) (xy 424.779174 -307.157754)
			(xy 424.805477 -307.116158) (xy 424.838112 -307.079321) (xy 424.876233 -307.048196) (xy 424.918854 -307.023589)
			(xy 424.96487 -307.006137) (xy 425.013089 -306.996293) (xy 425.062264 -306.994312) (xy 425.111119 -307.000244)
			(xy 425.15839 -307.013936) (xy 425.202852 -307.035034) (xy 425.243355 -307.06299) (xy 425.278848 -307.097082)
			(xy 425.308413 -307.136426) (xy 425.331284 -307.180003) (xy 425.346868 -307.226684) (xy 425.354763 -307.275261)
			(xy 425.355258 -307.299868) (xy 425.694106 -307.299868) (xy 425.698066 -307.250814) (xy 425.709843 -307.20303)
			(xy 425.729134 -307.157754) (xy 425.755437 -307.116158) (xy 425.788072 -307.079321) (xy 425.826193 -307.048196)
			(xy 425.868814 -307.023589) (xy 425.91483 -307.006137) (xy 425.963049 -306.996293) (xy 426.012224 -306.994312)
			(xy 426.061079 -307.000244) (xy 426.10835 -307.013936) (xy 426.152812 -307.035034) (xy 426.193315 -307.06299)
			(xy 426.228808 -307.097082) (xy 426.258373 -307.136426) (xy 426.281244 -307.180003) (xy 426.296828 -307.226684)
			(xy 426.304723 -307.275261) (xy 426.305218 -307.299868) (xy 427.594026 -307.299868) (xy 427.597986 -307.250814)
			(xy 427.609763 -307.20303) (xy 427.629054 -307.157754) (xy 427.655357 -307.116158) (xy 427.687992 -307.079321)
			(xy 427.726113 -307.048196) (xy 427.768734 -307.023589) (xy 427.81475 -307.006137) (xy 427.862969 -306.996293)
			(xy 427.912144 -306.994312) (xy 427.960999 -307.000244) (xy 428.00827 -307.013936) (xy 428.052732 -307.035034)
			(xy 428.093235 -307.06299) (xy 428.128728 -307.097082) (xy 428.158293 -307.136426) (xy 428.181164 -307.180003)
			(xy 428.196748 -307.226684) (xy 428.204643 -307.275261) (xy 428.205138 -307.299868) (xy 428.543986 -307.299868)
			(xy 428.547946 -307.250814) (xy 428.559723 -307.20303) (xy 428.579014 -307.157754) (xy 428.605317 -307.116158)
			(xy 428.637952 -307.079321) (xy 428.676073 -307.048196) (xy 428.718694 -307.023589) (xy 428.76471 -307.006137)
			(xy 428.812929 -306.996293) (xy 428.862104 -306.994312) (xy 428.910959 -307.000244) (xy 428.95823 -307.013936)
			(xy 429.002692 -307.035034) (xy 429.043195 -307.06299) (xy 429.078688 -307.097082) (xy 429.108253 -307.136426)
			(xy 429.131124 -307.180003) (xy 429.146708 -307.226684) (xy 429.154603 -307.275261) (xy 429.155098 -307.299868)
			(xy 429.154603 -307.324475) (xy 429.146708 -307.373052) (xy 429.131124 -307.419733) (xy 429.108253 -307.46331)
			(xy 429.078688 -307.502654) (xy 429.043195 -307.536746) (xy 429.002692 -307.564702) (xy 428.95823 -307.5858)
			(xy 428.910959 -307.599492) (xy 428.862104 -307.605424) (xy 428.812929 -307.603443) (xy 428.76471 -307.593599)
			(xy 428.718694 -307.576147) (xy 428.676073 -307.55154) (xy 428.637952 -307.520415) (xy 428.605317 -307.483578)
			(xy 428.579014 -307.441982) (xy 428.559723 -307.396706) (xy 428.547946 -307.348922) (xy 428.543986 -307.299868)
			(xy 428.205138 -307.299868) (xy 428.204643 -307.324475) (xy 428.196748 -307.373052) (xy 428.181164 -307.419733)
			(xy 428.158293 -307.46331) (xy 428.128728 -307.502654) (xy 428.093235 -307.536746) (xy 428.052732 -307.564702)
			(xy 428.00827 -307.5858) (xy 427.960999 -307.599492) (xy 427.912144 -307.605424) (xy 427.862969 -307.603443)
			(xy 427.81475 -307.593599) (xy 427.768734 -307.576147) (xy 427.726113 -307.55154) (xy 427.687992 -307.520415)
			(xy 427.655357 -307.483578) (xy 427.629054 -307.441982) (xy 427.609763 -307.396706) (xy 427.597986 -307.348922)
			(xy 427.594026 -307.299868) (xy 426.305218 -307.299868) (xy 426.304723 -307.324475) (xy 426.296828 -307.373052)
			(xy 426.281244 -307.419733) (xy 426.258373 -307.46331) (xy 426.228808 -307.502654) (xy 426.193315 -307.536746)
			(xy 426.152812 -307.564702) (xy 426.10835 -307.5858) (xy 426.061079 -307.599492) (xy 426.012224 -307.605424)
			(xy 425.963049 -307.603443) (xy 425.91483 -307.593599) (xy 425.868814 -307.576147) (xy 425.826193 -307.55154)
			(xy 425.788072 -307.520415) (xy 425.755437 -307.483578) (xy 425.729134 -307.441982) (xy 425.709843 -307.396706)
			(xy 425.698066 -307.348922) (xy 425.694106 -307.299868) (xy 425.355258 -307.299868) (xy 425.354763 -307.324475)
			(xy 425.346868 -307.373052) (xy 425.331284 -307.419733) (xy 425.308413 -307.46331) (xy 425.278848 -307.502654)
			(xy 425.243355 -307.536746) (xy 425.202852 -307.564702) (xy 425.15839 -307.5858) (xy 425.111119 -307.599492)
			(xy 425.062264 -307.605424) (xy 425.013089 -307.603443) (xy 424.96487 -307.593599) (xy 424.918854 -307.576147)
			(xy 424.876233 -307.55154) (xy 424.838112 -307.520415) (xy 424.805477 -307.483578) (xy 424.779174 -307.441982)
			(xy 424.759883 -307.396706) (xy 424.748106 -307.348922) (xy 424.744146 -307.299868) (xy 391.155174 -307.299868)
			(xy 391.154679 -307.324475) (xy 391.146784 -307.373052) (xy 391.1312 -307.419733) (xy 391.108329 -307.46331)
			(xy 391.078764 -307.502654) (xy 391.043271 -307.536746) (xy 391.002768 -307.564702) (xy 390.958306 -307.5858)
			(xy 390.911035 -307.599492) (xy 390.86218 -307.605424) (xy 390.813005 -307.603443) (xy 390.764786 -307.593599)
			(xy 390.71877 -307.576147) (xy 390.676149 -307.55154) (xy 390.638028 -307.520415) (xy 390.605393 -307.483578)
			(xy 390.57909 -307.441982) (xy 390.559799 -307.396706) (xy 390.548022 -307.348922) (xy 390.544062 -307.299868)
			(xy 390.205214 -307.299868) (xy 390.204719 -307.324475) (xy 390.196824 -307.373052) (xy 390.18124 -307.419733)
			(xy 390.158369 -307.46331) (xy 390.128804 -307.502654) (xy 390.093311 -307.536746) (xy 390.052808 -307.564702)
			(xy 390.008346 -307.5858) (xy 389.961075 -307.599492) (xy 389.91222 -307.605424) (xy 389.863045 -307.603443)
			(xy 389.814826 -307.593599) (xy 389.76881 -307.576147) (xy 389.726189 -307.55154) (xy 389.688068 -307.520415)
			(xy 389.655433 -307.483578) (xy 389.62913 -307.441982) (xy 389.609839 -307.396706) (xy 389.598062 -307.348922)
			(xy 389.594102 -307.299868) (xy 388.305294 -307.299868) (xy 388.304799 -307.324475) (xy 388.296904 -307.373052)
			(xy 388.28132 -307.419733) (xy 388.258449 -307.46331) (xy 388.228884 -307.502654) (xy 388.193391 -307.536746)
			(xy 388.152888 -307.564702) (xy 388.108426 -307.5858) (xy 388.061155 -307.599492) (xy 388.0123 -307.605424)
			(xy 387.963125 -307.603443) (xy 387.914906 -307.593599) (xy 387.86889 -307.576147) (xy 387.826269 -307.55154)
			(xy 387.788148 -307.520415) (xy 387.755513 -307.483578) (xy 387.72921 -307.441982) (xy 387.709919 -307.396706)
			(xy 387.698142 -307.348922) (xy 387.694182 -307.299868) (xy 387.355334 -307.299868) (xy 387.354839 -307.324475)
			(xy 387.346944 -307.373052) (xy 387.33136 -307.419733) (xy 387.308489 -307.46331) (xy 387.278924 -307.502654)
			(xy 387.243431 -307.536746) (xy 387.202928 -307.564702) (xy 387.158466 -307.5858) (xy 387.111195 -307.599492)
			(xy 387.06234 -307.605424) (xy 387.013165 -307.603443) (xy 386.964946 -307.593599) (xy 386.91893 -307.576147)
			(xy 386.876309 -307.55154) (xy 386.838188 -307.520415) (xy 386.805553 -307.483578) (xy 386.77925 -307.441982)
			(xy 386.759959 -307.396706) (xy 386.748182 -307.348922) (xy 386.744222 -307.299868) (xy 313.055 -307.299868)
			(xy 313.054505 -307.324475) (xy 313.04661 -307.373052) (xy 313.031026 -307.419733) (xy 313.008155 -307.46331)
			(xy 312.97859 -307.502654) (xy 312.943097 -307.536746) (xy 312.902594 -307.564702) (xy 312.858132 -307.5858)
			(xy 312.810861 -307.599492) (xy 312.762006 -307.605424) (xy 312.712831 -307.603443) (xy 312.664612 -307.593599)
			(xy 312.618596 -307.576147) (xy 312.575975 -307.55154) (xy 312.537854 -307.520415) (xy 312.505219 -307.483578)
			(xy 312.478916 -307.441982) (xy 312.459625 -307.396706) (xy 312.447848 -307.348922) (xy 312.443888 -307.299868)
			(xy 312.10504 -307.299868) (xy 312.104545 -307.324475) (xy 312.09665 -307.373052) (xy 312.081066 -307.419733)
			(xy 312.058195 -307.46331) (xy 312.02863 -307.502654) (xy 311.993137 -307.536746) (xy 311.952634 -307.564702)
			(xy 311.908172 -307.5858) (xy 311.860901 -307.599492) (xy 311.812046 -307.605424) (xy 311.762871 -307.603443)
			(xy 311.714652 -307.593599) (xy 311.668636 -307.576147) (xy 311.626015 -307.55154) (xy 311.587894 -307.520415)
			(xy 311.555259 -307.483578) (xy 311.528956 -307.441982) (xy 311.509665 -307.396706) (xy 311.497888 -307.348922)
			(xy 311.493928 -307.299868) (xy 310.20512 -307.299868) (xy 310.204625 -307.324475) (xy 310.19673 -307.373052)
			(xy 310.181146 -307.419733) (xy 310.158275 -307.46331) (xy 310.12871 -307.502654) (xy 310.093217 -307.536746)
			(xy 310.052714 -307.564702) (xy 310.008252 -307.5858) (xy 309.960981 -307.599492) (xy 309.912126 -307.605424)
			(xy 309.862951 -307.603443) (xy 309.814732 -307.593599) (xy 309.768716 -307.576147) (xy 309.726095 -307.55154)
			(xy 309.687974 -307.520415) (xy 309.655339 -307.483578) (xy 309.629036 -307.441982) (xy 309.609745 -307.396706)
			(xy 309.597968 -307.348922) (xy 309.594008 -307.299868) (xy 309.25516 -307.299868) (xy 309.254665 -307.324475)
			(xy 309.24677 -307.373052) (xy 309.231186 -307.419733) (xy 309.208315 -307.46331) (xy 309.17875 -307.502654)
			(xy 309.143257 -307.536746) (xy 309.102754 -307.564702) (xy 309.058292 -307.5858) (xy 309.011021 -307.599492)
			(xy 308.962166 -307.605424) (xy 308.912991 -307.603443) (xy 308.864772 -307.593599) (xy 308.818756 -307.576147)
			(xy 308.776135 -307.55154) (xy 308.738014 -307.520415) (xy 308.705379 -307.483578) (xy 308.679076 -307.441982)
			(xy 308.659785 -307.396706) (xy 308.648008 -307.348922) (xy 308.644048 -307.299868) (xy 275.055076 -307.299868)
			(xy 275.054581 -307.324475) (xy 275.046686 -307.373052) (xy 275.031102 -307.419733) (xy 275.008231 -307.46331)
			(xy 274.978666 -307.502654) (xy 274.943173 -307.536746) (xy 274.90267 -307.564702) (xy 274.858208 -307.5858)
			(xy 274.810937 -307.599492) (xy 274.762082 -307.605424) (xy 274.712907 -307.603443) (xy 274.664688 -307.593599)
			(xy 274.618672 -307.576147) (xy 274.576051 -307.55154) (xy 274.53793 -307.520415) (xy 274.505295 -307.483578)
			(xy 274.478992 -307.441982) (xy 274.459701 -307.396706) (xy 274.447924 -307.348922) (xy 274.443964 -307.299868)
			(xy 274.105116 -307.299868) (xy 274.104621 -307.324475) (xy 274.096726 -307.373052) (xy 274.081142 -307.419733)
			(xy 274.058271 -307.46331) (xy 274.028706 -307.502654) (xy 273.993213 -307.536746) (xy 273.95271 -307.564702)
			(xy 273.908248 -307.5858) (xy 273.860977 -307.599492) (xy 273.812122 -307.605424) (xy 273.762947 -307.603443)
			(xy 273.714728 -307.593599) (xy 273.668712 -307.576147) (xy 273.626091 -307.55154) (xy 273.58797 -307.520415)
			(xy 273.555335 -307.483578) (xy 273.529032 -307.441982) (xy 273.509741 -307.396706) (xy 273.497964 -307.348922)
			(xy 273.494004 -307.299868) (xy 272.205196 -307.299868) (xy 272.204701 -307.324475) (xy 272.196806 -307.373052)
			(xy 272.181222 -307.419733) (xy 272.158351 -307.46331) (xy 272.128786 -307.502654) (xy 272.093293 -307.536746)
			(xy 272.05279 -307.564702) (xy 272.008328 -307.5858) (xy 271.961057 -307.599492) (xy 271.912202 -307.605424)
			(xy 271.863027 -307.603443) (xy 271.814808 -307.593599) (xy 271.768792 -307.576147) (xy 271.726171 -307.55154)
			(xy 271.68805 -307.520415) (xy 271.655415 -307.483578) (xy 271.629112 -307.441982) (xy 271.609821 -307.396706)
			(xy 271.598044 -307.348922) (xy 271.594084 -307.299868) (xy 271.255236 -307.299868) (xy 271.254741 -307.324475)
			(xy 271.246846 -307.373052) (xy 271.231262 -307.419733) (xy 271.208391 -307.46331) (xy 271.178826 -307.502654)
			(xy 271.143333 -307.536746) (xy 271.10283 -307.564702) (xy 271.058368 -307.5858) (xy 271.011097 -307.599492)
			(xy 270.962242 -307.605424) (xy 270.913067 -307.603443) (xy 270.864848 -307.593599) (xy 270.818832 -307.576147)
			(xy 270.776211 -307.55154) (xy 270.73809 -307.520415) (xy 270.705455 -307.483578) (xy 270.679152 -307.441982)
			(xy 270.659861 -307.396706) (xy 270.648084 -307.348922) (xy 270.644124 -307.299868) (xy 248.902577 -307.299868)
			(xy 248.925005 -307.347712) (xy 248.941083 -307.401154) (xy 248.949209 -307.456368) (xy 248.949718 -307.484272)
			(xy 248.949209 -307.512176) (xy 248.941083 -307.56739) (xy 248.928951 -307.607716) (xy 462.556604 -307.607716)
			(xy 462.560677 -307.552057) (xy 462.572812 -307.497584) (xy 462.592748 -307.445458) (xy 462.620062 -307.39679)
			(xy 462.65417 -307.352618) (xy 462.694347 -307.313883) (xy 462.739735 -307.281411) (xy 462.789367 -307.255893)
			(xy 462.842187 -307.237874) (xy 462.897066 -307.227737) (xy 462.952837 -307.225699) (xy 463.008311 -307.231802)
			(xy 463.062304 -307.245918) (xy 463.113667 -307.267745) (xy 463.161305 -307.296818) (xy 463.204201 -307.332517)
			(xy 463.241443 -307.374081) (xy 463.272237 -307.420625) (xy 463.295925 -307.471156) (xy 463.312003 -307.524598)
			(xy 463.320129 -307.579812) (xy 463.320638 -307.607716) (xy 463.320129 -307.63562) (xy 463.312003 -307.690834)
			(xy 463.295925 -307.744276) (xy 463.272237 -307.794807) (xy 463.241443 -307.841351) (xy 463.204201 -307.882915)
			(xy 463.161305 -307.918614) (xy 463.113667 -307.947687) (xy 463.062304 -307.969514) (xy 463.008311 -307.98363)
			(xy 462.952837 -307.989733) (xy 462.897066 -307.987695) (xy 462.842187 -307.977558) (xy 462.789367 -307.959539)
			(xy 462.739735 -307.934021) (xy 462.694347 -307.901549) (xy 462.65417 -307.862814) (xy 462.620062 -307.818642)
			(xy 462.592748 -307.769974) (xy 462.572812 -307.717848) (xy 462.560677 -307.663375) (xy 462.556604 -307.607716)
			(xy 248.928951 -307.607716) (xy 248.925005 -307.620832) (xy 248.901317 -307.671363) (xy 248.870523 -307.717907)
			(xy 248.833281 -307.759471) (xy 248.790385 -307.79517) (xy 248.742747 -307.824243) (xy 248.691384 -307.84607)
			(xy 248.637391 -307.860186) (xy 248.581917 -307.866289) (xy 248.526146 -307.864251) (xy 248.471267 -307.854114)
			(xy 248.418447 -307.836095) (xy 248.368815 -307.810577) (xy 248.323427 -307.778105) (xy 248.28325 -307.73937)
			(xy 248.249142 -307.695198) (xy 248.221828 -307.64653) (xy 248.201892 -307.594404) (xy 248.189757 -307.539931)
			(xy 248.185684 -307.484272) (xy 232.69956 -307.484272) (xy 232.699051 -307.512176) (xy 232.690925 -307.56739)
			(xy 232.674847 -307.620832) (xy 232.651159 -307.671363) (xy 232.620365 -307.717907) (xy 232.583123 -307.759471)
			(xy 232.540227 -307.79517) (xy 232.492589 -307.824243) (xy 232.441226 -307.84607) (xy 232.387233 -307.860186)
			(xy 232.331759 -307.866289) (xy 232.275988 -307.864251) (xy 232.221109 -307.854114) (xy 232.168289 -307.836095)
			(xy 232.118657 -307.810577) (xy 232.073269 -307.778105) (xy 232.033092 -307.73937) (xy 231.998984 -307.695198)
			(xy 231.97167 -307.64653) (xy 231.951734 -307.594404) (xy 231.939599 -307.539931) (xy 231.935526 -307.484272)
			(xy 196.892559 -307.484272) (xy 196.878746 -307.502654) (xy 196.843253 -307.536746) (xy 196.80275 -307.564702)
			(xy 196.758288 -307.5858) (xy 196.711017 -307.599492) (xy 196.662162 -307.605424) (xy 196.612987 -307.603443)
			(xy 196.564768 -307.593599) (xy 196.518752 -307.576147) (xy 196.476131 -307.55154) (xy 196.43801 -307.520415)
			(xy 196.405375 -307.483578) (xy 196.379072 -307.441982) (xy 196.359781 -307.396706) (xy 196.348004 -307.348922)
			(xy 196.344044 -307.299868) (xy 196.005196 -307.299868) (xy 196.004701 -307.324475) (xy 195.996806 -307.373052)
			(xy 195.981222 -307.419733) (xy 195.958351 -307.46331) (xy 195.928786 -307.502654) (xy 195.893293 -307.536746)
			(xy 195.85279 -307.564702) (xy 195.808328 -307.5858) (xy 195.761057 -307.599492) (xy 195.712202 -307.605424)
			(xy 195.663027 -307.603443) (xy 195.614808 -307.593599) (xy 195.568792 -307.576147) (xy 195.526171 -307.55154)
			(xy 195.48805 -307.520415) (xy 195.455415 -307.483578) (xy 195.429112 -307.441982) (xy 195.409821 -307.396706)
			(xy 195.398044 -307.348922) (xy 195.394084 -307.299868) (xy 194.105276 -307.299868) (xy 194.104781 -307.324475)
			(xy 194.096886 -307.373052) (xy 194.081302 -307.419733) (xy 194.058431 -307.46331) (xy 194.028866 -307.502654)
			(xy 193.993373 -307.536746) (xy 193.95287 -307.564702) (xy 193.908408 -307.5858) (xy 193.861137 -307.599492)
			(xy 193.812282 -307.605424) (xy 193.763107 -307.603443) (xy 193.714888 -307.593599) (xy 193.668872 -307.576147)
			(xy 193.626251 -307.55154) (xy 193.58813 -307.520415) (xy 193.555495 -307.483578) (xy 193.529192 -307.441982)
			(xy 193.509901 -307.396706) (xy 193.498124 -307.348922) (xy 193.494164 -307.299868) (xy 193.155316 -307.299868)
			(xy 193.154821 -307.324475) (xy 193.146926 -307.373052) (xy 193.131342 -307.419733) (xy 193.108471 -307.46331)
			(xy 193.078906 -307.502654) (xy 193.043413 -307.536746) (xy 193.00291 -307.564702) (xy 192.958448 -307.5858)
			(xy 192.911177 -307.599492) (xy 192.862322 -307.605424) (xy 192.813147 -307.603443) (xy 192.764928 -307.593599)
			(xy 192.718912 -307.576147) (xy 192.676291 -307.55154) (xy 192.63817 -307.520415) (xy 192.605535 -307.483578)
			(xy 192.579232 -307.441982) (xy 192.559941 -307.396706) (xy 192.548164 -307.348922) (xy 192.544204 -307.299868)
			(xy 158.955232 -307.299868) (xy 158.954737 -307.324475) (xy 158.946842 -307.373052) (xy 158.931258 -307.419733)
			(xy 158.908387 -307.46331) (xy 158.878822 -307.502654) (xy 158.843329 -307.536746) (xy 158.802826 -307.564702)
			(xy 158.758364 -307.5858) (xy 158.711093 -307.599492) (xy 158.662238 -307.605424) (xy 158.613063 -307.603443)
			(xy 158.564844 -307.593599) (xy 158.518828 -307.576147) (xy 158.476207 -307.55154) (xy 158.438086 -307.520415)
			(xy 158.405451 -307.483578) (xy 158.379148 -307.441982) (xy 158.359857 -307.396706) (xy 158.34808 -307.348922)
			(xy 158.34412 -307.299868) (xy 158.005272 -307.299868) (xy 158.004777 -307.324475) (xy 157.996882 -307.373052)
			(xy 157.981298 -307.419733) (xy 157.958427 -307.46331) (xy 157.928862 -307.502654) (xy 157.893369 -307.536746)
			(xy 157.852866 -307.564702) (xy 157.808404 -307.5858) (xy 157.761133 -307.599492) (xy 157.712278 -307.605424)
			(xy 157.663103 -307.603443) (xy 157.614884 -307.593599) (xy 157.568868 -307.576147) (xy 157.526247 -307.55154)
			(xy 157.488126 -307.520415) (xy 157.455491 -307.483578) (xy 157.429188 -307.441982) (xy 157.409897 -307.396706)
			(xy 157.39812 -307.348922) (xy 157.39416 -307.299868) (xy 156.105352 -307.299868) (xy 156.104857 -307.324475)
			(xy 156.096962 -307.373052) (xy 156.081378 -307.419733) (xy 156.058507 -307.46331) (xy 156.028942 -307.502654)
			(xy 155.993449 -307.536746) (xy 155.952946 -307.564702) (xy 155.908484 -307.5858) (xy 155.861213 -307.599492)
			(xy 155.812358 -307.605424) (xy 155.763183 -307.603443) (xy 155.714964 -307.593599) (xy 155.668948 -307.576147)
			(xy 155.626327 -307.55154) (xy 155.588206 -307.520415) (xy 155.555571 -307.483578) (xy 155.529268 -307.441982)
			(xy 155.509977 -307.396706) (xy 155.4982 -307.348922) (xy 155.49424 -307.299868) (xy 155.155392 -307.299868)
			(xy 155.154897 -307.324475) (xy 155.147002 -307.373052) (xy 155.131418 -307.419733) (xy 155.108547 -307.46331)
			(xy 155.078982 -307.502654) (xy 155.043489 -307.536746) (xy 155.002986 -307.564702) (xy 154.958524 -307.5858)
			(xy 154.911253 -307.599492) (xy 154.862398 -307.605424) (xy 154.813223 -307.603443) (xy 154.765004 -307.593599)
			(xy 154.718988 -307.576147) (xy 154.676367 -307.55154) (xy 154.638246 -307.520415) (xy 154.605611 -307.483578)
			(xy 154.579308 -307.441982) (xy 154.560017 -307.396706) (xy 154.54824 -307.348922) (xy 154.54428 -307.299868)
			(xy 80.855058 -307.299868) (xy 80.854563 -307.324475) (xy 80.846668 -307.373052) (xy 80.831084 -307.419733)
			(xy 80.808213 -307.46331) (xy 80.778648 -307.502654) (xy 80.743155 -307.536746) (xy 80.702652 -307.564702)
			(xy 80.65819 -307.5858) (xy 80.610919 -307.599492) (xy 80.562064 -307.605424) (xy 80.512889 -307.603443)
			(xy 80.46467 -307.593599) (xy 80.418654 -307.576147) (xy 80.376033 -307.55154) (xy 80.337912 -307.520415)
			(xy 80.305277 -307.483578) (xy 80.278974 -307.441982) (xy 80.259683 -307.396706) (xy 80.247906 -307.348922)
			(xy 80.243946 -307.299868) (xy 79.905098 -307.299868) (xy 79.904603 -307.324475) (xy 79.896708 -307.373052)
			(xy 79.881124 -307.419733) (xy 79.858253 -307.46331) (xy 79.828688 -307.502654) (xy 79.793195 -307.536746)
			(xy 79.752692 -307.564702) (xy 79.70823 -307.5858) (xy 79.660959 -307.599492) (xy 79.612104 -307.605424)
			(xy 79.562929 -307.603443) (xy 79.51471 -307.593599) (xy 79.468694 -307.576147) (xy 79.426073 -307.55154)
			(xy 79.387952 -307.520415) (xy 79.355317 -307.483578) (xy 79.329014 -307.441982) (xy 79.309723 -307.396706)
			(xy 79.297946 -307.348922) (xy 79.293986 -307.299868) (xy 78.005178 -307.299868) (xy 78.004683 -307.324475)
			(xy 77.996788 -307.373052) (xy 77.981204 -307.419733) (xy 77.958333 -307.46331) (xy 77.928768 -307.502654)
			(xy 77.893275 -307.536746) (xy 77.852772 -307.564702) (xy 77.80831 -307.5858) (xy 77.761039 -307.599492)
			(xy 77.712184 -307.605424) (xy 77.663009 -307.603443) (xy 77.61479 -307.593599) (xy 77.568774 -307.576147)
			(xy 77.526153 -307.55154) (xy 77.488032 -307.520415) (xy 77.455397 -307.483578) (xy 77.429094 -307.441982)
			(xy 77.409803 -307.396706) (xy 77.398026 -307.348922) (xy 77.394066 -307.299868) (xy 77.055218 -307.299868)
			(xy 77.054723 -307.324475) (xy 77.046828 -307.373052) (xy 77.031244 -307.419733) (xy 77.008373 -307.46331)
			(xy 76.978808 -307.502654) (xy 76.943315 -307.536746) (xy 76.902812 -307.564702) (xy 76.85835 -307.5858)
			(xy 76.811079 -307.599492) (xy 76.762224 -307.605424) (xy 76.713049 -307.603443) (xy 76.66483 -307.593599)
			(xy 76.618814 -307.576147) (xy 76.576193 -307.55154) (xy 76.538072 -307.520415) (xy 76.505437 -307.483578)
			(xy 76.479134 -307.441982) (xy 76.459843 -307.396706) (xy 76.448066 -307.348922) (xy 76.444106 -307.299868)
			(xy 42.855134 -307.299868) (xy 42.854639 -307.324475) (xy 42.846744 -307.373052) (xy 42.83116 -307.419733)
			(xy 42.808289 -307.46331) (xy 42.778724 -307.502654) (xy 42.743231 -307.536746) (xy 42.702728 -307.564702)
			(xy 42.658266 -307.5858) (xy 42.610995 -307.599492) (xy 42.56214 -307.605424) (xy 42.512965 -307.603443)
			(xy 42.464746 -307.593599) (xy 42.41873 -307.576147) (xy 42.376109 -307.55154) (xy 42.337988 -307.520415)
			(xy 42.305353 -307.483578) (xy 42.27905 -307.441982) (xy 42.259759 -307.396706) (xy 42.247982 -307.348922)
			(xy 42.244022 -307.299868) (xy 41.905174 -307.299868) (xy 41.904679 -307.324475) (xy 41.896784 -307.373052)
			(xy 41.8812 -307.419733) (xy 41.858329 -307.46331) (xy 41.828764 -307.502654) (xy 41.793271 -307.536746)
			(xy 41.752768 -307.564702) (xy 41.708306 -307.5858) (xy 41.661035 -307.599492) (xy 41.61218 -307.605424)
			(xy 41.563005 -307.603443) (xy 41.514786 -307.593599) (xy 41.46877 -307.576147) (xy 41.426149 -307.55154)
			(xy 41.388028 -307.520415) (xy 41.355393 -307.483578) (xy 41.32909 -307.441982) (xy 41.309799 -307.396706)
			(xy 41.298022 -307.348922) (xy 41.294062 -307.299868) (xy 40.005254 -307.299868) (xy 40.004759 -307.324475)
			(xy 39.996864 -307.373052) (xy 39.98128 -307.419733) (xy 39.958409 -307.46331) (xy 39.928844 -307.502654)
			(xy 39.893351 -307.536746) (xy 39.852848 -307.564702) (xy 39.808386 -307.5858) (xy 39.761115 -307.599492)
			(xy 39.71226 -307.605424) (xy 39.663085 -307.603443) (xy 39.614866 -307.593599) (xy 39.56885 -307.576147)
			(xy 39.526229 -307.55154) (xy 39.488108 -307.520415) (xy 39.455473 -307.483578) (xy 39.42917 -307.441982)
			(xy 39.409879 -307.396706) (xy 39.398102 -307.348922) (xy 39.394142 -307.299868) (xy 39.055294 -307.299868)
			(xy 39.054799 -307.324475) (xy 39.046904 -307.373052) (xy 39.03132 -307.419733) (xy 39.008449 -307.46331)
			(xy 38.978884 -307.502654) (xy 38.943391 -307.536746) (xy 38.902888 -307.564702) (xy 38.858426 -307.5858)
			(xy 38.811155 -307.599492) (xy 38.7623 -307.605424) (xy 38.713125 -307.603443) (xy 38.664906 -307.593599)
			(xy 38.61889 -307.576147) (xy 38.576269 -307.55154) (xy 38.538148 -307.520415) (xy 38.505513 -307.483578)
			(xy 38.47921 -307.441982) (xy 38.459919 -307.396706) (xy 38.448142 -307.348922) (xy 38.444182 -307.299868)
			(xy 0.508 -307.299868) (xy 0.508 -308.249828) (xy 36.544008 -308.249828) (xy 36.547968 -308.200774)
			(xy 36.559745 -308.15299) (xy 36.579036 -308.107714) (xy 36.605339 -308.066118) (xy 36.637974 -308.029281)
			(xy 36.676095 -307.998156) (xy 36.718716 -307.973549) (xy 36.764732 -307.956097) (xy 36.812951 -307.946253)
			(xy 36.862126 -307.944272) (xy 36.910981 -307.950204) (xy 36.958252 -307.963896) (xy 37.002714 -307.984994)
			(xy 37.043217 -308.01295) (xy 37.07871 -308.047042) (xy 37.108275 -308.086386) (xy 37.131146 -308.129963)
			(xy 37.14673 -308.176644) (xy 37.154625 -308.225221) (xy 37.15512 -308.249828) (xy 37.493968 -308.249828)
			(xy 37.497928 -308.200774) (xy 37.509705 -308.15299) (xy 37.528996 -308.107714) (xy 37.555299 -308.066118)
			(xy 37.587934 -308.029281) (xy 37.626055 -307.998156) (xy 37.668676 -307.973549) (xy 37.714692 -307.956097)
			(xy 37.762911 -307.946253) (xy 37.812086 -307.944272) (xy 37.860941 -307.950204) (xy 37.908212 -307.963896)
			(xy 37.952674 -307.984994) (xy 37.993177 -308.01295) (xy 38.02867 -308.047042) (xy 38.058235 -308.086386)
			(xy 38.081106 -308.129963) (xy 38.09669 -308.176644) (xy 38.104585 -308.225221) (xy 38.10508 -308.249828)
			(xy 43.193982 -308.249828) (xy 43.197942 -308.200774) (xy 43.209719 -308.15299) (xy 43.22901 -308.107714)
			(xy 43.255313 -308.066118) (xy 43.287948 -308.029281) (xy 43.326069 -307.998156) (xy 43.36869 -307.973549)
			(xy 43.414706 -307.956097) (xy 43.462925 -307.946253) (xy 43.5121 -307.944272) (xy 43.560955 -307.950204)
			(xy 43.608226 -307.963896) (xy 43.652688 -307.984994) (xy 43.693191 -308.01295) (xy 43.728684 -308.047042)
			(xy 43.758249 -308.086386) (xy 43.78112 -308.129963) (xy 43.796704 -308.176644) (xy 43.804599 -308.225221)
			(xy 43.805094 -308.249828) (xy 44.143942 -308.249828) (xy 44.147902 -308.200774) (xy 44.159679 -308.15299)
			(xy 44.17897 -308.107714) (xy 44.205273 -308.066118) (xy 44.237908 -308.029281) (xy 44.276029 -307.998156)
			(xy 44.31865 -307.973549) (xy 44.364666 -307.956097) (xy 44.412885 -307.946253) (xy 44.46206 -307.944272)
			(xy 44.510915 -307.950204) (xy 44.558186 -307.963896) (xy 44.602648 -307.984994) (xy 44.643151 -308.01295)
			(xy 44.678644 -308.047042) (xy 44.708209 -308.086386) (xy 44.73108 -308.129963) (xy 44.746664 -308.176644)
			(xy 44.754559 -308.225221) (xy 44.755054 -308.249828) (xy 74.544186 -308.249828) (xy 74.548146 -308.200774)
			(xy 74.559923 -308.15299) (xy 74.579214 -308.107714) (xy 74.605517 -308.066118) (xy 74.638152 -308.029281)
			(xy 74.676273 -307.998156) (xy 74.718894 -307.973549) (xy 74.76491 -307.956097) (xy 74.813129 -307.946253)
			(xy 74.862304 -307.944272) (xy 74.911159 -307.950204) (xy 74.95843 -307.963896) (xy 75.002892 -307.984994)
			(xy 75.043395 -308.01295) (xy 75.078888 -308.047042) (xy 75.108453 -308.086386) (xy 75.131324 -308.129963)
			(xy 75.146908 -308.176644) (xy 75.154803 -308.225221) (xy 75.155298 -308.249828) (xy 75.494146 -308.249828)
			(xy 75.498106 -308.200774) (xy 75.509883 -308.15299) (xy 75.529174 -308.107714) (xy 75.555477 -308.066118)
			(xy 75.588112 -308.029281) (xy 75.626233 -307.998156) (xy 75.668854 -307.973549) (xy 75.71487 -307.956097)
			(xy 75.763089 -307.946253) (xy 75.812264 -307.944272) (xy 75.861119 -307.950204) (xy 75.90839 -307.963896)
			(xy 75.952852 -307.984994) (xy 75.993355 -308.01295) (xy 76.028848 -308.047042) (xy 76.058413 -308.086386)
			(xy 76.081284 -308.129963) (xy 76.096868 -308.176644) (xy 76.104763 -308.225221) (xy 76.105258 -308.249828)
			(xy 81.19416 -308.249828) (xy 81.19812 -308.200774) (xy 81.209897 -308.15299) (xy 81.229188 -308.107714)
			(xy 81.255491 -308.066118) (xy 81.288126 -308.029281) (xy 81.326247 -307.998156) (xy 81.368868 -307.973549)
			(xy 81.414884 -307.956097) (xy 81.463103 -307.946253) (xy 81.512278 -307.944272) (xy 81.561133 -307.950204)
			(xy 81.608404 -307.963896) (xy 81.652866 -307.984994) (xy 81.693369 -308.01295) (xy 81.728862 -308.047042)
			(xy 81.758427 -308.086386) (xy 81.781298 -308.129963) (xy 81.796882 -308.176644) (xy 81.804777 -308.225221)
			(xy 81.805272 -308.249828) (xy 82.14412 -308.249828) (xy 82.14808 -308.200774) (xy 82.159857 -308.15299)
			(xy 82.179148 -308.107714) (xy 82.205451 -308.066118) (xy 82.238086 -308.029281) (xy 82.276207 -307.998156)
			(xy 82.318828 -307.973549) (xy 82.364844 -307.956097) (xy 82.413063 -307.946253) (xy 82.462238 -307.944272)
			(xy 82.511093 -307.950204) (xy 82.558364 -307.963896) (xy 82.602826 -307.984994) (xy 82.643329 -308.01295)
			(xy 82.678822 -308.047042) (xy 82.708387 -308.086386) (xy 82.731258 -308.129963) (xy 82.746842 -308.176644)
			(xy 82.754737 -308.225221) (xy 82.755232 -308.249828) (xy 152.644106 -308.249828) (xy 152.648066 -308.200774)
			(xy 152.659843 -308.15299) (xy 152.679134 -308.107714) (xy 152.705437 -308.066118) (xy 152.738072 -308.029281)
			(xy 152.776193 -307.998156) (xy 152.818814 -307.973549) (xy 152.86483 -307.956097) (xy 152.913049 -307.946253)
			(xy 152.962224 -307.944272) (xy 153.011079 -307.950204) (xy 153.05835 -307.963896) (xy 153.102812 -307.984994)
			(xy 153.143315 -308.01295) (xy 153.178808 -308.047042) (xy 153.208373 -308.086386) (xy 153.231244 -308.129963)
			(xy 153.246828 -308.176644) (xy 153.254723 -308.225221) (xy 153.255218 -308.249828) (xy 153.594066 -308.249828)
			(xy 153.598026 -308.200774) (xy 153.609803 -308.15299) (xy 153.629094 -308.107714) (xy 153.655397 -308.066118)
			(xy 153.688032 -308.029281) (xy 153.726153 -307.998156) (xy 153.768774 -307.973549) (xy 153.81479 -307.956097)
			(xy 153.863009 -307.946253) (xy 153.912184 -307.944272) (xy 153.961039 -307.950204) (xy 154.00831 -307.963896)
			(xy 154.052772 -307.984994) (xy 154.093275 -308.01295) (xy 154.128768 -308.047042) (xy 154.158333 -308.086386)
			(xy 154.181204 -308.129963) (xy 154.196788 -308.176644) (xy 154.204683 -308.225221) (xy 154.205178 -308.249828)
			(xy 159.29408 -308.249828) (xy 159.29804 -308.200774) (xy 159.309817 -308.15299) (xy 159.329108 -308.107714)
			(xy 159.355411 -308.066118) (xy 159.388046 -308.029281) (xy 159.426167 -307.998156) (xy 159.468788 -307.973549)
			(xy 159.514804 -307.956097) (xy 159.563023 -307.946253) (xy 159.612198 -307.944272) (xy 159.661053 -307.950204)
			(xy 159.708324 -307.963896) (xy 159.752786 -307.984994) (xy 159.793289 -308.01295) (xy 159.828782 -308.047042)
			(xy 159.858347 -308.086386) (xy 159.881218 -308.129963) (xy 159.896802 -308.176644) (xy 159.904697 -308.225221)
			(xy 159.905192 -308.249828) (xy 160.24404 -308.249828) (xy 160.248 -308.200774) (xy 160.259777 -308.15299)
			(xy 160.279068 -308.107714) (xy 160.305371 -308.066118) (xy 160.338006 -308.029281) (xy 160.376127 -307.998156)
			(xy 160.418748 -307.973549) (xy 160.464764 -307.956097) (xy 160.512983 -307.946253) (xy 160.562158 -307.944272)
			(xy 160.611013 -307.950204) (xy 160.658284 -307.963896) (xy 160.702746 -307.984994) (xy 160.743249 -308.01295)
			(xy 160.778742 -308.047042) (xy 160.808307 -308.086386) (xy 160.831178 -308.129963) (xy 160.846762 -308.176644)
			(xy 160.854657 -308.225221) (xy 160.855152 -308.249828) (xy 190.644284 -308.249828) (xy 190.648244 -308.200774)
			(xy 190.660021 -308.15299) (xy 190.679312 -308.107714) (xy 190.705615 -308.066118) (xy 190.73825 -308.029281)
			(xy 190.776371 -307.998156) (xy 190.818992 -307.973549) (xy 190.865008 -307.956097) (xy 190.913227 -307.946253)
			(xy 190.962402 -307.944272) (xy 191.011257 -307.950204) (xy 191.058528 -307.963896) (xy 191.10299 -307.984994)
			(xy 191.143493 -308.01295) (xy 191.178986 -308.047042) (xy 191.208551 -308.086386) (xy 191.231422 -308.129963)
			(xy 191.247006 -308.176644) (xy 191.254901 -308.225221) (xy 191.255396 -308.249828) (xy 191.594244 -308.249828)
			(xy 191.598204 -308.200774) (xy 191.609981 -308.15299) (xy 191.629272 -308.107714) (xy 191.655575 -308.066118)
			(xy 191.68821 -308.029281) (xy 191.726331 -307.998156) (xy 191.768952 -307.973549) (xy 191.814968 -307.956097)
			(xy 191.863187 -307.946253) (xy 191.912362 -307.944272) (xy 191.961217 -307.950204) (xy 192.008488 -307.963896)
			(xy 192.05295 -307.984994) (xy 192.093453 -308.01295) (xy 192.128946 -308.047042) (xy 192.158511 -308.086386)
			(xy 192.181382 -308.129963) (xy 192.196966 -308.176644) (xy 192.204861 -308.225221) (xy 192.205356 -308.249828)
			(xy 197.294258 -308.249828) (xy 197.298218 -308.200774) (xy 197.309995 -308.15299) (xy 197.329286 -308.107714)
			(xy 197.355589 -308.066118) (xy 197.388224 -308.029281) (xy 197.426345 -307.998156) (xy 197.468966 -307.973549)
			(xy 197.514982 -307.956097) (xy 197.563201 -307.946253) (xy 197.612376 -307.944272) (xy 197.661231 -307.950204)
			(xy 197.708502 -307.963896) (xy 197.752964 -307.984994) (xy 197.793467 -308.01295) (xy 197.82896 -308.047042)
			(xy 197.858525 -308.086386) (xy 197.881396 -308.129963) (xy 197.89698 -308.176644) (xy 197.904875 -308.225221)
			(xy 197.90537 -308.249828) (xy 198.244218 -308.249828) (xy 198.248178 -308.200774) (xy 198.259955 -308.15299)
			(xy 198.279246 -308.107714) (xy 198.305549 -308.066118) (xy 198.338184 -308.029281) (xy 198.376305 -307.998156)
			(xy 198.418926 -307.973549) (xy 198.464942 -307.956097) (xy 198.513161 -307.946253) (xy 198.562336 -307.944272)
			(xy 198.611191 -307.950204) (xy 198.658462 -307.963896) (xy 198.702924 -307.984994) (xy 198.743427 -308.01295)
			(xy 198.77892 -308.047042) (xy 198.808485 -308.086386) (xy 198.831356 -308.129963) (xy 198.84694 -308.176644)
			(xy 198.854835 -308.225221) (xy 198.85533 -308.249828) (xy 198.854835 -308.274435) (xy 198.84694 -308.323012)
			(xy 198.831356 -308.369693) (xy 198.808485 -308.41327) (xy 198.77892 -308.452614) (xy 198.743427 -308.486706)
			(xy 198.702924 -308.514662) (xy 198.658462 -308.53576) (xy 198.611191 -308.549452) (xy 198.562336 -308.555384)
			(xy 198.513161 -308.553403) (xy 198.464942 -308.543559) (xy 198.418926 -308.526107) (xy 198.376305 -308.5015)
			(xy 198.338184 -308.470375) (xy 198.305549 -308.433538) (xy 198.279246 -308.391942) (xy 198.259955 -308.346666)
			(xy 198.248178 -308.298882) (xy 198.244218 -308.249828) (xy 197.90537 -308.249828) (xy 197.904875 -308.274435)
			(xy 197.89698 -308.323012) (xy 197.881396 -308.369693) (xy 197.858525 -308.41327) (xy 197.82896 -308.452614)
			(xy 197.793467 -308.486706) (xy 197.752964 -308.514662) (xy 197.708502 -308.53576) (xy 197.661231 -308.549452)
			(xy 197.612376 -308.555384) (xy 197.563201 -308.553403) (xy 197.514982 -308.543559) (xy 197.468966 -308.526107)
			(xy 197.426345 -308.5015) (xy 197.388224 -308.470375) (xy 197.355589 -308.433538) (xy 197.329286 -308.391942)
			(xy 197.309995 -308.346666) (xy 197.298218 -308.298882) (xy 197.294258 -308.249828) (xy 192.205356 -308.249828)
			(xy 192.204861 -308.274435) (xy 192.196966 -308.323012) (xy 192.181382 -308.369693) (xy 192.158511 -308.41327)
			(xy 192.128946 -308.452614) (xy 192.093453 -308.486706) (xy 192.05295 -308.514662) (xy 192.008488 -308.53576)
			(xy 191.961217 -308.549452) (xy 191.912362 -308.555384) (xy 191.863187 -308.553403) (xy 191.814968 -308.543559)
			(xy 191.768952 -308.526107) (xy 191.726331 -308.5015) (xy 191.68821 -308.470375) (xy 191.655575 -308.433538)
			(xy 191.629272 -308.391942) (xy 191.609981 -308.346666) (xy 191.598204 -308.298882) (xy 191.594244 -308.249828)
			(xy 191.255396 -308.249828) (xy 191.254901 -308.274435) (xy 191.247006 -308.323012) (xy 191.231422 -308.369693)
			(xy 191.208551 -308.41327) (xy 191.178986 -308.452614) (xy 191.143493 -308.486706) (xy 191.10299 -308.514662)
			(xy 191.058528 -308.53576) (xy 191.011257 -308.549452) (xy 190.962402 -308.555384) (xy 190.913227 -308.553403)
			(xy 190.865008 -308.543559) (xy 190.818992 -308.526107) (xy 190.776371 -308.5015) (xy 190.73825 -308.470375)
			(xy 190.705615 -308.433538) (xy 190.679312 -308.391942) (xy 190.660021 -308.346666) (xy 190.648244 -308.298882)
			(xy 190.644284 -308.249828) (xy 160.855152 -308.249828) (xy 160.854657 -308.274435) (xy 160.846762 -308.323012)
			(xy 160.831178 -308.369693) (xy 160.808307 -308.41327) (xy 160.778742 -308.452614) (xy 160.743249 -308.486706)
			(xy 160.702746 -308.514662) (xy 160.658284 -308.53576) (xy 160.611013 -308.549452) (xy 160.562158 -308.555384)
			(xy 160.512983 -308.553403) (xy 160.464764 -308.543559) (xy 160.418748 -308.526107) (xy 160.376127 -308.5015)
			(xy 160.338006 -308.470375) (xy 160.305371 -308.433538) (xy 160.279068 -308.391942) (xy 160.259777 -308.346666)
			(xy 160.248 -308.298882) (xy 160.24404 -308.249828) (xy 159.905192 -308.249828) (xy 159.904697 -308.274435)
			(xy 159.896802 -308.323012) (xy 159.881218 -308.369693) (xy 159.858347 -308.41327) (xy 159.828782 -308.452614)
			(xy 159.793289 -308.486706) (xy 159.752786 -308.514662) (xy 159.708324 -308.53576) (xy 159.661053 -308.549452)
			(xy 159.612198 -308.555384) (xy 159.563023 -308.553403) (xy 159.514804 -308.543559) (xy 159.468788 -308.526107)
			(xy 159.426167 -308.5015) (xy 159.388046 -308.470375) (xy 159.355411 -308.433538) (xy 159.329108 -308.391942)
			(xy 159.309817 -308.346666) (xy 159.29804 -308.298882) (xy 159.29408 -308.249828) (xy 154.205178 -308.249828)
			(xy 154.204683 -308.274435) (xy 154.196788 -308.323012) (xy 154.181204 -308.369693) (xy 154.158333 -308.41327)
			(xy 154.128768 -308.452614) (xy 154.093275 -308.486706) (xy 154.052772 -308.514662) (xy 154.00831 -308.53576)
			(xy 153.961039 -308.549452) (xy 153.912184 -308.555384) (xy 153.863009 -308.553403) (xy 153.81479 -308.543559)
			(xy 153.768774 -308.526107) (xy 153.726153 -308.5015) (xy 153.688032 -308.470375) (xy 153.655397 -308.433538)
			(xy 153.629094 -308.391942) (xy 153.609803 -308.346666) (xy 153.598026 -308.298882) (xy 153.594066 -308.249828)
			(xy 153.255218 -308.249828) (xy 153.254723 -308.274435) (xy 153.246828 -308.323012) (xy 153.231244 -308.369693)
			(xy 153.208373 -308.41327) (xy 153.178808 -308.452614) (xy 153.143315 -308.486706) (xy 153.102812 -308.514662)
			(xy 153.05835 -308.53576) (xy 153.011079 -308.549452) (xy 152.962224 -308.555384) (xy 152.913049 -308.553403)
			(xy 152.86483 -308.543559) (xy 152.818814 -308.526107) (xy 152.776193 -308.5015) (xy 152.738072 -308.470375)
			(xy 152.705437 -308.433538) (xy 152.679134 -308.391942) (xy 152.659843 -308.346666) (xy 152.648066 -308.298882)
			(xy 152.644106 -308.249828) (xy 82.755232 -308.249828) (xy 82.754737 -308.274435) (xy 82.746842 -308.323012)
			(xy 82.731258 -308.369693) (xy 82.708387 -308.41327) (xy 82.678822 -308.452614) (xy 82.643329 -308.486706)
			(xy 82.602826 -308.514662) (xy 82.558364 -308.53576) (xy 82.511093 -308.549452) (xy 82.462238 -308.555384)
			(xy 82.413063 -308.553403) (xy 82.364844 -308.543559) (xy 82.318828 -308.526107) (xy 82.276207 -308.5015)
			(xy 82.238086 -308.470375) (xy 82.205451 -308.433538) (xy 82.179148 -308.391942) (xy 82.159857 -308.346666)
			(xy 82.14808 -308.298882) (xy 82.14412 -308.249828) (xy 81.805272 -308.249828) (xy 81.804777 -308.274435)
			(xy 81.796882 -308.323012) (xy 81.781298 -308.369693) (xy 81.758427 -308.41327) (xy 81.728862 -308.452614)
			(xy 81.693369 -308.486706) (xy 81.652866 -308.514662) (xy 81.608404 -308.53576) (xy 81.561133 -308.549452)
			(xy 81.512278 -308.555384) (xy 81.463103 -308.553403) (xy 81.414884 -308.543559) (xy 81.368868 -308.526107)
			(xy 81.326247 -308.5015) (xy 81.288126 -308.470375) (xy 81.255491 -308.433538) (xy 81.229188 -308.391942)
			(xy 81.209897 -308.346666) (xy 81.19812 -308.298882) (xy 81.19416 -308.249828) (xy 76.105258 -308.249828)
			(xy 76.104763 -308.274435) (xy 76.096868 -308.323012) (xy 76.081284 -308.369693) (xy 76.058413 -308.41327)
			(xy 76.028848 -308.452614) (xy 75.993355 -308.486706) (xy 75.952852 -308.514662) (xy 75.90839 -308.53576)
			(xy 75.861119 -308.549452) (xy 75.812264 -308.555384) (xy 75.763089 -308.553403) (xy 75.71487 -308.543559)
			(xy 75.668854 -308.526107) (xy 75.626233 -308.5015) (xy 75.588112 -308.470375) (xy 75.555477 -308.433538)
			(xy 75.529174 -308.391942) (xy 75.509883 -308.346666) (xy 75.498106 -308.298882) (xy 75.494146 -308.249828)
			(xy 75.155298 -308.249828) (xy 75.154803 -308.274435) (xy 75.146908 -308.323012) (xy 75.131324 -308.369693)
			(xy 75.108453 -308.41327) (xy 75.078888 -308.452614) (xy 75.043395 -308.486706) (xy 75.002892 -308.514662)
			(xy 74.95843 -308.53576) (xy 74.911159 -308.549452) (xy 74.862304 -308.555384) (xy 74.813129 -308.553403)
			(xy 74.76491 -308.543559) (xy 74.718894 -308.526107) (xy 74.676273 -308.5015) (xy 74.638152 -308.470375)
			(xy 74.605517 -308.433538) (xy 74.579214 -308.391942) (xy 74.559923 -308.346666) (xy 74.548146 -308.298882)
			(xy 74.544186 -308.249828) (xy 44.755054 -308.249828) (xy 44.754559 -308.274435) (xy 44.746664 -308.323012)
			(xy 44.73108 -308.369693) (xy 44.708209 -308.41327) (xy 44.678644 -308.452614) (xy 44.643151 -308.486706)
			(xy 44.602648 -308.514662) (xy 44.558186 -308.53576) (xy 44.510915 -308.549452) (xy 44.46206 -308.555384)
			(xy 44.412885 -308.553403) (xy 44.364666 -308.543559) (xy 44.31865 -308.526107) (xy 44.276029 -308.5015)
			(xy 44.237908 -308.470375) (xy 44.205273 -308.433538) (xy 44.17897 -308.391942) (xy 44.159679 -308.346666)
			(xy 44.147902 -308.298882) (xy 44.143942 -308.249828) (xy 43.805094 -308.249828) (xy 43.804599 -308.274435)
			(xy 43.796704 -308.323012) (xy 43.78112 -308.369693) (xy 43.758249 -308.41327) (xy 43.728684 -308.452614)
			(xy 43.693191 -308.486706) (xy 43.652688 -308.514662) (xy 43.608226 -308.53576) (xy 43.560955 -308.549452)
			(xy 43.5121 -308.555384) (xy 43.462925 -308.553403) (xy 43.414706 -308.543559) (xy 43.36869 -308.526107)
			(xy 43.326069 -308.5015) (xy 43.287948 -308.470375) (xy 43.255313 -308.433538) (xy 43.22901 -308.391942)
			(xy 43.209719 -308.346666) (xy 43.197942 -308.298882) (xy 43.193982 -308.249828) (xy 38.10508 -308.249828)
			(xy 38.104585 -308.274435) (xy 38.09669 -308.323012) (xy 38.081106 -308.369693) (xy 38.058235 -308.41327)
			(xy 38.02867 -308.452614) (xy 37.993177 -308.486706) (xy 37.952674 -308.514662) (xy 37.908212 -308.53576)
			(xy 37.860941 -308.549452) (xy 37.812086 -308.555384) (xy 37.762911 -308.553403) (xy 37.714692 -308.543559)
			(xy 37.668676 -308.526107) (xy 37.626055 -308.5015) (xy 37.587934 -308.470375) (xy 37.555299 -308.433538)
			(xy 37.528996 -308.391942) (xy 37.509705 -308.346666) (xy 37.497928 -308.298882) (xy 37.493968 -308.249828)
			(xy 37.15512 -308.249828) (xy 37.154625 -308.274435) (xy 37.14673 -308.323012) (xy 37.131146 -308.369693)
			(xy 37.108275 -308.41327) (xy 37.07871 -308.452614) (xy 37.043217 -308.486706) (xy 37.002714 -308.514662)
			(xy 36.958252 -308.53576) (xy 36.910981 -308.549452) (xy 36.862126 -308.555384) (xy 36.812951 -308.553403)
			(xy 36.764732 -308.543559) (xy 36.718716 -308.526107) (xy 36.676095 -308.5015) (xy 36.637974 -308.470375)
			(xy 36.605339 -308.433538) (xy 36.579036 -308.391942) (xy 36.559745 -308.346666) (xy 36.547968 -308.298882)
			(xy 36.544008 -308.249828) (xy 0.508 -308.249828) (xy 0.508 -308.568852) (xy 231.935526 -308.568852)
			(xy 231.939599 -308.513193) (xy 231.951734 -308.45872) (xy 231.97167 -308.406594) (xy 231.998984 -308.357926)
			(xy 232.033092 -308.313754) (xy 232.073269 -308.275019) (xy 232.118657 -308.242547) (xy 232.168289 -308.217029)
			(xy 232.221109 -308.19901) (xy 232.275988 -308.188873) (xy 232.331759 -308.186835) (xy 232.387233 -308.192938)
			(xy 232.441226 -308.207054) (xy 232.492589 -308.228881) (xy 232.540227 -308.257954) (xy 232.583123 -308.293653)
			(xy 232.620365 -308.335217) (xy 232.651159 -308.381761) (xy 232.674847 -308.432292) (xy 232.690925 -308.485734)
			(xy 232.699051 -308.540948) (xy 232.69956 -308.568852) (xy 248.185684 -308.568852) (xy 248.189757 -308.513193)
			(xy 248.201892 -308.45872) (xy 248.221828 -308.406594) (xy 248.249142 -308.357926) (xy 248.28325 -308.313754)
			(xy 248.323427 -308.275019) (xy 248.368815 -308.242547) (xy 248.418447 -308.217029) (xy 248.471267 -308.19901)
			(xy 248.526146 -308.188873) (xy 248.581917 -308.186835) (xy 248.637391 -308.192938) (xy 248.691384 -308.207054)
			(xy 248.742747 -308.228881) (xy 248.77707 -308.249828) (xy 268.74395 -308.249828) (xy 268.74791 -308.200774)
			(xy 268.759687 -308.15299) (xy 268.778978 -308.107714) (xy 268.805281 -308.066118) (xy 268.837916 -308.029281)
			(xy 268.876037 -307.998156) (xy 268.918658 -307.973549) (xy 268.964674 -307.956097) (xy 269.012893 -307.946253)
			(xy 269.062068 -307.944272) (xy 269.110923 -307.950204) (xy 269.158194 -307.963896) (xy 269.202656 -307.984994)
			(xy 269.243159 -308.01295) (xy 269.278652 -308.047042) (xy 269.308217 -308.086386) (xy 269.331088 -308.129963)
			(xy 269.346672 -308.176644) (xy 269.354567 -308.225221) (xy 269.355062 -308.249828) (xy 269.69391 -308.249828)
			(xy 269.69787 -308.200774) (xy 269.709647 -308.15299) (xy 269.728938 -308.107714) (xy 269.755241 -308.066118)
			(xy 269.787876 -308.029281) (xy 269.825997 -307.998156) (xy 269.868618 -307.973549) (xy 269.914634 -307.956097)
			(xy 269.962853 -307.946253) (xy 270.012028 -307.944272) (xy 270.060883 -307.950204) (xy 270.108154 -307.963896)
			(xy 270.152616 -307.984994) (xy 270.193119 -308.01295) (xy 270.228612 -308.047042) (xy 270.258177 -308.086386)
			(xy 270.281048 -308.129963) (xy 270.296632 -308.176644) (xy 270.304527 -308.225221) (xy 270.305022 -308.249828)
			(xy 275.393924 -308.249828) (xy 275.397884 -308.200774) (xy 275.409661 -308.15299) (xy 275.428952 -308.107714)
			(xy 275.455255 -308.066118) (xy 275.48789 -308.029281) (xy 275.526011 -307.998156) (xy 275.568632 -307.973549)
			(xy 275.614648 -307.956097) (xy 275.662867 -307.946253) (xy 275.712042 -307.944272) (xy 275.760897 -307.950204)
			(xy 275.808168 -307.963896) (xy 275.85263 -307.984994) (xy 275.893133 -308.01295) (xy 275.928626 -308.047042)
			(xy 275.958191 -308.086386) (xy 275.981062 -308.129963) (xy 275.996646 -308.176644) (xy 276.004541 -308.225221)
			(xy 276.005036 -308.249828) (xy 276.343884 -308.249828) (xy 276.347844 -308.200774) (xy 276.359621 -308.15299)
			(xy 276.378912 -308.107714) (xy 276.405215 -308.066118) (xy 276.43785 -308.029281) (xy 276.475971 -307.998156)
			(xy 276.518592 -307.973549) (xy 276.564608 -307.956097) (xy 276.612827 -307.946253) (xy 276.662002 -307.944272)
			(xy 276.710857 -307.950204) (xy 276.758128 -307.963896) (xy 276.80259 -307.984994) (xy 276.843093 -308.01295)
			(xy 276.878586 -308.047042) (xy 276.908151 -308.086386) (xy 276.931022 -308.129963) (xy 276.946606 -308.176644)
			(xy 276.954501 -308.225221) (xy 276.954996 -308.249828) (xy 306.744128 -308.249828) (xy 306.748088 -308.200774)
			(xy 306.759865 -308.15299) (xy 306.779156 -308.107714) (xy 306.805459 -308.066118) (xy 306.838094 -308.029281)
			(xy 306.876215 -307.998156) (xy 306.918836 -307.973549) (xy 306.964852 -307.956097) (xy 307.013071 -307.946253)
			(xy 307.062246 -307.944272) (xy 307.111101 -307.950204) (xy 307.158372 -307.963896) (xy 307.202834 -307.984994)
			(xy 307.243337 -308.01295) (xy 307.27883 -308.047042) (xy 307.308395 -308.086386) (xy 307.331266 -308.129963)
			(xy 307.34685 -308.176644) (xy 307.354745 -308.225221) (xy 307.35524 -308.249828) (xy 307.694088 -308.249828)
			(xy 307.698048 -308.200774) (xy 307.709825 -308.15299) (xy 307.729116 -308.107714) (xy 307.755419 -308.066118)
			(xy 307.788054 -308.029281) (xy 307.826175 -307.998156) (xy 307.868796 -307.973549) (xy 307.914812 -307.956097)
			(xy 307.963031 -307.946253) (xy 308.012206 -307.944272) (xy 308.061061 -307.950204) (xy 308.108332 -307.963896)
			(xy 308.152794 -307.984994) (xy 308.193297 -308.01295) (xy 308.22879 -308.047042) (xy 308.258355 -308.086386)
			(xy 308.281226 -308.129963) (xy 308.29681 -308.176644) (xy 308.304705 -308.225221) (xy 308.3052 -308.249828)
			(xy 313.394102 -308.249828) (xy 313.398062 -308.200774) (xy 313.409839 -308.15299) (xy 313.42913 -308.107714)
			(xy 313.455433 -308.066118) (xy 313.488068 -308.029281) (xy 313.526189 -307.998156) (xy 313.56881 -307.973549)
			(xy 313.614826 -307.956097) (xy 313.663045 -307.946253) (xy 313.71222 -307.944272) (xy 313.761075 -307.950204)
			(xy 313.808346 -307.963896) (xy 313.852808 -307.984994) (xy 313.893311 -308.01295) (xy 313.928804 -308.047042)
			(xy 313.958369 -308.086386) (xy 313.98124 -308.129963) (xy 313.996824 -308.176644) (xy 314.004719 -308.225221)
			(xy 314.005214 -308.249828) (xy 314.344062 -308.249828) (xy 314.348022 -308.200774) (xy 314.359799 -308.15299)
			(xy 314.37909 -308.107714) (xy 314.405393 -308.066118) (xy 314.438028 -308.029281) (xy 314.476149 -307.998156)
			(xy 314.51877 -307.973549) (xy 314.564786 -307.956097) (xy 314.613005 -307.946253) (xy 314.66218 -307.944272)
			(xy 314.711035 -307.950204) (xy 314.758306 -307.963896) (xy 314.802768 -307.984994) (xy 314.843271 -308.01295)
			(xy 314.878764 -308.047042) (xy 314.908329 -308.086386) (xy 314.9312 -308.129963) (xy 314.946784 -308.176644)
			(xy 314.954679 -308.225221) (xy 314.955174 -308.249828) (xy 384.844048 -308.249828) (xy 384.848008 -308.200774)
			(xy 384.859785 -308.15299) (xy 384.879076 -308.107714) (xy 384.905379 -308.066118) (xy 384.938014 -308.029281)
			(xy 384.976135 -307.998156) (xy 385.018756 -307.973549) (xy 385.064772 -307.956097) (xy 385.112991 -307.946253)
			(xy 385.162166 -307.944272) (xy 385.211021 -307.950204) (xy 385.258292 -307.963896) (xy 385.302754 -307.984994)
			(xy 385.343257 -308.01295) (xy 385.37875 -308.047042) (xy 385.408315 -308.086386) (xy 385.431186 -308.129963)
			(xy 385.44677 -308.176644) (xy 385.454665 -308.225221) (xy 385.45516 -308.249828) (xy 385.794008 -308.249828)
			(xy 385.797968 -308.200774) (xy 385.809745 -308.15299) (xy 385.829036 -308.107714) (xy 385.855339 -308.066118)
			(xy 385.887974 -308.029281) (xy 385.926095 -307.998156) (xy 385.968716 -307.973549) (xy 386.014732 -307.956097)
			(xy 386.062951 -307.946253) (xy 386.112126 -307.944272) (xy 386.160981 -307.950204) (xy 386.208252 -307.963896)
			(xy 386.252714 -307.984994) (xy 386.293217 -308.01295) (xy 386.32871 -308.047042) (xy 386.358275 -308.086386)
			(xy 386.381146 -308.129963) (xy 386.39673 -308.176644) (xy 386.404625 -308.225221) (xy 386.40512 -308.249828)
			(xy 391.494022 -308.249828) (xy 391.497982 -308.200774) (xy 391.509759 -308.15299) (xy 391.52905 -308.107714)
			(xy 391.555353 -308.066118) (xy 391.587988 -308.029281) (xy 391.626109 -307.998156) (xy 391.66873 -307.973549)
			(xy 391.714746 -307.956097) (xy 391.762965 -307.946253) (xy 391.81214 -307.944272) (xy 391.860995 -307.950204)
			(xy 391.908266 -307.963896) (xy 391.952728 -307.984994) (xy 391.993231 -308.01295) (xy 392.028724 -308.047042)
			(xy 392.058289 -308.086386) (xy 392.08116 -308.129963) (xy 392.096744 -308.176644) (xy 392.104639 -308.225221)
			(xy 392.105134 -308.249828) (xy 392.443982 -308.249828) (xy 392.447942 -308.200774) (xy 392.459719 -308.15299)
			(xy 392.47901 -308.107714) (xy 392.505313 -308.066118) (xy 392.537948 -308.029281) (xy 392.576069 -307.998156)
			(xy 392.61869 -307.973549) (xy 392.664706 -307.956097) (xy 392.712925 -307.946253) (xy 392.7621 -307.944272)
			(xy 392.810955 -307.950204) (xy 392.858226 -307.963896) (xy 392.902688 -307.984994) (xy 392.943191 -308.01295)
			(xy 392.978684 -308.047042) (xy 393.008249 -308.086386) (xy 393.03112 -308.129963) (xy 393.046704 -308.176644)
			(xy 393.054599 -308.225221) (xy 393.055094 -308.249828) (xy 422.844226 -308.249828) (xy 422.848186 -308.200774)
			(xy 422.859963 -308.15299) (xy 422.879254 -308.107714) (xy 422.905557 -308.066118) (xy 422.938192 -308.029281)
			(xy 422.976313 -307.998156) (xy 423.018934 -307.973549) (xy 423.06495 -307.956097) (xy 423.113169 -307.946253)
			(xy 423.162344 -307.944272) (xy 423.211199 -307.950204) (xy 423.25847 -307.963896) (xy 423.302932 -307.984994)
			(xy 423.343435 -308.01295) (xy 423.378928 -308.047042) (xy 423.408493 -308.086386) (xy 423.431364 -308.129963)
			(xy 423.446948 -308.176644) (xy 423.454843 -308.225221) (xy 423.455338 -308.249828) (xy 423.794186 -308.249828)
			(xy 423.798146 -308.200774) (xy 423.809923 -308.15299) (xy 423.829214 -308.107714) (xy 423.855517 -308.066118)
			(xy 423.888152 -308.029281) (xy 423.926273 -307.998156) (xy 423.968894 -307.973549) (xy 424.01491 -307.956097)
			(xy 424.063129 -307.946253) (xy 424.112304 -307.944272) (xy 424.161159 -307.950204) (xy 424.20843 -307.963896)
			(xy 424.252892 -307.984994) (xy 424.293395 -308.01295) (xy 424.328888 -308.047042) (xy 424.358453 -308.086386)
			(xy 424.381324 -308.129963) (xy 424.396908 -308.176644) (xy 424.404803 -308.225221) (xy 424.405298 -308.249828)
			(xy 429.4942 -308.249828) (xy 429.49816 -308.200774) (xy 429.509937 -308.15299) (xy 429.529228 -308.107714)
			(xy 429.555531 -308.066118) (xy 429.588166 -308.029281) (xy 429.626287 -307.998156) (xy 429.668908 -307.973549)
			(xy 429.714924 -307.956097) (xy 429.763143 -307.946253) (xy 429.812318 -307.944272) (xy 429.861173 -307.950204)
			(xy 429.908444 -307.963896) (xy 429.952906 -307.984994) (xy 429.993409 -308.01295) (xy 430.028902 -308.047042)
			(xy 430.058467 -308.086386) (xy 430.081338 -308.129963) (xy 430.096922 -308.176644) (xy 430.104817 -308.225221)
			(xy 430.105312 -308.249828) (xy 430.44416 -308.249828) (xy 430.44812 -308.200774) (xy 430.459897 -308.15299)
			(xy 430.479188 -308.107714) (xy 430.505491 -308.066118) (xy 430.538126 -308.029281) (xy 430.576247 -307.998156)
			(xy 430.618868 -307.973549) (xy 430.664884 -307.956097) (xy 430.713103 -307.946253) (xy 430.762278 -307.944272)
			(xy 430.811133 -307.950204) (xy 430.858404 -307.963896) (xy 430.902866 -307.984994) (xy 430.943369 -308.01295)
			(xy 430.978862 -308.047042) (xy 431.008427 -308.086386) (xy 431.031298 -308.129963) (xy 431.046882 -308.176644)
			(xy 431.054777 -308.225221) (xy 431.055272 -308.249828) (xy 431.054777 -308.274435) (xy 431.046882 -308.323012)
			(xy 431.031298 -308.369693) (xy 431.008427 -308.41327) (xy 430.978862 -308.452614) (xy 430.943369 -308.486706)
			(xy 430.902866 -308.514662) (xy 430.858404 -308.53576) (xy 430.811133 -308.549452) (xy 430.762278 -308.555384)
			(xy 430.713103 -308.553403) (xy 430.664884 -308.543559) (xy 430.618868 -308.526107) (xy 430.576247 -308.5015)
			(xy 430.538126 -308.470375) (xy 430.505491 -308.433538) (xy 430.479188 -308.391942) (xy 430.459897 -308.346666)
			(xy 430.44812 -308.298882) (xy 430.44416 -308.249828) (xy 430.105312 -308.249828) (xy 430.104817 -308.274435)
			(xy 430.096922 -308.323012) (xy 430.081338 -308.369693) (xy 430.058467 -308.41327) (xy 430.028902 -308.452614)
			(xy 429.993409 -308.486706) (xy 429.952906 -308.514662) (xy 429.908444 -308.53576) (xy 429.861173 -308.549452)
			(xy 429.812318 -308.555384) (xy 429.763143 -308.553403) (xy 429.714924 -308.543559) (xy 429.668908 -308.526107)
			(xy 429.626287 -308.5015) (xy 429.588166 -308.470375) (xy 429.555531 -308.433538) (xy 429.529228 -308.391942)
			(xy 429.509937 -308.346666) (xy 429.49816 -308.298882) (xy 429.4942 -308.249828) (xy 424.405298 -308.249828)
			(xy 424.404803 -308.274435) (xy 424.396908 -308.323012) (xy 424.381324 -308.369693) (xy 424.358453 -308.41327)
			(xy 424.328888 -308.452614) (xy 424.293395 -308.486706) (xy 424.252892 -308.514662) (xy 424.20843 -308.53576)
			(xy 424.161159 -308.549452) (xy 424.112304 -308.555384) (xy 424.063129 -308.553403) (xy 424.01491 -308.543559)
			(xy 423.968894 -308.526107) (xy 423.926273 -308.5015) (xy 423.888152 -308.470375) (xy 423.855517 -308.433538)
			(xy 423.829214 -308.391942) (xy 423.809923 -308.346666) (xy 423.798146 -308.298882) (xy 423.794186 -308.249828)
			(xy 423.455338 -308.249828) (xy 423.454843 -308.274435) (xy 423.446948 -308.323012) (xy 423.431364 -308.369693)
			(xy 423.408493 -308.41327) (xy 423.378928 -308.452614) (xy 423.343435 -308.486706) (xy 423.302932 -308.514662)
			(xy 423.25847 -308.53576) (xy 423.211199 -308.549452) (xy 423.162344 -308.555384) (xy 423.113169 -308.553403)
			(xy 423.06495 -308.543559) (xy 423.018934 -308.526107) (xy 422.976313 -308.5015) (xy 422.938192 -308.470375)
			(xy 422.905557 -308.433538) (xy 422.879254 -308.391942) (xy 422.859963 -308.346666) (xy 422.848186 -308.298882)
			(xy 422.844226 -308.249828) (xy 393.055094 -308.249828) (xy 393.054599 -308.274435) (xy 393.046704 -308.323012)
			(xy 393.03112 -308.369693) (xy 393.008249 -308.41327) (xy 392.978684 -308.452614) (xy 392.943191 -308.486706)
			(xy 392.902688 -308.514662) (xy 392.858226 -308.53576) (xy 392.810955 -308.549452) (xy 392.7621 -308.555384)
			(xy 392.712925 -308.553403) (xy 392.664706 -308.543559) (xy 392.61869 -308.526107) (xy 392.576069 -308.5015)
			(xy 392.537948 -308.470375) (xy 392.505313 -308.433538) (xy 392.47901 -308.391942) (xy 392.459719 -308.346666)
			(xy 392.447942 -308.298882) (xy 392.443982 -308.249828) (xy 392.105134 -308.249828) (xy 392.104639 -308.274435)
			(xy 392.096744 -308.323012) (xy 392.08116 -308.369693) (xy 392.058289 -308.41327) (xy 392.028724 -308.452614)
			(xy 391.993231 -308.486706) (xy 391.952728 -308.514662) (xy 391.908266 -308.53576) (xy 391.860995 -308.549452)
			(xy 391.81214 -308.555384) (xy 391.762965 -308.553403) (xy 391.714746 -308.543559) (xy 391.66873 -308.526107)
			(xy 391.626109 -308.5015) (xy 391.587988 -308.470375) (xy 391.555353 -308.433538) (xy 391.52905 -308.391942)
			(xy 391.509759 -308.346666) (xy 391.497982 -308.298882) (xy 391.494022 -308.249828) (xy 386.40512 -308.249828)
			(xy 386.404625 -308.274435) (xy 386.39673 -308.323012) (xy 386.381146 -308.369693) (xy 386.358275 -308.41327)
			(xy 386.32871 -308.452614) (xy 386.293217 -308.486706) (xy 386.252714 -308.514662) (xy 386.208252 -308.53576)
			(xy 386.160981 -308.549452) (xy 386.112126 -308.555384) (xy 386.062951 -308.553403) (xy 386.014732 -308.543559)
			(xy 385.968716 -308.526107) (xy 385.926095 -308.5015) (xy 385.887974 -308.470375) (xy 385.855339 -308.433538)
			(xy 385.829036 -308.391942) (xy 385.809745 -308.346666) (xy 385.797968 -308.298882) (xy 385.794008 -308.249828)
			(xy 385.45516 -308.249828) (xy 385.454665 -308.274435) (xy 385.44677 -308.323012) (xy 385.431186 -308.369693)
			(xy 385.408315 -308.41327) (xy 385.37875 -308.452614) (xy 385.343257 -308.486706) (xy 385.302754 -308.514662)
			(xy 385.258292 -308.53576) (xy 385.211021 -308.549452) (xy 385.162166 -308.555384) (xy 385.112991 -308.553403)
			(xy 385.064772 -308.543559) (xy 385.018756 -308.526107) (xy 384.976135 -308.5015) (xy 384.938014 -308.470375)
			(xy 384.905379 -308.433538) (xy 384.879076 -308.391942) (xy 384.859785 -308.346666) (xy 384.848008 -308.298882)
			(xy 384.844048 -308.249828) (xy 314.955174 -308.249828) (xy 314.954679 -308.274435) (xy 314.946784 -308.323012)
			(xy 314.9312 -308.369693) (xy 314.908329 -308.41327) (xy 314.878764 -308.452614) (xy 314.843271 -308.486706)
			(xy 314.802768 -308.514662) (xy 314.758306 -308.53576) (xy 314.711035 -308.549452) (xy 314.66218 -308.555384)
			(xy 314.613005 -308.553403) (xy 314.564786 -308.543559) (xy 314.51877 -308.526107) (xy 314.476149 -308.5015)
			(xy 314.438028 -308.470375) (xy 314.405393 -308.433538) (xy 314.37909 -308.391942) (xy 314.359799 -308.346666)
			(xy 314.348022 -308.298882) (xy 314.344062 -308.249828) (xy 314.005214 -308.249828) (xy 314.004719 -308.274435)
			(xy 313.996824 -308.323012) (xy 313.98124 -308.369693) (xy 313.958369 -308.41327) (xy 313.928804 -308.452614)
			(xy 313.893311 -308.486706) (xy 313.852808 -308.514662) (xy 313.808346 -308.53576) (xy 313.761075 -308.549452)
			(xy 313.71222 -308.555384) (xy 313.663045 -308.553403) (xy 313.614826 -308.543559) (xy 313.56881 -308.526107)
			(xy 313.526189 -308.5015) (xy 313.488068 -308.470375) (xy 313.455433 -308.433538) (xy 313.42913 -308.391942)
			(xy 313.409839 -308.346666) (xy 313.398062 -308.298882) (xy 313.394102 -308.249828) (xy 308.3052 -308.249828)
			(xy 308.304705 -308.274435) (xy 308.29681 -308.323012) (xy 308.281226 -308.369693) (xy 308.258355 -308.41327)
			(xy 308.22879 -308.452614) (xy 308.193297 -308.486706) (xy 308.152794 -308.514662) (xy 308.108332 -308.53576)
			(xy 308.061061 -308.549452) (xy 308.012206 -308.555384) (xy 307.963031 -308.553403) (xy 307.914812 -308.543559)
			(xy 307.868796 -308.526107) (xy 307.826175 -308.5015) (xy 307.788054 -308.470375) (xy 307.755419 -308.433538)
			(xy 307.729116 -308.391942) (xy 307.709825 -308.346666) (xy 307.698048 -308.298882) (xy 307.694088 -308.249828)
			(xy 307.35524 -308.249828) (xy 307.354745 -308.274435) (xy 307.34685 -308.323012) (xy 307.331266 -308.369693)
			(xy 307.308395 -308.41327) (xy 307.27883 -308.452614) (xy 307.243337 -308.486706) (xy 307.202834 -308.514662)
			(xy 307.158372 -308.53576) (xy 307.111101 -308.549452) (xy 307.062246 -308.555384) (xy 307.013071 -308.553403)
			(xy 306.964852 -308.543559) (xy 306.918836 -308.526107) (xy 306.876215 -308.5015) (xy 306.838094 -308.470375)
			(xy 306.805459 -308.433538) (xy 306.779156 -308.391942) (xy 306.759865 -308.346666) (xy 306.748088 -308.298882)
			(xy 306.744128 -308.249828) (xy 276.954996 -308.249828) (xy 276.954501 -308.274435) (xy 276.946606 -308.323012)
			(xy 276.931022 -308.369693) (xy 276.908151 -308.41327) (xy 276.878586 -308.452614) (xy 276.843093 -308.486706)
			(xy 276.80259 -308.514662) (xy 276.758128 -308.53576) (xy 276.710857 -308.549452) (xy 276.662002 -308.555384)
			(xy 276.612827 -308.553403) (xy 276.564608 -308.543559) (xy 276.518592 -308.526107) (xy 276.475971 -308.5015)
			(xy 276.43785 -308.470375) (xy 276.405215 -308.433538) (xy 276.378912 -308.391942) (xy 276.359621 -308.346666)
			(xy 276.347844 -308.298882) (xy 276.343884 -308.249828) (xy 276.005036 -308.249828) (xy 276.004541 -308.274435)
			(xy 275.996646 -308.323012) (xy 275.981062 -308.369693) (xy 275.958191 -308.41327) (xy 275.928626 -308.452614)
			(xy 275.893133 -308.486706) (xy 275.85263 -308.514662) (xy 275.808168 -308.53576) (xy 275.760897 -308.549452)
			(xy 275.712042 -308.555384) (xy 275.662867 -308.553403) (xy 275.614648 -308.543559) (xy 275.568632 -308.526107)
			(xy 275.526011 -308.5015) (xy 275.48789 -308.470375) (xy 275.455255 -308.433538) (xy 275.428952 -308.391942)
			(xy 275.409661 -308.346666) (xy 275.397884 -308.298882) (xy 275.393924 -308.249828) (xy 270.305022 -308.249828)
			(xy 270.304527 -308.274435) (xy 270.296632 -308.323012) (xy 270.281048 -308.369693) (xy 270.258177 -308.41327)
			(xy 270.228612 -308.452614) (xy 270.193119 -308.486706) (xy 270.152616 -308.514662) (xy 270.108154 -308.53576)
			(xy 270.060883 -308.549452) (xy 270.012028 -308.555384) (xy 269.962853 -308.553403) (xy 269.914634 -308.543559)
			(xy 269.868618 -308.526107) (xy 269.825997 -308.5015) (xy 269.787876 -308.470375) (xy 269.755241 -308.433538)
			(xy 269.728938 -308.391942) (xy 269.709647 -308.346666) (xy 269.69787 -308.298882) (xy 269.69391 -308.249828)
			(xy 269.355062 -308.249828) (xy 269.354567 -308.274435) (xy 269.346672 -308.323012) (xy 269.331088 -308.369693)
			(xy 269.308217 -308.41327) (xy 269.278652 -308.452614) (xy 269.243159 -308.486706) (xy 269.202656 -308.514662)
			(xy 269.158194 -308.53576) (xy 269.110923 -308.549452) (xy 269.062068 -308.555384) (xy 269.012893 -308.553403)
			(xy 268.964674 -308.543559) (xy 268.918658 -308.526107) (xy 268.876037 -308.5015) (xy 268.837916 -308.470375)
			(xy 268.805281 -308.433538) (xy 268.778978 -308.391942) (xy 268.759687 -308.346666) (xy 268.74791 -308.298882)
			(xy 268.74395 -308.249828) (xy 248.77707 -308.249828) (xy 248.790385 -308.257954) (xy 248.833281 -308.293653)
			(xy 248.870523 -308.335217) (xy 248.901317 -308.381761) (xy 248.925005 -308.432292) (xy 248.941083 -308.485734)
			(xy 248.949209 -308.540948) (xy 248.949718 -308.568852) (xy 248.949209 -308.596756) (xy 248.941083 -308.65197)
			(xy 248.928951 -308.692296) (xy 462.556604 -308.692296) (xy 462.560677 -308.636637) (xy 462.572812 -308.582164)
			(xy 462.592748 -308.530038) (xy 462.620062 -308.48137) (xy 462.65417 -308.437198) (xy 462.694347 -308.398463)
			(xy 462.739735 -308.365991) (xy 462.789367 -308.340473) (xy 462.842187 -308.322454) (xy 462.897066 -308.312317)
			(xy 462.952837 -308.310279) (xy 463.008311 -308.316382) (xy 463.062304 -308.330498) (xy 463.113667 -308.352325)
			(xy 463.161305 -308.381398) (xy 463.204201 -308.417097) (xy 463.241443 -308.458661) (xy 463.272237 -308.505205)
			(xy 463.295925 -308.555736) (xy 463.312003 -308.609178) (xy 463.320129 -308.664392) (xy 463.320638 -308.692296)
			(xy 463.320129 -308.7202) (xy 463.312003 -308.775414) (xy 463.295925 -308.828856) (xy 463.272237 -308.879387)
			(xy 463.241443 -308.925931) (xy 463.204201 -308.967495) (xy 463.161305 -309.003194) (xy 463.113667 -309.032267)
			(xy 463.062304 -309.054094) (xy 463.008311 -309.06821) (xy 462.952837 -309.074313) (xy 462.897066 -309.072275)
			(xy 462.842187 -309.062138) (xy 462.789367 -309.044119) (xy 462.739735 -309.018601) (xy 462.694347 -308.986129)
			(xy 462.65417 -308.947394) (xy 462.620062 -308.903222) (xy 462.592748 -308.854554) (xy 462.572812 -308.802428)
			(xy 462.560677 -308.747955) (xy 462.556604 -308.692296) (xy 248.928951 -308.692296) (xy 248.925005 -308.705412)
			(xy 248.901317 -308.755943) (xy 248.870523 -308.802487) (xy 248.833281 -308.844051) (xy 248.790385 -308.87975)
			(xy 248.742747 -308.908823) (xy 248.691384 -308.93065) (xy 248.637391 -308.944766) (xy 248.581917 -308.950869)
			(xy 248.526146 -308.948831) (xy 248.471267 -308.938694) (xy 248.418447 -308.920675) (xy 248.368815 -308.895157)
			(xy 248.323427 -308.862685) (xy 248.28325 -308.82395) (xy 248.249142 -308.779778) (xy 248.221828 -308.73111)
			(xy 248.201892 -308.678984) (xy 248.189757 -308.624511) (xy 248.185684 -308.568852) (xy 232.69956 -308.568852)
			(xy 232.699051 -308.596756) (xy 232.690925 -308.65197) (xy 232.674847 -308.705412) (xy 232.651159 -308.755943)
			(xy 232.620365 -308.802487) (xy 232.583123 -308.844051) (xy 232.540227 -308.87975) (xy 232.492589 -308.908823)
			(xy 232.441226 -308.93065) (xy 232.387233 -308.944766) (xy 232.331759 -308.950869) (xy 232.275988 -308.948831)
			(xy 232.221109 -308.938694) (xy 232.168289 -308.920675) (xy 232.118657 -308.895157) (xy 232.073269 -308.862685)
			(xy 232.033092 -308.82395) (xy 231.998984 -308.779778) (xy 231.97167 -308.73111) (xy 231.951734 -308.678984)
			(xy 231.939599 -308.624511) (xy 231.935526 -308.568852) (xy 0.508 -308.568852) (xy 0.508 -309.199788)
			(xy 38.444182 -309.199788) (xy 38.448142 -309.150734) (xy 38.459919 -309.10295) (xy 38.47921 -309.057674)
			(xy 38.505513 -309.016078) (xy 38.538148 -308.979241) (xy 38.576269 -308.948116) (xy 38.61889 -308.923509)
			(xy 38.664906 -308.906057) (xy 38.713125 -308.896213) (xy 38.7623 -308.894232) (xy 38.811155 -308.900164)
			(xy 38.858426 -308.913856) (xy 38.902888 -308.934954) (xy 38.943391 -308.96291) (xy 38.978884 -308.997002)
			(xy 39.008449 -309.036346) (xy 39.03132 -309.079923) (xy 39.046904 -309.126604) (xy 39.054799 -309.175181)
			(xy 39.055294 -309.199788) (xy 39.394142 -309.199788) (xy 39.398102 -309.150734) (xy 39.409879 -309.10295)
			(xy 39.42917 -309.057674) (xy 39.455473 -309.016078) (xy 39.488108 -308.979241) (xy 39.526229 -308.948116)
			(xy 39.56885 -308.923509) (xy 39.614866 -308.906057) (xy 39.663085 -308.896213) (xy 39.71226 -308.894232)
			(xy 39.761115 -308.900164) (xy 39.808386 -308.913856) (xy 39.852848 -308.934954) (xy 39.893351 -308.96291)
			(xy 39.928844 -308.997002) (xy 39.958409 -309.036346) (xy 39.98128 -309.079923) (xy 39.996864 -309.126604)
			(xy 40.004759 -309.175181) (xy 40.005254 -309.199788) (xy 41.294062 -309.199788) (xy 41.298022 -309.150734)
			(xy 41.309799 -309.10295) (xy 41.32909 -309.057674) (xy 41.355393 -309.016078) (xy 41.388028 -308.979241)
			(xy 41.426149 -308.948116) (xy 41.46877 -308.923509) (xy 41.514786 -308.906057) (xy 41.563005 -308.896213)
			(xy 41.61218 -308.894232) (xy 41.661035 -308.900164) (xy 41.708306 -308.913856) (xy 41.752768 -308.934954)
			(xy 41.793271 -308.96291) (xy 41.828764 -308.997002) (xy 41.858329 -309.036346) (xy 41.8812 -309.079923)
			(xy 41.896784 -309.126604) (xy 41.904679 -309.175181) (xy 41.905174 -309.199788) (xy 42.244022 -309.199788)
			(xy 42.247982 -309.150734) (xy 42.259759 -309.10295) (xy 42.27905 -309.057674) (xy 42.305353 -309.016078)
			(xy 42.337988 -308.979241) (xy 42.376109 -308.948116) (xy 42.41873 -308.923509) (xy 42.464746 -308.906057)
			(xy 42.512965 -308.896213) (xy 42.56214 -308.894232) (xy 42.610995 -308.900164) (xy 42.658266 -308.913856)
			(xy 42.702728 -308.934954) (xy 42.743231 -308.96291) (xy 42.778724 -308.997002) (xy 42.808289 -309.036346)
			(xy 42.83116 -309.079923) (xy 42.846744 -309.126604) (xy 42.854639 -309.175181) (xy 42.855134 -309.199788)
			(xy 76.444106 -309.199788) (xy 76.448066 -309.150734) (xy 76.459843 -309.10295) (xy 76.479134 -309.057674)
			(xy 76.505437 -309.016078) (xy 76.538072 -308.979241) (xy 76.576193 -308.948116) (xy 76.618814 -308.923509)
			(xy 76.66483 -308.906057) (xy 76.713049 -308.896213) (xy 76.762224 -308.894232) (xy 76.811079 -308.900164)
			(xy 76.85835 -308.913856) (xy 76.902812 -308.934954) (xy 76.943315 -308.96291) (xy 76.978808 -308.997002)
			(xy 77.008373 -309.036346) (xy 77.031244 -309.079923) (xy 77.046828 -309.126604) (xy 77.054723 -309.175181)
			(xy 77.055218 -309.199788) (xy 77.394066 -309.199788) (xy 77.398026 -309.150734) (xy 77.409803 -309.10295)
			(xy 77.429094 -309.057674) (xy 77.455397 -309.016078) (xy 77.488032 -308.979241) (xy 77.526153 -308.948116)
			(xy 77.568774 -308.923509) (xy 77.61479 -308.906057) (xy 77.663009 -308.896213) (xy 77.712184 -308.894232)
			(xy 77.761039 -308.900164) (xy 77.80831 -308.913856) (xy 77.852772 -308.934954) (xy 77.893275 -308.96291)
			(xy 77.928768 -308.997002) (xy 77.958333 -309.036346) (xy 77.981204 -309.079923) (xy 77.996788 -309.126604)
			(xy 78.004683 -309.175181) (xy 78.005178 -309.199788) (xy 79.293986 -309.199788) (xy 79.297946 -309.150734)
			(xy 79.309723 -309.10295) (xy 79.329014 -309.057674) (xy 79.355317 -309.016078) (xy 79.387952 -308.979241)
			(xy 79.426073 -308.948116) (xy 79.468694 -308.923509) (xy 79.51471 -308.906057) (xy 79.562929 -308.896213)
			(xy 79.612104 -308.894232) (xy 79.660959 -308.900164) (xy 79.70823 -308.913856) (xy 79.752692 -308.934954)
			(xy 79.793195 -308.96291) (xy 79.828688 -308.997002) (xy 79.858253 -309.036346) (xy 79.881124 -309.079923)
			(xy 79.896708 -309.126604) (xy 79.904603 -309.175181) (xy 79.905098 -309.199788) (xy 80.243946 -309.199788)
			(xy 80.247906 -309.150734) (xy 80.259683 -309.10295) (xy 80.278974 -309.057674) (xy 80.305277 -309.016078)
			(xy 80.337912 -308.979241) (xy 80.376033 -308.948116) (xy 80.418654 -308.923509) (xy 80.46467 -308.906057)
			(xy 80.512889 -308.896213) (xy 80.562064 -308.894232) (xy 80.610919 -308.900164) (xy 80.65819 -308.913856)
			(xy 80.702652 -308.934954) (xy 80.743155 -308.96291) (xy 80.778648 -308.997002) (xy 80.808213 -309.036346)
			(xy 80.831084 -309.079923) (xy 80.846668 -309.126604) (xy 80.854563 -309.175181) (xy 80.855058 -309.199788)
			(xy 154.54428 -309.199788) (xy 154.54824 -309.150734) (xy 154.560017 -309.10295) (xy 154.579308 -309.057674)
			(xy 154.605611 -309.016078) (xy 154.638246 -308.979241) (xy 154.676367 -308.948116) (xy 154.718988 -308.923509)
			(xy 154.765004 -308.906057) (xy 154.813223 -308.896213) (xy 154.862398 -308.894232) (xy 154.911253 -308.900164)
			(xy 154.958524 -308.913856) (xy 155.002986 -308.934954) (xy 155.043489 -308.96291) (xy 155.078982 -308.997002)
			(xy 155.108547 -309.036346) (xy 155.131418 -309.079923) (xy 155.147002 -309.126604) (xy 155.154897 -309.175181)
			(xy 155.155392 -309.199788) (xy 155.49424 -309.199788) (xy 155.4982 -309.150734) (xy 155.509977 -309.10295)
			(xy 155.529268 -309.057674) (xy 155.555571 -309.016078) (xy 155.588206 -308.979241) (xy 155.626327 -308.948116)
			(xy 155.668948 -308.923509) (xy 155.714964 -308.906057) (xy 155.763183 -308.896213) (xy 155.812358 -308.894232)
			(xy 155.861213 -308.900164) (xy 155.908484 -308.913856) (xy 155.952946 -308.934954) (xy 155.993449 -308.96291)
			(xy 156.028942 -308.997002) (xy 156.058507 -309.036346) (xy 156.081378 -309.079923) (xy 156.096962 -309.126604)
			(xy 156.104857 -309.175181) (xy 156.105352 -309.199788) (xy 157.39416 -309.199788) (xy 157.39812 -309.150734)
			(xy 157.409897 -309.10295) (xy 157.429188 -309.057674) (xy 157.455491 -309.016078) (xy 157.488126 -308.979241)
			(xy 157.526247 -308.948116) (xy 157.568868 -308.923509) (xy 157.614884 -308.906057) (xy 157.663103 -308.896213)
			(xy 157.712278 -308.894232) (xy 157.761133 -308.900164) (xy 157.808404 -308.913856) (xy 157.852866 -308.934954)
			(xy 157.893369 -308.96291) (xy 157.928862 -308.997002) (xy 157.958427 -309.036346) (xy 157.981298 -309.079923)
			(xy 157.996882 -309.126604) (xy 158.004777 -309.175181) (xy 158.005272 -309.199788) (xy 158.34412 -309.199788)
			(xy 158.34808 -309.150734) (xy 158.359857 -309.10295) (xy 158.379148 -309.057674) (xy 158.405451 -309.016078)
			(xy 158.438086 -308.979241) (xy 158.476207 -308.948116) (xy 158.518828 -308.923509) (xy 158.564844 -308.906057)
			(xy 158.613063 -308.896213) (xy 158.662238 -308.894232) (xy 158.711093 -308.900164) (xy 158.758364 -308.913856)
			(xy 158.802826 -308.934954) (xy 158.843329 -308.96291) (xy 158.878822 -308.997002) (xy 158.908387 -309.036346)
			(xy 158.931258 -309.079923) (xy 158.946842 -309.126604) (xy 158.954737 -309.175181) (xy 158.955232 -309.199788)
			(xy 192.544204 -309.199788) (xy 192.548164 -309.150734) (xy 192.559941 -309.10295) (xy 192.579232 -309.057674)
			(xy 192.605535 -309.016078) (xy 192.63817 -308.979241) (xy 192.676291 -308.948116) (xy 192.718912 -308.923509)
			(xy 192.764928 -308.906057) (xy 192.813147 -308.896213) (xy 192.862322 -308.894232) (xy 192.911177 -308.900164)
			(xy 192.958448 -308.913856) (xy 193.00291 -308.934954) (xy 193.043413 -308.96291) (xy 193.078906 -308.997002)
			(xy 193.108471 -309.036346) (xy 193.131342 -309.079923) (xy 193.146926 -309.126604) (xy 193.154821 -309.175181)
			(xy 193.155316 -309.199788) (xy 193.494164 -309.199788) (xy 193.498124 -309.150734) (xy 193.509901 -309.10295)
			(xy 193.529192 -309.057674) (xy 193.555495 -309.016078) (xy 193.58813 -308.979241) (xy 193.626251 -308.948116)
			(xy 193.668872 -308.923509) (xy 193.714888 -308.906057) (xy 193.763107 -308.896213) (xy 193.812282 -308.894232)
			(xy 193.861137 -308.900164) (xy 193.908408 -308.913856) (xy 193.95287 -308.934954) (xy 193.993373 -308.96291)
			(xy 194.028866 -308.997002) (xy 194.058431 -309.036346) (xy 194.081302 -309.079923) (xy 194.096886 -309.126604)
			(xy 194.104781 -309.175181) (xy 194.105276 -309.199788) (xy 195.394084 -309.199788) (xy 195.398044 -309.150734)
			(xy 195.409821 -309.10295) (xy 195.429112 -309.057674) (xy 195.455415 -309.016078) (xy 195.48805 -308.979241)
			(xy 195.526171 -308.948116) (xy 195.568792 -308.923509) (xy 195.614808 -308.906057) (xy 195.663027 -308.896213)
			(xy 195.712202 -308.894232) (xy 195.761057 -308.900164) (xy 195.808328 -308.913856) (xy 195.85279 -308.934954)
			(xy 195.893293 -308.96291) (xy 195.928786 -308.997002) (xy 195.958351 -309.036346) (xy 195.981222 -309.079923)
			(xy 195.996806 -309.126604) (xy 196.004701 -309.175181) (xy 196.005196 -309.199788) (xy 196.344044 -309.199788)
			(xy 196.348004 -309.150734) (xy 196.359781 -309.10295) (xy 196.379072 -309.057674) (xy 196.405375 -309.016078)
			(xy 196.43801 -308.979241) (xy 196.476131 -308.948116) (xy 196.518752 -308.923509) (xy 196.564768 -308.906057)
			(xy 196.612987 -308.896213) (xy 196.662162 -308.894232) (xy 196.711017 -308.900164) (xy 196.758288 -308.913856)
			(xy 196.80275 -308.934954) (xy 196.843253 -308.96291) (xy 196.878746 -308.997002) (xy 196.908311 -309.036346)
			(xy 196.931182 -309.079923) (xy 196.946766 -309.126604) (xy 196.954661 -309.175181) (xy 196.955156 -309.199788)
			(xy 270.644124 -309.199788) (xy 270.648084 -309.150734) (xy 270.659861 -309.10295) (xy 270.679152 -309.057674)
			(xy 270.705455 -309.016078) (xy 270.73809 -308.979241) (xy 270.776211 -308.948116) (xy 270.818832 -308.923509)
			(xy 270.864848 -308.906057) (xy 270.913067 -308.896213) (xy 270.962242 -308.894232) (xy 271.011097 -308.900164)
			(xy 271.058368 -308.913856) (xy 271.10283 -308.934954) (xy 271.143333 -308.96291) (xy 271.178826 -308.997002)
			(xy 271.208391 -309.036346) (xy 271.231262 -309.079923) (xy 271.246846 -309.126604) (xy 271.254741 -309.175181)
			(xy 271.255236 -309.199788) (xy 271.594084 -309.199788) (xy 271.598044 -309.150734) (xy 271.609821 -309.10295)
			(xy 271.629112 -309.057674) (xy 271.655415 -309.016078) (xy 271.68805 -308.979241) (xy 271.726171 -308.948116)
			(xy 271.768792 -308.923509) (xy 271.814808 -308.906057) (xy 271.863027 -308.896213) (xy 271.912202 -308.894232)
			(xy 271.961057 -308.900164) (xy 272.008328 -308.913856) (xy 272.05279 -308.934954) (xy 272.093293 -308.96291)
			(xy 272.128786 -308.997002) (xy 272.158351 -309.036346) (xy 272.181222 -309.079923) (xy 272.196806 -309.126604)
			(xy 272.204701 -309.175181) (xy 272.205196 -309.199788) (xy 273.494004 -309.199788) (xy 273.497964 -309.150734)
			(xy 273.509741 -309.10295) (xy 273.529032 -309.057674) (xy 273.555335 -309.016078) (xy 273.58797 -308.979241)
			(xy 273.626091 -308.948116) (xy 273.668712 -308.923509) (xy 273.714728 -308.906057) (xy 273.762947 -308.896213)
			(xy 273.812122 -308.894232) (xy 273.860977 -308.900164) (xy 273.908248 -308.913856) (xy 273.95271 -308.934954)
			(xy 273.993213 -308.96291) (xy 274.028706 -308.997002) (xy 274.058271 -309.036346) (xy 274.081142 -309.079923)
			(xy 274.096726 -309.126604) (xy 274.104621 -309.175181) (xy 274.105116 -309.199788) (xy 274.443964 -309.199788)
			(xy 274.447924 -309.150734) (xy 274.459701 -309.10295) (xy 274.478992 -309.057674) (xy 274.505295 -309.016078)
			(xy 274.53793 -308.979241) (xy 274.576051 -308.948116) (xy 274.618672 -308.923509) (xy 274.664688 -308.906057)
			(xy 274.712907 -308.896213) (xy 274.762082 -308.894232) (xy 274.810937 -308.900164) (xy 274.858208 -308.913856)
			(xy 274.90267 -308.934954) (xy 274.943173 -308.96291) (xy 274.978666 -308.997002) (xy 275.008231 -309.036346)
			(xy 275.031102 -309.079923) (xy 275.046686 -309.126604) (xy 275.054581 -309.175181) (xy 275.055076 -309.199788)
			(xy 308.644048 -309.199788) (xy 308.648008 -309.150734) (xy 308.659785 -309.10295) (xy 308.679076 -309.057674)
			(xy 308.705379 -309.016078) (xy 308.738014 -308.979241) (xy 308.776135 -308.948116) (xy 308.818756 -308.923509)
			(xy 308.864772 -308.906057) (xy 308.912991 -308.896213) (xy 308.962166 -308.894232) (xy 309.011021 -308.900164)
			(xy 309.058292 -308.913856) (xy 309.102754 -308.934954) (xy 309.143257 -308.96291) (xy 309.17875 -308.997002)
			(xy 309.208315 -309.036346) (xy 309.231186 -309.079923) (xy 309.24677 -309.126604) (xy 309.254665 -309.175181)
			(xy 309.25516 -309.199788) (xy 309.594008 -309.199788) (xy 309.597968 -309.150734) (xy 309.609745 -309.10295)
			(xy 309.629036 -309.057674) (xy 309.655339 -309.016078) (xy 309.687974 -308.979241) (xy 309.726095 -308.948116)
			(xy 309.768716 -308.923509) (xy 309.814732 -308.906057) (xy 309.862951 -308.896213) (xy 309.912126 -308.894232)
			(xy 309.960981 -308.900164) (xy 310.008252 -308.913856) (xy 310.052714 -308.934954) (xy 310.093217 -308.96291)
			(xy 310.12871 -308.997002) (xy 310.158275 -309.036346) (xy 310.181146 -309.079923) (xy 310.19673 -309.126604)
			(xy 310.204625 -309.175181) (xy 310.20512 -309.199788) (xy 311.493928 -309.199788) (xy 311.497888 -309.150734)
			(xy 311.509665 -309.10295) (xy 311.528956 -309.057674) (xy 311.555259 -309.016078) (xy 311.587894 -308.979241)
			(xy 311.626015 -308.948116) (xy 311.668636 -308.923509) (xy 311.714652 -308.906057) (xy 311.762871 -308.896213)
			(xy 311.812046 -308.894232) (xy 311.860901 -308.900164) (xy 311.908172 -308.913856) (xy 311.952634 -308.934954)
			(xy 311.993137 -308.96291) (xy 312.02863 -308.997002) (xy 312.058195 -309.036346) (xy 312.081066 -309.079923)
			(xy 312.09665 -309.126604) (xy 312.104545 -309.175181) (xy 312.10504 -309.199788) (xy 312.443888 -309.199788)
			(xy 312.447848 -309.150734) (xy 312.459625 -309.10295) (xy 312.478916 -309.057674) (xy 312.505219 -309.016078)
			(xy 312.537854 -308.979241) (xy 312.575975 -308.948116) (xy 312.618596 -308.923509) (xy 312.664612 -308.906057)
			(xy 312.712831 -308.896213) (xy 312.762006 -308.894232) (xy 312.810861 -308.900164) (xy 312.858132 -308.913856)
			(xy 312.902594 -308.934954) (xy 312.943097 -308.96291) (xy 312.97859 -308.997002) (xy 313.008155 -309.036346)
			(xy 313.031026 -309.079923) (xy 313.04661 -309.126604) (xy 313.054505 -309.175181) (xy 313.055 -309.199788)
			(xy 386.744222 -309.199788) (xy 386.748182 -309.150734) (xy 386.759959 -309.10295) (xy 386.77925 -309.057674)
			(xy 386.805553 -309.016078) (xy 386.838188 -308.979241) (xy 386.876309 -308.948116) (xy 386.91893 -308.923509)
			(xy 386.964946 -308.906057) (xy 387.013165 -308.896213) (xy 387.06234 -308.894232) (xy 387.111195 -308.900164)
			(xy 387.158466 -308.913856) (xy 387.202928 -308.934954) (xy 387.243431 -308.96291) (xy 387.278924 -308.997002)
			(xy 387.308489 -309.036346) (xy 387.33136 -309.079923) (xy 387.346944 -309.126604) (xy 387.354839 -309.175181)
			(xy 387.355334 -309.199788) (xy 387.694182 -309.199788) (xy 387.698142 -309.150734) (xy 387.709919 -309.10295)
			(xy 387.72921 -309.057674) (xy 387.755513 -309.016078) (xy 387.788148 -308.979241) (xy 387.826269 -308.948116)
			(xy 387.86889 -308.923509) (xy 387.914906 -308.906057) (xy 387.963125 -308.896213) (xy 388.0123 -308.894232)
			(xy 388.061155 -308.900164) (xy 388.108426 -308.913856) (xy 388.152888 -308.934954) (xy 388.193391 -308.96291)
			(xy 388.228884 -308.997002) (xy 388.258449 -309.036346) (xy 388.28132 -309.079923) (xy 388.296904 -309.126604)
			(xy 388.304799 -309.175181) (xy 388.305294 -309.199788) (xy 389.594102 -309.199788) (xy 389.598062 -309.150734)
			(xy 389.609839 -309.10295) (xy 389.62913 -309.057674) (xy 389.655433 -309.016078) (xy 389.688068 -308.979241)
			(xy 389.726189 -308.948116) (xy 389.76881 -308.923509) (xy 389.814826 -308.906057) (xy 389.863045 -308.896213)
			(xy 389.91222 -308.894232) (xy 389.961075 -308.900164) (xy 390.008346 -308.913856) (xy 390.052808 -308.934954)
			(xy 390.093311 -308.96291) (xy 390.128804 -308.997002) (xy 390.158369 -309.036346) (xy 390.18124 -309.079923)
			(xy 390.196824 -309.126604) (xy 390.204719 -309.175181) (xy 390.205214 -309.199788) (xy 390.544062 -309.199788)
			(xy 390.548022 -309.150734) (xy 390.559799 -309.10295) (xy 390.57909 -309.057674) (xy 390.605393 -309.016078)
			(xy 390.638028 -308.979241) (xy 390.676149 -308.948116) (xy 390.71877 -308.923509) (xy 390.764786 -308.906057)
			(xy 390.813005 -308.896213) (xy 390.86218 -308.894232) (xy 390.911035 -308.900164) (xy 390.958306 -308.913856)
			(xy 391.002768 -308.934954) (xy 391.043271 -308.96291) (xy 391.078764 -308.997002) (xy 391.108329 -309.036346)
			(xy 391.1312 -309.079923) (xy 391.146784 -309.126604) (xy 391.154679 -309.175181) (xy 391.155174 -309.199788)
			(xy 424.744146 -309.199788) (xy 424.748106 -309.150734) (xy 424.759883 -309.10295) (xy 424.779174 -309.057674)
			(xy 424.805477 -309.016078) (xy 424.838112 -308.979241) (xy 424.876233 -308.948116) (xy 424.918854 -308.923509)
			(xy 424.96487 -308.906057) (xy 425.013089 -308.896213) (xy 425.062264 -308.894232) (xy 425.111119 -308.900164)
			(xy 425.15839 -308.913856) (xy 425.202852 -308.934954) (xy 425.243355 -308.96291) (xy 425.278848 -308.997002)
			(xy 425.308413 -309.036346) (xy 425.331284 -309.079923) (xy 425.346868 -309.126604) (xy 425.354763 -309.175181)
			(xy 425.355258 -309.199788) (xy 425.694106 -309.199788) (xy 425.698066 -309.150734) (xy 425.709843 -309.10295)
			(xy 425.729134 -309.057674) (xy 425.755437 -309.016078) (xy 425.788072 -308.979241) (xy 425.826193 -308.948116)
			(xy 425.868814 -308.923509) (xy 425.91483 -308.906057) (xy 425.963049 -308.896213) (xy 426.012224 -308.894232)
			(xy 426.061079 -308.900164) (xy 426.10835 -308.913856) (xy 426.152812 -308.934954) (xy 426.193315 -308.96291)
			(xy 426.228808 -308.997002) (xy 426.258373 -309.036346) (xy 426.281244 -309.079923) (xy 426.296828 -309.126604)
			(xy 426.304723 -309.175181) (xy 426.305218 -309.199788) (xy 427.594026 -309.199788) (xy 427.597986 -309.150734)
			(xy 427.609763 -309.10295) (xy 427.629054 -309.057674) (xy 427.655357 -309.016078) (xy 427.687992 -308.979241)
			(xy 427.726113 -308.948116) (xy 427.768734 -308.923509) (xy 427.81475 -308.906057) (xy 427.862969 -308.896213)
			(xy 427.912144 -308.894232) (xy 427.960999 -308.900164) (xy 428.00827 -308.913856) (xy 428.052732 -308.934954)
			(xy 428.093235 -308.96291) (xy 428.128728 -308.997002) (xy 428.158293 -309.036346) (xy 428.181164 -309.079923)
			(xy 428.196748 -309.126604) (xy 428.204643 -309.175181) (xy 428.205138 -309.199788) (xy 428.543986 -309.199788)
			(xy 428.547946 -309.150734) (xy 428.559723 -309.10295) (xy 428.579014 -309.057674) (xy 428.605317 -309.016078)
			(xy 428.637952 -308.979241) (xy 428.676073 -308.948116) (xy 428.718694 -308.923509) (xy 428.76471 -308.906057)
			(xy 428.812929 -308.896213) (xy 428.862104 -308.894232) (xy 428.910959 -308.900164) (xy 428.95823 -308.913856)
			(xy 429.002692 -308.934954) (xy 429.043195 -308.96291) (xy 429.078688 -308.997002) (xy 429.108253 -309.036346)
			(xy 429.131124 -309.079923) (xy 429.146708 -309.126604) (xy 429.154603 -309.175181) (xy 429.155098 -309.199788)
			(xy 429.154603 -309.224395) (xy 429.146708 -309.272972) (xy 429.131124 -309.319653) (xy 429.108253 -309.36323)
			(xy 429.078688 -309.402574) (xy 429.043195 -309.436666) (xy 429.002692 -309.464622) (xy 428.95823 -309.48572)
			(xy 428.910959 -309.499412) (xy 428.862104 -309.505344) (xy 428.812929 -309.503363) (xy 428.76471 -309.493519)
			(xy 428.718694 -309.476067) (xy 428.676073 -309.45146) (xy 428.637952 -309.420335) (xy 428.605317 -309.383498)
			(xy 428.579014 -309.341902) (xy 428.559723 -309.296626) (xy 428.547946 -309.248842) (xy 428.543986 -309.199788)
			(xy 428.205138 -309.199788) (xy 428.204643 -309.224395) (xy 428.196748 -309.272972) (xy 428.181164 -309.319653)
			(xy 428.158293 -309.36323) (xy 428.128728 -309.402574) (xy 428.093235 -309.436666) (xy 428.052732 -309.464622)
			(xy 428.00827 -309.48572) (xy 427.960999 -309.499412) (xy 427.912144 -309.505344) (xy 427.862969 -309.503363)
			(xy 427.81475 -309.493519) (xy 427.768734 -309.476067) (xy 427.726113 -309.45146) (xy 427.687992 -309.420335)
			(xy 427.655357 -309.383498) (xy 427.629054 -309.341902) (xy 427.609763 -309.296626) (xy 427.597986 -309.248842)
			(xy 427.594026 -309.199788) (xy 426.305218 -309.199788) (xy 426.304723 -309.224395) (xy 426.296828 -309.272972)
			(xy 426.281244 -309.319653) (xy 426.258373 -309.36323) (xy 426.228808 -309.402574) (xy 426.193315 -309.436666)
			(xy 426.152812 -309.464622) (xy 426.10835 -309.48572) (xy 426.061079 -309.499412) (xy 426.012224 -309.505344)
			(xy 425.963049 -309.503363) (xy 425.91483 -309.493519) (xy 425.868814 -309.476067) (xy 425.826193 -309.45146)
			(xy 425.788072 -309.420335) (xy 425.755437 -309.383498) (xy 425.729134 -309.341902) (xy 425.709843 -309.296626)
			(xy 425.698066 -309.248842) (xy 425.694106 -309.199788) (xy 425.355258 -309.199788) (xy 425.354763 -309.224395)
			(xy 425.346868 -309.272972) (xy 425.331284 -309.319653) (xy 425.308413 -309.36323) (xy 425.278848 -309.402574)
			(xy 425.243355 -309.436666) (xy 425.202852 -309.464622) (xy 425.15839 -309.48572) (xy 425.111119 -309.499412)
			(xy 425.062264 -309.505344) (xy 425.013089 -309.503363) (xy 424.96487 -309.493519) (xy 424.918854 -309.476067)
			(xy 424.876233 -309.45146) (xy 424.838112 -309.420335) (xy 424.805477 -309.383498) (xy 424.779174 -309.341902)
			(xy 424.759883 -309.296626) (xy 424.748106 -309.248842) (xy 424.744146 -309.199788) (xy 391.155174 -309.199788)
			(xy 391.154679 -309.224395) (xy 391.146784 -309.272972) (xy 391.1312 -309.319653) (xy 391.108329 -309.36323)
			(xy 391.078764 -309.402574) (xy 391.043271 -309.436666) (xy 391.002768 -309.464622) (xy 390.958306 -309.48572)
			(xy 390.911035 -309.499412) (xy 390.86218 -309.505344) (xy 390.813005 -309.503363) (xy 390.764786 -309.493519)
			(xy 390.71877 -309.476067) (xy 390.676149 -309.45146) (xy 390.638028 -309.420335) (xy 390.605393 -309.383498)
			(xy 390.57909 -309.341902) (xy 390.559799 -309.296626) (xy 390.548022 -309.248842) (xy 390.544062 -309.199788)
			(xy 390.205214 -309.199788) (xy 390.204719 -309.224395) (xy 390.196824 -309.272972) (xy 390.18124 -309.319653)
			(xy 390.158369 -309.36323) (xy 390.128804 -309.402574) (xy 390.093311 -309.436666) (xy 390.052808 -309.464622)
			(xy 390.008346 -309.48572) (xy 389.961075 -309.499412) (xy 389.91222 -309.505344) (xy 389.863045 -309.503363)
			(xy 389.814826 -309.493519) (xy 389.76881 -309.476067) (xy 389.726189 -309.45146) (xy 389.688068 -309.420335)
			(xy 389.655433 -309.383498) (xy 389.62913 -309.341902) (xy 389.609839 -309.296626) (xy 389.598062 -309.248842)
			(xy 389.594102 -309.199788) (xy 388.305294 -309.199788) (xy 388.304799 -309.224395) (xy 388.296904 -309.272972)
			(xy 388.28132 -309.319653) (xy 388.258449 -309.36323) (xy 388.228884 -309.402574) (xy 388.193391 -309.436666)
			(xy 388.152888 -309.464622) (xy 388.108426 -309.48572) (xy 388.061155 -309.499412) (xy 388.0123 -309.505344)
			(xy 387.963125 -309.503363) (xy 387.914906 -309.493519) (xy 387.86889 -309.476067) (xy 387.826269 -309.45146)
			(xy 387.788148 -309.420335) (xy 387.755513 -309.383498) (xy 387.72921 -309.341902) (xy 387.709919 -309.296626)
			(xy 387.698142 -309.248842) (xy 387.694182 -309.199788) (xy 387.355334 -309.199788) (xy 387.354839 -309.224395)
			(xy 387.346944 -309.272972) (xy 387.33136 -309.319653) (xy 387.308489 -309.36323) (xy 387.278924 -309.402574)
			(xy 387.243431 -309.436666) (xy 387.202928 -309.464622) (xy 387.158466 -309.48572) (xy 387.111195 -309.499412)
			(xy 387.06234 -309.505344) (xy 387.013165 -309.503363) (xy 386.964946 -309.493519) (xy 386.91893 -309.476067)
			(xy 386.876309 -309.45146) (xy 386.838188 -309.420335) (xy 386.805553 -309.383498) (xy 386.77925 -309.341902)
			(xy 386.759959 -309.296626) (xy 386.748182 -309.248842) (xy 386.744222 -309.199788) (xy 313.055 -309.199788)
			(xy 313.054505 -309.224395) (xy 313.04661 -309.272972) (xy 313.031026 -309.319653) (xy 313.008155 -309.36323)
			(xy 312.97859 -309.402574) (xy 312.943097 -309.436666) (xy 312.902594 -309.464622) (xy 312.858132 -309.48572)
			(xy 312.810861 -309.499412) (xy 312.762006 -309.505344) (xy 312.712831 -309.503363) (xy 312.664612 -309.493519)
			(xy 312.618596 -309.476067) (xy 312.575975 -309.45146) (xy 312.537854 -309.420335) (xy 312.505219 -309.383498)
			(xy 312.478916 -309.341902) (xy 312.459625 -309.296626) (xy 312.447848 -309.248842) (xy 312.443888 -309.199788)
			(xy 312.10504 -309.199788) (xy 312.104545 -309.224395) (xy 312.09665 -309.272972) (xy 312.081066 -309.319653)
			(xy 312.058195 -309.36323) (xy 312.02863 -309.402574) (xy 311.993137 -309.436666) (xy 311.952634 -309.464622)
			(xy 311.908172 -309.48572) (xy 311.860901 -309.499412) (xy 311.812046 -309.505344) (xy 311.762871 -309.503363)
			(xy 311.714652 -309.493519) (xy 311.668636 -309.476067) (xy 311.626015 -309.45146) (xy 311.587894 -309.420335)
			(xy 311.555259 -309.383498) (xy 311.528956 -309.341902) (xy 311.509665 -309.296626) (xy 311.497888 -309.248842)
			(xy 311.493928 -309.199788) (xy 310.20512 -309.199788) (xy 310.204625 -309.224395) (xy 310.19673 -309.272972)
			(xy 310.181146 -309.319653) (xy 310.158275 -309.36323) (xy 310.12871 -309.402574) (xy 310.093217 -309.436666)
			(xy 310.052714 -309.464622) (xy 310.008252 -309.48572) (xy 309.960981 -309.499412) (xy 309.912126 -309.505344)
			(xy 309.862951 -309.503363) (xy 309.814732 -309.493519) (xy 309.768716 -309.476067) (xy 309.726095 -309.45146)
			(xy 309.687974 -309.420335) (xy 309.655339 -309.383498) (xy 309.629036 -309.341902) (xy 309.609745 -309.296626)
			(xy 309.597968 -309.248842) (xy 309.594008 -309.199788) (xy 309.25516 -309.199788) (xy 309.254665 -309.224395)
			(xy 309.24677 -309.272972) (xy 309.231186 -309.319653) (xy 309.208315 -309.36323) (xy 309.17875 -309.402574)
			(xy 309.143257 -309.436666) (xy 309.102754 -309.464622) (xy 309.058292 -309.48572) (xy 309.011021 -309.499412)
			(xy 308.962166 -309.505344) (xy 308.912991 -309.503363) (xy 308.864772 -309.493519) (xy 308.818756 -309.476067)
			(xy 308.776135 -309.45146) (xy 308.738014 -309.420335) (xy 308.705379 -309.383498) (xy 308.679076 -309.341902)
			(xy 308.659785 -309.296626) (xy 308.648008 -309.248842) (xy 308.644048 -309.199788) (xy 275.055076 -309.199788)
			(xy 275.054581 -309.224395) (xy 275.046686 -309.272972) (xy 275.031102 -309.319653) (xy 275.008231 -309.36323)
			(xy 274.978666 -309.402574) (xy 274.943173 -309.436666) (xy 274.90267 -309.464622) (xy 274.858208 -309.48572)
			(xy 274.810937 -309.499412) (xy 274.762082 -309.505344) (xy 274.712907 -309.503363) (xy 274.664688 -309.493519)
			(xy 274.618672 -309.476067) (xy 274.576051 -309.45146) (xy 274.53793 -309.420335) (xy 274.505295 -309.383498)
			(xy 274.478992 -309.341902) (xy 274.459701 -309.296626) (xy 274.447924 -309.248842) (xy 274.443964 -309.199788)
			(xy 274.105116 -309.199788) (xy 274.104621 -309.224395) (xy 274.096726 -309.272972) (xy 274.081142 -309.319653)
			(xy 274.058271 -309.36323) (xy 274.028706 -309.402574) (xy 273.993213 -309.436666) (xy 273.95271 -309.464622)
			(xy 273.908248 -309.48572) (xy 273.860977 -309.499412) (xy 273.812122 -309.505344) (xy 273.762947 -309.503363)
			(xy 273.714728 -309.493519) (xy 273.668712 -309.476067) (xy 273.626091 -309.45146) (xy 273.58797 -309.420335)
			(xy 273.555335 -309.383498) (xy 273.529032 -309.341902) (xy 273.509741 -309.296626) (xy 273.497964 -309.248842)
			(xy 273.494004 -309.199788) (xy 272.205196 -309.199788) (xy 272.204701 -309.224395) (xy 272.196806 -309.272972)
			(xy 272.181222 -309.319653) (xy 272.158351 -309.36323) (xy 272.128786 -309.402574) (xy 272.093293 -309.436666)
			(xy 272.05279 -309.464622) (xy 272.008328 -309.48572) (xy 271.961057 -309.499412) (xy 271.912202 -309.505344)
			(xy 271.863027 -309.503363) (xy 271.814808 -309.493519) (xy 271.768792 -309.476067) (xy 271.726171 -309.45146)
			(xy 271.68805 -309.420335) (xy 271.655415 -309.383498) (xy 271.629112 -309.341902) (xy 271.609821 -309.296626)
			(xy 271.598044 -309.248842) (xy 271.594084 -309.199788) (xy 271.255236 -309.199788) (xy 271.254741 -309.224395)
			(xy 271.246846 -309.272972) (xy 271.231262 -309.319653) (xy 271.208391 -309.36323) (xy 271.178826 -309.402574)
			(xy 271.143333 -309.436666) (xy 271.10283 -309.464622) (xy 271.058368 -309.48572) (xy 271.011097 -309.499412)
			(xy 270.962242 -309.505344) (xy 270.913067 -309.503363) (xy 270.864848 -309.493519) (xy 270.818832 -309.476067)
			(xy 270.776211 -309.45146) (xy 270.73809 -309.420335) (xy 270.705455 -309.383498) (xy 270.679152 -309.341902)
			(xy 270.659861 -309.296626) (xy 270.648084 -309.248842) (xy 270.644124 -309.199788) (xy 196.955156 -309.199788)
			(xy 196.954661 -309.224395) (xy 196.946766 -309.272972) (xy 196.931182 -309.319653) (xy 196.908311 -309.36323)
			(xy 196.878746 -309.402574) (xy 196.843253 -309.436666) (xy 196.80275 -309.464622) (xy 196.758288 -309.48572)
			(xy 196.711017 -309.499412) (xy 196.662162 -309.505344) (xy 196.612987 -309.503363) (xy 196.564768 -309.493519)
			(xy 196.518752 -309.476067) (xy 196.476131 -309.45146) (xy 196.43801 -309.420335) (xy 196.405375 -309.383498)
			(xy 196.379072 -309.341902) (xy 196.359781 -309.296626) (xy 196.348004 -309.248842) (xy 196.344044 -309.199788)
			(xy 196.005196 -309.199788) (xy 196.004701 -309.224395) (xy 195.996806 -309.272972) (xy 195.981222 -309.319653)
			(xy 195.958351 -309.36323) (xy 195.928786 -309.402574) (xy 195.893293 -309.436666) (xy 195.85279 -309.464622)
			(xy 195.808328 -309.48572) (xy 195.761057 -309.499412) (xy 195.712202 -309.505344) (xy 195.663027 -309.503363)
			(xy 195.614808 -309.493519) (xy 195.568792 -309.476067) (xy 195.526171 -309.45146) (xy 195.48805 -309.420335)
			(xy 195.455415 -309.383498) (xy 195.429112 -309.341902) (xy 195.409821 -309.296626) (xy 195.398044 -309.248842)
			(xy 195.394084 -309.199788) (xy 194.105276 -309.199788) (xy 194.104781 -309.224395) (xy 194.096886 -309.272972)
			(xy 194.081302 -309.319653) (xy 194.058431 -309.36323) (xy 194.028866 -309.402574) (xy 193.993373 -309.436666)
			(xy 193.95287 -309.464622) (xy 193.908408 -309.48572) (xy 193.861137 -309.499412) (xy 193.812282 -309.505344)
			(xy 193.763107 -309.503363) (xy 193.714888 -309.493519) (xy 193.668872 -309.476067) (xy 193.626251 -309.45146)
			(xy 193.58813 -309.420335) (xy 193.555495 -309.383498) (xy 193.529192 -309.341902) (xy 193.509901 -309.296626)
			(xy 193.498124 -309.248842) (xy 193.494164 -309.199788) (xy 193.155316 -309.199788) (xy 193.154821 -309.224395)
			(xy 193.146926 -309.272972) (xy 193.131342 -309.319653) (xy 193.108471 -309.36323) (xy 193.078906 -309.402574)
			(xy 193.043413 -309.436666) (xy 193.00291 -309.464622) (xy 192.958448 -309.48572) (xy 192.911177 -309.499412)
			(xy 192.862322 -309.505344) (xy 192.813147 -309.503363) (xy 192.764928 -309.493519) (xy 192.718912 -309.476067)
			(xy 192.676291 -309.45146) (xy 192.63817 -309.420335) (xy 192.605535 -309.383498) (xy 192.579232 -309.341902)
			(xy 192.559941 -309.296626) (xy 192.548164 -309.248842) (xy 192.544204 -309.199788) (xy 158.955232 -309.199788)
			(xy 158.954737 -309.224395) (xy 158.946842 -309.272972) (xy 158.931258 -309.319653) (xy 158.908387 -309.36323)
			(xy 158.878822 -309.402574) (xy 158.843329 -309.436666) (xy 158.802826 -309.464622) (xy 158.758364 -309.48572)
			(xy 158.711093 -309.499412) (xy 158.662238 -309.505344) (xy 158.613063 -309.503363) (xy 158.564844 -309.493519)
			(xy 158.518828 -309.476067) (xy 158.476207 -309.45146) (xy 158.438086 -309.420335) (xy 158.405451 -309.383498)
			(xy 158.379148 -309.341902) (xy 158.359857 -309.296626) (xy 158.34808 -309.248842) (xy 158.34412 -309.199788)
			(xy 158.005272 -309.199788) (xy 158.004777 -309.224395) (xy 157.996882 -309.272972) (xy 157.981298 -309.319653)
			(xy 157.958427 -309.36323) (xy 157.928862 -309.402574) (xy 157.893369 -309.436666) (xy 157.852866 -309.464622)
			(xy 157.808404 -309.48572) (xy 157.761133 -309.499412) (xy 157.712278 -309.505344) (xy 157.663103 -309.503363)
			(xy 157.614884 -309.493519) (xy 157.568868 -309.476067) (xy 157.526247 -309.45146) (xy 157.488126 -309.420335)
			(xy 157.455491 -309.383498) (xy 157.429188 -309.341902) (xy 157.409897 -309.296626) (xy 157.39812 -309.248842)
			(xy 157.39416 -309.199788) (xy 156.105352 -309.199788) (xy 156.104857 -309.224395) (xy 156.096962 -309.272972)
			(xy 156.081378 -309.319653) (xy 156.058507 -309.36323) (xy 156.028942 -309.402574) (xy 155.993449 -309.436666)
			(xy 155.952946 -309.464622) (xy 155.908484 -309.48572) (xy 155.861213 -309.499412) (xy 155.812358 -309.505344)
			(xy 155.763183 -309.503363) (xy 155.714964 -309.493519) (xy 155.668948 -309.476067) (xy 155.626327 -309.45146)
			(xy 155.588206 -309.420335) (xy 155.555571 -309.383498) (xy 155.529268 -309.341902) (xy 155.509977 -309.296626)
			(xy 155.4982 -309.248842) (xy 155.49424 -309.199788) (xy 155.155392 -309.199788) (xy 155.154897 -309.224395)
			(xy 155.147002 -309.272972) (xy 155.131418 -309.319653) (xy 155.108547 -309.36323) (xy 155.078982 -309.402574)
			(xy 155.043489 -309.436666) (xy 155.002986 -309.464622) (xy 154.958524 -309.48572) (xy 154.911253 -309.499412)
			(xy 154.862398 -309.505344) (xy 154.813223 -309.503363) (xy 154.765004 -309.493519) (xy 154.718988 -309.476067)
			(xy 154.676367 -309.45146) (xy 154.638246 -309.420335) (xy 154.605611 -309.383498) (xy 154.579308 -309.341902)
			(xy 154.560017 -309.296626) (xy 154.54824 -309.248842) (xy 154.54428 -309.199788) (xy 80.855058 -309.199788)
			(xy 80.854563 -309.224395) (xy 80.846668 -309.272972) (xy 80.831084 -309.319653) (xy 80.808213 -309.36323)
			(xy 80.778648 -309.402574) (xy 80.743155 -309.436666) (xy 80.702652 -309.464622) (xy 80.65819 -309.48572)
			(xy 80.610919 -309.499412) (xy 80.562064 -309.505344) (xy 80.512889 -309.503363) (xy 80.46467 -309.493519)
			(xy 80.418654 -309.476067) (xy 80.376033 -309.45146) (xy 80.337912 -309.420335) (xy 80.305277 -309.383498)
			(xy 80.278974 -309.341902) (xy 80.259683 -309.296626) (xy 80.247906 -309.248842) (xy 80.243946 -309.199788)
			(xy 79.905098 -309.199788) (xy 79.904603 -309.224395) (xy 79.896708 -309.272972) (xy 79.881124 -309.319653)
			(xy 79.858253 -309.36323) (xy 79.828688 -309.402574) (xy 79.793195 -309.436666) (xy 79.752692 -309.464622)
			(xy 79.70823 -309.48572) (xy 79.660959 -309.499412) (xy 79.612104 -309.505344) (xy 79.562929 -309.503363)
			(xy 79.51471 -309.493519) (xy 79.468694 -309.476067) (xy 79.426073 -309.45146) (xy 79.387952 -309.420335)
			(xy 79.355317 -309.383498) (xy 79.329014 -309.341902) (xy 79.309723 -309.296626) (xy 79.297946 -309.248842)
			(xy 79.293986 -309.199788) (xy 78.005178 -309.199788) (xy 78.004683 -309.224395) (xy 77.996788 -309.272972)
			(xy 77.981204 -309.319653) (xy 77.958333 -309.36323) (xy 77.928768 -309.402574) (xy 77.893275 -309.436666)
			(xy 77.852772 -309.464622) (xy 77.80831 -309.48572) (xy 77.761039 -309.499412) (xy 77.712184 -309.505344)
			(xy 77.663009 -309.503363) (xy 77.61479 -309.493519) (xy 77.568774 -309.476067) (xy 77.526153 -309.45146)
			(xy 77.488032 -309.420335) (xy 77.455397 -309.383498) (xy 77.429094 -309.341902) (xy 77.409803 -309.296626)
			(xy 77.398026 -309.248842) (xy 77.394066 -309.199788) (xy 77.055218 -309.199788) (xy 77.054723 -309.224395)
			(xy 77.046828 -309.272972) (xy 77.031244 -309.319653) (xy 77.008373 -309.36323) (xy 76.978808 -309.402574)
			(xy 76.943315 -309.436666) (xy 76.902812 -309.464622) (xy 76.85835 -309.48572) (xy 76.811079 -309.499412)
			(xy 76.762224 -309.505344) (xy 76.713049 -309.503363) (xy 76.66483 -309.493519) (xy 76.618814 -309.476067)
			(xy 76.576193 -309.45146) (xy 76.538072 -309.420335) (xy 76.505437 -309.383498) (xy 76.479134 -309.341902)
			(xy 76.459843 -309.296626) (xy 76.448066 -309.248842) (xy 76.444106 -309.199788) (xy 42.855134 -309.199788)
			(xy 42.854639 -309.224395) (xy 42.846744 -309.272972) (xy 42.83116 -309.319653) (xy 42.808289 -309.36323)
			(xy 42.778724 -309.402574) (xy 42.743231 -309.436666) (xy 42.702728 -309.464622) (xy 42.658266 -309.48572)
			(xy 42.610995 -309.499412) (xy 42.56214 -309.505344) (xy 42.512965 -309.503363) (xy 42.464746 -309.493519)
			(xy 42.41873 -309.476067) (xy 42.376109 -309.45146) (xy 42.337988 -309.420335) (xy 42.305353 -309.383498)
			(xy 42.27905 -309.341902) (xy 42.259759 -309.296626) (xy 42.247982 -309.248842) (xy 42.244022 -309.199788)
			(xy 41.905174 -309.199788) (xy 41.904679 -309.224395) (xy 41.896784 -309.272972) (xy 41.8812 -309.319653)
			(xy 41.858329 -309.36323) (xy 41.828764 -309.402574) (xy 41.793271 -309.436666) (xy 41.752768 -309.464622)
			(xy 41.708306 -309.48572) (xy 41.661035 -309.499412) (xy 41.61218 -309.505344) (xy 41.563005 -309.503363)
			(xy 41.514786 -309.493519) (xy 41.46877 -309.476067) (xy 41.426149 -309.45146) (xy 41.388028 -309.420335)
			(xy 41.355393 -309.383498) (xy 41.32909 -309.341902) (xy 41.309799 -309.296626) (xy 41.298022 -309.248842)
			(xy 41.294062 -309.199788) (xy 40.005254 -309.199788) (xy 40.004759 -309.224395) (xy 39.996864 -309.272972)
			(xy 39.98128 -309.319653) (xy 39.958409 -309.36323) (xy 39.928844 -309.402574) (xy 39.893351 -309.436666)
			(xy 39.852848 -309.464622) (xy 39.808386 -309.48572) (xy 39.761115 -309.499412) (xy 39.71226 -309.505344)
			(xy 39.663085 -309.503363) (xy 39.614866 -309.493519) (xy 39.56885 -309.476067) (xy 39.526229 -309.45146)
			(xy 39.488108 -309.420335) (xy 39.455473 -309.383498) (xy 39.42917 -309.341902) (xy 39.409879 -309.296626)
			(xy 39.398102 -309.248842) (xy 39.394142 -309.199788) (xy 39.055294 -309.199788) (xy 39.054799 -309.224395)
			(xy 39.046904 -309.272972) (xy 39.03132 -309.319653) (xy 39.008449 -309.36323) (xy 38.978884 -309.402574)
			(xy 38.943391 -309.436666) (xy 38.902888 -309.464622) (xy 38.858426 -309.48572) (xy 38.811155 -309.499412)
			(xy 38.7623 -309.505344) (xy 38.713125 -309.503363) (xy 38.664906 -309.493519) (xy 38.61889 -309.476067)
			(xy 38.576269 -309.45146) (xy 38.538148 -309.420335) (xy 38.505513 -309.383498) (xy 38.47921 -309.341902)
			(xy 38.459919 -309.296626) (xy 38.448142 -309.248842) (xy 38.444182 -309.199788) (xy 0.508 -309.199788)
			(xy 0.508 -310.149748) (xy 36.544008 -310.149748) (xy 36.547968 -310.100694) (xy 36.559745 -310.05291)
			(xy 36.579036 -310.007634) (xy 36.605339 -309.966038) (xy 36.637974 -309.929201) (xy 36.676095 -309.898076)
			(xy 36.718716 -309.873469) (xy 36.764732 -309.856017) (xy 36.812951 -309.846173) (xy 36.862126 -309.844192)
			(xy 36.910981 -309.850124) (xy 36.958252 -309.863816) (xy 37.002714 -309.884914) (xy 37.043217 -309.91287)
			(xy 37.07871 -309.946962) (xy 37.108275 -309.986306) (xy 37.131146 -310.029883) (xy 37.14673 -310.076564)
			(xy 37.154625 -310.125141) (xy 37.15512 -310.149748) (xy 37.493968 -310.149748) (xy 37.497928 -310.100694)
			(xy 37.509705 -310.05291) (xy 37.528996 -310.007634) (xy 37.555299 -309.966038) (xy 37.587934 -309.929201)
			(xy 37.626055 -309.898076) (xy 37.668676 -309.873469) (xy 37.714692 -309.856017) (xy 37.762911 -309.846173)
			(xy 37.812086 -309.844192) (xy 37.860941 -309.850124) (xy 37.908212 -309.863816) (xy 37.952674 -309.884914)
			(xy 37.993177 -309.91287) (xy 38.02867 -309.946962) (xy 38.058235 -309.986306) (xy 38.081106 -310.029883)
			(xy 38.09669 -310.076564) (xy 38.104585 -310.125141) (xy 38.10508 -310.149748) (xy 81.19416 -310.149748)
			(xy 81.19812 -310.100694) (xy 81.209897 -310.05291) (xy 81.229188 -310.007634) (xy 81.255491 -309.966038)
			(xy 81.288126 -309.929201) (xy 81.326247 -309.898076) (xy 81.368868 -309.873469) (xy 81.414884 -309.856017)
			(xy 81.463103 -309.846173) (xy 81.512278 -309.844192) (xy 81.561133 -309.850124) (xy 81.608404 -309.863816)
			(xy 81.652866 -309.884914) (xy 81.693369 -309.91287) (xy 81.728862 -309.946962) (xy 81.758427 -309.986306)
			(xy 81.781298 -310.029883) (xy 81.796882 -310.076564) (xy 81.804777 -310.125141) (xy 81.805272 -310.149748)
			(xy 82.14412 -310.149748) (xy 82.14808 -310.100694) (xy 82.159857 -310.05291) (xy 82.179148 -310.007634)
			(xy 82.205451 -309.966038) (xy 82.238086 -309.929201) (xy 82.276207 -309.898076) (xy 82.318828 -309.873469)
			(xy 82.364844 -309.856017) (xy 82.413063 -309.846173) (xy 82.462238 -309.844192) (xy 82.511093 -309.850124)
			(xy 82.558364 -309.863816) (xy 82.602826 -309.884914) (xy 82.643329 -309.91287) (xy 82.678822 -309.946962)
			(xy 82.708387 -309.986306) (xy 82.731258 -310.029883) (xy 82.746842 -310.076564) (xy 82.754737 -310.125141)
			(xy 82.755232 -310.149748) (xy 152.644106 -310.149748) (xy 152.648066 -310.100694) (xy 152.659843 -310.05291)
			(xy 152.679134 -310.007634) (xy 152.705437 -309.966038) (xy 152.738072 -309.929201) (xy 152.776193 -309.898076)
			(xy 152.818814 -309.873469) (xy 152.86483 -309.856017) (xy 152.913049 -309.846173) (xy 152.962224 -309.844192)
			(xy 153.011079 -309.850124) (xy 153.05835 -309.863816) (xy 153.102812 -309.884914) (xy 153.143315 -309.91287)
			(xy 153.178808 -309.946962) (xy 153.208373 -309.986306) (xy 153.231244 -310.029883) (xy 153.246828 -310.076564)
			(xy 153.254723 -310.125141) (xy 153.255218 -310.149748) (xy 153.594066 -310.149748) (xy 153.598026 -310.100694)
			(xy 153.609803 -310.05291) (xy 153.629094 -310.007634) (xy 153.655397 -309.966038) (xy 153.688032 -309.929201)
			(xy 153.726153 -309.898076) (xy 153.768774 -309.873469) (xy 153.81479 -309.856017) (xy 153.863009 -309.846173)
			(xy 153.912184 -309.844192) (xy 153.961039 -309.850124) (xy 154.00831 -309.863816) (xy 154.052772 -309.884914)
			(xy 154.093275 -309.91287) (xy 154.128768 -309.946962) (xy 154.158333 -309.986306) (xy 154.181204 -310.029883)
			(xy 154.196788 -310.076564) (xy 154.204683 -310.125141) (xy 154.205178 -310.149748) (xy 197.294258 -310.149748)
			(xy 197.298218 -310.100694) (xy 197.309995 -310.05291) (xy 197.329286 -310.007634) (xy 197.355589 -309.966038)
			(xy 197.388224 -309.929201) (xy 197.426345 -309.898076) (xy 197.468966 -309.873469) (xy 197.514982 -309.856017)
			(xy 197.563201 -309.846173) (xy 197.612376 -309.844192) (xy 197.661231 -309.850124) (xy 197.708502 -309.863816)
			(xy 197.752964 -309.884914) (xy 197.793467 -309.91287) (xy 197.82896 -309.946962) (xy 197.858525 -309.986306)
			(xy 197.881396 -310.029883) (xy 197.89698 -310.076564) (xy 197.904875 -310.125141) (xy 197.90537 -310.149748)
			(xy 198.244218 -310.149748) (xy 198.248178 -310.100694) (xy 198.259955 -310.05291) (xy 198.279246 -310.007634)
			(xy 198.305549 -309.966038) (xy 198.338184 -309.929201) (xy 198.376305 -309.898076) (xy 198.418926 -309.873469)
			(xy 198.464942 -309.856017) (xy 198.513161 -309.846173) (xy 198.562336 -309.844192) (xy 198.611191 -309.850124)
			(xy 198.658462 -309.863816) (xy 198.702924 -309.884914) (xy 198.743427 -309.91287) (xy 198.77892 -309.946962)
			(xy 198.808485 -309.986306) (xy 198.831356 -310.029883) (xy 198.84694 -310.076564) (xy 198.854835 -310.125141)
			(xy 198.85533 -310.149748) (xy 268.74395 -310.149748) (xy 268.74791 -310.100694) (xy 268.759687 -310.05291)
			(xy 268.778978 -310.007634) (xy 268.805281 -309.966038) (xy 268.837916 -309.929201) (xy 268.876037 -309.898076)
			(xy 268.918658 -309.873469) (xy 268.964674 -309.856017) (xy 269.012893 -309.846173) (xy 269.062068 -309.844192)
			(xy 269.110923 -309.850124) (xy 269.158194 -309.863816) (xy 269.202656 -309.884914) (xy 269.243159 -309.91287)
			(xy 269.278652 -309.946962) (xy 269.308217 -309.986306) (xy 269.331088 -310.029883) (xy 269.346672 -310.076564)
			(xy 269.354567 -310.125141) (xy 269.355062 -310.149748) (xy 269.69391 -310.149748) (xy 269.69787 -310.100694)
			(xy 269.709647 -310.05291) (xy 269.728938 -310.007634) (xy 269.755241 -309.966038) (xy 269.787876 -309.929201)
			(xy 269.825997 -309.898076) (xy 269.868618 -309.873469) (xy 269.914634 -309.856017) (xy 269.962853 -309.846173)
			(xy 270.012028 -309.844192) (xy 270.060883 -309.850124) (xy 270.108154 -309.863816) (xy 270.152616 -309.884914)
			(xy 270.193119 -309.91287) (xy 270.228612 -309.946962) (xy 270.258177 -309.986306) (xy 270.281048 -310.029883)
			(xy 270.296632 -310.076564) (xy 270.304527 -310.125141) (xy 270.305022 -310.149748) (xy 313.394102 -310.149748)
			(xy 313.398062 -310.100694) (xy 313.409839 -310.05291) (xy 313.42913 -310.007634) (xy 313.455433 -309.966038)
			(xy 313.488068 -309.929201) (xy 313.526189 -309.898076) (xy 313.56881 -309.873469) (xy 313.614826 -309.856017)
			(xy 313.663045 -309.846173) (xy 313.71222 -309.844192) (xy 313.761075 -309.850124) (xy 313.808346 -309.863816)
			(xy 313.852808 -309.884914) (xy 313.893311 -309.91287) (xy 313.928804 -309.946962) (xy 313.958369 -309.986306)
			(xy 313.98124 -310.029883) (xy 313.996824 -310.076564) (xy 314.004719 -310.125141) (xy 314.005214 -310.149748)
			(xy 314.344062 -310.149748) (xy 314.348022 -310.100694) (xy 314.359799 -310.05291) (xy 314.37909 -310.007634)
			(xy 314.405393 -309.966038) (xy 314.438028 -309.929201) (xy 314.476149 -309.898076) (xy 314.51877 -309.873469)
			(xy 314.564786 -309.856017) (xy 314.613005 -309.846173) (xy 314.66218 -309.844192) (xy 314.711035 -309.850124)
			(xy 314.758306 -309.863816) (xy 314.802768 -309.884914) (xy 314.843271 -309.91287) (xy 314.878764 -309.946962)
			(xy 314.908329 -309.986306) (xy 314.9312 -310.029883) (xy 314.946784 -310.076564) (xy 314.954679 -310.125141)
			(xy 314.955174 -310.149748) (xy 384.844048 -310.149748) (xy 384.848008 -310.100694) (xy 384.859785 -310.05291)
			(xy 384.879076 -310.007634) (xy 384.905379 -309.966038) (xy 384.938014 -309.929201) (xy 384.976135 -309.898076)
			(xy 385.018756 -309.873469) (xy 385.064772 -309.856017) (xy 385.112991 -309.846173) (xy 385.162166 -309.844192)
			(xy 385.211021 -309.850124) (xy 385.258292 -309.863816) (xy 385.302754 -309.884914) (xy 385.343257 -309.91287)
			(xy 385.37875 -309.946962) (xy 385.408315 -309.986306) (xy 385.431186 -310.029883) (xy 385.44677 -310.076564)
			(xy 385.454665 -310.125141) (xy 385.45516 -310.149748) (xy 385.794008 -310.149748) (xy 385.797968 -310.100694)
			(xy 385.809745 -310.05291) (xy 385.829036 -310.007634) (xy 385.855339 -309.966038) (xy 385.887974 -309.929201)
			(xy 385.926095 -309.898076) (xy 385.968716 -309.873469) (xy 386.014732 -309.856017) (xy 386.062951 -309.846173)
			(xy 386.112126 -309.844192) (xy 386.160981 -309.850124) (xy 386.208252 -309.863816) (xy 386.252714 -309.884914)
			(xy 386.293217 -309.91287) (xy 386.32871 -309.946962) (xy 386.358275 -309.986306) (xy 386.381146 -310.029883)
			(xy 386.39673 -310.076564) (xy 386.404625 -310.125141) (xy 386.40512 -310.149748) (xy 429.4942 -310.149748)
			(xy 429.49816 -310.100694) (xy 429.509937 -310.05291) (xy 429.529228 -310.007634) (xy 429.555531 -309.966038)
			(xy 429.588166 -309.929201) (xy 429.626287 -309.898076) (xy 429.668908 -309.873469) (xy 429.714924 -309.856017)
			(xy 429.763143 -309.846173) (xy 429.812318 -309.844192) (xy 429.861173 -309.850124) (xy 429.908444 -309.863816)
			(xy 429.952906 -309.884914) (xy 429.993409 -309.91287) (xy 430.028902 -309.946962) (xy 430.058467 -309.986306)
			(xy 430.081338 -310.029883) (xy 430.096922 -310.076564) (xy 430.104817 -310.125141) (xy 430.105312 -310.149748)
			(xy 430.44416 -310.149748) (xy 430.44812 -310.100694) (xy 430.459897 -310.05291) (xy 430.479188 -310.007634)
			(xy 430.505491 -309.966038) (xy 430.538126 -309.929201) (xy 430.576247 -309.898076) (xy 430.618868 -309.873469)
			(xy 430.664884 -309.856017) (xy 430.713103 -309.846173) (xy 430.762278 -309.844192) (xy 430.811133 -309.850124)
			(xy 430.858404 -309.863816) (xy 430.902866 -309.884914) (xy 430.943369 -309.91287) (xy 430.978862 -309.946962)
			(xy 431.008427 -309.986306) (xy 431.031298 -310.029883) (xy 431.046882 -310.076564) (xy 431.054777 -310.125141)
			(xy 431.055272 -310.149748) (xy 431.054777 -310.174355) (xy 431.046882 -310.222932) (xy 431.031298 -310.269613)
			(xy 431.008427 -310.31319) (xy 430.978862 -310.352534) (xy 430.943369 -310.386626) (xy 430.902866 -310.414582)
			(xy 430.858404 -310.43568) (xy 430.811133 -310.449372) (xy 430.762278 -310.455304) (xy 430.713103 -310.453323)
			(xy 430.664884 -310.443479) (xy 430.618868 -310.426027) (xy 430.576247 -310.40142) (xy 430.538126 -310.370295)
			(xy 430.505491 -310.333458) (xy 430.479188 -310.291862) (xy 430.459897 -310.246586) (xy 430.44812 -310.198802)
			(xy 430.44416 -310.149748) (xy 430.105312 -310.149748) (xy 430.104817 -310.174355) (xy 430.096922 -310.222932)
			(xy 430.081338 -310.269613) (xy 430.058467 -310.31319) (xy 430.028902 -310.352534) (xy 429.993409 -310.386626)
			(xy 429.952906 -310.414582) (xy 429.908444 -310.43568) (xy 429.861173 -310.449372) (xy 429.812318 -310.455304)
			(xy 429.763143 -310.453323) (xy 429.714924 -310.443479) (xy 429.668908 -310.426027) (xy 429.626287 -310.40142)
			(xy 429.588166 -310.370295) (xy 429.555531 -310.333458) (xy 429.529228 -310.291862) (xy 429.509937 -310.246586)
			(xy 429.49816 -310.198802) (xy 429.4942 -310.149748) (xy 386.40512 -310.149748) (xy 386.404625 -310.174355)
			(xy 386.39673 -310.222932) (xy 386.381146 -310.269613) (xy 386.358275 -310.31319) (xy 386.32871 -310.352534)
			(xy 386.293217 -310.386626) (xy 386.252714 -310.414582) (xy 386.208252 -310.43568) (xy 386.160981 -310.449372)
			(xy 386.112126 -310.455304) (xy 386.062951 -310.453323) (xy 386.014732 -310.443479) (xy 385.968716 -310.426027)
			(xy 385.926095 -310.40142) (xy 385.887974 -310.370295) (xy 385.855339 -310.333458) (xy 385.829036 -310.291862)
			(xy 385.809745 -310.246586) (xy 385.797968 -310.198802) (xy 385.794008 -310.149748) (xy 385.45516 -310.149748)
			(xy 385.454665 -310.174355) (xy 385.44677 -310.222932) (xy 385.431186 -310.269613) (xy 385.408315 -310.31319)
			(xy 385.37875 -310.352534) (xy 385.343257 -310.386626) (xy 385.302754 -310.414582) (xy 385.258292 -310.43568)
			(xy 385.211021 -310.449372) (xy 385.162166 -310.455304) (xy 385.112991 -310.453323) (xy 385.064772 -310.443479)
			(xy 385.018756 -310.426027) (xy 384.976135 -310.40142) (xy 384.938014 -310.370295) (xy 384.905379 -310.333458)
			(xy 384.879076 -310.291862) (xy 384.859785 -310.246586) (xy 384.848008 -310.198802) (xy 384.844048 -310.149748)
			(xy 314.955174 -310.149748) (xy 314.954679 -310.174355) (xy 314.946784 -310.222932) (xy 314.9312 -310.269613)
			(xy 314.908329 -310.31319) (xy 314.878764 -310.352534) (xy 314.843271 -310.386626) (xy 314.802768 -310.414582)
			(xy 314.758306 -310.43568) (xy 314.711035 -310.449372) (xy 314.66218 -310.455304) (xy 314.613005 -310.453323)
			(xy 314.564786 -310.443479) (xy 314.51877 -310.426027) (xy 314.476149 -310.40142) (xy 314.438028 -310.370295)
			(xy 314.405393 -310.333458) (xy 314.37909 -310.291862) (xy 314.359799 -310.246586) (xy 314.348022 -310.198802)
			(xy 314.344062 -310.149748) (xy 314.005214 -310.149748) (xy 314.004719 -310.174355) (xy 313.996824 -310.222932)
			(xy 313.98124 -310.269613) (xy 313.958369 -310.31319) (xy 313.928804 -310.352534) (xy 313.893311 -310.386626)
			(xy 313.852808 -310.414582) (xy 313.808346 -310.43568) (xy 313.761075 -310.449372) (xy 313.71222 -310.455304)
			(xy 313.663045 -310.453323) (xy 313.614826 -310.443479) (xy 313.56881 -310.426027) (xy 313.526189 -310.40142)
			(xy 313.488068 -310.370295) (xy 313.455433 -310.333458) (xy 313.42913 -310.291862) (xy 313.409839 -310.246586)
			(xy 313.398062 -310.198802) (xy 313.394102 -310.149748) (xy 270.305022 -310.149748) (xy 270.304527 -310.174355)
			(xy 270.296632 -310.222932) (xy 270.281048 -310.269613) (xy 270.258177 -310.31319) (xy 270.228612 -310.352534)
			(xy 270.193119 -310.386626) (xy 270.152616 -310.414582) (xy 270.108154 -310.43568) (xy 270.060883 -310.449372)
			(xy 270.012028 -310.455304) (xy 269.962853 -310.453323) (xy 269.914634 -310.443479) (xy 269.868618 -310.426027)
			(xy 269.825997 -310.40142) (xy 269.787876 -310.370295) (xy 269.755241 -310.333458) (xy 269.728938 -310.291862)
			(xy 269.709647 -310.246586) (xy 269.69787 -310.198802) (xy 269.69391 -310.149748) (xy 269.355062 -310.149748)
			(xy 269.354567 -310.174355) (xy 269.346672 -310.222932) (xy 269.331088 -310.269613) (xy 269.308217 -310.31319)
			(xy 269.278652 -310.352534) (xy 269.243159 -310.386626) (xy 269.202656 -310.414582) (xy 269.158194 -310.43568)
			(xy 269.110923 -310.449372) (xy 269.062068 -310.455304) (xy 269.012893 -310.453323) (xy 268.964674 -310.443479)
			(xy 268.918658 -310.426027) (xy 268.876037 -310.40142) (xy 268.837916 -310.370295) (xy 268.805281 -310.333458)
			(xy 268.778978 -310.291862) (xy 268.759687 -310.246586) (xy 268.74791 -310.198802) (xy 268.74395 -310.149748)
			(xy 198.85533 -310.149748) (xy 198.854835 -310.174355) (xy 198.84694 -310.222932) (xy 198.831356 -310.269613)
			(xy 198.808485 -310.31319) (xy 198.77892 -310.352534) (xy 198.743427 -310.386626) (xy 198.702924 -310.414582)
			(xy 198.658462 -310.43568) (xy 198.611191 -310.449372) (xy 198.562336 -310.455304) (xy 198.513161 -310.453323)
			(xy 198.464942 -310.443479) (xy 198.418926 -310.426027) (xy 198.376305 -310.40142) (xy 198.338184 -310.370295)
			(xy 198.305549 -310.333458) (xy 198.279246 -310.291862) (xy 198.259955 -310.246586) (xy 198.248178 -310.198802)
			(xy 198.244218 -310.149748) (xy 197.90537 -310.149748) (xy 197.904875 -310.174355) (xy 197.89698 -310.222932)
			(xy 197.881396 -310.269613) (xy 197.858525 -310.31319) (xy 197.82896 -310.352534) (xy 197.793467 -310.386626)
			(xy 197.752964 -310.414582) (xy 197.708502 -310.43568) (xy 197.661231 -310.449372) (xy 197.612376 -310.455304)
			(xy 197.563201 -310.453323) (xy 197.514982 -310.443479) (xy 197.468966 -310.426027) (xy 197.426345 -310.40142)
			(xy 197.388224 -310.370295) (xy 197.355589 -310.333458) (xy 197.329286 -310.291862) (xy 197.309995 -310.246586)
			(xy 197.298218 -310.198802) (xy 197.294258 -310.149748) (xy 154.205178 -310.149748) (xy 154.204683 -310.174355)
			(xy 154.196788 -310.222932) (xy 154.181204 -310.269613) (xy 154.158333 -310.31319) (xy 154.128768 -310.352534)
			(xy 154.093275 -310.386626) (xy 154.052772 -310.414582) (xy 154.00831 -310.43568) (xy 153.961039 -310.449372)
			(xy 153.912184 -310.455304) (xy 153.863009 -310.453323) (xy 153.81479 -310.443479) (xy 153.768774 -310.426027)
			(xy 153.726153 -310.40142) (xy 153.688032 -310.370295) (xy 153.655397 -310.333458) (xy 153.629094 -310.291862)
			(xy 153.609803 -310.246586) (xy 153.598026 -310.198802) (xy 153.594066 -310.149748) (xy 153.255218 -310.149748)
			(xy 153.254723 -310.174355) (xy 153.246828 -310.222932) (xy 153.231244 -310.269613) (xy 153.208373 -310.31319)
			(xy 153.178808 -310.352534) (xy 153.143315 -310.386626) (xy 153.102812 -310.414582) (xy 153.05835 -310.43568)
			(xy 153.011079 -310.449372) (xy 152.962224 -310.455304) (xy 152.913049 -310.453323) (xy 152.86483 -310.443479)
			(xy 152.818814 -310.426027) (xy 152.776193 -310.40142) (xy 152.738072 -310.370295) (xy 152.705437 -310.333458)
			(xy 152.679134 -310.291862) (xy 152.659843 -310.246586) (xy 152.648066 -310.198802) (xy 152.644106 -310.149748)
			(xy 82.755232 -310.149748) (xy 82.754737 -310.174355) (xy 82.746842 -310.222932) (xy 82.731258 -310.269613)
			(xy 82.708387 -310.31319) (xy 82.678822 -310.352534) (xy 82.643329 -310.386626) (xy 82.602826 -310.414582)
			(xy 82.558364 -310.43568) (xy 82.511093 -310.449372) (xy 82.462238 -310.455304) (xy 82.413063 -310.453323)
			(xy 82.364844 -310.443479) (xy 82.318828 -310.426027) (xy 82.276207 -310.40142) (xy 82.238086 -310.370295)
			(xy 82.205451 -310.333458) (xy 82.179148 -310.291862) (xy 82.159857 -310.246586) (xy 82.14808 -310.198802)
			(xy 82.14412 -310.149748) (xy 81.805272 -310.149748) (xy 81.804777 -310.174355) (xy 81.796882 -310.222932)
			(xy 81.781298 -310.269613) (xy 81.758427 -310.31319) (xy 81.728862 -310.352534) (xy 81.693369 -310.386626)
			(xy 81.652866 -310.414582) (xy 81.608404 -310.43568) (xy 81.561133 -310.449372) (xy 81.512278 -310.455304)
			(xy 81.463103 -310.453323) (xy 81.414884 -310.443479) (xy 81.368868 -310.426027) (xy 81.326247 -310.40142)
			(xy 81.288126 -310.370295) (xy 81.255491 -310.333458) (xy 81.229188 -310.291862) (xy 81.209897 -310.246586)
			(xy 81.19812 -310.198802) (xy 81.19416 -310.149748) (xy 38.10508 -310.149748) (xy 38.104585 -310.174355)
			(xy 38.09669 -310.222932) (xy 38.081106 -310.269613) (xy 38.058235 -310.31319) (xy 38.02867 -310.352534)
			(xy 37.993177 -310.386626) (xy 37.952674 -310.414582) (xy 37.908212 -310.43568) (xy 37.860941 -310.449372)
			(xy 37.812086 -310.455304) (xy 37.762911 -310.453323) (xy 37.714692 -310.443479) (xy 37.668676 -310.426027)
			(xy 37.626055 -310.40142) (xy 37.587934 -310.370295) (xy 37.555299 -310.333458) (xy 37.528996 -310.291862)
			(xy 37.509705 -310.246586) (xy 37.497928 -310.198802) (xy 37.493968 -310.149748) (xy 37.15512 -310.149748)
			(xy 37.154625 -310.174355) (xy 37.14673 -310.222932) (xy 37.131146 -310.269613) (xy 37.108275 -310.31319)
			(xy 37.07871 -310.352534) (xy 37.043217 -310.386626) (xy 37.002714 -310.414582) (xy 36.958252 -310.43568)
			(xy 36.910981 -310.449372) (xy 36.862126 -310.455304) (xy 36.812951 -310.453323) (xy 36.764732 -310.443479)
			(xy 36.718716 -310.426027) (xy 36.676095 -310.40142) (xy 36.637974 -310.370295) (xy 36.605339 -310.333458)
			(xy 36.579036 -310.291862) (xy 36.559745 -310.246586) (xy 36.547968 -310.198802) (xy 36.544008 -310.149748)
			(xy 0.508 -310.149748) (xy 0.508 -311.099962) (xy 39.394142 -311.099962) (xy 39.398102 -311.050908)
			(xy 39.409879 -311.003124) (xy 39.42917 -310.957848) (xy 39.455473 -310.916252) (xy 39.488108 -310.879415)
			(xy 39.526229 -310.84829) (xy 39.56885 -310.823683) (xy 39.614866 -310.806231) (xy 39.663085 -310.796387)
			(xy 39.71226 -310.794406) (xy 39.761115 -310.800338) (xy 39.808386 -310.81403) (xy 39.852848 -310.835128)
			(xy 39.893351 -310.863084) (xy 39.928844 -310.897176) (xy 39.958409 -310.93652) (xy 39.98128 -310.980097)
			(xy 39.996864 -311.026778) (xy 40.004759 -311.075355) (xy 40.005254 -311.099962) (xy 41.294062 -311.099962)
			(xy 41.298022 -311.050908) (xy 41.309799 -311.003124) (xy 41.32909 -310.957848) (xy 41.355393 -310.916252)
			(xy 41.388028 -310.879415) (xy 41.426149 -310.84829) (xy 41.46877 -310.823683) (xy 41.514786 -310.806231)
			(xy 41.563005 -310.796387) (xy 41.61218 -310.794406) (xy 41.661035 -310.800338) (xy 41.708306 -310.81403)
			(xy 41.752768 -310.835128) (xy 41.793271 -310.863084) (xy 41.828764 -310.897176) (xy 41.858329 -310.93652)
			(xy 41.8812 -310.980097) (xy 41.896784 -311.026778) (xy 41.904679 -311.075355) (xy 41.905174 -311.099962)
			(xy 43.193982 -311.099962) (xy 43.197942 -311.050908) (xy 43.209719 -311.003124) (xy 43.22901 -310.957848)
			(xy 43.255313 -310.916252) (xy 43.287948 -310.879415) (xy 43.326069 -310.84829) (xy 43.36869 -310.823683)
			(xy 43.414706 -310.806231) (xy 43.462925 -310.796387) (xy 43.5121 -310.794406) (xy 43.560955 -310.800338)
			(xy 43.608226 -310.81403) (xy 43.652688 -310.835128) (xy 43.693191 -310.863084) (xy 43.728684 -310.897176)
			(xy 43.758249 -310.93652) (xy 43.78112 -310.980097) (xy 43.796704 -311.026778) (xy 43.804599 -311.075355)
			(xy 43.805094 -311.099962) (xy 45.094156 -311.099962) (xy 45.098116 -311.050908) (xy 45.109893 -311.003124)
			(xy 45.129184 -310.957848) (xy 45.155487 -310.916252) (xy 45.188122 -310.879415) (xy 45.226243 -310.84829)
			(xy 45.268864 -310.823683) (xy 45.31488 -310.806231) (xy 45.363099 -310.796387) (xy 45.412274 -310.794406)
			(xy 45.461129 -310.800338) (xy 45.5084 -310.81403) (xy 45.552862 -310.835128) (xy 45.593365 -310.863084)
			(xy 45.628858 -310.897176) (xy 45.658423 -310.93652) (xy 45.681294 -310.980097) (xy 45.696878 -311.026778)
			(xy 45.704773 -311.075355) (xy 45.705268 -311.099962) (xy 46.994076 -311.099962) (xy 46.998036 -311.050908)
			(xy 47.009813 -311.003124) (xy 47.029104 -310.957848) (xy 47.055407 -310.916252) (xy 47.088042 -310.879415)
			(xy 47.126163 -310.84829) (xy 47.168784 -310.823683) (xy 47.2148 -310.806231) (xy 47.263019 -310.796387)
			(xy 47.312194 -310.794406) (xy 47.361049 -310.800338) (xy 47.40832 -310.81403) (xy 47.452782 -310.835128)
			(xy 47.493285 -310.863084) (xy 47.528778 -310.897176) (xy 47.558343 -310.93652) (xy 47.581214 -310.980097)
			(xy 47.596798 -311.026778) (xy 47.604693 -311.075355) (xy 47.605188 -311.099962) (xy 48.893996 -311.099962)
			(xy 48.897956 -311.050908) (xy 48.909733 -311.003124) (xy 48.929024 -310.957848) (xy 48.955327 -310.916252)
			(xy 48.987962 -310.879415) (xy 49.026083 -310.84829) (xy 49.068704 -310.823683) (xy 49.11472 -310.806231)
			(xy 49.162939 -310.796387) (xy 49.212114 -310.794406) (xy 49.260969 -310.800338) (xy 49.30824 -310.81403)
			(xy 49.352702 -310.835128) (xy 49.393205 -310.863084) (xy 49.428698 -310.897176) (xy 49.458263 -310.93652)
			(xy 49.481134 -310.980097) (xy 49.496718 -311.026778) (xy 49.504613 -311.075355) (xy 49.505108 -311.099962)
			(xy 50.79417 -311.099962) (xy 50.79813 -311.050908) (xy 50.809907 -311.003124) (xy 50.829198 -310.957848)
			(xy 50.855501 -310.916252) (xy 50.888136 -310.879415) (xy 50.926257 -310.84829) (xy 50.968878 -310.823683)
			(xy 51.014894 -310.806231) (xy 51.063113 -310.796387) (xy 51.112288 -310.794406) (xy 51.161143 -310.800338)
			(xy 51.208414 -310.81403) (xy 51.252876 -310.835128) (xy 51.293379 -310.863084) (xy 51.328872 -310.897176)
			(xy 51.358437 -310.93652) (xy 51.381308 -310.980097) (xy 51.396892 -311.026778) (xy 51.404787 -311.075355)
			(xy 51.405282 -311.099962) (xy 52.69409 -311.099962) (xy 52.69805 -311.050908) (xy 52.709827 -311.003124)
			(xy 52.729118 -310.957848) (xy 52.755421 -310.916252) (xy 52.788056 -310.879415) (xy 52.826177 -310.84829)
			(xy 52.868798 -310.823683) (xy 52.914814 -310.806231) (xy 52.963033 -310.796387) (xy 53.012208 -310.794406)
			(xy 53.061063 -310.800338) (xy 53.108334 -310.81403) (xy 53.152796 -310.835128) (xy 53.193299 -310.863084)
			(xy 53.228792 -310.897176) (xy 53.258357 -310.93652) (xy 53.281228 -310.980097) (xy 53.296812 -311.026778)
			(xy 53.304707 -311.075355) (xy 53.305202 -311.099962) (xy 54.59401 -311.099962) (xy 54.59797 -311.050908)
			(xy 54.609747 -311.003124) (xy 54.629038 -310.957848) (xy 54.655341 -310.916252) (xy 54.687976 -310.879415)
			(xy 54.726097 -310.84829) (xy 54.768718 -310.823683) (xy 54.814734 -310.806231) (xy 54.862953 -310.796387)
			(xy 54.912128 -310.794406) (xy 54.960983 -310.800338) (xy 55.008254 -310.81403) (xy 55.052716 -310.835128)
			(xy 55.093219 -310.863084) (xy 55.128712 -310.897176) (xy 55.158277 -310.93652) (xy 55.181148 -310.980097)
			(xy 55.196732 -311.026778) (xy 55.204627 -311.075355) (xy 55.205122 -311.099962) (xy 56.494184 -311.099962)
			(xy 56.498144 -311.050908) (xy 56.509921 -311.003124) (xy 56.529212 -310.957848) (xy 56.555515 -310.916252)
			(xy 56.58815 -310.879415) (xy 56.626271 -310.84829) (xy 56.668892 -310.823683) (xy 56.714908 -310.806231)
			(xy 56.763127 -310.796387) (xy 56.812302 -310.794406) (xy 56.861157 -310.800338) (xy 56.908428 -310.81403)
			(xy 56.95289 -310.835128) (xy 56.993393 -310.863084) (xy 57.028886 -310.897176) (xy 57.058451 -310.93652)
			(xy 57.081322 -310.980097) (xy 57.096906 -311.026778) (xy 57.104801 -311.075355) (xy 57.105296 -311.099962)
			(xy 58.394104 -311.099962) (xy 58.398064 -311.050908) (xy 58.409841 -311.003124) (xy 58.429132 -310.957848)
			(xy 58.455435 -310.916252) (xy 58.48807 -310.879415) (xy 58.526191 -310.84829) (xy 58.568812 -310.823683)
			(xy 58.614828 -310.806231) (xy 58.663047 -310.796387) (xy 58.712222 -310.794406) (xy 58.761077 -310.800338)
			(xy 58.808348 -310.81403) (xy 58.85281 -310.835128) (xy 58.893313 -310.863084) (xy 58.928806 -310.897176)
			(xy 58.958371 -310.93652) (xy 58.981242 -310.980097) (xy 58.996826 -311.026778) (xy 59.004721 -311.075355)
			(xy 59.005216 -311.099962) (xy 60.294024 -311.099962) (xy 60.297984 -311.050908) (xy 60.309761 -311.003124)
			(xy 60.329052 -310.957848) (xy 60.355355 -310.916252) (xy 60.38799 -310.879415) (xy 60.426111 -310.84829)
			(xy 60.468732 -310.823683) (xy 60.514748 -310.806231) (xy 60.562967 -310.796387) (xy 60.612142 -310.794406)
			(xy 60.660997 -310.800338) (xy 60.708268 -310.81403) (xy 60.75273 -310.835128) (xy 60.793233 -310.863084)
			(xy 60.828726 -310.897176) (xy 60.858291 -310.93652) (xy 60.881162 -310.980097) (xy 60.896746 -311.026778)
			(xy 60.904641 -311.075355) (xy 60.905136 -311.099962) (xy 62.193944 -311.099962) (xy 62.197904 -311.050908)
			(xy 62.209681 -311.003124) (xy 62.228972 -310.957848) (xy 62.255275 -310.916252) (xy 62.28791 -310.879415)
			(xy 62.326031 -310.84829) (xy 62.368652 -310.823683) (xy 62.414668 -310.806231) (xy 62.462887 -310.796387)
			(xy 62.512062 -310.794406) (xy 62.560917 -310.800338) (xy 62.608188 -310.81403) (xy 62.65265 -310.835128)
			(xy 62.693153 -310.863084) (xy 62.728646 -310.897176) (xy 62.758211 -310.93652) (xy 62.781082 -310.980097)
			(xy 62.796666 -311.026778) (xy 62.804561 -311.075355) (xy 62.805056 -311.099962) (xy 64.094118 -311.099962)
			(xy 64.098078 -311.050908) (xy 64.109855 -311.003124) (xy 64.129146 -310.957848) (xy 64.155449 -310.916252)
			(xy 64.188084 -310.879415) (xy 64.226205 -310.84829) (xy 64.268826 -310.823683) (xy 64.314842 -310.806231)
			(xy 64.363061 -310.796387) (xy 64.412236 -310.794406) (xy 64.461091 -310.800338) (xy 64.508362 -310.81403)
			(xy 64.552824 -310.835128) (xy 64.593327 -310.863084) (xy 64.62882 -310.897176) (xy 64.658385 -310.93652)
			(xy 64.681256 -310.980097) (xy 64.69684 -311.026778) (xy 64.704735 -311.075355) (xy 64.70523 -311.099962)
			(xy 65.994038 -311.099962) (xy 65.997998 -311.050908) (xy 66.009775 -311.003124) (xy 66.029066 -310.957848)
			(xy 66.055369 -310.916252) (xy 66.088004 -310.879415) (xy 66.126125 -310.84829) (xy 66.168746 -310.823683)
			(xy 66.214762 -310.806231) (xy 66.262981 -310.796387) (xy 66.312156 -310.794406) (xy 66.361011 -310.800338)
			(xy 66.408282 -310.81403) (xy 66.452744 -310.835128) (xy 66.493247 -310.863084) (xy 66.52874 -310.897176)
			(xy 66.558305 -310.93652) (xy 66.581176 -310.980097) (xy 66.59676 -311.026778) (xy 66.604655 -311.075355)
			(xy 66.60515 -311.099962) (xy 67.893958 -311.099962) (xy 67.897918 -311.050908) (xy 67.909695 -311.003124)
			(xy 67.928986 -310.957848) (xy 67.955289 -310.916252) (xy 67.987924 -310.879415) (xy 68.026045 -310.84829)
			(xy 68.068666 -310.823683) (xy 68.114682 -310.806231) (xy 68.162901 -310.796387) (xy 68.212076 -310.794406)
			(xy 68.260931 -310.800338) (xy 68.308202 -310.81403) (xy 68.352664 -310.835128) (xy 68.393167 -310.863084)
			(xy 68.42866 -310.897176) (xy 68.458225 -310.93652) (xy 68.481096 -310.980097) (xy 68.49668 -311.026778)
			(xy 68.504575 -311.075355) (xy 68.50507 -311.099962) (xy 69.794132 -311.099962) (xy 69.798092 -311.050908)
			(xy 69.809869 -311.003124) (xy 69.82916 -310.957848) (xy 69.855463 -310.916252) (xy 69.888098 -310.879415)
			(xy 69.926219 -310.84829) (xy 69.96884 -310.823683) (xy 70.014856 -310.806231) (xy 70.063075 -310.796387)
			(xy 70.11225 -310.794406) (xy 70.161105 -310.800338) (xy 70.208376 -310.81403) (xy 70.252838 -310.835128)
			(xy 70.293341 -310.863084) (xy 70.328834 -310.897176) (xy 70.358399 -310.93652) (xy 70.38127 -310.980097)
			(xy 70.396854 -311.026778) (xy 70.404749 -311.075355) (xy 70.405244 -311.099962) (xy 71.694052 -311.099962)
			(xy 71.698012 -311.050908) (xy 71.709789 -311.003124) (xy 71.72908 -310.957848) (xy 71.755383 -310.916252)
			(xy 71.788018 -310.879415) (xy 71.826139 -310.84829) (xy 71.86876 -310.823683) (xy 71.914776 -310.806231)
			(xy 71.962995 -310.796387) (xy 72.01217 -310.794406) (xy 72.061025 -310.800338) (xy 72.108296 -310.81403)
			(xy 72.152758 -310.835128) (xy 72.193261 -310.863084) (xy 72.228754 -310.897176) (xy 72.258319 -310.93652)
			(xy 72.28119 -310.980097) (xy 72.296774 -311.026778) (xy 72.304669 -311.075355) (xy 72.305164 -311.099962)
			(xy 73.593972 -311.099962) (xy 73.597932 -311.050908) (xy 73.609709 -311.003124) (xy 73.629 -310.957848)
			(xy 73.655303 -310.916252) (xy 73.687938 -310.879415) (xy 73.726059 -310.84829) (xy 73.76868 -310.823683)
			(xy 73.814696 -310.806231) (xy 73.862915 -310.796387) (xy 73.91209 -310.794406) (xy 73.960945 -310.800338)
			(xy 74.008216 -310.81403) (xy 74.052678 -310.835128) (xy 74.093181 -310.863084) (xy 74.128674 -310.897176)
			(xy 74.158239 -310.93652) (xy 74.18111 -310.980097) (xy 74.196694 -311.026778) (xy 74.204589 -311.075355)
			(xy 74.205084 -311.099962) (xy 75.494146 -311.099962) (xy 75.498106 -311.050908) (xy 75.509883 -311.003124)
			(xy 75.529174 -310.957848) (xy 75.555477 -310.916252) (xy 75.588112 -310.879415) (xy 75.626233 -310.84829)
			(xy 75.668854 -310.823683) (xy 75.71487 -310.806231) (xy 75.763089 -310.796387) (xy 75.812264 -310.794406)
			(xy 75.861119 -310.800338) (xy 75.90839 -310.81403) (xy 75.952852 -310.835128) (xy 75.993355 -310.863084)
			(xy 76.028848 -310.897176) (xy 76.058413 -310.93652) (xy 76.081284 -310.980097) (xy 76.096868 -311.026778)
			(xy 76.104763 -311.075355) (xy 76.105258 -311.099962) (xy 77.394066 -311.099962) (xy 77.398026 -311.050908)
			(xy 77.409803 -311.003124) (xy 77.429094 -310.957848) (xy 77.455397 -310.916252) (xy 77.488032 -310.879415)
			(xy 77.526153 -310.84829) (xy 77.568774 -310.823683) (xy 77.61479 -310.806231) (xy 77.663009 -310.796387)
			(xy 77.712184 -310.794406) (xy 77.761039 -310.800338) (xy 77.80831 -310.81403) (xy 77.852772 -310.835128)
			(xy 77.893275 -310.863084) (xy 77.928768 -310.897176) (xy 77.958333 -310.93652) (xy 77.981204 -310.980097)
			(xy 77.996788 -311.026778) (xy 78.004683 -311.075355) (xy 78.005178 -311.099962) (xy 79.293986 -311.099962)
			(xy 79.297946 -311.050908) (xy 79.309723 -311.003124) (xy 79.329014 -310.957848) (xy 79.355317 -310.916252)
			(xy 79.387952 -310.879415) (xy 79.426073 -310.84829) (xy 79.468694 -310.823683) (xy 79.51471 -310.806231)
			(xy 79.562929 -310.796387) (xy 79.612104 -310.794406) (xy 79.660959 -310.800338) (xy 79.70823 -310.81403)
			(xy 79.752692 -310.835128) (xy 79.793195 -310.863084) (xy 79.828688 -310.897176) (xy 79.858253 -310.93652)
			(xy 79.881124 -310.980097) (xy 79.896708 -311.026778) (xy 79.904603 -311.075355) (xy 79.905098 -311.099962)
			(xy 155.49424 -311.099962) (xy 155.4982 -311.050908) (xy 155.509977 -311.003124) (xy 155.529268 -310.957848)
			(xy 155.555571 -310.916252) (xy 155.588206 -310.879415) (xy 155.626327 -310.84829) (xy 155.668948 -310.823683)
			(xy 155.714964 -310.806231) (xy 155.763183 -310.796387) (xy 155.812358 -310.794406) (xy 155.861213 -310.800338)
			(xy 155.908484 -310.81403) (xy 155.952946 -310.835128) (xy 155.993449 -310.863084) (xy 156.028942 -310.897176)
			(xy 156.058507 -310.93652) (xy 156.081378 -310.980097) (xy 156.096962 -311.026778) (xy 156.104857 -311.075355)
			(xy 156.105352 -311.099962) (xy 157.39416 -311.099962) (xy 157.39812 -311.050908) (xy 157.409897 -311.003124)
			(xy 157.429188 -310.957848) (xy 157.455491 -310.916252) (xy 157.488126 -310.879415) (xy 157.526247 -310.84829)
			(xy 157.568868 -310.823683) (xy 157.614884 -310.806231) (xy 157.663103 -310.796387) (xy 157.712278 -310.794406)
			(xy 157.761133 -310.800338) (xy 157.808404 -310.81403) (xy 157.852866 -310.835128) (xy 157.893369 -310.863084)
			(xy 157.928862 -310.897176) (xy 157.958427 -310.93652) (xy 157.981298 -310.980097) (xy 157.996882 -311.026778)
			(xy 158.004777 -311.075355) (xy 158.005272 -311.099962) (xy 159.29408 -311.099962) (xy 159.29804 -311.050908)
			(xy 159.309817 -311.003124) (xy 159.329108 -310.957848) (xy 159.355411 -310.916252) (xy 159.388046 -310.879415)
			(xy 159.426167 -310.84829) (xy 159.468788 -310.823683) (xy 159.514804 -310.806231) (xy 159.563023 -310.796387)
			(xy 159.612198 -310.794406) (xy 159.661053 -310.800338) (xy 159.708324 -310.81403) (xy 159.752786 -310.835128)
			(xy 159.793289 -310.863084) (xy 159.828782 -310.897176) (xy 159.858347 -310.93652) (xy 159.881218 -310.980097)
			(xy 159.896802 -311.026778) (xy 159.904697 -311.075355) (xy 159.905192 -311.099962) (xy 161.194254 -311.099962)
			(xy 161.198214 -311.050908) (xy 161.209991 -311.003124) (xy 161.229282 -310.957848) (xy 161.255585 -310.916252)
			(xy 161.28822 -310.879415) (xy 161.326341 -310.84829) (xy 161.368962 -310.823683) (xy 161.414978 -310.806231)
			(xy 161.463197 -310.796387) (xy 161.512372 -310.794406) (xy 161.561227 -310.800338) (xy 161.608498 -310.81403)
			(xy 161.65296 -310.835128) (xy 161.693463 -310.863084) (xy 161.728956 -310.897176) (xy 161.758521 -310.93652)
			(xy 161.781392 -310.980097) (xy 161.796976 -311.026778) (xy 161.804871 -311.075355) (xy 161.805366 -311.099962)
			(xy 163.094174 -311.099962) (xy 163.098134 -311.050908) (xy 163.109911 -311.003124) (xy 163.129202 -310.957848)
			(xy 163.155505 -310.916252) (xy 163.18814 -310.879415) (xy 163.226261 -310.84829) (xy 163.268882 -310.823683)
			(xy 163.314898 -310.806231) (xy 163.363117 -310.796387) (xy 163.412292 -310.794406) (xy 163.461147 -310.800338)
			(xy 163.508418 -310.81403) (xy 163.55288 -310.835128) (xy 163.593383 -310.863084) (xy 163.628876 -310.897176)
			(xy 163.658441 -310.93652) (xy 163.681312 -310.980097) (xy 163.696896 -311.026778) (xy 163.704791 -311.075355)
			(xy 163.705286 -311.099962) (xy 164.994094 -311.099962) (xy 164.998054 -311.050908) (xy 165.009831 -311.003124)
			(xy 165.029122 -310.957848) (xy 165.055425 -310.916252) (xy 165.08806 -310.879415) (xy 165.126181 -310.84829)
			(xy 165.168802 -310.823683) (xy 165.214818 -310.806231) (xy 165.263037 -310.796387) (xy 165.312212 -310.794406)
			(xy 165.361067 -310.800338) (xy 165.408338 -310.81403) (xy 165.4528 -310.835128) (xy 165.493303 -310.863084)
			(xy 165.528796 -310.897176) (xy 165.558361 -310.93652) (xy 165.581232 -310.980097) (xy 165.596816 -311.026778)
			(xy 165.604711 -311.075355) (xy 165.605206 -311.099962) (xy 166.894268 -311.099962) (xy 166.898228 -311.050908)
			(xy 166.910005 -311.003124) (xy 166.929296 -310.957848) (xy 166.955599 -310.916252) (xy 166.988234 -310.879415)
			(xy 167.026355 -310.84829) (xy 167.068976 -310.823683) (xy 167.114992 -310.806231) (xy 167.163211 -310.796387)
			(xy 167.212386 -310.794406) (xy 167.261241 -310.800338) (xy 167.308512 -310.81403) (xy 167.352974 -310.835128)
			(xy 167.393477 -310.863084) (xy 167.42897 -310.897176) (xy 167.458535 -310.93652) (xy 167.481406 -310.980097)
			(xy 167.49699 -311.026778) (xy 167.504885 -311.075355) (xy 167.50538 -311.099962) (xy 168.794188 -311.099962)
			(xy 168.798148 -311.050908) (xy 168.809925 -311.003124) (xy 168.829216 -310.957848) (xy 168.855519 -310.916252)
			(xy 168.888154 -310.879415) (xy 168.926275 -310.84829) (xy 168.968896 -310.823683) (xy 169.014912 -310.806231)
			(xy 169.063131 -310.796387) (xy 169.112306 -310.794406) (xy 169.161161 -310.800338) (xy 169.208432 -310.81403)
			(xy 169.252894 -310.835128) (xy 169.293397 -310.863084) (xy 169.32889 -310.897176) (xy 169.358455 -310.93652)
			(xy 169.381326 -310.980097) (xy 169.39691 -311.026778) (xy 169.404805 -311.075355) (xy 169.4053 -311.099962)
			(xy 170.694108 -311.099962) (xy 170.698068 -311.050908) (xy 170.709845 -311.003124) (xy 170.729136 -310.957848)
			(xy 170.755439 -310.916252) (xy 170.788074 -310.879415) (xy 170.826195 -310.84829) (xy 170.868816 -310.823683)
			(xy 170.914832 -310.806231) (xy 170.963051 -310.796387) (xy 171.012226 -310.794406) (xy 171.061081 -310.800338)
			(xy 171.108352 -310.81403) (xy 171.152814 -310.835128) (xy 171.193317 -310.863084) (xy 171.22881 -310.897176)
			(xy 171.258375 -310.93652) (xy 171.281246 -310.980097) (xy 171.29683 -311.026778) (xy 171.304725 -311.075355)
			(xy 171.30522 -311.099962) (xy 172.594282 -311.099962) (xy 172.598242 -311.050908) (xy 172.610019 -311.003124)
			(xy 172.62931 -310.957848) (xy 172.655613 -310.916252) (xy 172.688248 -310.879415) (xy 172.726369 -310.84829)
			(xy 172.76899 -310.823683) (xy 172.815006 -310.806231) (xy 172.863225 -310.796387) (xy 172.9124 -310.794406)
			(xy 172.961255 -310.800338) (xy 173.008526 -310.81403) (xy 173.052988 -310.835128) (xy 173.093491 -310.863084)
			(xy 173.128984 -310.897176) (xy 173.158549 -310.93652) (xy 173.18142 -310.980097) (xy 173.197004 -311.026778)
			(xy 173.204899 -311.075355) (xy 173.205394 -311.099962) (xy 174.494202 -311.099962) (xy 174.498162 -311.050908)
			(xy 174.509939 -311.003124) (xy 174.52923 -310.957848) (xy 174.555533 -310.916252) (xy 174.588168 -310.879415)
			(xy 174.626289 -310.84829) (xy 174.66891 -310.823683) (xy 174.714926 -310.806231) (xy 174.763145 -310.796387)
			(xy 174.81232 -310.794406) (xy 174.861175 -310.800338) (xy 174.908446 -310.81403) (xy 174.952908 -310.835128)
			(xy 174.993411 -310.863084) (xy 175.028904 -310.897176) (xy 175.058469 -310.93652) (xy 175.08134 -310.980097)
			(xy 175.096924 -311.026778) (xy 175.104819 -311.075355) (xy 175.105314 -311.099962) (xy 176.394122 -311.099962)
			(xy 176.398082 -311.050908) (xy 176.409859 -311.003124) (xy 176.42915 -310.957848) (xy 176.455453 -310.916252)
			(xy 176.488088 -310.879415) (xy 176.526209 -310.84829) (xy 176.56883 -310.823683) (xy 176.614846 -310.806231)
			(xy 176.663065 -310.796387) (xy 176.71224 -310.794406) (xy 176.761095 -310.800338) (xy 176.808366 -310.81403)
			(xy 176.852828 -310.835128) (xy 176.893331 -310.863084) (xy 176.928824 -310.897176) (xy 176.958389 -310.93652)
			(xy 176.98126 -310.980097) (xy 176.996844 -311.026778) (xy 177.004739 -311.075355) (xy 177.005234 -311.099962)
			(xy 178.294042 -311.099962) (xy 178.298002 -311.050908) (xy 178.309779 -311.003124) (xy 178.32907 -310.957848)
			(xy 178.355373 -310.916252) (xy 178.388008 -310.879415) (xy 178.426129 -310.84829) (xy 178.46875 -310.823683)
			(xy 178.514766 -310.806231) (xy 178.562985 -310.796387) (xy 178.61216 -310.794406) (xy 178.661015 -310.800338)
			(xy 178.708286 -310.81403) (xy 178.752748 -310.835128) (xy 178.793251 -310.863084) (xy 178.828744 -310.897176)
			(xy 178.858309 -310.93652) (xy 178.88118 -310.980097) (xy 178.896764 -311.026778) (xy 178.904659 -311.075355)
			(xy 178.905154 -311.099962) (xy 180.194216 -311.099962) (xy 180.198176 -311.050908) (xy 180.209953 -311.003124)
			(xy 180.229244 -310.957848) (xy 180.255547 -310.916252) (xy 180.288182 -310.879415) (xy 180.326303 -310.84829)
			(xy 180.368924 -310.823683) (xy 180.41494 -310.806231) (xy 180.463159 -310.796387) (xy 180.512334 -310.794406)
			(xy 180.561189 -310.800338) (xy 180.60846 -310.81403) (xy 180.652922 -310.835128) (xy 180.693425 -310.863084)
			(xy 180.728918 -310.897176) (xy 180.758483 -310.93652) (xy 180.781354 -310.980097) (xy 180.796938 -311.026778)
			(xy 180.804833 -311.075355) (xy 180.805328 -311.099962) (xy 182.094136 -311.099962) (xy 182.098096 -311.050908)
			(xy 182.109873 -311.003124) (xy 182.129164 -310.957848) (xy 182.155467 -310.916252) (xy 182.188102 -310.879415)
			(xy 182.226223 -310.84829) (xy 182.268844 -310.823683) (xy 182.31486 -310.806231) (xy 182.363079 -310.796387)
			(xy 182.412254 -310.794406) (xy 182.461109 -310.800338) (xy 182.50838 -310.81403) (xy 182.552842 -310.835128)
			(xy 182.593345 -310.863084) (xy 182.628838 -310.897176) (xy 182.658403 -310.93652) (xy 182.681274 -310.980097)
			(xy 182.696858 -311.026778) (xy 182.704753 -311.075355) (xy 182.705248 -311.099962) (xy 183.994056 -311.099962)
			(xy 183.998016 -311.050908) (xy 184.009793 -311.003124) (xy 184.029084 -310.957848) (xy 184.055387 -310.916252)
			(xy 184.088022 -310.879415) (xy 184.126143 -310.84829) (xy 184.168764 -310.823683) (xy 184.21478 -310.806231)
			(xy 184.262999 -310.796387) (xy 184.312174 -310.794406) (xy 184.361029 -310.800338) (xy 184.4083 -310.81403)
			(xy 184.452762 -310.835128) (xy 184.493265 -310.863084) (xy 184.528758 -310.897176) (xy 184.558323 -310.93652)
			(xy 184.581194 -310.980097) (xy 184.596778 -311.026778) (xy 184.604673 -311.075355) (xy 184.605168 -311.099962)
			(xy 185.89423 -311.099962) (xy 185.89819 -311.050908) (xy 185.909967 -311.003124) (xy 185.929258 -310.957848)
			(xy 185.955561 -310.916252) (xy 185.988196 -310.879415) (xy 186.026317 -310.84829) (xy 186.068938 -310.823683)
			(xy 186.114954 -310.806231) (xy 186.163173 -310.796387) (xy 186.212348 -310.794406) (xy 186.261203 -310.800338)
			(xy 186.308474 -310.81403) (xy 186.352936 -310.835128) (xy 186.393439 -310.863084) (xy 186.428932 -310.897176)
			(xy 186.458497 -310.93652) (xy 186.481368 -310.980097) (xy 186.496952 -311.026778) (xy 186.504847 -311.075355)
			(xy 186.505342 -311.099962) (xy 187.79415 -311.099962) (xy 187.79811 -311.050908) (xy 187.809887 -311.003124)
			(xy 187.829178 -310.957848) (xy 187.855481 -310.916252) (xy 187.888116 -310.879415) (xy 187.926237 -310.84829)
			(xy 187.968858 -310.823683) (xy 188.014874 -310.806231) (xy 188.063093 -310.796387) (xy 188.112268 -310.794406)
			(xy 188.161123 -310.800338) (xy 188.208394 -310.81403) (xy 188.252856 -310.835128) (xy 188.293359 -310.863084)
			(xy 188.328852 -310.897176) (xy 188.358417 -310.93652) (xy 188.381288 -310.980097) (xy 188.396872 -311.026778)
			(xy 188.404767 -311.075355) (xy 188.405262 -311.099962) (xy 189.69407 -311.099962) (xy 189.69803 -311.050908)
			(xy 189.709807 -311.003124) (xy 189.729098 -310.957848) (xy 189.755401 -310.916252) (xy 189.788036 -310.879415)
			(xy 189.826157 -310.84829) (xy 189.868778 -310.823683) (xy 189.914794 -310.806231) (xy 189.963013 -310.796387)
			(xy 190.012188 -310.794406) (xy 190.061043 -310.800338) (xy 190.108314 -310.81403) (xy 190.152776 -310.835128)
			(xy 190.193279 -310.863084) (xy 190.228772 -310.897176) (xy 190.258337 -310.93652) (xy 190.281208 -310.980097)
			(xy 190.296792 -311.026778) (xy 190.304687 -311.075355) (xy 190.305182 -311.099962) (xy 191.594244 -311.099962)
			(xy 191.598204 -311.050908) (xy 191.609981 -311.003124) (xy 191.629272 -310.957848) (xy 191.655575 -310.916252)
			(xy 191.68821 -310.879415) (xy 191.726331 -310.84829) (xy 191.768952 -310.823683) (xy 191.814968 -310.806231)
			(xy 191.863187 -310.796387) (xy 191.912362 -310.794406) (xy 191.961217 -310.800338) (xy 192.008488 -310.81403)
			(xy 192.05295 -310.835128) (xy 192.093453 -310.863084) (xy 192.128946 -310.897176) (xy 192.158511 -310.93652)
			(xy 192.181382 -310.980097) (xy 192.196966 -311.026778) (xy 192.204861 -311.075355) (xy 192.205356 -311.099962)
			(xy 193.494164 -311.099962) (xy 193.498124 -311.050908) (xy 193.509901 -311.003124) (xy 193.529192 -310.957848)
			(xy 193.555495 -310.916252) (xy 193.58813 -310.879415) (xy 193.626251 -310.84829) (xy 193.668872 -310.823683)
			(xy 193.714888 -310.806231) (xy 193.763107 -310.796387) (xy 193.812282 -310.794406) (xy 193.861137 -310.800338)
			(xy 193.908408 -310.81403) (xy 193.95287 -310.835128) (xy 193.993373 -310.863084) (xy 194.028866 -310.897176)
			(xy 194.058431 -310.93652) (xy 194.081302 -310.980097) (xy 194.096886 -311.026778) (xy 194.104781 -311.075355)
			(xy 194.105276 -311.099962) (xy 195.394084 -311.099962) (xy 195.398044 -311.050908) (xy 195.409821 -311.003124)
			(xy 195.429112 -310.957848) (xy 195.455415 -310.916252) (xy 195.48805 -310.879415) (xy 195.526171 -310.84829)
			(xy 195.568792 -310.823683) (xy 195.614808 -310.806231) (xy 195.663027 -310.796387) (xy 195.712202 -310.794406)
			(xy 195.761057 -310.800338) (xy 195.808328 -310.81403) (xy 195.85279 -310.835128) (xy 195.893293 -310.863084)
			(xy 195.928786 -310.897176) (xy 195.958351 -310.93652) (xy 195.981222 -310.980097) (xy 195.996806 -311.026778)
			(xy 196.004701 -311.075355) (xy 196.005196 -311.099962) (xy 271.594084 -311.099962) (xy 271.598044 -311.050908)
			(xy 271.609821 -311.003124) (xy 271.629112 -310.957848) (xy 271.655415 -310.916252) (xy 271.68805 -310.879415)
			(xy 271.726171 -310.84829) (xy 271.768792 -310.823683) (xy 271.814808 -310.806231) (xy 271.863027 -310.796387)
			(xy 271.912202 -310.794406) (xy 271.961057 -310.800338) (xy 272.008328 -310.81403) (xy 272.05279 -310.835128)
			(xy 272.093293 -310.863084) (xy 272.128786 -310.897176) (xy 272.158351 -310.93652) (xy 272.181222 -310.980097)
			(xy 272.196806 -311.026778) (xy 272.204701 -311.075355) (xy 272.205196 -311.099962) (xy 273.494004 -311.099962)
			(xy 273.497964 -311.050908) (xy 273.509741 -311.003124) (xy 273.529032 -310.957848) (xy 273.555335 -310.916252)
			(xy 273.58797 -310.879415) (xy 273.626091 -310.84829) (xy 273.668712 -310.823683) (xy 273.714728 -310.806231)
			(xy 273.762947 -310.796387) (xy 273.812122 -310.794406) (xy 273.860977 -310.800338) (xy 273.908248 -310.81403)
			(xy 273.95271 -310.835128) (xy 273.993213 -310.863084) (xy 274.028706 -310.897176) (xy 274.058271 -310.93652)
			(xy 274.081142 -310.980097) (xy 274.096726 -311.026778) (xy 274.104621 -311.075355) (xy 274.105116 -311.099962)
			(xy 275.393924 -311.099962) (xy 275.397884 -311.050908) (xy 275.409661 -311.003124) (xy 275.428952 -310.957848)
			(xy 275.455255 -310.916252) (xy 275.48789 -310.879415) (xy 275.526011 -310.84829) (xy 275.568632 -310.823683)
			(xy 275.614648 -310.806231) (xy 275.662867 -310.796387) (xy 275.712042 -310.794406) (xy 275.760897 -310.800338)
			(xy 275.808168 -310.81403) (xy 275.85263 -310.835128) (xy 275.893133 -310.863084) (xy 275.928626 -310.897176)
			(xy 275.958191 -310.93652) (xy 275.981062 -310.980097) (xy 275.996646 -311.026778) (xy 276.004541 -311.075355)
			(xy 276.005036 -311.099962) (xy 277.294098 -311.099962) (xy 277.298058 -311.050908) (xy 277.309835 -311.003124)
			(xy 277.329126 -310.957848) (xy 277.355429 -310.916252) (xy 277.388064 -310.879415) (xy 277.426185 -310.84829)
			(xy 277.468806 -310.823683) (xy 277.514822 -310.806231) (xy 277.563041 -310.796387) (xy 277.612216 -310.794406)
			(xy 277.661071 -310.800338) (xy 277.708342 -310.81403) (xy 277.752804 -310.835128) (xy 277.793307 -310.863084)
			(xy 277.8288 -310.897176) (xy 277.858365 -310.93652) (xy 277.881236 -310.980097) (xy 277.89682 -311.026778)
			(xy 277.904715 -311.075355) (xy 277.90521 -311.099962) (xy 279.194018 -311.099962) (xy 279.197978 -311.050908)
			(xy 279.209755 -311.003124) (xy 279.229046 -310.957848) (xy 279.255349 -310.916252) (xy 279.287984 -310.879415)
			(xy 279.326105 -310.84829) (xy 279.368726 -310.823683) (xy 279.414742 -310.806231) (xy 279.462961 -310.796387)
			(xy 279.512136 -310.794406) (xy 279.560991 -310.800338) (xy 279.608262 -310.81403) (xy 279.652724 -310.835128)
			(xy 279.693227 -310.863084) (xy 279.72872 -310.897176) (xy 279.758285 -310.93652) (xy 279.781156 -310.980097)
			(xy 279.79674 -311.026778) (xy 279.804635 -311.075355) (xy 279.80513 -311.099962) (xy 281.093938 -311.099962)
			(xy 281.097898 -311.050908) (xy 281.109675 -311.003124) (xy 281.128966 -310.957848) (xy 281.155269 -310.916252)
			(xy 281.187904 -310.879415) (xy 281.226025 -310.84829) (xy 281.268646 -310.823683) (xy 281.314662 -310.806231)
			(xy 281.362881 -310.796387) (xy 281.412056 -310.794406) (xy 281.460911 -310.800338) (xy 281.508182 -310.81403)
			(xy 281.552644 -310.835128) (xy 281.593147 -310.863084) (xy 281.62864 -310.897176) (xy 281.658205 -310.93652)
			(xy 281.681076 -310.980097) (xy 281.69666 -311.026778) (xy 281.704555 -311.075355) (xy 281.70505 -311.099962)
			(xy 282.994112 -311.099962) (xy 282.998072 -311.050908) (xy 283.009849 -311.003124) (xy 283.02914 -310.957848)
			(xy 283.055443 -310.916252) (xy 283.088078 -310.879415) (xy 283.126199 -310.84829) (xy 283.16882 -310.823683)
			(xy 283.214836 -310.806231) (xy 283.263055 -310.796387) (xy 283.31223 -310.794406) (xy 283.361085 -310.800338)
			(xy 283.408356 -310.81403) (xy 283.452818 -310.835128) (xy 283.493321 -310.863084) (xy 283.528814 -310.897176)
			(xy 283.558379 -310.93652) (xy 283.58125 -310.980097) (xy 283.596834 -311.026778) (xy 283.604729 -311.075355)
			(xy 283.605224 -311.099962) (xy 284.894032 -311.099962) (xy 284.897992 -311.050908) (xy 284.909769 -311.003124)
			(xy 284.92906 -310.957848) (xy 284.955363 -310.916252) (xy 284.987998 -310.879415) (xy 285.026119 -310.84829)
			(xy 285.06874 -310.823683) (xy 285.114756 -310.806231) (xy 285.162975 -310.796387) (xy 285.21215 -310.794406)
			(xy 285.261005 -310.800338) (xy 285.308276 -310.81403) (xy 285.352738 -310.835128) (xy 285.393241 -310.863084)
			(xy 285.428734 -310.897176) (xy 285.458299 -310.93652) (xy 285.48117 -310.980097) (xy 285.496754 -311.026778)
			(xy 285.504649 -311.075355) (xy 285.505144 -311.099962) (xy 286.793952 -311.099962) (xy 286.797912 -311.050908)
			(xy 286.809689 -311.003124) (xy 286.82898 -310.957848) (xy 286.855283 -310.916252) (xy 286.887918 -310.879415)
			(xy 286.926039 -310.84829) (xy 286.96866 -310.823683) (xy 287.014676 -310.806231) (xy 287.062895 -310.796387)
			(xy 287.11207 -310.794406) (xy 287.160925 -310.800338) (xy 287.208196 -310.81403) (xy 287.252658 -310.835128)
			(xy 287.293161 -310.863084) (xy 287.328654 -310.897176) (xy 287.358219 -310.93652) (xy 287.38109 -310.980097)
			(xy 287.396674 -311.026778) (xy 287.404569 -311.075355) (xy 287.405064 -311.099962) (xy 288.694126 -311.099962)
			(xy 288.698086 -311.050908) (xy 288.709863 -311.003124) (xy 288.729154 -310.957848) (xy 288.755457 -310.916252)
			(xy 288.788092 -310.879415) (xy 288.826213 -310.84829) (xy 288.868834 -310.823683) (xy 288.91485 -310.806231)
			(xy 288.963069 -310.796387) (xy 289.012244 -310.794406) (xy 289.061099 -310.800338) (xy 289.10837 -310.81403)
			(xy 289.152832 -310.835128) (xy 289.193335 -310.863084) (xy 289.228828 -310.897176) (xy 289.258393 -310.93652)
			(xy 289.281264 -310.980097) (xy 289.296848 -311.026778) (xy 289.304743 -311.075355) (xy 289.305238 -311.099962)
			(xy 290.594046 -311.099962) (xy 290.598006 -311.050908) (xy 290.609783 -311.003124) (xy 290.629074 -310.957848)
			(xy 290.655377 -310.916252) (xy 290.688012 -310.879415) (xy 290.726133 -310.84829) (xy 290.768754 -310.823683)
			(xy 290.81477 -310.806231) (xy 290.862989 -310.796387) (xy 290.912164 -310.794406) (xy 290.961019 -310.800338)
			(xy 291.00829 -310.81403) (xy 291.052752 -310.835128) (xy 291.093255 -310.863084) (xy 291.128748 -310.897176)
			(xy 291.158313 -310.93652) (xy 291.181184 -310.980097) (xy 291.196768 -311.026778) (xy 291.204663 -311.075355)
			(xy 291.205158 -311.099962) (xy 292.493966 -311.099962) (xy 292.497926 -311.050908) (xy 292.509703 -311.003124)
			(xy 292.528994 -310.957848) (xy 292.555297 -310.916252) (xy 292.587932 -310.879415) (xy 292.626053 -310.84829)
			(xy 292.668674 -310.823683) (xy 292.71469 -310.806231) (xy 292.762909 -310.796387) (xy 292.812084 -310.794406)
			(xy 292.860939 -310.800338) (xy 292.90821 -310.81403) (xy 292.952672 -310.835128) (xy 292.993175 -310.863084)
			(xy 293.028668 -310.897176) (xy 293.058233 -310.93652) (xy 293.081104 -310.980097) (xy 293.096688 -311.026778)
			(xy 293.104583 -311.075355) (xy 293.105078 -311.099962) (xy 294.393886 -311.099962) (xy 294.397846 -311.050908)
			(xy 294.409623 -311.003124) (xy 294.428914 -310.957848) (xy 294.455217 -310.916252) (xy 294.487852 -310.879415)
			(xy 294.525973 -310.84829) (xy 294.568594 -310.823683) (xy 294.61461 -310.806231) (xy 294.662829 -310.796387)
			(xy 294.712004 -310.794406) (xy 294.760859 -310.800338) (xy 294.80813 -310.81403) (xy 294.852592 -310.835128)
			(xy 294.893095 -310.863084) (xy 294.928588 -310.897176) (xy 294.958153 -310.93652) (xy 294.981024 -310.980097)
			(xy 294.996608 -311.026778) (xy 295.004503 -311.075355) (xy 295.004998 -311.099962) (xy 296.29406 -311.099962)
			(xy 296.29802 -311.050908) (xy 296.309797 -311.003124) (xy 296.329088 -310.957848) (xy 296.355391 -310.916252)
			(xy 296.388026 -310.879415) (xy 296.426147 -310.84829) (xy 296.468768 -310.823683) (xy 296.514784 -310.806231)
			(xy 296.563003 -310.796387) (xy 296.612178 -310.794406) (xy 296.661033 -310.800338) (xy 296.708304 -310.81403)
			(xy 296.752766 -310.835128) (xy 296.793269 -310.863084) (xy 296.828762 -310.897176) (xy 296.858327 -310.93652)
			(xy 296.881198 -310.980097) (xy 296.896782 -311.026778) (xy 296.904677 -311.075355) (xy 296.905172 -311.099962)
			(xy 298.19398 -311.099962) (xy 298.19794 -311.050908) (xy 298.209717 -311.003124) (xy 298.229008 -310.957848)
			(xy 298.255311 -310.916252) (xy 298.287946 -310.879415) (xy 298.326067 -310.84829) (xy 298.368688 -310.823683)
			(xy 298.414704 -310.806231) (xy 298.462923 -310.796387) (xy 298.512098 -310.794406) (xy 298.560953 -310.800338)
			(xy 298.608224 -310.81403) (xy 298.652686 -310.835128) (xy 298.693189 -310.863084) (xy 298.728682 -310.897176)
			(xy 298.758247 -310.93652) (xy 298.781118 -310.980097) (xy 298.796702 -311.026778) (xy 298.804597 -311.075355)
			(xy 298.805092 -311.099962) (xy 300.0939 -311.099962) (xy 300.09786 -311.050908) (xy 300.109637 -311.003124)
			(xy 300.128928 -310.957848) (xy 300.155231 -310.916252) (xy 300.187866 -310.879415) (xy 300.225987 -310.84829)
			(xy 300.268608 -310.823683) (xy 300.314624 -310.806231) (xy 300.362843 -310.796387) (xy 300.412018 -310.794406)
			(xy 300.460873 -310.800338) (xy 300.508144 -310.81403) (xy 300.552606 -310.835128) (xy 300.593109 -310.863084)
			(xy 300.628602 -310.897176) (xy 300.658167 -310.93652) (xy 300.681038 -310.980097) (xy 300.696622 -311.026778)
			(xy 300.704517 -311.075355) (xy 300.705012 -311.099962) (xy 301.994074 -311.099962) (xy 301.998034 -311.050908)
			(xy 302.009811 -311.003124) (xy 302.029102 -310.957848) (xy 302.055405 -310.916252) (xy 302.08804 -310.879415)
			(xy 302.126161 -310.84829) (xy 302.168782 -310.823683) (xy 302.214798 -310.806231) (xy 302.263017 -310.796387)
			(xy 302.312192 -310.794406) (xy 302.361047 -310.800338) (xy 302.408318 -310.81403) (xy 302.45278 -310.835128)
			(xy 302.493283 -310.863084) (xy 302.528776 -310.897176) (xy 302.558341 -310.93652) (xy 302.581212 -310.980097)
			(xy 302.596796 -311.026778) (xy 302.604691 -311.075355) (xy 302.605186 -311.099962) (xy 303.893994 -311.099962)
			(xy 303.897954 -311.050908) (xy 303.909731 -311.003124) (xy 303.929022 -310.957848) (xy 303.955325 -310.916252)
			(xy 303.98796 -310.879415) (xy 304.026081 -310.84829) (xy 304.068702 -310.823683) (xy 304.114718 -310.806231)
			(xy 304.162937 -310.796387) (xy 304.212112 -310.794406) (xy 304.260967 -310.800338) (xy 304.308238 -310.81403)
			(xy 304.3527 -310.835128) (xy 304.393203 -310.863084) (xy 304.428696 -310.897176) (xy 304.458261 -310.93652)
			(xy 304.481132 -310.980097) (xy 304.496716 -311.026778) (xy 304.504611 -311.075355) (xy 304.505106 -311.099962)
			(xy 305.793914 -311.099962) (xy 305.797874 -311.050908) (xy 305.809651 -311.003124) (xy 305.828942 -310.957848)
			(xy 305.855245 -310.916252) (xy 305.88788 -310.879415) (xy 305.926001 -310.84829) (xy 305.968622 -310.823683)
			(xy 306.014638 -310.806231) (xy 306.062857 -310.796387) (xy 306.112032 -310.794406) (xy 306.160887 -310.800338)
			(xy 306.208158 -310.81403) (xy 306.25262 -310.835128) (xy 306.293123 -310.863084) (xy 306.328616 -310.897176)
			(xy 306.358181 -310.93652) (xy 306.381052 -310.980097) (xy 306.396636 -311.026778) (xy 306.404531 -311.075355)
			(xy 306.405026 -311.099962) (xy 307.694088 -311.099962) (xy 307.698048 -311.050908) (xy 307.709825 -311.003124)
			(xy 307.729116 -310.957848) (xy 307.755419 -310.916252) (xy 307.788054 -310.879415) (xy 307.826175 -310.84829)
			(xy 307.868796 -310.823683) (xy 307.914812 -310.806231) (xy 307.963031 -310.796387) (xy 308.012206 -310.794406)
			(xy 308.061061 -310.800338) (xy 308.108332 -310.81403) (xy 308.152794 -310.835128) (xy 308.193297 -310.863084)
			(xy 308.22879 -310.897176) (xy 308.258355 -310.93652) (xy 308.281226 -310.980097) (xy 308.29681 -311.026778)
			(xy 308.304705 -311.075355) (xy 308.3052 -311.099962) (xy 309.594008 -311.099962) (xy 309.597968 -311.050908)
			(xy 309.609745 -311.003124) (xy 309.629036 -310.957848) (xy 309.655339 -310.916252) (xy 309.687974 -310.879415)
			(xy 309.726095 -310.84829) (xy 309.768716 -310.823683) (xy 309.814732 -310.806231) (xy 309.862951 -310.796387)
			(xy 309.912126 -310.794406) (xy 309.960981 -310.800338) (xy 310.008252 -310.81403) (xy 310.052714 -310.835128)
			(xy 310.093217 -310.863084) (xy 310.12871 -310.897176) (xy 310.158275 -310.93652) (xy 310.181146 -310.980097)
			(xy 310.19673 -311.026778) (xy 310.204625 -311.075355) (xy 310.20512 -311.099962) (xy 311.493928 -311.099962)
			(xy 311.497888 -311.050908) (xy 311.509665 -311.003124) (xy 311.528956 -310.957848) (xy 311.555259 -310.916252)
			(xy 311.587894 -310.879415) (xy 311.626015 -310.84829) (xy 311.668636 -310.823683) (xy 311.714652 -310.806231)
			(xy 311.762871 -310.796387) (xy 311.812046 -310.794406) (xy 311.860901 -310.800338) (xy 311.908172 -310.81403)
			(xy 311.952634 -310.835128) (xy 311.993137 -310.863084) (xy 312.02863 -310.897176) (xy 312.058195 -310.93652)
			(xy 312.081066 -310.980097) (xy 312.09665 -311.026778) (xy 312.104545 -311.075355) (xy 312.10504 -311.099962)
			(xy 387.694182 -311.099962) (xy 387.698142 -311.050908) (xy 387.709919 -311.003124) (xy 387.72921 -310.957848)
			(xy 387.755513 -310.916252) (xy 387.788148 -310.879415) (xy 387.826269 -310.84829) (xy 387.86889 -310.823683)
			(xy 387.914906 -310.806231) (xy 387.963125 -310.796387) (xy 388.0123 -310.794406) (xy 388.061155 -310.800338)
			(xy 388.108426 -310.81403) (xy 388.152888 -310.835128) (xy 388.193391 -310.863084) (xy 388.228884 -310.897176)
			(xy 388.258449 -310.93652) (xy 388.28132 -310.980097) (xy 388.296904 -311.026778) (xy 388.304799 -311.075355)
			(xy 388.305294 -311.099962) (xy 389.594102 -311.099962) (xy 389.598062 -311.050908) (xy 389.609839 -311.003124)
			(xy 389.62913 -310.957848) (xy 389.655433 -310.916252) (xy 389.688068 -310.879415) (xy 389.726189 -310.84829)
			(xy 389.76881 -310.823683) (xy 389.814826 -310.806231) (xy 389.863045 -310.796387) (xy 389.91222 -310.794406)
			(xy 389.961075 -310.800338) (xy 390.008346 -310.81403) (xy 390.052808 -310.835128) (xy 390.093311 -310.863084)
			(xy 390.128804 -310.897176) (xy 390.158369 -310.93652) (xy 390.18124 -310.980097) (xy 390.196824 -311.026778)
			(xy 390.204719 -311.075355) (xy 390.205214 -311.099962) (xy 391.494022 -311.099962) (xy 391.497982 -311.050908)
			(xy 391.509759 -311.003124) (xy 391.52905 -310.957848) (xy 391.555353 -310.916252) (xy 391.587988 -310.879415)
			(xy 391.626109 -310.84829) (xy 391.66873 -310.823683) (xy 391.714746 -310.806231) (xy 391.762965 -310.796387)
			(xy 391.81214 -310.794406) (xy 391.860995 -310.800338) (xy 391.908266 -310.81403) (xy 391.952728 -310.835128)
			(xy 391.993231 -310.863084) (xy 392.028724 -310.897176) (xy 392.058289 -310.93652) (xy 392.08116 -310.980097)
			(xy 392.096744 -311.026778) (xy 392.104639 -311.075355) (xy 392.105134 -311.099962) (xy 393.394196 -311.099962)
			(xy 393.398156 -311.050908) (xy 393.409933 -311.003124) (xy 393.429224 -310.957848) (xy 393.455527 -310.916252)
			(xy 393.488162 -310.879415) (xy 393.526283 -310.84829) (xy 393.568904 -310.823683) (xy 393.61492 -310.806231)
			(xy 393.663139 -310.796387) (xy 393.712314 -310.794406) (xy 393.761169 -310.800338) (xy 393.80844 -310.81403)
			(xy 393.852902 -310.835128) (xy 393.893405 -310.863084) (xy 393.928898 -310.897176) (xy 393.958463 -310.93652)
			(xy 393.981334 -310.980097) (xy 393.996918 -311.026778) (xy 394.004813 -311.075355) (xy 394.005308 -311.099962)
			(xy 395.294116 -311.099962) (xy 395.298076 -311.050908) (xy 395.309853 -311.003124) (xy 395.329144 -310.957848)
			(xy 395.355447 -310.916252) (xy 395.388082 -310.879415) (xy 395.426203 -310.84829) (xy 395.468824 -310.823683)
			(xy 395.51484 -310.806231) (xy 395.563059 -310.796387) (xy 395.612234 -310.794406) (xy 395.661089 -310.800338)
			(xy 395.70836 -310.81403) (xy 395.752822 -310.835128) (xy 395.793325 -310.863084) (xy 395.828818 -310.897176)
			(xy 395.858383 -310.93652) (xy 395.881254 -310.980097) (xy 395.896838 -311.026778) (xy 395.904733 -311.075355)
			(xy 395.905228 -311.099962) (xy 397.194036 -311.099962) (xy 397.197996 -311.050908) (xy 397.209773 -311.003124)
			(xy 397.229064 -310.957848) (xy 397.255367 -310.916252) (xy 397.288002 -310.879415) (xy 397.326123 -310.84829)
			(xy 397.368744 -310.823683) (xy 397.41476 -310.806231) (xy 397.462979 -310.796387) (xy 397.512154 -310.794406)
			(xy 397.561009 -310.800338) (xy 397.60828 -310.81403) (xy 397.652742 -310.835128) (xy 397.693245 -310.863084)
			(xy 397.728738 -310.897176) (xy 397.758303 -310.93652) (xy 397.781174 -310.980097) (xy 397.796758 -311.026778)
			(xy 397.804653 -311.075355) (xy 397.805148 -311.099962) (xy 399.09421 -311.099962) (xy 399.09817 -311.050908)
			(xy 399.109947 -311.003124) (xy 399.129238 -310.957848) (xy 399.155541 -310.916252) (xy 399.188176 -310.879415)
			(xy 399.226297 -310.84829) (xy 399.268918 -310.823683) (xy 399.314934 -310.806231) (xy 399.363153 -310.796387)
			(xy 399.412328 -310.794406) (xy 399.461183 -310.800338) (xy 399.508454 -310.81403) (xy 399.552916 -310.835128)
			(xy 399.593419 -310.863084) (xy 399.628912 -310.897176) (xy 399.658477 -310.93652) (xy 399.681348 -310.980097)
			(xy 399.696932 -311.026778) (xy 399.704827 -311.075355) (xy 399.705322 -311.099962) (xy 400.99413 -311.099962)
			(xy 400.99809 -311.050908) (xy 401.009867 -311.003124) (xy 401.029158 -310.957848) (xy 401.055461 -310.916252)
			(xy 401.088096 -310.879415) (xy 401.126217 -310.84829) (xy 401.168838 -310.823683) (xy 401.214854 -310.806231)
			(xy 401.263073 -310.796387) (xy 401.312248 -310.794406) (xy 401.361103 -310.800338) (xy 401.408374 -310.81403)
			(xy 401.452836 -310.835128) (xy 401.493339 -310.863084) (xy 401.528832 -310.897176) (xy 401.558397 -310.93652)
			(xy 401.581268 -310.980097) (xy 401.596852 -311.026778) (xy 401.604747 -311.075355) (xy 401.605242 -311.099962)
			(xy 402.89405 -311.099962) (xy 402.89801 -311.050908) (xy 402.909787 -311.003124) (xy 402.929078 -310.957848)
			(xy 402.955381 -310.916252) (xy 402.988016 -310.879415) (xy 403.026137 -310.84829) (xy 403.068758 -310.823683)
			(xy 403.114774 -310.806231) (xy 403.162993 -310.796387) (xy 403.212168 -310.794406) (xy 403.261023 -310.800338)
			(xy 403.308294 -310.81403) (xy 403.352756 -310.835128) (xy 403.393259 -310.863084) (xy 403.428752 -310.897176)
			(xy 403.458317 -310.93652) (xy 403.481188 -310.980097) (xy 403.496772 -311.026778) (xy 403.504667 -311.075355)
			(xy 403.505162 -311.099962) (xy 404.794224 -311.099962) (xy 404.798184 -311.050908) (xy 404.809961 -311.003124)
			(xy 404.829252 -310.957848) (xy 404.855555 -310.916252) (xy 404.88819 -310.879415) (xy 404.926311 -310.84829)
			(xy 404.968932 -310.823683) (xy 405.014948 -310.806231) (xy 405.063167 -310.796387) (xy 405.112342 -310.794406)
			(xy 405.161197 -310.800338) (xy 405.208468 -310.81403) (xy 405.25293 -310.835128) (xy 405.293433 -310.863084)
			(xy 405.328926 -310.897176) (xy 405.358491 -310.93652) (xy 405.381362 -310.980097) (xy 405.396946 -311.026778)
			(xy 405.404841 -311.075355) (xy 405.405336 -311.099962) (xy 406.694144 -311.099962) (xy 406.698104 -311.050908)
			(xy 406.709881 -311.003124) (xy 406.729172 -310.957848) (xy 406.755475 -310.916252) (xy 406.78811 -310.879415)
			(xy 406.826231 -310.84829) (xy 406.868852 -310.823683) (xy 406.914868 -310.806231) (xy 406.963087 -310.796387)
			(xy 407.012262 -310.794406) (xy 407.061117 -310.800338) (xy 407.108388 -310.81403) (xy 407.15285 -310.835128)
			(xy 407.193353 -310.863084) (xy 407.228846 -310.897176) (xy 407.258411 -310.93652) (xy 407.281282 -310.980097)
			(xy 407.296866 -311.026778) (xy 407.304761 -311.075355) (xy 407.305256 -311.099962) (xy 408.594064 -311.099962)
			(xy 408.598024 -311.050908) (xy 408.609801 -311.003124) (xy 408.629092 -310.957848) (xy 408.655395 -310.916252)
			(xy 408.68803 -310.879415) (xy 408.726151 -310.84829) (xy 408.768772 -310.823683) (xy 408.814788 -310.806231)
			(xy 408.863007 -310.796387) (xy 408.912182 -310.794406) (xy 408.961037 -310.800338) (xy 409.008308 -310.81403)
			(xy 409.05277 -310.835128) (xy 409.093273 -310.863084) (xy 409.128766 -310.897176) (xy 409.158331 -310.93652)
			(xy 409.181202 -310.980097) (xy 409.196786 -311.026778) (xy 409.204681 -311.075355) (xy 409.205176 -311.099962)
			(xy 410.493984 -311.099962) (xy 410.497944 -311.050908) (xy 410.509721 -311.003124) (xy 410.529012 -310.957848)
			(xy 410.555315 -310.916252) (xy 410.58795 -310.879415) (xy 410.626071 -310.84829) (xy 410.668692 -310.823683)
			(xy 410.714708 -310.806231) (xy 410.762927 -310.796387) (xy 410.812102 -310.794406) (xy 410.860957 -310.800338)
			(xy 410.908228 -310.81403) (xy 410.95269 -310.835128) (xy 410.993193 -310.863084) (xy 411.028686 -310.897176)
			(xy 411.058251 -310.93652) (xy 411.081122 -310.980097) (xy 411.096706 -311.026778) (xy 411.104601 -311.075355)
			(xy 411.105096 -311.099962) (xy 412.394158 -311.099962) (xy 412.398118 -311.050908) (xy 412.409895 -311.003124)
			(xy 412.429186 -310.957848) (xy 412.455489 -310.916252) (xy 412.488124 -310.879415) (xy 412.526245 -310.84829)
			(xy 412.568866 -310.823683) (xy 412.614882 -310.806231) (xy 412.663101 -310.796387) (xy 412.712276 -310.794406)
			(xy 412.761131 -310.800338) (xy 412.808402 -310.81403) (xy 412.852864 -310.835128) (xy 412.893367 -310.863084)
			(xy 412.92886 -310.897176) (xy 412.958425 -310.93652) (xy 412.981296 -310.980097) (xy 412.99688 -311.026778)
			(xy 413.004775 -311.075355) (xy 413.00527 -311.099962) (xy 414.294078 -311.099962) (xy 414.298038 -311.050908)
			(xy 414.309815 -311.003124) (xy 414.329106 -310.957848) (xy 414.355409 -310.916252) (xy 414.388044 -310.879415)
			(xy 414.426165 -310.84829) (xy 414.468786 -310.823683) (xy 414.514802 -310.806231) (xy 414.563021 -310.796387)
			(xy 414.612196 -310.794406) (xy 414.661051 -310.800338) (xy 414.708322 -310.81403) (xy 414.752784 -310.835128)
			(xy 414.793287 -310.863084) (xy 414.82878 -310.897176) (xy 414.858345 -310.93652) (xy 414.881216 -310.980097)
			(xy 414.8968 -311.026778) (xy 414.904695 -311.075355) (xy 414.90519 -311.099962) (xy 416.193998 -311.099962)
			(xy 416.197958 -311.050908) (xy 416.209735 -311.003124) (xy 416.229026 -310.957848) (xy 416.255329 -310.916252)
			(xy 416.287964 -310.879415) (xy 416.326085 -310.84829) (xy 416.368706 -310.823683) (xy 416.414722 -310.806231)
			(xy 416.462941 -310.796387) (xy 416.512116 -310.794406) (xy 416.560971 -310.800338) (xy 416.608242 -310.81403)
			(xy 416.652704 -310.835128) (xy 416.693207 -310.863084) (xy 416.7287 -310.897176) (xy 416.758265 -310.93652)
			(xy 416.781136 -310.980097) (xy 416.79672 -311.026778) (xy 416.804615 -311.075355) (xy 416.80511 -311.099962)
			(xy 418.094172 -311.099962) (xy 418.098132 -311.050908) (xy 418.109909 -311.003124) (xy 418.1292 -310.957848)
			(xy 418.155503 -310.916252) (xy 418.188138 -310.879415) (xy 418.226259 -310.84829) (xy 418.26888 -310.823683)
			(xy 418.314896 -310.806231) (xy 418.363115 -310.796387) (xy 418.41229 -310.794406) (xy 418.461145 -310.800338)
			(xy 418.508416 -310.81403) (xy 418.552878 -310.835128) (xy 418.593381 -310.863084) (xy 418.628874 -310.897176)
			(xy 418.658439 -310.93652) (xy 418.68131 -310.980097) (xy 418.696894 -311.026778) (xy 418.704789 -311.075355)
			(xy 418.705284 -311.099962) (xy 419.994092 -311.099962) (xy 419.998052 -311.050908) (xy 420.009829 -311.003124)
			(xy 420.02912 -310.957848) (xy 420.055423 -310.916252) (xy 420.088058 -310.879415) (xy 420.126179 -310.84829)
			(xy 420.1688 -310.823683) (xy 420.214816 -310.806231) (xy 420.263035 -310.796387) (xy 420.31221 -310.794406)
			(xy 420.361065 -310.800338) (xy 420.408336 -310.81403) (xy 420.452798 -310.835128) (xy 420.493301 -310.863084)
			(xy 420.528794 -310.897176) (xy 420.558359 -310.93652) (xy 420.58123 -310.980097) (xy 420.596814 -311.026778)
			(xy 420.604709 -311.075355) (xy 420.605204 -311.099962) (xy 421.894012 -311.099962) (xy 421.897972 -311.050908)
			(xy 421.909749 -311.003124) (xy 421.92904 -310.957848) (xy 421.955343 -310.916252) (xy 421.987978 -310.879415)
			(xy 422.026099 -310.84829) (xy 422.06872 -310.823683) (xy 422.114736 -310.806231) (xy 422.162955 -310.796387)
			(xy 422.21213 -310.794406) (xy 422.260985 -310.800338) (xy 422.308256 -310.81403) (xy 422.352718 -310.835128)
			(xy 422.393221 -310.863084) (xy 422.428714 -310.897176) (xy 422.458279 -310.93652) (xy 422.48115 -310.980097)
			(xy 422.496734 -311.026778) (xy 422.504629 -311.075355) (xy 422.505124 -311.099962) (xy 423.794186 -311.099962)
			(xy 423.798146 -311.050908) (xy 423.809923 -311.003124) (xy 423.829214 -310.957848) (xy 423.855517 -310.916252)
			(xy 423.888152 -310.879415) (xy 423.926273 -310.84829) (xy 423.968894 -310.823683) (xy 424.01491 -310.806231)
			(xy 424.063129 -310.796387) (xy 424.112304 -310.794406) (xy 424.161159 -310.800338) (xy 424.20843 -310.81403)
			(xy 424.252892 -310.835128) (xy 424.293395 -310.863084) (xy 424.328888 -310.897176) (xy 424.358453 -310.93652)
			(xy 424.381324 -310.980097) (xy 424.396908 -311.026778) (xy 424.404803 -311.075355) (xy 424.405298 -311.099962)
			(xy 425.694106 -311.099962) (xy 425.698066 -311.050908) (xy 425.709843 -311.003124) (xy 425.729134 -310.957848)
			(xy 425.755437 -310.916252) (xy 425.788072 -310.879415) (xy 425.826193 -310.84829) (xy 425.868814 -310.823683)
			(xy 425.91483 -310.806231) (xy 425.963049 -310.796387) (xy 426.012224 -310.794406) (xy 426.061079 -310.800338)
			(xy 426.10835 -310.81403) (xy 426.152812 -310.835128) (xy 426.193315 -310.863084) (xy 426.228808 -310.897176)
			(xy 426.258373 -310.93652) (xy 426.281244 -310.980097) (xy 426.296828 -311.026778) (xy 426.304723 -311.075355)
			(xy 426.305218 -311.099962) (xy 427.594026 -311.099962) (xy 427.597986 -311.050908) (xy 427.609763 -311.003124)
			(xy 427.629054 -310.957848) (xy 427.655357 -310.916252) (xy 427.687992 -310.879415) (xy 427.726113 -310.84829)
			(xy 427.768734 -310.823683) (xy 427.81475 -310.806231) (xy 427.862969 -310.796387) (xy 427.912144 -310.794406)
			(xy 427.960999 -310.800338) (xy 428.00827 -310.81403) (xy 428.052732 -310.835128) (xy 428.093235 -310.863084)
			(xy 428.128728 -310.897176) (xy 428.158293 -310.93652) (xy 428.181164 -310.980097) (xy 428.196748 -311.026778)
			(xy 428.204643 -311.075355) (xy 428.205138 -311.099962) (xy 428.204643 -311.124569) (xy 428.196748 -311.173146)
			(xy 428.181164 -311.219827) (xy 428.158293 -311.263404) (xy 428.128728 -311.302748) (xy 428.093235 -311.33684)
			(xy 428.052732 -311.364796) (xy 428.00827 -311.385894) (xy 427.960999 -311.399586) (xy 427.912144 -311.405518)
			(xy 427.862969 -311.403537) (xy 427.81475 -311.393693) (xy 427.768734 -311.376241) (xy 427.726113 -311.351634)
			(xy 427.687992 -311.320509) (xy 427.655357 -311.283672) (xy 427.629054 -311.242076) (xy 427.609763 -311.1968)
			(xy 427.597986 -311.149016) (xy 427.594026 -311.099962) (xy 426.305218 -311.099962) (xy 426.304723 -311.124569)
			(xy 426.296828 -311.173146) (xy 426.281244 -311.219827) (xy 426.258373 -311.263404) (xy 426.228808 -311.302748)
			(xy 426.193315 -311.33684) (xy 426.152812 -311.364796) (xy 426.10835 -311.385894) (xy 426.061079 -311.399586)
			(xy 426.012224 -311.405518) (xy 425.963049 -311.403537) (xy 425.91483 -311.393693) (xy 425.868814 -311.376241)
			(xy 425.826193 -311.351634) (xy 425.788072 -311.320509) (xy 425.755437 -311.283672) (xy 425.729134 -311.242076)
			(xy 425.709843 -311.1968) (xy 425.698066 -311.149016) (xy 425.694106 -311.099962) (xy 424.405298 -311.099962)
			(xy 424.404803 -311.124569) (xy 424.396908 -311.173146) (xy 424.381324 -311.219827) (xy 424.358453 -311.263404)
			(xy 424.328888 -311.302748) (xy 424.293395 -311.33684) (xy 424.252892 -311.364796) (xy 424.20843 -311.385894)
			(xy 424.161159 -311.399586) (xy 424.112304 -311.405518) (xy 424.063129 -311.403537) (xy 424.01491 -311.393693)
			(xy 423.968894 -311.376241) (xy 423.926273 -311.351634) (xy 423.888152 -311.320509) (xy 423.855517 -311.283672)
			(xy 423.829214 -311.242076) (xy 423.809923 -311.1968) (xy 423.798146 -311.149016) (xy 423.794186 -311.099962)
			(xy 422.505124 -311.099962) (xy 422.504629 -311.124569) (xy 422.496734 -311.173146) (xy 422.48115 -311.219827)
			(xy 422.458279 -311.263404) (xy 422.428714 -311.302748) (xy 422.393221 -311.33684) (xy 422.352718 -311.364796)
			(xy 422.308256 -311.385894) (xy 422.260985 -311.399586) (xy 422.21213 -311.405518) (xy 422.162955 -311.403537)
			(xy 422.114736 -311.393693) (xy 422.06872 -311.376241) (xy 422.026099 -311.351634) (xy 421.987978 -311.320509)
			(xy 421.955343 -311.283672) (xy 421.92904 -311.242076) (xy 421.909749 -311.1968) (xy 421.897972 -311.149016)
			(xy 421.894012 -311.099962) (xy 420.605204 -311.099962) (xy 420.604709 -311.124569) (xy 420.596814 -311.173146)
			(xy 420.58123 -311.219827) (xy 420.558359 -311.263404) (xy 420.528794 -311.302748) (xy 420.493301 -311.33684)
			(xy 420.452798 -311.364796) (xy 420.408336 -311.385894) (xy 420.361065 -311.399586) (xy 420.31221 -311.405518)
			(xy 420.263035 -311.403537) (xy 420.214816 -311.393693) (xy 420.1688 -311.376241) (xy 420.126179 -311.351634)
			(xy 420.088058 -311.320509) (xy 420.055423 -311.283672) (xy 420.02912 -311.242076) (xy 420.009829 -311.1968)
			(xy 419.998052 -311.149016) (xy 419.994092 -311.099962) (xy 418.705284 -311.099962) (xy 418.704789 -311.124569)
			(xy 418.696894 -311.173146) (xy 418.68131 -311.219827) (xy 418.658439 -311.263404) (xy 418.628874 -311.302748)
			(xy 418.593381 -311.33684) (xy 418.552878 -311.364796) (xy 418.508416 -311.385894) (xy 418.461145 -311.399586)
			(xy 418.41229 -311.405518) (xy 418.363115 -311.403537) (xy 418.314896 -311.393693) (xy 418.26888 -311.376241)
			(xy 418.226259 -311.351634) (xy 418.188138 -311.320509) (xy 418.155503 -311.283672) (xy 418.1292 -311.242076)
			(xy 418.109909 -311.1968) (xy 418.098132 -311.149016) (xy 418.094172 -311.099962) (xy 416.80511 -311.099962)
			(xy 416.804615 -311.124569) (xy 416.79672 -311.173146) (xy 416.781136 -311.219827) (xy 416.758265 -311.263404)
			(xy 416.7287 -311.302748) (xy 416.693207 -311.33684) (xy 416.652704 -311.364796) (xy 416.608242 -311.385894)
			(xy 416.560971 -311.399586) (xy 416.512116 -311.405518) (xy 416.462941 -311.403537) (xy 416.414722 -311.393693)
			(xy 416.368706 -311.376241) (xy 416.326085 -311.351634) (xy 416.287964 -311.320509) (xy 416.255329 -311.283672)
			(xy 416.229026 -311.242076) (xy 416.209735 -311.1968) (xy 416.197958 -311.149016) (xy 416.193998 -311.099962)
			(xy 414.90519 -311.099962) (xy 414.904695 -311.124569) (xy 414.8968 -311.173146) (xy 414.881216 -311.219827)
			(xy 414.858345 -311.263404) (xy 414.82878 -311.302748) (xy 414.793287 -311.33684) (xy 414.752784 -311.364796)
			(xy 414.708322 -311.385894) (xy 414.661051 -311.399586) (xy 414.612196 -311.405518) (xy 414.563021 -311.403537)
			(xy 414.514802 -311.393693) (xy 414.468786 -311.376241) (xy 414.426165 -311.351634) (xy 414.388044 -311.320509)
			(xy 414.355409 -311.283672) (xy 414.329106 -311.242076) (xy 414.309815 -311.1968) (xy 414.298038 -311.149016)
			(xy 414.294078 -311.099962) (xy 413.00527 -311.099962) (xy 413.004775 -311.124569) (xy 412.99688 -311.173146)
			(xy 412.981296 -311.219827) (xy 412.958425 -311.263404) (xy 412.92886 -311.302748) (xy 412.893367 -311.33684)
			(xy 412.852864 -311.364796) (xy 412.808402 -311.385894) (xy 412.761131 -311.399586) (xy 412.712276 -311.405518)
			(xy 412.663101 -311.403537) (xy 412.614882 -311.393693) (xy 412.568866 -311.376241) (xy 412.526245 -311.351634)
			(xy 412.488124 -311.320509) (xy 412.455489 -311.283672) (xy 412.429186 -311.242076) (xy 412.409895 -311.1968)
			(xy 412.398118 -311.149016) (xy 412.394158 -311.099962) (xy 411.105096 -311.099962) (xy 411.104601 -311.124569)
			(xy 411.096706 -311.173146) (xy 411.081122 -311.219827) (xy 411.058251 -311.263404) (xy 411.028686 -311.302748)
			(xy 410.993193 -311.33684) (xy 410.95269 -311.364796) (xy 410.908228 -311.385894) (xy 410.860957 -311.399586)
			(xy 410.812102 -311.405518) (xy 410.762927 -311.403537) (xy 410.714708 -311.393693) (xy 410.668692 -311.376241)
			(xy 410.626071 -311.351634) (xy 410.58795 -311.320509) (xy 410.555315 -311.283672) (xy 410.529012 -311.242076)
			(xy 410.509721 -311.1968) (xy 410.497944 -311.149016) (xy 410.493984 -311.099962) (xy 409.205176 -311.099962)
			(xy 409.204681 -311.124569) (xy 409.196786 -311.173146) (xy 409.181202 -311.219827) (xy 409.158331 -311.263404)
			(xy 409.128766 -311.302748) (xy 409.093273 -311.33684) (xy 409.05277 -311.364796) (xy 409.008308 -311.385894)
			(xy 408.961037 -311.399586) (xy 408.912182 -311.405518) (xy 408.863007 -311.403537) (xy 408.814788 -311.393693)
			(xy 408.768772 -311.376241) (xy 408.726151 -311.351634) (xy 408.68803 -311.320509) (xy 408.655395 -311.283672)
			(xy 408.629092 -311.242076) (xy 408.609801 -311.1968) (xy 408.598024 -311.149016) (xy 408.594064 -311.099962)
			(xy 407.305256 -311.099962) (xy 407.304761 -311.124569) (xy 407.296866 -311.173146) (xy 407.281282 -311.219827)
			(xy 407.258411 -311.263404) (xy 407.228846 -311.302748) (xy 407.193353 -311.33684) (xy 407.15285 -311.364796)
			(xy 407.108388 -311.385894) (xy 407.061117 -311.399586) (xy 407.012262 -311.405518) (xy 406.963087 -311.403537)
			(xy 406.914868 -311.393693) (xy 406.868852 -311.376241) (xy 406.826231 -311.351634) (xy 406.78811 -311.320509)
			(xy 406.755475 -311.283672) (xy 406.729172 -311.242076) (xy 406.709881 -311.1968) (xy 406.698104 -311.149016)
			(xy 406.694144 -311.099962) (xy 405.405336 -311.099962) (xy 405.404841 -311.124569) (xy 405.396946 -311.173146)
			(xy 405.381362 -311.219827) (xy 405.358491 -311.263404) (xy 405.328926 -311.302748) (xy 405.293433 -311.33684)
			(xy 405.25293 -311.364796) (xy 405.208468 -311.385894) (xy 405.161197 -311.399586) (xy 405.112342 -311.405518)
			(xy 405.063167 -311.403537) (xy 405.014948 -311.393693) (xy 404.968932 -311.376241) (xy 404.926311 -311.351634)
			(xy 404.88819 -311.320509) (xy 404.855555 -311.283672) (xy 404.829252 -311.242076) (xy 404.809961 -311.1968)
			(xy 404.798184 -311.149016) (xy 404.794224 -311.099962) (xy 403.505162 -311.099962) (xy 403.504667 -311.124569)
			(xy 403.496772 -311.173146) (xy 403.481188 -311.219827) (xy 403.458317 -311.263404) (xy 403.428752 -311.302748)
			(xy 403.393259 -311.33684) (xy 403.352756 -311.364796) (xy 403.308294 -311.385894) (xy 403.261023 -311.399586)
			(xy 403.212168 -311.405518) (xy 403.162993 -311.403537) (xy 403.114774 -311.393693) (xy 403.068758 -311.376241)
			(xy 403.026137 -311.351634) (xy 402.988016 -311.320509) (xy 402.955381 -311.283672) (xy 402.929078 -311.242076)
			(xy 402.909787 -311.1968) (xy 402.89801 -311.149016) (xy 402.89405 -311.099962) (xy 401.605242 -311.099962)
			(xy 401.604747 -311.124569) (xy 401.596852 -311.173146) (xy 401.581268 -311.219827) (xy 401.558397 -311.263404)
			(xy 401.528832 -311.302748) (xy 401.493339 -311.33684) (xy 401.452836 -311.364796) (xy 401.408374 -311.385894)
			(xy 401.361103 -311.399586) (xy 401.312248 -311.405518) (xy 401.263073 -311.403537) (xy 401.214854 -311.393693)
			(xy 401.168838 -311.376241) (xy 401.126217 -311.351634) (xy 401.088096 -311.320509) (xy 401.055461 -311.283672)
			(xy 401.029158 -311.242076) (xy 401.009867 -311.1968) (xy 400.99809 -311.149016) (xy 400.99413 -311.099962)
			(xy 399.705322 -311.099962) (xy 399.704827 -311.124569) (xy 399.696932 -311.173146) (xy 399.681348 -311.219827)
			(xy 399.658477 -311.263404) (xy 399.628912 -311.302748) (xy 399.593419 -311.33684) (xy 399.552916 -311.364796)
			(xy 399.508454 -311.385894) (xy 399.461183 -311.399586) (xy 399.412328 -311.405518) (xy 399.363153 -311.403537)
			(xy 399.314934 -311.393693) (xy 399.268918 -311.376241) (xy 399.226297 -311.351634) (xy 399.188176 -311.320509)
			(xy 399.155541 -311.283672) (xy 399.129238 -311.242076) (xy 399.109947 -311.1968) (xy 399.09817 -311.149016)
			(xy 399.09421 -311.099962) (xy 397.805148 -311.099962) (xy 397.804653 -311.124569) (xy 397.796758 -311.173146)
			(xy 397.781174 -311.219827) (xy 397.758303 -311.263404) (xy 397.728738 -311.302748) (xy 397.693245 -311.33684)
			(xy 397.652742 -311.364796) (xy 397.60828 -311.385894) (xy 397.561009 -311.399586) (xy 397.512154 -311.405518)
			(xy 397.462979 -311.403537) (xy 397.41476 -311.393693) (xy 397.368744 -311.376241) (xy 397.326123 -311.351634)
			(xy 397.288002 -311.320509) (xy 397.255367 -311.283672) (xy 397.229064 -311.242076) (xy 397.209773 -311.1968)
			(xy 397.197996 -311.149016) (xy 397.194036 -311.099962) (xy 395.905228 -311.099962) (xy 395.904733 -311.124569)
			(xy 395.896838 -311.173146) (xy 395.881254 -311.219827) (xy 395.858383 -311.263404) (xy 395.828818 -311.302748)
			(xy 395.793325 -311.33684) (xy 395.752822 -311.364796) (xy 395.70836 -311.385894) (xy 395.661089 -311.399586)
			(xy 395.612234 -311.405518) (xy 395.563059 -311.403537) (xy 395.51484 -311.393693) (xy 395.468824 -311.376241)
			(xy 395.426203 -311.351634) (xy 395.388082 -311.320509) (xy 395.355447 -311.283672) (xy 395.329144 -311.242076)
			(xy 395.309853 -311.1968) (xy 395.298076 -311.149016) (xy 395.294116 -311.099962) (xy 394.005308 -311.099962)
			(xy 394.004813 -311.124569) (xy 393.996918 -311.173146) (xy 393.981334 -311.219827) (xy 393.958463 -311.263404)
			(xy 393.928898 -311.302748) (xy 393.893405 -311.33684) (xy 393.852902 -311.364796) (xy 393.80844 -311.385894)
			(xy 393.761169 -311.399586) (xy 393.712314 -311.405518) (xy 393.663139 -311.403537) (xy 393.61492 -311.393693)
			(xy 393.568904 -311.376241) (xy 393.526283 -311.351634) (xy 393.488162 -311.320509) (xy 393.455527 -311.283672)
			(xy 393.429224 -311.242076) (xy 393.409933 -311.1968) (xy 393.398156 -311.149016) (xy 393.394196 -311.099962)
			(xy 392.105134 -311.099962) (xy 392.104639 -311.124569) (xy 392.096744 -311.173146) (xy 392.08116 -311.219827)
			(xy 392.058289 -311.263404) (xy 392.028724 -311.302748) (xy 391.993231 -311.33684) (xy 391.952728 -311.364796)
			(xy 391.908266 -311.385894) (xy 391.860995 -311.399586) (xy 391.81214 -311.405518) (xy 391.762965 -311.403537)
			(xy 391.714746 -311.393693) (xy 391.66873 -311.376241) (xy 391.626109 -311.351634) (xy 391.587988 -311.320509)
			(xy 391.555353 -311.283672) (xy 391.52905 -311.242076) (xy 391.509759 -311.1968) (xy 391.497982 -311.149016)
			(xy 391.494022 -311.099962) (xy 390.205214 -311.099962) (xy 390.204719 -311.124569) (xy 390.196824 -311.173146)
			(xy 390.18124 -311.219827) (xy 390.158369 -311.263404) (xy 390.128804 -311.302748) (xy 390.093311 -311.33684)
			(xy 390.052808 -311.364796) (xy 390.008346 -311.385894) (xy 389.961075 -311.399586) (xy 389.91222 -311.405518)
			(xy 389.863045 -311.403537) (xy 389.814826 -311.393693) (xy 389.76881 -311.376241) (xy 389.726189 -311.351634)
			(xy 389.688068 -311.320509) (xy 389.655433 -311.283672) (xy 389.62913 -311.242076) (xy 389.609839 -311.1968)
			(xy 389.598062 -311.149016) (xy 389.594102 -311.099962) (xy 388.305294 -311.099962) (xy 388.304799 -311.124569)
			(xy 388.296904 -311.173146) (xy 388.28132 -311.219827) (xy 388.258449 -311.263404) (xy 388.228884 -311.302748)
			(xy 388.193391 -311.33684) (xy 388.152888 -311.364796) (xy 388.108426 -311.385894) (xy 388.061155 -311.399586)
			(xy 388.0123 -311.405518) (xy 387.963125 -311.403537) (xy 387.914906 -311.393693) (xy 387.86889 -311.376241)
			(xy 387.826269 -311.351634) (xy 387.788148 -311.320509) (xy 387.755513 -311.283672) (xy 387.72921 -311.242076)
			(xy 387.709919 -311.1968) (xy 387.698142 -311.149016) (xy 387.694182 -311.099962) (xy 312.10504 -311.099962)
			(xy 312.104545 -311.124569) (xy 312.09665 -311.173146) (xy 312.081066 -311.219827) (xy 312.058195 -311.263404)
			(xy 312.02863 -311.302748) (xy 311.993137 -311.33684) (xy 311.952634 -311.364796) (xy 311.908172 -311.385894)
			(xy 311.860901 -311.399586) (xy 311.812046 -311.405518) (xy 311.762871 -311.403537) (xy 311.714652 -311.393693)
			(xy 311.668636 -311.376241) (xy 311.626015 -311.351634) (xy 311.587894 -311.320509) (xy 311.555259 -311.283672)
			(xy 311.528956 -311.242076) (xy 311.509665 -311.1968) (xy 311.497888 -311.149016) (xy 311.493928 -311.099962)
			(xy 310.20512 -311.099962) (xy 310.204625 -311.124569) (xy 310.19673 -311.173146) (xy 310.181146 -311.219827)
			(xy 310.158275 -311.263404) (xy 310.12871 -311.302748) (xy 310.093217 -311.33684) (xy 310.052714 -311.364796)
			(xy 310.008252 -311.385894) (xy 309.960981 -311.399586) (xy 309.912126 -311.405518) (xy 309.862951 -311.403537)
			(xy 309.814732 -311.393693) (xy 309.768716 -311.376241) (xy 309.726095 -311.351634) (xy 309.687974 -311.320509)
			(xy 309.655339 -311.283672) (xy 309.629036 -311.242076) (xy 309.609745 -311.1968) (xy 309.597968 -311.149016)
			(xy 309.594008 -311.099962) (xy 308.3052 -311.099962) (xy 308.304705 -311.124569) (xy 308.29681 -311.173146)
			(xy 308.281226 -311.219827) (xy 308.258355 -311.263404) (xy 308.22879 -311.302748) (xy 308.193297 -311.33684)
			(xy 308.152794 -311.364796) (xy 308.108332 -311.385894) (xy 308.061061 -311.399586) (xy 308.012206 -311.405518)
			(xy 307.963031 -311.403537) (xy 307.914812 -311.393693) (xy 307.868796 -311.376241) (xy 307.826175 -311.351634)
			(xy 307.788054 -311.320509) (xy 307.755419 -311.283672) (xy 307.729116 -311.242076) (xy 307.709825 -311.1968)
			(xy 307.698048 -311.149016) (xy 307.694088 -311.099962) (xy 306.405026 -311.099962) (xy 306.404531 -311.124569)
			(xy 306.396636 -311.173146) (xy 306.381052 -311.219827) (xy 306.358181 -311.263404) (xy 306.328616 -311.302748)
			(xy 306.293123 -311.33684) (xy 306.25262 -311.364796) (xy 306.208158 -311.385894) (xy 306.160887 -311.399586)
			(xy 306.112032 -311.405518) (xy 306.062857 -311.403537) (xy 306.014638 -311.393693) (xy 305.968622 -311.376241)
			(xy 305.926001 -311.351634) (xy 305.88788 -311.320509) (xy 305.855245 -311.283672) (xy 305.828942 -311.242076)
			(xy 305.809651 -311.1968) (xy 305.797874 -311.149016) (xy 305.793914 -311.099962) (xy 304.505106 -311.099962)
			(xy 304.504611 -311.124569) (xy 304.496716 -311.173146) (xy 304.481132 -311.219827) (xy 304.458261 -311.263404)
			(xy 304.428696 -311.302748) (xy 304.393203 -311.33684) (xy 304.3527 -311.364796) (xy 304.308238 -311.385894)
			(xy 304.260967 -311.399586) (xy 304.212112 -311.405518) (xy 304.162937 -311.403537) (xy 304.114718 -311.393693)
			(xy 304.068702 -311.376241) (xy 304.026081 -311.351634) (xy 303.98796 -311.320509) (xy 303.955325 -311.283672)
			(xy 303.929022 -311.242076) (xy 303.909731 -311.1968) (xy 303.897954 -311.149016) (xy 303.893994 -311.099962)
			(xy 302.605186 -311.099962) (xy 302.604691 -311.124569) (xy 302.596796 -311.173146) (xy 302.581212 -311.219827)
			(xy 302.558341 -311.263404) (xy 302.528776 -311.302748) (xy 302.493283 -311.33684) (xy 302.45278 -311.364796)
			(xy 302.408318 -311.385894) (xy 302.361047 -311.399586) (xy 302.312192 -311.405518) (xy 302.263017 -311.403537)
			(xy 302.214798 -311.393693) (xy 302.168782 -311.376241) (xy 302.126161 -311.351634) (xy 302.08804 -311.320509)
			(xy 302.055405 -311.283672) (xy 302.029102 -311.242076) (xy 302.009811 -311.1968) (xy 301.998034 -311.149016)
			(xy 301.994074 -311.099962) (xy 300.705012 -311.099962) (xy 300.704517 -311.124569) (xy 300.696622 -311.173146)
			(xy 300.681038 -311.219827) (xy 300.658167 -311.263404) (xy 300.628602 -311.302748) (xy 300.593109 -311.33684)
			(xy 300.552606 -311.364796) (xy 300.508144 -311.385894) (xy 300.460873 -311.399586) (xy 300.412018 -311.405518)
			(xy 300.362843 -311.403537) (xy 300.314624 -311.393693) (xy 300.268608 -311.376241) (xy 300.225987 -311.351634)
			(xy 300.187866 -311.320509) (xy 300.155231 -311.283672) (xy 300.128928 -311.242076) (xy 300.109637 -311.1968)
			(xy 300.09786 -311.149016) (xy 300.0939 -311.099962) (xy 298.805092 -311.099962) (xy 298.804597 -311.124569)
			(xy 298.796702 -311.173146) (xy 298.781118 -311.219827) (xy 298.758247 -311.263404) (xy 298.728682 -311.302748)
			(xy 298.693189 -311.33684) (xy 298.652686 -311.364796) (xy 298.608224 -311.385894) (xy 298.560953 -311.399586)
			(xy 298.512098 -311.405518) (xy 298.462923 -311.403537) (xy 298.414704 -311.393693) (xy 298.368688 -311.376241)
			(xy 298.326067 -311.351634) (xy 298.287946 -311.320509) (xy 298.255311 -311.283672) (xy 298.229008 -311.242076)
			(xy 298.209717 -311.1968) (xy 298.19794 -311.149016) (xy 298.19398 -311.099962) (xy 296.905172 -311.099962)
			(xy 296.904677 -311.124569) (xy 296.896782 -311.173146) (xy 296.881198 -311.219827) (xy 296.858327 -311.263404)
			(xy 296.828762 -311.302748) (xy 296.793269 -311.33684) (xy 296.752766 -311.364796) (xy 296.708304 -311.385894)
			(xy 296.661033 -311.399586) (xy 296.612178 -311.405518) (xy 296.563003 -311.403537) (xy 296.514784 -311.393693)
			(xy 296.468768 -311.376241) (xy 296.426147 -311.351634) (xy 296.388026 -311.320509) (xy 296.355391 -311.283672)
			(xy 296.329088 -311.242076) (xy 296.309797 -311.1968) (xy 296.29802 -311.149016) (xy 296.29406 -311.099962)
			(xy 295.004998 -311.099962) (xy 295.004503 -311.124569) (xy 294.996608 -311.173146) (xy 294.981024 -311.219827)
			(xy 294.958153 -311.263404) (xy 294.928588 -311.302748) (xy 294.893095 -311.33684) (xy 294.852592 -311.364796)
			(xy 294.80813 -311.385894) (xy 294.760859 -311.399586) (xy 294.712004 -311.405518) (xy 294.662829 -311.403537)
			(xy 294.61461 -311.393693) (xy 294.568594 -311.376241) (xy 294.525973 -311.351634) (xy 294.487852 -311.320509)
			(xy 294.455217 -311.283672) (xy 294.428914 -311.242076) (xy 294.409623 -311.1968) (xy 294.397846 -311.149016)
			(xy 294.393886 -311.099962) (xy 293.105078 -311.099962) (xy 293.104583 -311.124569) (xy 293.096688 -311.173146)
			(xy 293.081104 -311.219827) (xy 293.058233 -311.263404) (xy 293.028668 -311.302748) (xy 292.993175 -311.33684)
			(xy 292.952672 -311.364796) (xy 292.90821 -311.385894) (xy 292.860939 -311.399586) (xy 292.812084 -311.405518)
			(xy 292.762909 -311.403537) (xy 292.71469 -311.393693) (xy 292.668674 -311.376241) (xy 292.626053 -311.351634)
			(xy 292.587932 -311.320509) (xy 292.555297 -311.283672) (xy 292.528994 -311.242076) (xy 292.509703 -311.1968)
			(xy 292.497926 -311.149016) (xy 292.493966 -311.099962) (xy 291.205158 -311.099962) (xy 291.204663 -311.124569)
			(xy 291.196768 -311.173146) (xy 291.181184 -311.219827) (xy 291.158313 -311.263404) (xy 291.128748 -311.302748)
			(xy 291.093255 -311.33684) (xy 291.052752 -311.364796) (xy 291.00829 -311.385894) (xy 290.961019 -311.399586)
			(xy 290.912164 -311.405518) (xy 290.862989 -311.403537) (xy 290.81477 -311.393693) (xy 290.768754 -311.376241)
			(xy 290.726133 -311.351634) (xy 290.688012 -311.320509) (xy 290.655377 -311.283672) (xy 290.629074 -311.242076)
			(xy 290.609783 -311.1968) (xy 290.598006 -311.149016) (xy 290.594046 -311.099962) (xy 289.305238 -311.099962)
			(xy 289.304743 -311.124569) (xy 289.296848 -311.173146) (xy 289.281264 -311.219827) (xy 289.258393 -311.263404)
			(xy 289.228828 -311.302748) (xy 289.193335 -311.33684) (xy 289.152832 -311.364796) (xy 289.10837 -311.385894)
			(xy 289.061099 -311.399586) (xy 289.012244 -311.405518) (xy 288.963069 -311.403537) (xy 288.91485 -311.393693)
			(xy 288.868834 -311.376241) (xy 288.826213 -311.351634) (xy 288.788092 -311.320509) (xy 288.755457 -311.283672)
			(xy 288.729154 -311.242076) (xy 288.709863 -311.1968) (xy 288.698086 -311.149016) (xy 288.694126 -311.099962)
			(xy 287.405064 -311.099962) (xy 287.404569 -311.124569) (xy 287.396674 -311.173146) (xy 287.38109 -311.219827)
			(xy 287.358219 -311.263404) (xy 287.328654 -311.302748) (xy 287.293161 -311.33684) (xy 287.252658 -311.364796)
			(xy 287.208196 -311.385894) (xy 287.160925 -311.399586) (xy 287.11207 -311.405518) (xy 287.062895 -311.403537)
			(xy 287.014676 -311.393693) (xy 286.96866 -311.376241) (xy 286.926039 -311.351634) (xy 286.887918 -311.320509)
			(xy 286.855283 -311.283672) (xy 286.82898 -311.242076) (xy 286.809689 -311.1968) (xy 286.797912 -311.149016)
			(xy 286.793952 -311.099962) (xy 285.505144 -311.099962) (xy 285.504649 -311.124569) (xy 285.496754 -311.173146)
			(xy 285.48117 -311.219827) (xy 285.458299 -311.263404) (xy 285.428734 -311.302748) (xy 285.393241 -311.33684)
			(xy 285.352738 -311.364796) (xy 285.308276 -311.385894) (xy 285.261005 -311.399586) (xy 285.21215 -311.405518)
			(xy 285.162975 -311.403537) (xy 285.114756 -311.393693) (xy 285.06874 -311.376241) (xy 285.026119 -311.351634)
			(xy 284.987998 -311.320509) (xy 284.955363 -311.283672) (xy 284.92906 -311.242076) (xy 284.909769 -311.1968)
			(xy 284.897992 -311.149016) (xy 284.894032 -311.099962) (xy 283.605224 -311.099962) (xy 283.604729 -311.124569)
			(xy 283.596834 -311.173146) (xy 283.58125 -311.219827) (xy 283.558379 -311.263404) (xy 283.528814 -311.302748)
			(xy 283.493321 -311.33684) (xy 283.452818 -311.364796) (xy 283.408356 -311.385894) (xy 283.361085 -311.399586)
			(xy 283.31223 -311.405518) (xy 283.263055 -311.403537) (xy 283.214836 -311.393693) (xy 283.16882 -311.376241)
			(xy 283.126199 -311.351634) (xy 283.088078 -311.320509) (xy 283.055443 -311.283672) (xy 283.02914 -311.242076)
			(xy 283.009849 -311.1968) (xy 282.998072 -311.149016) (xy 282.994112 -311.099962) (xy 281.70505 -311.099962)
			(xy 281.704555 -311.124569) (xy 281.69666 -311.173146) (xy 281.681076 -311.219827) (xy 281.658205 -311.263404)
			(xy 281.62864 -311.302748) (xy 281.593147 -311.33684) (xy 281.552644 -311.364796) (xy 281.508182 -311.385894)
			(xy 281.460911 -311.399586) (xy 281.412056 -311.405518) (xy 281.362881 -311.403537) (xy 281.314662 -311.393693)
			(xy 281.268646 -311.376241) (xy 281.226025 -311.351634) (xy 281.187904 -311.320509) (xy 281.155269 -311.283672)
			(xy 281.128966 -311.242076) (xy 281.109675 -311.1968) (xy 281.097898 -311.149016) (xy 281.093938 -311.099962)
			(xy 279.80513 -311.099962) (xy 279.804635 -311.124569) (xy 279.79674 -311.173146) (xy 279.781156 -311.219827)
			(xy 279.758285 -311.263404) (xy 279.72872 -311.302748) (xy 279.693227 -311.33684) (xy 279.652724 -311.364796)
			(xy 279.608262 -311.385894) (xy 279.560991 -311.399586) (xy 279.512136 -311.405518) (xy 279.462961 -311.403537)
			(xy 279.414742 -311.393693) (xy 279.368726 -311.376241) (xy 279.326105 -311.351634) (xy 279.287984 -311.320509)
			(xy 279.255349 -311.283672) (xy 279.229046 -311.242076) (xy 279.209755 -311.1968) (xy 279.197978 -311.149016)
			(xy 279.194018 -311.099962) (xy 277.90521 -311.099962) (xy 277.904715 -311.124569) (xy 277.89682 -311.173146)
			(xy 277.881236 -311.219827) (xy 277.858365 -311.263404) (xy 277.8288 -311.302748) (xy 277.793307 -311.33684)
			(xy 277.752804 -311.364796) (xy 277.708342 -311.385894) (xy 277.661071 -311.399586) (xy 277.612216 -311.405518)
			(xy 277.563041 -311.403537) (xy 277.514822 -311.393693) (xy 277.468806 -311.376241) (xy 277.426185 -311.351634)
			(xy 277.388064 -311.320509) (xy 277.355429 -311.283672) (xy 277.329126 -311.242076) (xy 277.309835 -311.1968)
			(xy 277.298058 -311.149016) (xy 277.294098 -311.099962) (xy 276.005036 -311.099962) (xy 276.004541 -311.124569)
			(xy 275.996646 -311.173146) (xy 275.981062 -311.219827) (xy 275.958191 -311.263404) (xy 275.928626 -311.302748)
			(xy 275.893133 -311.33684) (xy 275.85263 -311.364796) (xy 275.808168 -311.385894) (xy 275.760897 -311.399586)
			(xy 275.712042 -311.405518) (xy 275.662867 -311.403537) (xy 275.614648 -311.393693) (xy 275.568632 -311.376241)
			(xy 275.526011 -311.351634) (xy 275.48789 -311.320509) (xy 275.455255 -311.283672) (xy 275.428952 -311.242076)
			(xy 275.409661 -311.1968) (xy 275.397884 -311.149016) (xy 275.393924 -311.099962) (xy 274.105116 -311.099962)
			(xy 274.104621 -311.124569) (xy 274.096726 -311.173146) (xy 274.081142 -311.219827) (xy 274.058271 -311.263404)
			(xy 274.028706 -311.302748) (xy 273.993213 -311.33684) (xy 273.95271 -311.364796) (xy 273.908248 -311.385894)
			(xy 273.860977 -311.399586) (xy 273.812122 -311.405518) (xy 273.762947 -311.403537) (xy 273.714728 -311.393693)
			(xy 273.668712 -311.376241) (xy 273.626091 -311.351634) (xy 273.58797 -311.320509) (xy 273.555335 -311.283672)
			(xy 273.529032 -311.242076) (xy 273.509741 -311.1968) (xy 273.497964 -311.149016) (xy 273.494004 -311.099962)
			(xy 272.205196 -311.099962) (xy 272.204701 -311.124569) (xy 272.196806 -311.173146) (xy 272.181222 -311.219827)
			(xy 272.158351 -311.263404) (xy 272.128786 -311.302748) (xy 272.093293 -311.33684) (xy 272.05279 -311.364796)
			(xy 272.008328 -311.385894) (xy 271.961057 -311.399586) (xy 271.912202 -311.405518) (xy 271.863027 -311.403537)
			(xy 271.814808 -311.393693) (xy 271.768792 -311.376241) (xy 271.726171 -311.351634) (xy 271.68805 -311.320509)
			(xy 271.655415 -311.283672) (xy 271.629112 -311.242076) (xy 271.609821 -311.1968) (xy 271.598044 -311.149016)
			(xy 271.594084 -311.099962) (xy 196.005196 -311.099962) (xy 196.004701 -311.124569) (xy 195.996806 -311.173146)
			(xy 195.981222 -311.219827) (xy 195.958351 -311.263404) (xy 195.928786 -311.302748) (xy 195.893293 -311.33684)
			(xy 195.85279 -311.364796) (xy 195.808328 -311.385894) (xy 195.761057 -311.399586) (xy 195.712202 -311.405518)
			(xy 195.663027 -311.403537) (xy 195.614808 -311.393693) (xy 195.568792 -311.376241) (xy 195.526171 -311.351634)
			(xy 195.48805 -311.320509) (xy 195.455415 -311.283672) (xy 195.429112 -311.242076) (xy 195.409821 -311.1968)
			(xy 195.398044 -311.149016) (xy 195.394084 -311.099962) (xy 194.105276 -311.099962) (xy 194.104781 -311.124569)
			(xy 194.096886 -311.173146) (xy 194.081302 -311.219827) (xy 194.058431 -311.263404) (xy 194.028866 -311.302748)
			(xy 193.993373 -311.33684) (xy 193.95287 -311.364796) (xy 193.908408 -311.385894) (xy 193.861137 -311.399586)
			(xy 193.812282 -311.405518) (xy 193.763107 -311.403537) (xy 193.714888 -311.393693) (xy 193.668872 -311.376241)
			(xy 193.626251 -311.351634) (xy 193.58813 -311.320509) (xy 193.555495 -311.283672) (xy 193.529192 -311.242076)
			(xy 193.509901 -311.1968) (xy 193.498124 -311.149016) (xy 193.494164 -311.099962) (xy 192.205356 -311.099962)
			(xy 192.204861 -311.124569) (xy 192.196966 -311.173146) (xy 192.181382 -311.219827) (xy 192.158511 -311.263404)
			(xy 192.128946 -311.302748) (xy 192.093453 -311.33684) (xy 192.05295 -311.364796) (xy 192.008488 -311.385894)
			(xy 191.961217 -311.399586) (xy 191.912362 -311.405518) (xy 191.863187 -311.403537) (xy 191.814968 -311.393693)
			(xy 191.768952 -311.376241) (xy 191.726331 -311.351634) (xy 191.68821 -311.320509) (xy 191.655575 -311.283672)
			(xy 191.629272 -311.242076) (xy 191.609981 -311.1968) (xy 191.598204 -311.149016) (xy 191.594244 -311.099962)
			(xy 190.305182 -311.099962) (xy 190.304687 -311.124569) (xy 190.296792 -311.173146) (xy 190.281208 -311.219827)
			(xy 190.258337 -311.263404) (xy 190.228772 -311.302748) (xy 190.193279 -311.33684) (xy 190.152776 -311.364796)
			(xy 190.108314 -311.385894) (xy 190.061043 -311.399586) (xy 190.012188 -311.405518) (xy 189.963013 -311.403537)
			(xy 189.914794 -311.393693) (xy 189.868778 -311.376241) (xy 189.826157 -311.351634) (xy 189.788036 -311.320509)
			(xy 189.755401 -311.283672) (xy 189.729098 -311.242076) (xy 189.709807 -311.1968) (xy 189.69803 -311.149016)
			(xy 189.69407 -311.099962) (xy 188.405262 -311.099962) (xy 188.404767 -311.124569) (xy 188.396872 -311.173146)
			(xy 188.381288 -311.219827) (xy 188.358417 -311.263404) (xy 188.328852 -311.302748) (xy 188.293359 -311.33684)
			(xy 188.252856 -311.364796) (xy 188.208394 -311.385894) (xy 188.161123 -311.399586) (xy 188.112268 -311.405518)
			(xy 188.063093 -311.403537) (xy 188.014874 -311.393693) (xy 187.968858 -311.376241) (xy 187.926237 -311.351634)
			(xy 187.888116 -311.320509) (xy 187.855481 -311.283672) (xy 187.829178 -311.242076) (xy 187.809887 -311.1968)
			(xy 187.79811 -311.149016) (xy 187.79415 -311.099962) (xy 186.505342 -311.099962) (xy 186.504847 -311.124569)
			(xy 186.496952 -311.173146) (xy 186.481368 -311.219827) (xy 186.458497 -311.263404) (xy 186.428932 -311.302748)
			(xy 186.393439 -311.33684) (xy 186.352936 -311.364796) (xy 186.308474 -311.385894) (xy 186.261203 -311.399586)
			(xy 186.212348 -311.405518) (xy 186.163173 -311.403537) (xy 186.114954 -311.393693) (xy 186.068938 -311.376241)
			(xy 186.026317 -311.351634) (xy 185.988196 -311.320509) (xy 185.955561 -311.283672) (xy 185.929258 -311.242076)
			(xy 185.909967 -311.1968) (xy 185.89819 -311.149016) (xy 185.89423 -311.099962) (xy 184.605168 -311.099962)
			(xy 184.604673 -311.124569) (xy 184.596778 -311.173146) (xy 184.581194 -311.219827) (xy 184.558323 -311.263404)
			(xy 184.528758 -311.302748) (xy 184.493265 -311.33684) (xy 184.452762 -311.364796) (xy 184.4083 -311.385894)
			(xy 184.361029 -311.399586) (xy 184.312174 -311.405518) (xy 184.262999 -311.403537) (xy 184.21478 -311.393693)
			(xy 184.168764 -311.376241) (xy 184.126143 -311.351634) (xy 184.088022 -311.320509) (xy 184.055387 -311.283672)
			(xy 184.029084 -311.242076) (xy 184.009793 -311.1968) (xy 183.998016 -311.149016) (xy 183.994056 -311.099962)
			(xy 182.705248 -311.099962) (xy 182.704753 -311.124569) (xy 182.696858 -311.173146) (xy 182.681274 -311.219827)
			(xy 182.658403 -311.263404) (xy 182.628838 -311.302748) (xy 182.593345 -311.33684) (xy 182.552842 -311.364796)
			(xy 182.50838 -311.385894) (xy 182.461109 -311.399586) (xy 182.412254 -311.405518) (xy 182.363079 -311.403537)
			(xy 182.31486 -311.393693) (xy 182.268844 -311.376241) (xy 182.226223 -311.351634) (xy 182.188102 -311.320509)
			(xy 182.155467 -311.283672) (xy 182.129164 -311.242076) (xy 182.109873 -311.1968) (xy 182.098096 -311.149016)
			(xy 182.094136 -311.099962) (xy 180.805328 -311.099962) (xy 180.804833 -311.124569) (xy 180.796938 -311.173146)
			(xy 180.781354 -311.219827) (xy 180.758483 -311.263404) (xy 180.728918 -311.302748) (xy 180.693425 -311.33684)
			(xy 180.652922 -311.364796) (xy 180.60846 -311.385894) (xy 180.561189 -311.399586) (xy 180.512334 -311.405518)
			(xy 180.463159 -311.403537) (xy 180.41494 -311.393693) (xy 180.368924 -311.376241) (xy 180.326303 -311.351634)
			(xy 180.288182 -311.320509) (xy 180.255547 -311.283672) (xy 180.229244 -311.242076) (xy 180.209953 -311.1968)
			(xy 180.198176 -311.149016) (xy 180.194216 -311.099962) (xy 178.905154 -311.099962) (xy 178.904659 -311.124569)
			(xy 178.896764 -311.173146) (xy 178.88118 -311.219827) (xy 178.858309 -311.263404) (xy 178.828744 -311.302748)
			(xy 178.793251 -311.33684) (xy 178.752748 -311.364796) (xy 178.708286 -311.385894) (xy 178.661015 -311.399586)
			(xy 178.61216 -311.405518) (xy 178.562985 -311.403537) (xy 178.514766 -311.393693) (xy 178.46875 -311.376241)
			(xy 178.426129 -311.351634) (xy 178.388008 -311.320509) (xy 178.355373 -311.283672) (xy 178.32907 -311.242076)
			(xy 178.309779 -311.1968) (xy 178.298002 -311.149016) (xy 178.294042 -311.099962) (xy 177.005234 -311.099962)
			(xy 177.004739 -311.124569) (xy 176.996844 -311.173146) (xy 176.98126 -311.219827) (xy 176.958389 -311.263404)
			(xy 176.928824 -311.302748) (xy 176.893331 -311.33684) (xy 176.852828 -311.364796) (xy 176.808366 -311.385894)
			(xy 176.761095 -311.399586) (xy 176.71224 -311.405518) (xy 176.663065 -311.403537) (xy 176.614846 -311.393693)
			(xy 176.56883 -311.376241) (xy 176.526209 -311.351634) (xy 176.488088 -311.320509) (xy 176.455453 -311.283672)
			(xy 176.42915 -311.242076) (xy 176.409859 -311.1968) (xy 176.398082 -311.149016) (xy 176.394122 -311.099962)
			(xy 175.105314 -311.099962) (xy 175.104819 -311.124569) (xy 175.096924 -311.173146) (xy 175.08134 -311.219827)
			(xy 175.058469 -311.263404) (xy 175.028904 -311.302748) (xy 174.993411 -311.33684) (xy 174.952908 -311.364796)
			(xy 174.908446 -311.385894) (xy 174.861175 -311.399586) (xy 174.81232 -311.405518) (xy 174.763145 -311.403537)
			(xy 174.714926 -311.393693) (xy 174.66891 -311.376241) (xy 174.626289 -311.351634) (xy 174.588168 -311.320509)
			(xy 174.555533 -311.283672) (xy 174.52923 -311.242076) (xy 174.509939 -311.1968) (xy 174.498162 -311.149016)
			(xy 174.494202 -311.099962) (xy 173.205394 -311.099962) (xy 173.204899 -311.124569) (xy 173.197004 -311.173146)
			(xy 173.18142 -311.219827) (xy 173.158549 -311.263404) (xy 173.128984 -311.302748) (xy 173.093491 -311.33684)
			(xy 173.052988 -311.364796) (xy 173.008526 -311.385894) (xy 172.961255 -311.399586) (xy 172.9124 -311.405518)
			(xy 172.863225 -311.403537) (xy 172.815006 -311.393693) (xy 172.76899 -311.376241) (xy 172.726369 -311.351634)
			(xy 172.688248 -311.320509) (xy 172.655613 -311.283672) (xy 172.62931 -311.242076) (xy 172.610019 -311.1968)
			(xy 172.598242 -311.149016) (xy 172.594282 -311.099962) (xy 171.30522 -311.099962) (xy 171.304725 -311.124569)
			(xy 171.29683 -311.173146) (xy 171.281246 -311.219827) (xy 171.258375 -311.263404) (xy 171.22881 -311.302748)
			(xy 171.193317 -311.33684) (xy 171.152814 -311.364796) (xy 171.108352 -311.385894) (xy 171.061081 -311.399586)
			(xy 171.012226 -311.405518) (xy 170.963051 -311.403537) (xy 170.914832 -311.393693) (xy 170.868816 -311.376241)
			(xy 170.826195 -311.351634) (xy 170.788074 -311.320509) (xy 170.755439 -311.283672) (xy 170.729136 -311.242076)
			(xy 170.709845 -311.1968) (xy 170.698068 -311.149016) (xy 170.694108 -311.099962) (xy 169.4053 -311.099962)
			(xy 169.404805 -311.124569) (xy 169.39691 -311.173146) (xy 169.381326 -311.219827) (xy 169.358455 -311.263404)
			(xy 169.32889 -311.302748) (xy 169.293397 -311.33684) (xy 169.252894 -311.364796) (xy 169.208432 -311.385894)
			(xy 169.161161 -311.399586) (xy 169.112306 -311.405518) (xy 169.063131 -311.403537) (xy 169.014912 -311.393693)
			(xy 168.968896 -311.376241) (xy 168.926275 -311.351634) (xy 168.888154 -311.320509) (xy 168.855519 -311.283672)
			(xy 168.829216 -311.242076) (xy 168.809925 -311.1968) (xy 168.798148 -311.149016) (xy 168.794188 -311.099962)
			(xy 167.50538 -311.099962) (xy 167.504885 -311.124569) (xy 167.49699 -311.173146) (xy 167.481406 -311.219827)
			(xy 167.458535 -311.263404) (xy 167.42897 -311.302748) (xy 167.393477 -311.33684) (xy 167.352974 -311.364796)
			(xy 167.308512 -311.385894) (xy 167.261241 -311.399586) (xy 167.212386 -311.405518) (xy 167.163211 -311.403537)
			(xy 167.114992 -311.393693) (xy 167.068976 -311.376241) (xy 167.026355 -311.351634) (xy 166.988234 -311.320509)
			(xy 166.955599 -311.283672) (xy 166.929296 -311.242076) (xy 166.910005 -311.1968) (xy 166.898228 -311.149016)
			(xy 166.894268 -311.099962) (xy 165.605206 -311.099962) (xy 165.604711 -311.124569) (xy 165.596816 -311.173146)
			(xy 165.581232 -311.219827) (xy 165.558361 -311.263404) (xy 165.528796 -311.302748) (xy 165.493303 -311.33684)
			(xy 165.4528 -311.364796) (xy 165.408338 -311.385894) (xy 165.361067 -311.399586) (xy 165.312212 -311.405518)
			(xy 165.263037 -311.403537) (xy 165.214818 -311.393693) (xy 165.168802 -311.376241) (xy 165.126181 -311.351634)
			(xy 165.08806 -311.320509) (xy 165.055425 -311.283672) (xy 165.029122 -311.242076) (xy 165.009831 -311.1968)
			(xy 164.998054 -311.149016) (xy 164.994094 -311.099962) (xy 163.705286 -311.099962) (xy 163.704791 -311.124569)
			(xy 163.696896 -311.173146) (xy 163.681312 -311.219827) (xy 163.658441 -311.263404) (xy 163.628876 -311.302748)
			(xy 163.593383 -311.33684) (xy 163.55288 -311.364796) (xy 163.508418 -311.385894) (xy 163.461147 -311.399586)
			(xy 163.412292 -311.405518) (xy 163.363117 -311.403537) (xy 163.314898 -311.393693) (xy 163.268882 -311.376241)
			(xy 163.226261 -311.351634) (xy 163.18814 -311.320509) (xy 163.155505 -311.283672) (xy 163.129202 -311.242076)
			(xy 163.109911 -311.1968) (xy 163.098134 -311.149016) (xy 163.094174 -311.099962) (xy 161.805366 -311.099962)
			(xy 161.804871 -311.124569) (xy 161.796976 -311.173146) (xy 161.781392 -311.219827) (xy 161.758521 -311.263404)
			(xy 161.728956 -311.302748) (xy 161.693463 -311.33684) (xy 161.65296 -311.364796) (xy 161.608498 -311.385894)
			(xy 161.561227 -311.399586) (xy 161.512372 -311.405518) (xy 161.463197 -311.403537) (xy 161.414978 -311.393693)
			(xy 161.368962 -311.376241) (xy 161.326341 -311.351634) (xy 161.28822 -311.320509) (xy 161.255585 -311.283672)
			(xy 161.229282 -311.242076) (xy 161.209991 -311.1968) (xy 161.198214 -311.149016) (xy 161.194254 -311.099962)
			(xy 159.905192 -311.099962) (xy 159.904697 -311.124569) (xy 159.896802 -311.173146) (xy 159.881218 -311.219827)
			(xy 159.858347 -311.263404) (xy 159.828782 -311.302748) (xy 159.793289 -311.33684) (xy 159.752786 -311.364796)
			(xy 159.708324 -311.385894) (xy 159.661053 -311.399586) (xy 159.612198 -311.405518) (xy 159.563023 -311.403537)
			(xy 159.514804 -311.393693) (xy 159.468788 -311.376241) (xy 159.426167 -311.351634) (xy 159.388046 -311.320509)
			(xy 159.355411 -311.283672) (xy 159.329108 -311.242076) (xy 159.309817 -311.1968) (xy 159.29804 -311.149016)
			(xy 159.29408 -311.099962) (xy 158.005272 -311.099962) (xy 158.004777 -311.124569) (xy 157.996882 -311.173146)
			(xy 157.981298 -311.219827) (xy 157.958427 -311.263404) (xy 157.928862 -311.302748) (xy 157.893369 -311.33684)
			(xy 157.852866 -311.364796) (xy 157.808404 -311.385894) (xy 157.761133 -311.399586) (xy 157.712278 -311.405518)
			(xy 157.663103 -311.403537) (xy 157.614884 -311.393693) (xy 157.568868 -311.376241) (xy 157.526247 -311.351634)
			(xy 157.488126 -311.320509) (xy 157.455491 -311.283672) (xy 157.429188 -311.242076) (xy 157.409897 -311.1968)
			(xy 157.39812 -311.149016) (xy 157.39416 -311.099962) (xy 156.105352 -311.099962) (xy 156.104857 -311.124569)
			(xy 156.096962 -311.173146) (xy 156.081378 -311.219827) (xy 156.058507 -311.263404) (xy 156.028942 -311.302748)
			(xy 155.993449 -311.33684) (xy 155.952946 -311.364796) (xy 155.908484 -311.385894) (xy 155.861213 -311.399586)
			(xy 155.812358 -311.405518) (xy 155.763183 -311.403537) (xy 155.714964 -311.393693) (xy 155.668948 -311.376241)
			(xy 155.626327 -311.351634) (xy 155.588206 -311.320509) (xy 155.555571 -311.283672) (xy 155.529268 -311.242076)
			(xy 155.509977 -311.1968) (xy 155.4982 -311.149016) (xy 155.49424 -311.099962) (xy 79.905098 -311.099962)
			(xy 79.904603 -311.124569) (xy 79.896708 -311.173146) (xy 79.881124 -311.219827) (xy 79.858253 -311.263404)
			(xy 79.828688 -311.302748) (xy 79.793195 -311.33684) (xy 79.752692 -311.364796) (xy 79.70823 -311.385894)
			(xy 79.660959 -311.399586) (xy 79.612104 -311.405518) (xy 79.562929 -311.403537) (xy 79.51471 -311.393693)
			(xy 79.468694 -311.376241) (xy 79.426073 -311.351634) (xy 79.387952 -311.320509) (xy 79.355317 -311.283672)
			(xy 79.329014 -311.242076) (xy 79.309723 -311.1968) (xy 79.297946 -311.149016) (xy 79.293986 -311.099962)
			(xy 78.005178 -311.099962) (xy 78.004683 -311.124569) (xy 77.996788 -311.173146) (xy 77.981204 -311.219827)
			(xy 77.958333 -311.263404) (xy 77.928768 -311.302748) (xy 77.893275 -311.33684) (xy 77.852772 -311.364796)
			(xy 77.80831 -311.385894) (xy 77.761039 -311.399586) (xy 77.712184 -311.405518) (xy 77.663009 -311.403537)
			(xy 77.61479 -311.393693) (xy 77.568774 -311.376241) (xy 77.526153 -311.351634) (xy 77.488032 -311.320509)
			(xy 77.455397 -311.283672) (xy 77.429094 -311.242076) (xy 77.409803 -311.1968) (xy 77.398026 -311.149016)
			(xy 77.394066 -311.099962) (xy 76.105258 -311.099962) (xy 76.104763 -311.124569) (xy 76.096868 -311.173146)
			(xy 76.081284 -311.219827) (xy 76.058413 -311.263404) (xy 76.028848 -311.302748) (xy 75.993355 -311.33684)
			(xy 75.952852 -311.364796) (xy 75.90839 -311.385894) (xy 75.861119 -311.399586) (xy 75.812264 -311.405518)
			(xy 75.763089 -311.403537) (xy 75.71487 -311.393693) (xy 75.668854 -311.376241) (xy 75.626233 -311.351634)
			(xy 75.588112 -311.320509) (xy 75.555477 -311.283672) (xy 75.529174 -311.242076) (xy 75.509883 -311.1968)
			(xy 75.498106 -311.149016) (xy 75.494146 -311.099962) (xy 74.205084 -311.099962) (xy 74.204589 -311.124569)
			(xy 74.196694 -311.173146) (xy 74.18111 -311.219827) (xy 74.158239 -311.263404) (xy 74.128674 -311.302748)
			(xy 74.093181 -311.33684) (xy 74.052678 -311.364796) (xy 74.008216 -311.385894) (xy 73.960945 -311.399586)
			(xy 73.91209 -311.405518) (xy 73.862915 -311.403537) (xy 73.814696 -311.393693) (xy 73.76868 -311.376241)
			(xy 73.726059 -311.351634) (xy 73.687938 -311.320509) (xy 73.655303 -311.283672) (xy 73.629 -311.242076)
			(xy 73.609709 -311.1968) (xy 73.597932 -311.149016) (xy 73.593972 -311.099962) (xy 72.305164 -311.099962)
			(xy 72.304669 -311.124569) (xy 72.296774 -311.173146) (xy 72.28119 -311.219827) (xy 72.258319 -311.263404)
			(xy 72.228754 -311.302748) (xy 72.193261 -311.33684) (xy 72.152758 -311.364796) (xy 72.108296 -311.385894)
			(xy 72.061025 -311.399586) (xy 72.01217 -311.405518) (xy 71.962995 -311.403537) (xy 71.914776 -311.393693)
			(xy 71.86876 -311.376241) (xy 71.826139 -311.351634) (xy 71.788018 -311.320509) (xy 71.755383 -311.283672)
			(xy 71.72908 -311.242076) (xy 71.709789 -311.1968) (xy 71.698012 -311.149016) (xy 71.694052 -311.099962)
			(xy 70.405244 -311.099962) (xy 70.404749 -311.124569) (xy 70.396854 -311.173146) (xy 70.38127 -311.219827)
			(xy 70.358399 -311.263404) (xy 70.328834 -311.302748) (xy 70.293341 -311.33684) (xy 70.252838 -311.364796)
			(xy 70.208376 -311.385894) (xy 70.161105 -311.399586) (xy 70.11225 -311.405518) (xy 70.063075 -311.403537)
			(xy 70.014856 -311.393693) (xy 69.96884 -311.376241) (xy 69.926219 -311.351634) (xy 69.888098 -311.320509)
			(xy 69.855463 -311.283672) (xy 69.82916 -311.242076) (xy 69.809869 -311.1968) (xy 69.798092 -311.149016)
			(xy 69.794132 -311.099962) (xy 68.50507 -311.099962) (xy 68.504575 -311.124569) (xy 68.49668 -311.173146)
			(xy 68.481096 -311.219827) (xy 68.458225 -311.263404) (xy 68.42866 -311.302748) (xy 68.393167 -311.33684)
			(xy 68.352664 -311.364796) (xy 68.308202 -311.385894) (xy 68.260931 -311.399586) (xy 68.212076 -311.405518)
			(xy 68.162901 -311.403537) (xy 68.114682 -311.393693) (xy 68.068666 -311.376241) (xy 68.026045 -311.351634)
			(xy 67.987924 -311.320509) (xy 67.955289 -311.283672) (xy 67.928986 -311.242076) (xy 67.909695 -311.1968)
			(xy 67.897918 -311.149016) (xy 67.893958 -311.099962) (xy 66.60515 -311.099962) (xy 66.604655 -311.124569)
			(xy 66.59676 -311.173146) (xy 66.581176 -311.219827) (xy 66.558305 -311.263404) (xy 66.52874 -311.302748)
			(xy 66.493247 -311.33684) (xy 66.452744 -311.364796) (xy 66.408282 -311.385894) (xy 66.361011 -311.399586)
			(xy 66.312156 -311.405518) (xy 66.262981 -311.403537) (xy 66.214762 -311.393693) (xy 66.168746 -311.376241)
			(xy 66.126125 -311.351634) (xy 66.088004 -311.320509) (xy 66.055369 -311.283672) (xy 66.029066 -311.242076)
			(xy 66.009775 -311.1968) (xy 65.997998 -311.149016) (xy 65.994038 -311.099962) (xy 64.70523 -311.099962)
			(xy 64.704735 -311.124569) (xy 64.69684 -311.173146) (xy 64.681256 -311.219827) (xy 64.658385 -311.263404)
			(xy 64.62882 -311.302748) (xy 64.593327 -311.33684) (xy 64.552824 -311.364796) (xy 64.508362 -311.385894)
			(xy 64.461091 -311.399586) (xy 64.412236 -311.405518) (xy 64.363061 -311.403537) (xy 64.314842 -311.393693)
			(xy 64.268826 -311.376241) (xy 64.226205 -311.351634) (xy 64.188084 -311.320509) (xy 64.155449 -311.283672)
			(xy 64.129146 -311.242076) (xy 64.109855 -311.1968) (xy 64.098078 -311.149016) (xy 64.094118 -311.099962)
			(xy 62.805056 -311.099962) (xy 62.804561 -311.124569) (xy 62.796666 -311.173146) (xy 62.781082 -311.219827)
			(xy 62.758211 -311.263404) (xy 62.728646 -311.302748) (xy 62.693153 -311.33684) (xy 62.65265 -311.364796)
			(xy 62.608188 -311.385894) (xy 62.560917 -311.399586) (xy 62.512062 -311.405518) (xy 62.462887 -311.403537)
			(xy 62.414668 -311.393693) (xy 62.368652 -311.376241) (xy 62.326031 -311.351634) (xy 62.28791 -311.320509)
			(xy 62.255275 -311.283672) (xy 62.228972 -311.242076) (xy 62.209681 -311.1968) (xy 62.197904 -311.149016)
			(xy 62.193944 -311.099962) (xy 60.905136 -311.099962) (xy 60.904641 -311.124569) (xy 60.896746 -311.173146)
			(xy 60.881162 -311.219827) (xy 60.858291 -311.263404) (xy 60.828726 -311.302748) (xy 60.793233 -311.33684)
			(xy 60.75273 -311.364796) (xy 60.708268 -311.385894) (xy 60.660997 -311.399586) (xy 60.612142 -311.405518)
			(xy 60.562967 -311.403537) (xy 60.514748 -311.393693) (xy 60.468732 -311.376241) (xy 60.426111 -311.351634)
			(xy 60.38799 -311.320509) (xy 60.355355 -311.283672) (xy 60.329052 -311.242076) (xy 60.309761 -311.1968)
			(xy 60.297984 -311.149016) (xy 60.294024 -311.099962) (xy 59.005216 -311.099962) (xy 59.004721 -311.124569)
			(xy 58.996826 -311.173146) (xy 58.981242 -311.219827) (xy 58.958371 -311.263404) (xy 58.928806 -311.302748)
			(xy 58.893313 -311.33684) (xy 58.85281 -311.364796) (xy 58.808348 -311.385894) (xy 58.761077 -311.399586)
			(xy 58.712222 -311.405518) (xy 58.663047 -311.403537) (xy 58.614828 -311.393693) (xy 58.568812 -311.376241)
			(xy 58.526191 -311.351634) (xy 58.48807 -311.320509) (xy 58.455435 -311.283672) (xy 58.429132 -311.242076)
			(xy 58.409841 -311.1968) (xy 58.398064 -311.149016) (xy 58.394104 -311.099962) (xy 57.105296 -311.099962)
			(xy 57.104801 -311.124569) (xy 57.096906 -311.173146) (xy 57.081322 -311.219827) (xy 57.058451 -311.263404)
			(xy 57.028886 -311.302748) (xy 56.993393 -311.33684) (xy 56.95289 -311.364796) (xy 56.908428 -311.385894)
			(xy 56.861157 -311.399586) (xy 56.812302 -311.405518) (xy 56.763127 -311.403537) (xy 56.714908 -311.393693)
			(xy 56.668892 -311.376241) (xy 56.626271 -311.351634) (xy 56.58815 -311.320509) (xy 56.555515 -311.283672)
			(xy 56.529212 -311.242076) (xy 56.509921 -311.1968) (xy 56.498144 -311.149016) (xy 56.494184 -311.099962)
			(xy 55.205122 -311.099962) (xy 55.204627 -311.124569) (xy 55.196732 -311.173146) (xy 55.181148 -311.219827)
			(xy 55.158277 -311.263404) (xy 55.128712 -311.302748) (xy 55.093219 -311.33684) (xy 55.052716 -311.364796)
			(xy 55.008254 -311.385894) (xy 54.960983 -311.399586) (xy 54.912128 -311.405518) (xy 54.862953 -311.403537)
			(xy 54.814734 -311.393693) (xy 54.768718 -311.376241) (xy 54.726097 -311.351634) (xy 54.687976 -311.320509)
			(xy 54.655341 -311.283672) (xy 54.629038 -311.242076) (xy 54.609747 -311.1968) (xy 54.59797 -311.149016)
			(xy 54.59401 -311.099962) (xy 53.305202 -311.099962) (xy 53.304707 -311.124569) (xy 53.296812 -311.173146)
			(xy 53.281228 -311.219827) (xy 53.258357 -311.263404) (xy 53.228792 -311.302748) (xy 53.193299 -311.33684)
			(xy 53.152796 -311.364796) (xy 53.108334 -311.385894) (xy 53.061063 -311.399586) (xy 53.012208 -311.405518)
			(xy 52.963033 -311.403537) (xy 52.914814 -311.393693) (xy 52.868798 -311.376241) (xy 52.826177 -311.351634)
			(xy 52.788056 -311.320509) (xy 52.755421 -311.283672) (xy 52.729118 -311.242076) (xy 52.709827 -311.1968)
			(xy 52.69805 -311.149016) (xy 52.69409 -311.099962) (xy 51.405282 -311.099962) (xy 51.404787 -311.124569)
			(xy 51.396892 -311.173146) (xy 51.381308 -311.219827) (xy 51.358437 -311.263404) (xy 51.328872 -311.302748)
			(xy 51.293379 -311.33684) (xy 51.252876 -311.364796) (xy 51.208414 -311.385894) (xy 51.161143 -311.399586)
			(xy 51.112288 -311.405518) (xy 51.063113 -311.403537) (xy 51.014894 -311.393693) (xy 50.968878 -311.376241)
			(xy 50.926257 -311.351634) (xy 50.888136 -311.320509) (xy 50.855501 -311.283672) (xy 50.829198 -311.242076)
			(xy 50.809907 -311.1968) (xy 50.79813 -311.149016) (xy 50.79417 -311.099962) (xy 49.505108 -311.099962)
			(xy 49.504613 -311.124569) (xy 49.496718 -311.173146) (xy 49.481134 -311.219827) (xy 49.458263 -311.263404)
			(xy 49.428698 -311.302748) (xy 49.393205 -311.33684) (xy 49.352702 -311.364796) (xy 49.30824 -311.385894)
			(xy 49.260969 -311.399586) (xy 49.212114 -311.405518) (xy 49.162939 -311.403537) (xy 49.11472 -311.393693)
			(xy 49.068704 -311.376241) (xy 49.026083 -311.351634) (xy 48.987962 -311.320509) (xy 48.955327 -311.283672)
			(xy 48.929024 -311.242076) (xy 48.909733 -311.1968) (xy 48.897956 -311.149016) (xy 48.893996 -311.099962)
			(xy 47.605188 -311.099962) (xy 47.604693 -311.124569) (xy 47.596798 -311.173146) (xy 47.581214 -311.219827)
			(xy 47.558343 -311.263404) (xy 47.528778 -311.302748) (xy 47.493285 -311.33684) (xy 47.452782 -311.364796)
			(xy 47.40832 -311.385894) (xy 47.361049 -311.399586) (xy 47.312194 -311.405518) (xy 47.263019 -311.403537)
			(xy 47.2148 -311.393693) (xy 47.168784 -311.376241) (xy 47.126163 -311.351634) (xy 47.088042 -311.320509)
			(xy 47.055407 -311.283672) (xy 47.029104 -311.242076) (xy 47.009813 -311.1968) (xy 46.998036 -311.149016)
			(xy 46.994076 -311.099962) (xy 45.705268 -311.099962) (xy 45.704773 -311.124569) (xy 45.696878 -311.173146)
			(xy 45.681294 -311.219827) (xy 45.658423 -311.263404) (xy 45.628858 -311.302748) (xy 45.593365 -311.33684)
			(xy 45.552862 -311.364796) (xy 45.5084 -311.385894) (xy 45.461129 -311.399586) (xy 45.412274 -311.405518)
			(xy 45.363099 -311.403537) (xy 45.31488 -311.393693) (xy 45.268864 -311.376241) (xy 45.226243 -311.351634)
			(xy 45.188122 -311.320509) (xy 45.155487 -311.283672) (xy 45.129184 -311.242076) (xy 45.109893 -311.1968)
			(xy 45.098116 -311.149016) (xy 45.094156 -311.099962) (xy 43.805094 -311.099962) (xy 43.804599 -311.124569)
			(xy 43.796704 -311.173146) (xy 43.78112 -311.219827) (xy 43.758249 -311.263404) (xy 43.728684 -311.302748)
			(xy 43.693191 -311.33684) (xy 43.652688 -311.364796) (xy 43.608226 -311.385894) (xy 43.560955 -311.399586)
			(xy 43.5121 -311.405518) (xy 43.462925 -311.403537) (xy 43.414706 -311.393693) (xy 43.36869 -311.376241)
			(xy 43.326069 -311.351634) (xy 43.287948 -311.320509) (xy 43.255313 -311.283672) (xy 43.22901 -311.242076)
			(xy 43.209719 -311.1968) (xy 43.197942 -311.149016) (xy 43.193982 -311.099962) (xy 41.905174 -311.099962)
			(xy 41.904679 -311.124569) (xy 41.896784 -311.173146) (xy 41.8812 -311.219827) (xy 41.858329 -311.263404)
			(xy 41.828764 -311.302748) (xy 41.793271 -311.33684) (xy 41.752768 -311.364796) (xy 41.708306 -311.385894)
			(xy 41.661035 -311.399586) (xy 41.61218 -311.405518) (xy 41.563005 -311.403537) (xy 41.514786 -311.393693)
			(xy 41.46877 -311.376241) (xy 41.426149 -311.351634) (xy 41.388028 -311.320509) (xy 41.355393 -311.283672)
			(xy 41.32909 -311.242076) (xy 41.309799 -311.1968) (xy 41.298022 -311.149016) (xy 41.294062 -311.099962)
			(xy 40.005254 -311.099962) (xy 40.004759 -311.124569) (xy 39.996864 -311.173146) (xy 39.98128 -311.219827)
			(xy 39.958409 -311.263404) (xy 39.928844 -311.302748) (xy 39.893351 -311.33684) (xy 39.852848 -311.364796)
			(xy 39.808386 -311.385894) (xy 39.761115 -311.399586) (xy 39.71226 -311.405518) (xy 39.663085 -311.403537)
			(xy 39.614866 -311.393693) (xy 39.56885 -311.376241) (xy 39.526229 -311.351634) (xy 39.488108 -311.320509)
			(xy 39.455473 -311.283672) (xy 39.42917 -311.242076) (xy 39.409879 -311.1968) (xy 39.398102 -311.149016)
			(xy 39.394142 -311.099962) (xy 0.508 -311.099962) (xy 0.508 -312.049922) (xy 36.544008 -312.049922)
			(xy 36.547968 -312.000868) (xy 36.559745 -311.953084) (xy 36.579036 -311.907808) (xy 36.605339 -311.866212)
			(xy 36.637974 -311.829375) (xy 36.676095 -311.79825) (xy 36.718716 -311.773643) (xy 36.764732 -311.756191)
			(xy 36.812951 -311.746347) (xy 36.862126 -311.744366) (xy 36.910981 -311.750298) (xy 36.958252 -311.76399)
			(xy 37.002714 -311.785088) (xy 37.043217 -311.813044) (xy 37.07871 -311.847136) (xy 37.108275 -311.88648)
			(xy 37.131146 -311.930057) (xy 37.14673 -311.976738) (xy 37.154625 -312.025315) (xy 37.15512 -312.049922)
			(xy 37.493968 -312.049922) (xy 37.497928 -312.000868) (xy 37.509705 -311.953084) (xy 37.528996 -311.907808)
			(xy 37.555299 -311.866212) (xy 37.587934 -311.829375) (xy 37.626055 -311.79825) (xy 37.668676 -311.773643)
			(xy 37.714692 -311.756191) (xy 37.762911 -311.746347) (xy 37.812086 -311.744366) (xy 37.860941 -311.750298)
			(xy 37.908212 -311.76399) (xy 37.952674 -311.785088) (xy 37.993177 -311.813044) (xy 38.02867 -311.847136)
			(xy 38.058235 -311.88648) (xy 38.081106 -311.930057) (xy 38.09669 -311.976738) (xy 38.104585 -312.025315)
			(xy 38.10508 -312.049922) (xy 39.394142 -312.049922) (xy 39.398102 -312.000868) (xy 39.409879 -311.953084)
			(xy 39.42917 -311.907808) (xy 39.455473 -311.866212) (xy 39.488108 -311.829375) (xy 39.526229 -311.79825)
			(xy 39.56885 -311.773643) (xy 39.614866 -311.756191) (xy 39.663085 -311.746347) (xy 39.71226 -311.744366)
			(xy 39.761115 -311.750298) (xy 39.808386 -311.76399) (xy 39.852848 -311.785088) (xy 39.893351 -311.813044)
			(xy 39.928844 -311.847136) (xy 39.958409 -311.88648) (xy 39.98128 -311.930057) (xy 39.996864 -311.976738)
			(xy 40.004759 -312.025315) (xy 40.005254 -312.049922) (xy 41.294062 -312.049922) (xy 41.298022 -312.000868)
			(xy 41.309799 -311.953084) (xy 41.32909 -311.907808) (xy 41.355393 -311.866212) (xy 41.388028 -311.829375)
			(xy 41.426149 -311.79825) (xy 41.46877 -311.773643) (xy 41.514786 -311.756191) (xy 41.563005 -311.746347)
			(xy 41.61218 -311.744366) (xy 41.661035 -311.750298) (xy 41.708306 -311.76399) (xy 41.752768 -311.785088)
			(xy 41.793271 -311.813044) (xy 41.828764 -311.847136) (xy 41.858329 -311.88648) (xy 41.8812 -311.930057)
			(xy 41.896784 -311.976738) (xy 41.904679 -312.025315) (xy 41.905174 -312.049922) (xy 43.193982 -312.049922)
			(xy 43.197942 -312.000868) (xy 43.209719 -311.953084) (xy 43.22901 -311.907808) (xy 43.255313 -311.866212)
			(xy 43.287948 -311.829375) (xy 43.326069 -311.79825) (xy 43.36869 -311.773643) (xy 43.414706 -311.756191)
			(xy 43.462925 -311.746347) (xy 43.5121 -311.744366) (xy 43.560955 -311.750298) (xy 43.608226 -311.76399)
			(xy 43.652688 -311.785088) (xy 43.693191 -311.813044) (xy 43.728684 -311.847136) (xy 43.758249 -311.88648)
			(xy 43.78112 -311.930057) (xy 43.796704 -311.976738) (xy 43.804599 -312.025315) (xy 43.805094 -312.049922)
			(xy 45.094156 -312.049922) (xy 45.098116 -312.000868) (xy 45.109893 -311.953084) (xy 45.129184 -311.907808)
			(xy 45.155487 -311.866212) (xy 45.188122 -311.829375) (xy 45.226243 -311.79825) (xy 45.268864 -311.773643)
			(xy 45.31488 -311.756191) (xy 45.363099 -311.746347) (xy 45.412274 -311.744366) (xy 45.461129 -311.750298)
			(xy 45.5084 -311.76399) (xy 45.552862 -311.785088) (xy 45.593365 -311.813044) (xy 45.628858 -311.847136)
			(xy 45.658423 -311.88648) (xy 45.681294 -311.930057) (xy 45.696878 -311.976738) (xy 45.704773 -312.025315)
			(xy 45.705268 -312.049922) (xy 46.994076 -312.049922) (xy 46.998036 -312.000868) (xy 47.009813 -311.953084)
			(xy 47.029104 -311.907808) (xy 47.055407 -311.866212) (xy 47.088042 -311.829375) (xy 47.126163 -311.79825)
			(xy 47.168784 -311.773643) (xy 47.2148 -311.756191) (xy 47.263019 -311.746347) (xy 47.312194 -311.744366)
			(xy 47.361049 -311.750298) (xy 47.40832 -311.76399) (xy 47.452782 -311.785088) (xy 47.493285 -311.813044)
			(xy 47.528778 -311.847136) (xy 47.558343 -311.88648) (xy 47.581214 -311.930057) (xy 47.596798 -311.976738)
			(xy 47.604693 -312.025315) (xy 47.605188 -312.049922) (xy 48.893996 -312.049922) (xy 48.897956 -312.000868)
			(xy 48.909733 -311.953084) (xy 48.929024 -311.907808) (xy 48.955327 -311.866212) (xy 48.987962 -311.829375)
			(xy 49.026083 -311.79825) (xy 49.068704 -311.773643) (xy 49.11472 -311.756191) (xy 49.162939 -311.746347)
			(xy 49.212114 -311.744366) (xy 49.260969 -311.750298) (xy 49.30824 -311.76399) (xy 49.352702 -311.785088)
			(xy 49.393205 -311.813044) (xy 49.428698 -311.847136) (xy 49.458263 -311.88648) (xy 49.481134 -311.930057)
			(xy 49.496718 -311.976738) (xy 49.504613 -312.025315) (xy 49.505108 -312.049922) (xy 50.79417 -312.049922)
			(xy 50.79813 -312.000868) (xy 50.809907 -311.953084) (xy 50.829198 -311.907808) (xy 50.855501 -311.866212)
			(xy 50.888136 -311.829375) (xy 50.926257 -311.79825) (xy 50.968878 -311.773643) (xy 51.014894 -311.756191)
			(xy 51.063113 -311.746347) (xy 51.112288 -311.744366) (xy 51.161143 -311.750298) (xy 51.208414 -311.76399)
			(xy 51.252876 -311.785088) (xy 51.293379 -311.813044) (xy 51.328872 -311.847136) (xy 51.358437 -311.88648)
			(xy 51.381308 -311.930057) (xy 51.396892 -311.976738) (xy 51.404787 -312.025315) (xy 51.405282 -312.049922)
			(xy 52.69409 -312.049922) (xy 52.69805 -312.000868) (xy 52.709827 -311.953084) (xy 52.729118 -311.907808)
			(xy 52.755421 -311.866212) (xy 52.788056 -311.829375) (xy 52.826177 -311.79825) (xy 52.868798 -311.773643)
			(xy 52.914814 -311.756191) (xy 52.963033 -311.746347) (xy 53.012208 -311.744366) (xy 53.061063 -311.750298)
			(xy 53.108334 -311.76399) (xy 53.152796 -311.785088) (xy 53.193299 -311.813044) (xy 53.228792 -311.847136)
			(xy 53.258357 -311.88648) (xy 53.281228 -311.930057) (xy 53.296812 -311.976738) (xy 53.304707 -312.025315)
			(xy 53.305202 -312.049922) (xy 54.59401 -312.049922) (xy 54.59797 -312.000868) (xy 54.609747 -311.953084)
			(xy 54.629038 -311.907808) (xy 54.655341 -311.866212) (xy 54.687976 -311.829375) (xy 54.726097 -311.79825)
			(xy 54.768718 -311.773643) (xy 54.814734 -311.756191) (xy 54.862953 -311.746347) (xy 54.912128 -311.744366)
			(xy 54.960983 -311.750298) (xy 55.008254 -311.76399) (xy 55.052716 -311.785088) (xy 55.093219 -311.813044)
			(xy 55.128712 -311.847136) (xy 55.158277 -311.88648) (xy 55.181148 -311.930057) (xy 55.196732 -311.976738)
			(xy 55.204627 -312.025315) (xy 55.205122 -312.049922) (xy 56.494184 -312.049922) (xy 56.498144 -312.000868)
			(xy 56.509921 -311.953084) (xy 56.529212 -311.907808) (xy 56.555515 -311.866212) (xy 56.58815 -311.829375)
			(xy 56.626271 -311.79825) (xy 56.668892 -311.773643) (xy 56.714908 -311.756191) (xy 56.763127 -311.746347)
			(xy 56.812302 -311.744366) (xy 56.861157 -311.750298) (xy 56.908428 -311.76399) (xy 56.95289 -311.785088)
			(xy 56.993393 -311.813044) (xy 57.028886 -311.847136) (xy 57.058451 -311.88648) (xy 57.081322 -311.930057)
			(xy 57.096906 -311.976738) (xy 57.104801 -312.025315) (xy 57.105296 -312.049922) (xy 58.394104 -312.049922)
			(xy 58.398064 -312.000868) (xy 58.409841 -311.953084) (xy 58.429132 -311.907808) (xy 58.455435 -311.866212)
			(xy 58.48807 -311.829375) (xy 58.526191 -311.79825) (xy 58.568812 -311.773643) (xy 58.614828 -311.756191)
			(xy 58.663047 -311.746347) (xy 58.712222 -311.744366) (xy 58.761077 -311.750298) (xy 58.808348 -311.76399)
			(xy 58.85281 -311.785088) (xy 58.893313 -311.813044) (xy 58.928806 -311.847136) (xy 58.958371 -311.88648)
			(xy 58.981242 -311.930057) (xy 58.996826 -311.976738) (xy 59.004721 -312.025315) (xy 59.005216 -312.049922)
			(xy 60.294024 -312.049922) (xy 60.297984 -312.000868) (xy 60.309761 -311.953084) (xy 60.329052 -311.907808)
			(xy 60.355355 -311.866212) (xy 60.38799 -311.829375) (xy 60.426111 -311.79825) (xy 60.468732 -311.773643)
			(xy 60.514748 -311.756191) (xy 60.562967 -311.746347) (xy 60.612142 -311.744366) (xy 60.660997 -311.750298)
			(xy 60.708268 -311.76399) (xy 60.75273 -311.785088) (xy 60.793233 -311.813044) (xy 60.828726 -311.847136)
			(xy 60.858291 -311.88648) (xy 60.881162 -311.930057) (xy 60.896746 -311.976738) (xy 60.904641 -312.025315)
			(xy 60.905136 -312.049922) (xy 62.193944 -312.049922) (xy 62.197904 -312.000868) (xy 62.209681 -311.953084)
			(xy 62.228972 -311.907808) (xy 62.255275 -311.866212) (xy 62.28791 -311.829375) (xy 62.326031 -311.79825)
			(xy 62.368652 -311.773643) (xy 62.414668 -311.756191) (xy 62.462887 -311.746347) (xy 62.512062 -311.744366)
			(xy 62.560917 -311.750298) (xy 62.608188 -311.76399) (xy 62.65265 -311.785088) (xy 62.693153 -311.813044)
			(xy 62.728646 -311.847136) (xy 62.758211 -311.88648) (xy 62.781082 -311.930057) (xy 62.796666 -311.976738)
			(xy 62.804561 -312.025315) (xy 62.805056 -312.049922) (xy 64.094118 -312.049922) (xy 64.098078 -312.000868)
			(xy 64.109855 -311.953084) (xy 64.129146 -311.907808) (xy 64.155449 -311.866212) (xy 64.188084 -311.829375)
			(xy 64.226205 -311.79825) (xy 64.268826 -311.773643) (xy 64.314842 -311.756191) (xy 64.363061 -311.746347)
			(xy 64.412236 -311.744366) (xy 64.461091 -311.750298) (xy 64.508362 -311.76399) (xy 64.552824 -311.785088)
			(xy 64.593327 -311.813044) (xy 64.62882 -311.847136) (xy 64.658385 -311.88648) (xy 64.681256 -311.930057)
			(xy 64.69684 -311.976738) (xy 64.704735 -312.025315) (xy 64.70523 -312.049922) (xy 65.994038 -312.049922)
			(xy 65.997998 -312.000868) (xy 66.009775 -311.953084) (xy 66.029066 -311.907808) (xy 66.055369 -311.866212)
			(xy 66.088004 -311.829375) (xy 66.126125 -311.79825) (xy 66.168746 -311.773643) (xy 66.214762 -311.756191)
			(xy 66.262981 -311.746347) (xy 66.312156 -311.744366) (xy 66.361011 -311.750298) (xy 66.408282 -311.76399)
			(xy 66.452744 -311.785088) (xy 66.493247 -311.813044) (xy 66.52874 -311.847136) (xy 66.558305 -311.88648)
			(xy 66.581176 -311.930057) (xy 66.59676 -311.976738) (xy 66.604655 -312.025315) (xy 66.60515 -312.049922)
			(xy 67.893958 -312.049922) (xy 67.897918 -312.000868) (xy 67.909695 -311.953084) (xy 67.928986 -311.907808)
			(xy 67.955289 -311.866212) (xy 67.987924 -311.829375) (xy 68.026045 -311.79825) (xy 68.068666 -311.773643)
			(xy 68.114682 -311.756191) (xy 68.162901 -311.746347) (xy 68.212076 -311.744366) (xy 68.260931 -311.750298)
			(xy 68.308202 -311.76399) (xy 68.352664 -311.785088) (xy 68.393167 -311.813044) (xy 68.42866 -311.847136)
			(xy 68.458225 -311.88648) (xy 68.481096 -311.930057) (xy 68.49668 -311.976738) (xy 68.504575 -312.025315)
			(xy 68.50507 -312.049922) (xy 69.794132 -312.049922) (xy 69.798092 -312.000868) (xy 69.809869 -311.953084)
			(xy 69.82916 -311.907808) (xy 69.855463 -311.866212) (xy 69.888098 -311.829375) (xy 69.926219 -311.79825)
			(xy 69.96884 -311.773643) (xy 70.014856 -311.756191) (xy 70.063075 -311.746347) (xy 70.11225 -311.744366)
			(xy 70.161105 -311.750298) (xy 70.208376 -311.76399) (xy 70.252838 -311.785088) (xy 70.293341 -311.813044)
			(xy 70.328834 -311.847136) (xy 70.358399 -311.88648) (xy 70.38127 -311.930057) (xy 70.396854 -311.976738)
			(xy 70.404749 -312.025315) (xy 70.405244 -312.049922) (xy 71.694052 -312.049922) (xy 71.698012 -312.000868)
			(xy 71.709789 -311.953084) (xy 71.72908 -311.907808) (xy 71.755383 -311.866212) (xy 71.788018 -311.829375)
			(xy 71.826139 -311.79825) (xy 71.86876 -311.773643) (xy 71.914776 -311.756191) (xy 71.962995 -311.746347)
			(xy 72.01217 -311.744366) (xy 72.061025 -311.750298) (xy 72.108296 -311.76399) (xy 72.152758 -311.785088)
			(xy 72.193261 -311.813044) (xy 72.228754 -311.847136) (xy 72.258319 -311.88648) (xy 72.28119 -311.930057)
			(xy 72.296774 -311.976738) (xy 72.304669 -312.025315) (xy 72.305164 -312.049922) (xy 73.593972 -312.049922)
			(xy 73.597932 -312.000868) (xy 73.609709 -311.953084) (xy 73.629 -311.907808) (xy 73.655303 -311.866212)
			(xy 73.687938 -311.829375) (xy 73.726059 -311.79825) (xy 73.76868 -311.773643) (xy 73.814696 -311.756191)
			(xy 73.862915 -311.746347) (xy 73.91209 -311.744366) (xy 73.960945 -311.750298) (xy 74.008216 -311.76399)
			(xy 74.052678 -311.785088) (xy 74.093181 -311.813044) (xy 74.128674 -311.847136) (xy 74.158239 -311.88648)
			(xy 74.18111 -311.930057) (xy 74.196694 -311.976738) (xy 74.204589 -312.025315) (xy 74.205084 -312.049922)
			(xy 75.494146 -312.049922) (xy 75.498106 -312.000868) (xy 75.509883 -311.953084) (xy 75.529174 -311.907808)
			(xy 75.555477 -311.866212) (xy 75.588112 -311.829375) (xy 75.626233 -311.79825) (xy 75.668854 -311.773643)
			(xy 75.71487 -311.756191) (xy 75.763089 -311.746347) (xy 75.812264 -311.744366) (xy 75.861119 -311.750298)
			(xy 75.90839 -311.76399) (xy 75.952852 -311.785088) (xy 75.993355 -311.813044) (xy 76.028848 -311.847136)
			(xy 76.058413 -311.88648) (xy 76.081284 -311.930057) (xy 76.096868 -311.976738) (xy 76.104763 -312.025315)
			(xy 76.105258 -312.049922) (xy 77.394066 -312.049922) (xy 77.398026 -312.000868) (xy 77.409803 -311.953084)
			(xy 77.429094 -311.907808) (xy 77.455397 -311.866212) (xy 77.488032 -311.829375) (xy 77.526153 -311.79825)
			(xy 77.568774 -311.773643) (xy 77.61479 -311.756191) (xy 77.663009 -311.746347) (xy 77.712184 -311.744366)
			(xy 77.761039 -311.750298) (xy 77.80831 -311.76399) (xy 77.852772 -311.785088) (xy 77.893275 -311.813044)
			(xy 77.928768 -311.847136) (xy 77.958333 -311.88648) (xy 77.981204 -311.930057) (xy 77.996788 -311.976738)
			(xy 78.004683 -312.025315) (xy 78.005178 -312.049922) (xy 79.293986 -312.049922) (xy 79.297946 -312.000868)
			(xy 79.309723 -311.953084) (xy 79.329014 -311.907808) (xy 79.355317 -311.866212) (xy 79.387952 -311.829375)
			(xy 79.426073 -311.79825) (xy 79.468694 -311.773643) (xy 79.51471 -311.756191) (xy 79.562929 -311.746347)
			(xy 79.612104 -311.744366) (xy 79.660959 -311.750298) (xy 79.70823 -311.76399) (xy 79.752692 -311.785088)
			(xy 79.793195 -311.813044) (xy 79.828688 -311.847136) (xy 79.858253 -311.88648) (xy 79.881124 -311.930057)
			(xy 79.896708 -311.976738) (xy 79.904603 -312.025315) (xy 79.905098 -312.049922) (xy 81.19416 -312.049922)
			(xy 81.19812 -312.000868) (xy 81.209897 -311.953084) (xy 81.229188 -311.907808) (xy 81.255491 -311.866212)
			(xy 81.288126 -311.829375) (xy 81.326247 -311.79825) (xy 81.368868 -311.773643) (xy 81.414884 -311.756191)
			(xy 81.463103 -311.746347) (xy 81.512278 -311.744366) (xy 81.561133 -311.750298) (xy 81.608404 -311.76399)
			(xy 81.652866 -311.785088) (xy 81.693369 -311.813044) (xy 81.728862 -311.847136) (xy 81.758427 -311.88648)
			(xy 81.781298 -311.930057) (xy 81.796882 -311.976738) (xy 81.804777 -312.025315) (xy 81.805272 -312.049922)
			(xy 82.14412 -312.049922) (xy 82.14808 -312.000868) (xy 82.159857 -311.953084) (xy 82.179148 -311.907808)
			(xy 82.205451 -311.866212) (xy 82.238086 -311.829375) (xy 82.276207 -311.79825) (xy 82.318828 -311.773643)
			(xy 82.364844 -311.756191) (xy 82.413063 -311.746347) (xy 82.462238 -311.744366) (xy 82.511093 -311.750298)
			(xy 82.558364 -311.76399) (xy 82.602826 -311.785088) (xy 82.643329 -311.813044) (xy 82.678822 -311.847136)
			(xy 82.708387 -311.88648) (xy 82.731258 -311.930057) (xy 82.746842 -311.976738) (xy 82.754737 -312.025315)
			(xy 82.755232 -312.049922) (xy 152.644106 -312.049922) (xy 152.648066 -312.000868) (xy 152.659843 -311.953084)
			(xy 152.679134 -311.907808) (xy 152.705437 -311.866212) (xy 152.738072 -311.829375) (xy 152.776193 -311.79825)
			(xy 152.818814 -311.773643) (xy 152.86483 -311.756191) (xy 152.913049 -311.746347) (xy 152.962224 -311.744366)
			(xy 153.011079 -311.750298) (xy 153.05835 -311.76399) (xy 153.102812 -311.785088) (xy 153.143315 -311.813044)
			(xy 153.178808 -311.847136) (xy 153.208373 -311.88648) (xy 153.231244 -311.930057) (xy 153.246828 -311.976738)
			(xy 153.254723 -312.025315) (xy 153.255218 -312.049922) (xy 153.594066 -312.049922) (xy 153.598026 -312.000868)
			(xy 153.609803 -311.953084) (xy 153.629094 -311.907808) (xy 153.655397 -311.866212) (xy 153.688032 -311.829375)
			(xy 153.726153 -311.79825) (xy 153.768774 -311.773643) (xy 153.81479 -311.756191) (xy 153.863009 -311.746347)
			(xy 153.912184 -311.744366) (xy 153.961039 -311.750298) (xy 154.00831 -311.76399) (xy 154.052772 -311.785088)
			(xy 154.093275 -311.813044) (xy 154.128768 -311.847136) (xy 154.158333 -311.88648) (xy 154.181204 -311.930057)
			(xy 154.196788 -311.976738) (xy 154.204683 -312.025315) (xy 154.205178 -312.049922) (xy 155.49424 -312.049922)
			(xy 155.4982 -312.000868) (xy 155.509977 -311.953084) (xy 155.529268 -311.907808) (xy 155.555571 -311.866212)
			(xy 155.588206 -311.829375) (xy 155.626327 -311.79825) (xy 155.668948 -311.773643) (xy 155.714964 -311.756191)
			(xy 155.763183 -311.746347) (xy 155.812358 -311.744366) (xy 155.861213 -311.750298) (xy 155.908484 -311.76399)
			(xy 155.952946 -311.785088) (xy 155.993449 -311.813044) (xy 156.028942 -311.847136) (xy 156.058507 -311.88648)
			(xy 156.081378 -311.930057) (xy 156.096962 -311.976738) (xy 156.104857 -312.025315) (xy 156.105352 -312.049922)
			(xy 157.39416 -312.049922) (xy 157.39812 -312.000868) (xy 157.409897 -311.953084) (xy 157.429188 -311.907808)
			(xy 157.455491 -311.866212) (xy 157.488126 -311.829375) (xy 157.526247 -311.79825) (xy 157.568868 -311.773643)
			(xy 157.614884 -311.756191) (xy 157.663103 -311.746347) (xy 157.712278 -311.744366) (xy 157.761133 -311.750298)
			(xy 157.808404 -311.76399) (xy 157.852866 -311.785088) (xy 157.893369 -311.813044) (xy 157.928862 -311.847136)
			(xy 157.958427 -311.88648) (xy 157.981298 -311.930057) (xy 157.996882 -311.976738) (xy 158.004777 -312.025315)
			(xy 158.005272 -312.049922) (xy 159.29408 -312.049922) (xy 159.29804 -312.000868) (xy 159.309817 -311.953084)
			(xy 159.329108 -311.907808) (xy 159.355411 -311.866212) (xy 159.388046 -311.829375) (xy 159.426167 -311.79825)
			(xy 159.468788 -311.773643) (xy 159.514804 -311.756191) (xy 159.563023 -311.746347) (xy 159.612198 -311.744366)
			(xy 159.661053 -311.750298) (xy 159.708324 -311.76399) (xy 159.752786 -311.785088) (xy 159.793289 -311.813044)
			(xy 159.828782 -311.847136) (xy 159.858347 -311.88648) (xy 159.881218 -311.930057) (xy 159.896802 -311.976738)
			(xy 159.904697 -312.025315) (xy 159.905192 -312.049922) (xy 161.194254 -312.049922) (xy 161.198214 -312.000868)
			(xy 161.209991 -311.953084) (xy 161.229282 -311.907808) (xy 161.255585 -311.866212) (xy 161.28822 -311.829375)
			(xy 161.326341 -311.79825) (xy 161.368962 -311.773643) (xy 161.414978 -311.756191) (xy 161.463197 -311.746347)
			(xy 161.512372 -311.744366) (xy 161.561227 -311.750298) (xy 161.608498 -311.76399) (xy 161.65296 -311.785088)
			(xy 161.693463 -311.813044) (xy 161.728956 -311.847136) (xy 161.758521 -311.88648) (xy 161.781392 -311.930057)
			(xy 161.796976 -311.976738) (xy 161.804871 -312.025315) (xy 161.805366 -312.049922) (xy 163.094174 -312.049922)
			(xy 163.098134 -312.000868) (xy 163.109911 -311.953084) (xy 163.129202 -311.907808) (xy 163.155505 -311.866212)
			(xy 163.18814 -311.829375) (xy 163.226261 -311.79825) (xy 163.268882 -311.773643) (xy 163.314898 -311.756191)
			(xy 163.363117 -311.746347) (xy 163.412292 -311.744366) (xy 163.461147 -311.750298) (xy 163.508418 -311.76399)
			(xy 163.55288 -311.785088) (xy 163.593383 -311.813044) (xy 163.628876 -311.847136) (xy 163.658441 -311.88648)
			(xy 163.681312 -311.930057) (xy 163.696896 -311.976738) (xy 163.704791 -312.025315) (xy 163.705286 -312.049922)
			(xy 164.994094 -312.049922) (xy 164.998054 -312.000868) (xy 165.009831 -311.953084) (xy 165.029122 -311.907808)
			(xy 165.055425 -311.866212) (xy 165.08806 -311.829375) (xy 165.126181 -311.79825) (xy 165.168802 -311.773643)
			(xy 165.214818 -311.756191) (xy 165.263037 -311.746347) (xy 165.312212 -311.744366) (xy 165.361067 -311.750298)
			(xy 165.408338 -311.76399) (xy 165.4528 -311.785088) (xy 165.493303 -311.813044) (xy 165.528796 -311.847136)
			(xy 165.558361 -311.88648) (xy 165.581232 -311.930057) (xy 165.596816 -311.976738) (xy 165.604711 -312.025315)
			(xy 165.605206 -312.049922) (xy 166.894268 -312.049922) (xy 166.898228 -312.000868) (xy 166.910005 -311.953084)
			(xy 166.929296 -311.907808) (xy 166.955599 -311.866212) (xy 166.988234 -311.829375) (xy 167.026355 -311.79825)
			(xy 167.068976 -311.773643) (xy 167.114992 -311.756191) (xy 167.163211 -311.746347) (xy 167.212386 -311.744366)
			(xy 167.261241 -311.750298) (xy 167.308512 -311.76399) (xy 167.352974 -311.785088) (xy 167.393477 -311.813044)
			(xy 167.42897 -311.847136) (xy 167.458535 -311.88648) (xy 167.481406 -311.930057) (xy 167.49699 -311.976738)
			(xy 167.504885 -312.025315) (xy 167.50538 -312.049922) (xy 168.794188 -312.049922) (xy 168.798148 -312.000868)
			(xy 168.809925 -311.953084) (xy 168.829216 -311.907808) (xy 168.855519 -311.866212) (xy 168.888154 -311.829375)
			(xy 168.926275 -311.79825) (xy 168.968896 -311.773643) (xy 169.014912 -311.756191) (xy 169.063131 -311.746347)
			(xy 169.112306 -311.744366) (xy 169.161161 -311.750298) (xy 169.208432 -311.76399) (xy 169.252894 -311.785088)
			(xy 169.293397 -311.813044) (xy 169.32889 -311.847136) (xy 169.358455 -311.88648) (xy 169.381326 -311.930057)
			(xy 169.39691 -311.976738) (xy 169.404805 -312.025315) (xy 169.4053 -312.049922) (xy 170.694108 -312.049922)
			(xy 170.698068 -312.000868) (xy 170.709845 -311.953084) (xy 170.729136 -311.907808) (xy 170.755439 -311.866212)
			(xy 170.788074 -311.829375) (xy 170.826195 -311.79825) (xy 170.868816 -311.773643) (xy 170.914832 -311.756191)
			(xy 170.963051 -311.746347) (xy 171.012226 -311.744366) (xy 171.061081 -311.750298) (xy 171.108352 -311.76399)
			(xy 171.152814 -311.785088) (xy 171.193317 -311.813044) (xy 171.22881 -311.847136) (xy 171.258375 -311.88648)
			(xy 171.281246 -311.930057) (xy 171.29683 -311.976738) (xy 171.304725 -312.025315) (xy 171.30522 -312.049922)
			(xy 172.594282 -312.049922) (xy 172.598242 -312.000868) (xy 172.610019 -311.953084) (xy 172.62931 -311.907808)
			(xy 172.655613 -311.866212) (xy 172.688248 -311.829375) (xy 172.726369 -311.79825) (xy 172.76899 -311.773643)
			(xy 172.815006 -311.756191) (xy 172.863225 -311.746347) (xy 172.9124 -311.744366) (xy 172.961255 -311.750298)
			(xy 173.008526 -311.76399) (xy 173.052988 -311.785088) (xy 173.093491 -311.813044) (xy 173.128984 -311.847136)
			(xy 173.158549 -311.88648) (xy 173.18142 -311.930057) (xy 173.197004 -311.976738) (xy 173.204899 -312.025315)
			(xy 173.205394 -312.049922) (xy 174.494202 -312.049922) (xy 174.498162 -312.000868) (xy 174.509939 -311.953084)
			(xy 174.52923 -311.907808) (xy 174.555533 -311.866212) (xy 174.588168 -311.829375) (xy 174.626289 -311.79825)
			(xy 174.66891 -311.773643) (xy 174.714926 -311.756191) (xy 174.763145 -311.746347) (xy 174.81232 -311.744366)
			(xy 174.861175 -311.750298) (xy 174.908446 -311.76399) (xy 174.952908 -311.785088) (xy 174.993411 -311.813044)
			(xy 175.028904 -311.847136) (xy 175.058469 -311.88648) (xy 175.08134 -311.930057) (xy 175.096924 -311.976738)
			(xy 175.104819 -312.025315) (xy 175.105314 -312.049922) (xy 176.394122 -312.049922) (xy 176.398082 -312.000868)
			(xy 176.409859 -311.953084) (xy 176.42915 -311.907808) (xy 176.455453 -311.866212) (xy 176.488088 -311.829375)
			(xy 176.526209 -311.79825) (xy 176.56883 -311.773643) (xy 176.614846 -311.756191) (xy 176.663065 -311.746347)
			(xy 176.71224 -311.744366) (xy 176.761095 -311.750298) (xy 176.808366 -311.76399) (xy 176.852828 -311.785088)
			(xy 176.893331 -311.813044) (xy 176.928824 -311.847136) (xy 176.958389 -311.88648) (xy 176.98126 -311.930057)
			(xy 176.996844 -311.976738) (xy 177.004739 -312.025315) (xy 177.005234 -312.049922) (xy 178.294042 -312.049922)
			(xy 178.298002 -312.000868) (xy 178.309779 -311.953084) (xy 178.32907 -311.907808) (xy 178.355373 -311.866212)
			(xy 178.388008 -311.829375) (xy 178.426129 -311.79825) (xy 178.46875 -311.773643) (xy 178.514766 -311.756191)
			(xy 178.562985 -311.746347) (xy 178.61216 -311.744366) (xy 178.661015 -311.750298) (xy 178.708286 -311.76399)
			(xy 178.752748 -311.785088) (xy 178.793251 -311.813044) (xy 178.828744 -311.847136) (xy 178.858309 -311.88648)
			(xy 178.88118 -311.930057) (xy 178.896764 -311.976738) (xy 178.904659 -312.025315) (xy 178.905154 -312.049922)
			(xy 180.194216 -312.049922) (xy 180.198176 -312.000868) (xy 180.209953 -311.953084) (xy 180.229244 -311.907808)
			(xy 180.255547 -311.866212) (xy 180.288182 -311.829375) (xy 180.326303 -311.79825) (xy 180.368924 -311.773643)
			(xy 180.41494 -311.756191) (xy 180.463159 -311.746347) (xy 180.512334 -311.744366) (xy 180.561189 -311.750298)
			(xy 180.60846 -311.76399) (xy 180.652922 -311.785088) (xy 180.693425 -311.813044) (xy 180.728918 -311.847136)
			(xy 180.758483 -311.88648) (xy 180.781354 -311.930057) (xy 180.796938 -311.976738) (xy 180.804833 -312.025315)
			(xy 180.805328 -312.049922) (xy 182.094136 -312.049922) (xy 182.098096 -312.000868) (xy 182.109873 -311.953084)
			(xy 182.129164 -311.907808) (xy 182.155467 -311.866212) (xy 182.188102 -311.829375) (xy 182.226223 -311.79825)
			(xy 182.268844 -311.773643) (xy 182.31486 -311.756191) (xy 182.363079 -311.746347) (xy 182.412254 -311.744366)
			(xy 182.461109 -311.750298) (xy 182.50838 -311.76399) (xy 182.552842 -311.785088) (xy 182.593345 -311.813044)
			(xy 182.628838 -311.847136) (xy 182.658403 -311.88648) (xy 182.681274 -311.930057) (xy 182.696858 -311.976738)
			(xy 182.704753 -312.025315) (xy 182.705248 -312.049922) (xy 183.994056 -312.049922) (xy 183.998016 -312.000868)
			(xy 184.009793 -311.953084) (xy 184.029084 -311.907808) (xy 184.055387 -311.866212) (xy 184.088022 -311.829375)
			(xy 184.126143 -311.79825) (xy 184.168764 -311.773643) (xy 184.21478 -311.756191) (xy 184.262999 -311.746347)
			(xy 184.312174 -311.744366) (xy 184.361029 -311.750298) (xy 184.4083 -311.76399) (xy 184.452762 -311.785088)
			(xy 184.493265 -311.813044) (xy 184.528758 -311.847136) (xy 184.558323 -311.88648) (xy 184.581194 -311.930057)
			(xy 184.596778 -311.976738) (xy 184.604673 -312.025315) (xy 184.605168 -312.049922) (xy 185.89423 -312.049922)
			(xy 185.89819 -312.000868) (xy 185.909967 -311.953084) (xy 185.929258 -311.907808) (xy 185.955561 -311.866212)
			(xy 185.988196 -311.829375) (xy 186.026317 -311.79825) (xy 186.068938 -311.773643) (xy 186.114954 -311.756191)
			(xy 186.163173 -311.746347) (xy 186.212348 -311.744366) (xy 186.261203 -311.750298) (xy 186.308474 -311.76399)
			(xy 186.352936 -311.785088) (xy 186.393439 -311.813044) (xy 186.428932 -311.847136) (xy 186.458497 -311.88648)
			(xy 186.481368 -311.930057) (xy 186.496952 -311.976738) (xy 186.504847 -312.025315) (xy 186.505342 -312.049922)
			(xy 187.79415 -312.049922) (xy 187.79811 -312.000868) (xy 187.809887 -311.953084) (xy 187.829178 -311.907808)
			(xy 187.855481 -311.866212) (xy 187.888116 -311.829375) (xy 187.926237 -311.79825) (xy 187.968858 -311.773643)
			(xy 188.014874 -311.756191) (xy 188.063093 -311.746347) (xy 188.112268 -311.744366) (xy 188.161123 -311.750298)
			(xy 188.208394 -311.76399) (xy 188.252856 -311.785088) (xy 188.293359 -311.813044) (xy 188.328852 -311.847136)
			(xy 188.358417 -311.88648) (xy 188.381288 -311.930057) (xy 188.396872 -311.976738) (xy 188.404767 -312.025315)
			(xy 188.405262 -312.049922) (xy 189.69407 -312.049922) (xy 189.69803 -312.000868) (xy 189.709807 -311.953084)
			(xy 189.729098 -311.907808) (xy 189.755401 -311.866212) (xy 189.788036 -311.829375) (xy 189.826157 -311.79825)
			(xy 189.868778 -311.773643) (xy 189.914794 -311.756191) (xy 189.963013 -311.746347) (xy 190.012188 -311.744366)
			(xy 190.061043 -311.750298) (xy 190.108314 -311.76399) (xy 190.152776 -311.785088) (xy 190.193279 -311.813044)
			(xy 190.228772 -311.847136) (xy 190.258337 -311.88648) (xy 190.281208 -311.930057) (xy 190.296792 -311.976738)
			(xy 190.304687 -312.025315) (xy 190.305182 -312.049922) (xy 191.594244 -312.049922) (xy 191.598204 -312.000868)
			(xy 191.609981 -311.953084) (xy 191.629272 -311.907808) (xy 191.655575 -311.866212) (xy 191.68821 -311.829375)
			(xy 191.726331 -311.79825) (xy 191.768952 -311.773643) (xy 191.814968 -311.756191) (xy 191.863187 -311.746347)
			(xy 191.912362 -311.744366) (xy 191.961217 -311.750298) (xy 192.008488 -311.76399) (xy 192.05295 -311.785088)
			(xy 192.093453 -311.813044) (xy 192.128946 -311.847136) (xy 192.158511 -311.88648) (xy 192.181382 -311.930057)
			(xy 192.196966 -311.976738) (xy 192.204861 -312.025315) (xy 192.205356 -312.049922) (xy 193.494164 -312.049922)
			(xy 193.498124 -312.000868) (xy 193.509901 -311.953084) (xy 193.529192 -311.907808) (xy 193.555495 -311.866212)
			(xy 193.58813 -311.829375) (xy 193.626251 -311.79825) (xy 193.668872 -311.773643) (xy 193.714888 -311.756191)
			(xy 193.763107 -311.746347) (xy 193.812282 -311.744366) (xy 193.861137 -311.750298) (xy 193.908408 -311.76399)
			(xy 193.95287 -311.785088) (xy 193.993373 -311.813044) (xy 194.028866 -311.847136) (xy 194.058431 -311.88648)
			(xy 194.081302 -311.930057) (xy 194.096886 -311.976738) (xy 194.104781 -312.025315) (xy 194.105276 -312.049922)
			(xy 195.394084 -312.049922) (xy 195.398044 -312.000868) (xy 195.409821 -311.953084) (xy 195.429112 -311.907808)
			(xy 195.455415 -311.866212) (xy 195.48805 -311.829375) (xy 195.526171 -311.79825) (xy 195.568792 -311.773643)
			(xy 195.614808 -311.756191) (xy 195.663027 -311.746347) (xy 195.712202 -311.744366) (xy 195.761057 -311.750298)
			(xy 195.808328 -311.76399) (xy 195.85279 -311.785088) (xy 195.893293 -311.813044) (xy 195.928786 -311.847136)
			(xy 195.958351 -311.88648) (xy 195.981222 -311.930057) (xy 195.996806 -311.976738) (xy 196.004701 -312.025315)
			(xy 196.005196 -312.049922) (xy 197.294258 -312.049922) (xy 197.298218 -312.000868) (xy 197.309995 -311.953084)
			(xy 197.329286 -311.907808) (xy 197.355589 -311.866212) (xy 197.388224 -311.829375) (xy 197.426345 -311.79825)
			(xy 197.468966 -311.773643) (xy 197.514982 -311.756191) (xy 197.563201 -311.746347) (xy 197.612376 -311.744366)
			(xy 197.661231 -311.750298) (xy 197.708502 -311.76399) (xy 197.752964 -311.785088) (xy 197.793467 -311.813044)
			(xy 197.82896 -311.847136) (xy 197.858525 -311.88648) (xy 197.881396 -311.930057) (xy 197.89698 -311.976738)
			(xy 197.904875 -312.025315) (xy 197.90537 -312.049922) (xy 198.244218 -312.049922) (xy 198.248178 -312.000868)
			(xy 198.259955 -311.953084) (xy 198.279246 -311.907808) (xy 198.305549 -311.866212) (xy 198.338184 -311.829375)
			(xy 198.376305 -311.79825) (xy 198.418926 -311.773643) (xy 198.464942 -311.756191) (xy 198.513161 -311.746347)
			(xy 198.562336 -311.744366) (xy 198.611191 -311.750298) (xy 198.658462 -311.76399) (xy 198.702924 -311.785088)
			(xy 198.743427 -311.813044) (xy 198.77892 -311.847136) (xy 198.808485 -311.88648) (xy 198.831356 -311.930057)
			(xy 198.84694 -311.976738) (xy 198.854835 -312.025315) (xy 198.85533 -312.049922) (xy 268.74395 -312.049922)
			(xy 268.74791 -312.000868) (xy 268.759687 -311.953084) (xy 268.778978 -311.907808) (xy 268.805281 -311.866212)
			(xy 268.837916 -311.829375) (xy 268.876037 -311.79825) (xy 268.918658 -311.773643) (xy 268.964674 -311.756191)
			(xy 269.012893 -311.746347) (xy 269.062068 -311.744366) (xy 269.110923 -311.750298) (xy 269.158194 -311.76399)
			(xy 269.202656 -311.785088) (xy 269.243159 -311.813044) (xy 269.278652 -311.847136) (xy 269.308217 -311.88648)
			(xy 269.331088 -311.930057) (xy 269.346672 -311.976738) (xy 269.354567 -312.025315) (xy 269.355062 -312.049922)
			(xy 269.69391 -312.049922) (xy 269.69787 -312.000868) (xy 269.709647 -311.953084) (xy 269.728938 -311.907808)
			(xy 269.755241 -311.866212) (xy 269.787876 -311.829375) (xy 269.825997 -311.79825) (xy 269.868618 -311.773643)
			(xy 269.914634 -311.756191) (xy 269.962853 -311.746347) (xy 270.012028 -311.744366) (xy 270.060883 -311.750298)
			(xy 270.108154 -311.76399) (xy 270.152616 -311.785088) (xy 270.193119 -311.813044) (xy 270.228612 -311.847136)
			(xy 270.258177 -311.88648) (xy 270.281048 -311.930057) (xy 270.296632 -311.976738) (xy 270.304527 -312.025315)
			(xy 270.305022 -312.049922) (xy 271.594084 -312.049922) (xy 271.598044 -312.000868) (xy 271.609821 -311.953084)
			(xy 271.629112 -311.907808) (xy 271.655415 -311.866212) (xy 271.68805 -311.829375) (xy 271.726171 -311.79825)
			(xy 271.768792 -311.773643) (xy 271.814808 -311.756191) (xy 271.863027 -311.746347) (xy 271.912202 -311.744366)
			(xy 271.961057 -311.750298) (xy 272.008328 -311.76399) (xy 272.05279 -311.785088) (xy 272.093293 -311.813044)
			(xy 272.128786 -311.847136) (xy 272.158351 -311.88648) (xy 272.181222 -311.930057) (xy 272.196806 -311.976738)
			(xy 272.204701 -312.025315) (xy 272.205196 -312.049922) (xy 273.494004 -312.049922) (xy 273.497964 -312.000868)
			(xy 273.509741 -311.953084) (xy 273.529032 -311.907808) (xy 273.555335 -311.866212) (xy 273.58797 -311.829375)
			(xy 273.626091 -311.79825) (xy 273.668712 -311.773643) (xy 273.714728 -311.756191) (xy 273.762947 -311.746347)
			(xy 273.812122 -311.744366) (xy 273.860977 -311.750298) (xy 273.908248 -311.76399) (xy 273.95271 -311.785088)
			(xy 273.993213 -311.813044) (xy 274.028706 -311.847136) (xy 274.058271 -311.88648) (xy 274.081142 -311.930057)
			(xy 274.096726 -311.976738) (xy 274.104621 -312.025315) (xy 274.105116 -312.049922) (xy 275.393924 -312.049922)
			(xy 275.397884 -312.000868) (xy 275.409661 -311.953084) (xy 275.428952 -311.907808) (xy 275.455255 -311.866212)
			(xy 275.48789 -311.829375) (xy 275.526011 -311.79825) (xy 275.568632 -311.773643) (xy 275.614648 -311.756191)
			(xy 275.662867 -311.746347) (xy 275.712042 -311.744366) (xy 275.760897 -311.750298) (xy 275.808168 -311.76399)
			(xy 275.85263 -311.785088) (xy 275.893133 -311.813044) (xy 275.928626 -311.847136) (xy 275.958191 -311.88648)
			(xy 275.981062 -311.930057) (xy 275.996646 -311.976738) (xy 276.004541 -312.025315) (xy 276.005036 -312.049922)
			(xy 277.294098 -312.049922) (xy 277.298058 -312.000868) (xy 277.309835 -311.953084) (xy 277.329126 -311.907808)
			(xy 277.355429 -311.866212) (xy 277.388064 -311.829375) (xy 277.426185 -311.79825) (xy 277.468806 -311.773643)
			(xy 277.514822 -311.756191) (xy 277.563041 -311.746347) (xy 277.612216 -311.744366) (xy 277.661071 -311.750298)
			(xy 277.708342 -311.76399) (xy 277.752804 -311.785088) (xy 277.793307 -311.813044) (xy 277.8288 -311.847136)
			(xy 277.858365 -311.88648) (xy 277.881236 -311.930057) (xy 277.89682 -311.976738) (xy 277.904715 -312.025315)
			(xy 277.90521 -312.049922) (xy 279.194018 -312.049922) (xy 279.197978 -312.000868) (xy 279.209755 -311.953084)
			(xy 279.229046 -311.907808) (xy 279.255349 -311.866212) (xy 279.287984 -311.829375) (xy 279.326105 -311.79825)
			(xy 279.368726 -311.773643) (xy 279.414742 -311.756191) (xy 279.462961 -311.746347) (xy 279.512136 -311.744366)
			(xy 279.560991 -311.750298) (xy 279.608262 -311.76399) (xy 279.652724 -311.785088) (xy 279.693227 -311.813044)
			(xy 279.72872 -311.847136) (xy 279.758285 -311.88648) (xy 279.781156 -311.930057) (xy 279.79674 -311.976738)
			(xy 279.804635 -312.025315) (xy 279.80513 -312.049922) (xy 281.093938 -312.049922) (xy 281.097898 -312.000868)
			(xy 281.109675 -311.953084) (xy 281.128966 -311.907808) (xy 281.155269 -311.866212) (xy 281.187904 -311.829375)
			(xy 281.226025 -311.79825) (xy 281.268646 -311.773643) (xy 281.314662 -311.756191) (xy 281.362881 -311.746347)
			(xy 281.412056 -311.744366) (xy 281.460911 -311.750298) (xy 281.508182 -311.76399) (xy 281.552644 -311.785088)
			(xy 281.593147 -311.813044) (xy 281.62864 -311.847136) (xy 281.658205 -311.88648) (xy 281.681076 -311.930057)
			(xy 281.69666 -311.976738) (xy 281.704555 -312.025315) (xy 281.70505 -312.049922) (xy 282.994112 -312.049922)
			(xy 282.998072 -312.000868) (xy 283.009849 -311.953084) (xy 283.02914 -311.907808) (xy 283.055443 -311.866212)
			(xy 283.088078 -311.829375) (xy 283.126199 -311.79825) (xy 283.16882 -311.773643) (xy 283.214836 -311.756191)
			(xy 283.263055 -311.746347) (xy 283.31223 -311.744366) (xy 283.361085 -311.750298) (xy 283.408356 -311.76399)
			(xy 283.452818 -311.785088) (xy 283.493321 -311.813044) (xy 283.528814 -311.847136) (xy 283.558379 -311.88648)
			(xy 283.58125 -311.930057) (xy 283.596834 -311.976738) (xy 283.604729 -312.025315) (xy 283.605224 -312.049922)
			(xy 284.894032 -312.049922) (xy 284.897992 -312.000868) (xy 284.909769 -311.953084) (xy 284.92906 -311.907808)
			(xy 284.955363 -311.866212) (xy 284.987998 -311.829375) (xy 285.026119 -311.79825) (xy 285.06874 -311.773643)
			(xy 285.114756 -311.756191) (xy 285.162975 -311.746347) (xy 285.21215 -311.744366) (xy 285.261005 -311.750298)
			(xy 285.308276 -311.76399) (xy 285.352738 -311.785088) (xy 285.393241 -311.813044) (xy 285.428734 -311.847136)
			(xy 285.458299 -311.88648) (xy 285.48117 -311.930057) (xy 285.496754 -311.976738) (xy 285.504649 -312.025315)
			(xy 285.505144 -312.049922) (xy 286.793952 -312.049922) (xy 286.797912 -312.000868) (xy 286.809689 -311.953084)
			(xy 286.82898 -311.907808) (xy 286.855283 -311.866212) (xy 286.887918 -311.829375) (xy 286.926039 -311.79825)
			(xy 286.96866 -311.773643) (xy 287.014676 -311.756191) (xy 287.062895 -311.746347) (xy 287.11207 -311.744366)
			(xy 287.160925 -311.750298) (xy 287.208196 -311.76399) (xy 287.252658 -311.785088) (xy 287.293161 -311.813044)
			(xy 287.328654 -311.847136) (xy 287.358219 -311.88648) (xy 287.38109 -311.930057) (xy 287.396674 -311.976738)
			(xy 287.404569 -312.025315) (xy 287.405064 -312.049922) (xy 288.694126 -312.049922) (xy 288.698086 -312.000868)
			(xy 288.709863 -311.953084) (xy 288.729154 -311.907808) (xy 288.755457 -311.866212) (xy 288.788092 -311.829375)
			(xy 288.826213 -311.79825) (xy 288.868834 -311.773643) (xy 288.91485 -311.756191) (xy 288.963069 -311.746347)
			(xy 289.012244 -311.744366) (xy 289.061099 -311.750298) (xy 289.10837 -311.76399) (xy 289.152832 -311.785088)
			(xy 289.193335 -311.813044) (xy 289.228828 -311.847136) (xy 289.258393 -311.88648) (xy 289.281264 -311.930057)
			(xy 289.296848 -311.976738) (xy 289.304743 -312.025315) (xy 289.305238 -312.049922) (xy 290.594046 -312.049922)
			(xy 290.598006 -312.000868) (xy 290.609783 -311.953084) (xy 290.629074 -311.907808) (xy 290.655377 -311.866212)
			(xy 290.688012 -311.829375) (xy 290.726133 -311.79825) (xy 290.768754 -311.773643) (xy 290.81477 -311.756191)
			(xy 290.862989 -311.746347) (xy 290.912164 -311.744366) (xy 290.961019 -311.750298) (xy 291.00829 -311.76399)
			(xy 291.052752 -311.785088) (xy 291.093255 -311.813044) (xy 291.128748 -311.847136) (xy 291.158313 -311.88648)
			(xy 291.181184 -311.930057) (xy 291.196768 -311.976738) (xy 291.204663 -312.025315) (xy 291.205158 -312.049922)
			(xy 292.493966 -312.049922) (xy 292.497926 -312.000868) (xy 292.509703 -311.953084) (xy 292.528994 -311.907808)
			(xy 292.555297 -311.866212) (xy 292.587932 -311.829375) (xy 292.626053 -311.79825) (xy 292.668674 -311.773643)
			(xy 292.71469 -311.756191) (xy 292.762909 -311.746347) (xy 292.812084 -311.744366) (xy 292.860939 -311.750298)
			(xy 292.90821 -311.76399) (xy 292.952672 -311.785088) (xy 292.993175 -311.813044) (xy 293.028668 -311.847136)
			(xy 293.058233 -311.88648) (xy 293.081104 -311.930057) (xy 293.096688 -311.976738) (xy 293.104583 -312.025315)
			(xy 293.105078 -312.049922) (xy 294.393886 -312.049922) (xy 294.397846 -312.000868) (xy 294.409623 -311.953084)
			(xy 294.428914 -311.907808) (xy 294.455217 -311.866212) (xy 294.487852 -311.829375) (xy 294.525973 -311.79825)
			(xy 294.568594 -311.773643) (xy 294.61461 -311.756191) (xy 294.662829 -311.746347) (xy 294.712004 -311.744366)
			(xy 294.760859 -311.750298) (xy 294.80813 -311.76399) (xy 294.852592 -311.785088) (xy 294.893095 -311.813044)
			(xy 294.928588 -311.847136) (xy 294.958153 -311.88648) (xy 294.981024 -311.930057) (xy 294.996608 -311.976738)
			(xy 295.004503 -312.025315) (xy 295.004998 -312.049922) (xy 296.29406 -312.049922) (xy 296.29802 -312.000868)
			(xy 296.309797 -311.953084) (xy 296.329088 -311.907808) (xy 296.355391 -311.866212) (xy 296.388026 -311.829375)
			(xy 296.426147 -311.79825) (xy 296.468768 -311.773643) (xy 296.514784 -311.756191) (xy 296.563003 -311.746347)
			(xy 296.612178 -311.744366) (xy 296.661033 -311.750298) (xy 296.708304 -311.76399) (xy 296.752766 -311.785088)
			(xy 296.793269 -311.813044) (xy 296.828762 -311.847136) (xy 296.858327 -311.88648) (xy 296.881198 -311.930057)
			(xy 296.896782 -311.976738) (xy 296.904677 -312.025315) (xy 296.905172 -312.049922) (xy 298.19398 -312.049922)
			(xy 298.19794 -312.000868) (xy 298.209717 -311.953084) (xy 298.229008 -311.907808) (xy 298.255311 -311.866212)
			(xy 298.287946 -311.829375) (xy 298.326067 -311.79825) (xy 298.368688 -311.773643) (xy 298.414704 -311.756191)
			(xy 298.462923 -311.746347) (xy 298.512098 -311.744366) (xy 298.560953 -311.750298) (xy 298.608224 -311.76399)
			(xy 298.652686 -311.785088) (xy 298.693189 -311.813044) (xy 298.728682 -311.847136) (xy 298.758247 -311.88648)
			(xy 298.781118 -311.930057) (xy 298.796702 -311.976738) (xy 298.804597 -312.025315) (xy 298.805092 -312.049922)
			(xy 300.0939 -312.049922) (xy 300.09786 -312.000868) (xy 300.109637 -311.953084) (xy 300.128928 -311.907808)
			(xy 300.155231 -311.866212) (xy 300.187866 -311.829375) (xy 300.225987 -311.79825) (xy 300.268608 -311.773643)
			(xy 300.314624 -311.756191) (xy 300.362843 -311.746347) (xy 300.412018 -311.744366) (xy 300.460873 -311.750298)
			(xy 300.508144 -311.76399) (xy 300.552606 -311.785088) (xy 300.593109 -311.813044) (xy 300.628602 -311.847136)
			(xy 300.658167 -311.88648) (xy 300.681038 -311.930057) (xy 300.696622 -311.976738) (xy 300.704517 -312.025315)
			(xy 300.705012 -312.049922) (xy 301.994074 -312.049922) (xy 301.998034 -312.000868) (xy 302.009811 -311.953084)
			(xy 302.029102 -311.907808) (xy 302.055405 -311.866212) (xy 302.08804 -311.829375) (xy 302.126161 -311.79825)
			(xy 302.168782 -311.773643) (xy 302.214798 -311.756191) (xy 302.263017 -311.746347) (xy 302.312192 -311.744366)
			(xy 302.361047 -311.750298) (xy 302.408318 -311.76399) (xy 302.45278 -311.785088) (xy 302.493283 -311.813044)
			(xy 302.528776 -311.847136) (xy 302.558341 -311.88648) (xy 302.581212 -311.930057) (xy 302.596796 -311.976738)
			(xy 302.604691 -312.025315) (xy 302.605186 -312.049922) (xy 303.893994 -312.049922) (xy 303.897954 -312.000868)
			(xy 303.909731 -311.953084) (xy 303.929022 -311.907808) (xy 303.955325 -311.866212) (xy 303.98796 -311.829375)
			(xy 304.026081 -311.79825) (xy 304.068702 -311.773643) (xy 304.114718 -311.756191) (xy 304.162937 -311.746347)
			(xy 304.212112 -311.744366) (xy 304.260967 -311.750298) (xy 304.308238 -311.76399) (xy 304.3527 -311.785088)
			(xy 304.393203 -311.813044) (xy 304.428696 -311.847136) (xy 304.458261 -311.88648) (xy 304.481132 -311.930057)
			(xy 304.496716 -311.976738) (xy 304.504611 -312.025315) (xy 304.505106 -312.049922) (xy 305.793914 -312.049922)
			(xy 305.797874 -312.000868) (xy 305.809651 -311.953084) (xy 305.828942 -311.907808) (xy 305.855245 -311.866212)
			(xy 305.88788 -311.829375) (xy 305.926001 -311.79825) (xy 305.968622 -311.773643) (xy 306.014638 -311.756191)
			(xy 306.062857 -311.746347) (xy 306.112032 -311.744366) (xy 306.160887 -311.750298) (xy 306.208158 -311.76399)
			(xy 306.25262 -311.785088) (xy 306.293123 -311.813044) (xy 306.328616 -311.847136) (xy 306.358181 -311.88648)
			(xy 306.381052 -311.930057) (xy 306.396636 -311.976738) (xy 306.404531 -312.025315) (xy 306.405026 -312.049922)
			(xy 307.694088 -312.049922) (xy 307.698048 -312.000868) (xy 307.709825 -311.953084) (xy 307.729116 -311.907808)
			(xy 307.755419 -311.866212) (xy 307.788054 -311.829375) (xy 307.826175 -311.79825) (xy 307.868796 -311.773643)
			(xy 307.914812 -311.756191) (xy 307.963031 -311.746347) (xy 308.012206 -311.744366) (xy 308.061061 -311.750298)
			(xy 308.108332 -311.76399) (xy 308.152794 -311.785088) (xy 308.193297 -311.813044) (xy 308.22879 -311.847136)
			(xy 308.258355 -311.88648) (xy 308.281226 -311.930057) (xy 308.29681 -311.976738) (xy 308.304705 -312.025315)
			(xy 308.3052 -312.049922) (xy 309.594008 -312.049922) (xy 309.597968 -312.000868) (xy 309.609745 -311.953084)
			(xy 309.629036 -311.907808) (xy 309.655339 -311.866212) (xy 309.687974 -311.829375) (xy 309.726095 -311.79825)
			(xy 309.768716 -311.773643) (xy 309.814732 -311.756191) (xy 309.862951 -311.746347) (xy 309.912126 -311.744366)
			(xy 309.960981 -311.750298) (xy 310.008252 -311.76399) (xy 310.052714 -311.785088) (xy 310.093217 -311.813044)
			(xy 310.12871 -311.847136) (xy 310.158275 -311.88648) (xy 310.181146 -311.930057) (xy 310.19673 -311.976738)
			(xy 310.204625 -312.025315) (xy 310.20512 -312.049922) (xy 311.493928 -312.049922) (xy 311.497888 -312.000868)
			(xy 311.509665 -311.953084) (xy 311.528956 -311.907808) (xy 311.555259 -311.866212) (xy 311.587894 -311.829375)
			(xy 311.626015 -311.79825) (xy 311.668636 -311.773643) (xy 311.714652 -311.756191) (xy 311.762871 -311.746347)
			(xy 311.812046 -311.744366) (xy 311.860901 -311.750298) (xy 311.908172 -311.76399) (xy 311.952634 -311.785088)
			(xy 311.993137 -311.813044) (xy 312.02863 -311.847136) (xy 312.058195 -311.88648) (xy 312.081066 -311.930057)
			(xy 312.09665 -311.976738) (xy 312.104545 -312.025315) (xy 312.10504 -312.049922) (xy 313.394102 -312.049922)
			(xy 313.398062 -312.000868) (xy 313.409839 -311.953084) (xy 313.42913 -311.907808) (xy 313.455433 -311.866212)
			(xy 313.488068 -311.829375) (xy 313.526189 -311.79825) (xy 313.56881 -311.773643) (xy 313.614826 -311.756191)
			(xy 313.663045 -311.746347) (xy 313.71222 -311.744366) (xy 313.761075 -311.750298) (xy 313.808346 -311.76399)
			(xy 313.852808 -311.785088) (xy 313.893311 -311.813044) (xy 313.928804 -311.847136) (xy 313.958369 -311.88648)
			(xy 313.98124 -311.930057) (xy 313.996824 -311.976738) (xy 314.004719 -312.025315) (xy 314.005214 -312.049922)
			(xy 314.344062 -312.049922) (xy 314.348022 -312.000868) (xy 314.359799 -311.953084) (xy 314.37909 -311.907808)
			(xy 314.405393 -311.866212) (xy 314.438028 -311.829375) (xy 314.476149 -311.79825) (xy 314.51877 -311.773643)
			(xy 314.564786 -311.756191) (xy 314.613005 -311.746347) (xy 314.66218 -311.744366) (xy 314.711035 -311.750298)
			(xy 314.758306 -311.76399) (xy 314.802768 -311.785088) (xy 314.843271 -311.813044) (xy 314.878764 -311.847136)
			(xy 314.908329 -311.88648) (xy 314.9312 -311.930057) (xy 314.946784 -311.976738) (xy 314.954679 -312.025315)
			(xy 314.955174 -312.049922) (xy 384.844048 -312.049922) (xy 384.848008 -312.000868) (xy 384.859785 -311.953084)
			(xy 384.879076 -311.907808) (xy 384.905379 -311.866212) (xy 384.938014 -311.829375) (xy 384.976135 -311.79825)
			(xy 385.018756 -311.773643) (xy 385.064772 -311.756191) (xy 385.112991 -311.746347) (xy 385.162166 -311.744366)
			(xy 385.211021 -311.750298) (xy 385.258292 -311.76399) (xy 385.302754 -311.785088) (xy 385.343257 -311.813044)
			(xy 385.37875 -311.847136) (xy 385.408315 -311.88648) (xy 385.431186 -311.930057) (xy 385.44677 -311.976738)
			(xy 385.454665 -312.025315) (xy 385.45516 -312.049922) (xy 385.794008 -312.049922) (xy 385.797968 -312.000868)
			(xy 385.809745 -311.953084) (xy 385.829036 -311.907808) (xy 385.855339 -311.866212) (xy 385.887974 -311.829375)
			(xy 385.926095 -311.79825) (xy 385.968716 -311.773643) (xy 386.014732 -311.756191) (xy 386.062951 -311.746347)
			(xy 386.112126 -311.744366) (xy 386.160981 -311.750298) (xy 386.208252 -311.76399) (xy 386.252714 -311.785088)
			(xy 386.293217 -311.813044) (xy 386.32871 -311.847136) (xy 386.358275 -311.88648) (xy 386.381146 -311.930057)
			(xy 386.39673 -311.976738) (xy 386.404625 -312.025315) (xy 386.40512 -312.049922) (xy 387.694182 -312.049922)
			(xy 387.698142 -312.000868) (xy 387.709919 -311.953084) (xy 387.72921 -311.907808) (xy 387.755513 -311.866212)
			(xy 387.788148 -311.829375) (xy 387.826269 -311.79825) (xy 387.86889 -311.773643) (xy 387.914906 -311.756191)
			(xy 387.963125 -311.746347) (xy 388.0123 -311.744366) (xy 388.061155 -311.750298) (xy 388.108426 -311.76399)
			(xy 388.152888 -311.785088) (xy 388.193391 -311.813044) (xy 388.228884 -311.847136) (xy 388.258449 -311.88648)
			(xy 388.28132 -311.930057) (xy 388.296904 -311.976738) (xy 388.304799 -312.025315) (xy 388.305294 -312.049922)
			(xy 389.594102 -312.049922) (xy 389.598062 -312.000868) (xy 389.609839 -311.953084) (xy 389.62913 -311.907808)
			(xy 389.655433 -311.866212) (xy 389.688068 -311.829375) (xy 389.726189 -311.79825) (xy 389.76881 -311.773643)
			(xy 389.814826 -311.756191) (xy 389.863045 -311.746347) (xy 389.91222 -311.744366) (xy 389.961075 -311.750298)
			(xy 390.008346 -311.76399) (xy 390.052808 -311.785088) (xy 390.093311 -311.813044) (xy 390.128804 -311.847136)
			(xy 390.158369 -311.88648) (xy 390.18124 -311.930057) (xy 390.196824 -311.976738) (xy 390.204719 -312.025315)
			(xy 390.205214 -312.049922) (xy 391.494022 -312.049922) (xy 391.497982 -312.000868) (xy 391.509759 -311.953084)
			(xy 391.52905 -311.907808) (xy 391.555353 -311.866212) (xy 391.587988 -311.829375) (xy 391.626109 -311.79825)
			(xy 391.66873 -311.773643) (xy 391.714746 -311.756191) (xy 391.762965 -311.746347) (xy 391.81214 -311.744366)
			(xy 391.860995 -311.750298) (xy 391.908266 -311.76399) (xy 391.952728 -311.785088) (xy 391.993231 -311.813044)
			(xy 392.028724 -311.847136) (xy 392.058289 -311.88648) (xy 392.08116 -311.930057) (xy 392.096744 -311.976738)
			(xy 392.104639 -312.025315) (xy 392.105134 -312.049922) (xy 393.394196 -312.049922) (xy 393.398156 -312.000868)
			(xy 393.409933 -311.953084) (xy 393.429224 -311.907808) (xy 393.455527 -311.866212) (xy 393.488162 -311.829375)
			(xy 393.526283 -311.79825) (xy 393.568904 -311.773643) (xy 393.61492 -311.756191) (xy 393.663139 -311.746347)
			(xy 393.712314 -311.744366) (xy 393.761169 -311.750298) (xy 393.80844 -311.76399) (xy 393.852902 -311.785088)
			(xy 393.893405 -311.813044) (xy 393.928898 -311.847136) (xy 393.958463 -311.88648) (xy 393.981334 -311.930057)
			(xy 393.996918 -311.976738) (xy 394.004813 -312.025315) (xy 394.005308 -312.049922) (xy 395.294116 -312.049922)
			(xy 395.298076 -312.000868) (xy 395.309853 -311.953084) (xy 395.329144 -311.907808) (xy 395.355447 -311.866212)
			(xy 395.388082 -311.829375) (xy 395.426203 -311.79825) (xy 395.468824 -311.773643) (xy 395.51484 -311.756191)
			(xy 395.563059 -311.746347) (xy 395.612234 -311.744366) (xy 395.661089 -311.750298) (xy 395.70836 -311.76399)
			(xy 395.752822 -311.785088) (xy 395.793325 -311.813044) (xy 395.828818 -311.847136) (xy 395.858383 -311.88648)
			(xy 395.881254 -311.930057) (xy 395.896838 -311.976738) (xy 395.904733 -312.025315) (xy 395.905228 -312.049922)
			(xy 397.194036 -312.049922) (xy 397.197996 -312.000868) (xy 397.209773 -311.953084) (xy 397.229064 -311.907808)
			(xy 397.255367 -311.866212) (xy 397.288002 -311.829375) (xy 397.326123 -311.79825) (xy 397.368744 -311.773643)
			(xy 397.41476 -311.756191) (xy 397.462979 -311.746347) (xy 397.512154 -311.744366) (xy 397.561009 -311.750298)
			(xy 397.60828 -311.76399) (xy 397.652742 -311.785088) (xy 397.693245 -311.813044) (xy 397.728738 -311.847136)
			(xy 397.758303 -311.88648) (xy 397.781174 -311.930057) (xy 397.796758 -311.976738) (xy 397.804653 -312.025315)
			(xy 397.805148 -312.049922) (xy 399.09421 -312.049922) (xy 399.09817 -312.000868) (xy 399.109947 -311.953084)
			(xy 399.129238 -311.907808) (xy 399.155541 -311.866212) (xy 399.188176 -311.829375) (xy 399.226297 -311.79825)
			(xy 399.268918 -311.773643) (xy 399.314934 -311.756191) (xy 399.363153 -311.746347) (xy 399.412328 -311.744366)
			(xy 399.461183 -311.750298) (xy 399.508454 -311.76399) (xy 399.552916 -311.785088) (xy 399.593419 -311.813044)
			(xy 399.628912 -311.847136) (xy 399.658477 -311.88648) (xy 399.681348 -311.930057) (xy 399.696932 -311.976738)
			(xy 399.704827 -312.025315) (xy 399.705322 -312.049922) (xy 400.99413 -312.049922) (xy 400.99809 -312.000868)
			(xy 401.009867 -311.953084) (xy 401.029158 -311.907808) (xy 401.055461 -311.866212) (xy 401.088096 -311.829375)
			(xy 401.126217 -311.79825) (xy 401.168838 -311.773643) (xy 401.214854 -311.756191) (xy 401.263073 -311.746347)
			(xy 401.312248 -311.744366) (xy 401.361103 -311.750298) (xy 401.408374 -311.76399) (xy 401.452836 -311.785088)
			(xy 401.493339 -311.813044) (xy 401.528832 -311.847136) (xy 401.558397 -311.88648) (xy 401.581268 -311.930057)
			(xy 401.596852 -311.976738) (xy 401.604747 -312.025315) (xy 401.605242 -312.049922) (xy 402.89405 -312.049922)
			(xy 402.89801 -312.000868) (xy 402.909787 -311.953084) (xy 402.929078 -311.907808) (xy 402.955381 -311.866212)
			(xy 402.988016 -311.829375) (xy 403.026137 -311.79825) (xy 403.068758 -311.773643) (xy 403.114774 -311.756191)
			(xy 403.162993 -311.746347) (xy 403.212168 -311.744366) (xy 403.261023 -311.750298) (xy 403.308294 -311.76399)
			(xy 403.352756 -311.785088) (xy 403.393259 -311.813044) (xy 403.428752 -311.847136) (xy 403.458317 -311.88648)
			(xy 403.481188 -311.930057) (xy 403.496772 -311.976738) (xy 403.504667 -312.025315) (xy 403.505162 -312.049922)
			(xy 404.794224 -312.049922) (xy 404.798184 -312.000868) (xy 404.809961 -311.953084) (xy 404.829252 -311.907808)
			(xy 404.855555 -311.866212) (xy 404.88819 -311.829375) (xy 404.926311 -311.79825) (xy 404.968932 -311.773643)
			(xy 405.014948 -311.756191) (xy 405.063167 -311.746347) (xy 405.112342 -311.744366) (xy 405.161197 -311.750298)
			(xy 405.208468 -311.76399) (xy 405.25293 -311.785088) (xy 405.293433 -311.813044) (xy 405.328926 -311.847136)
			(xy 405.358491 -311.88648) (xy 405.381362 -311.930057) (xy 405.396946 -311.976738) (xy 405.404841 -312.025315)
			(xy 405.405336 -312.049922) (xy 406.694144 -312.049922) (xy 406.698104 -312.000868) (xy 406.709881 -311.953084)
			(xy 406.729172 -311.907808) (xy 406.755475 -311.866212) (xy 406.78811 -311.829375) (xy 406.826231 -311.79825)
			(xy 406.868852 -311.773643) (xy 406.914868 -311.756191) (xy 406.963087 -311.746347) (xy 407.012262 -311.744366)
			(xy 407.061117 -311.750298) (xy 407.108388 -311.76399) (xy 407.15285 -311.785088) (xy 407.193353 -311.813044)
			(xy 407.228846 -311.847136) (xy 407.258411 -311.88648) (xy 407.281282 -311.930057) (xy 407.296866 -311.976738)
			(xy 407.304761 -312.025315) (xy 407.305256 -312.049922) (xy 408.594064 -312.049922) (xy 408.598024 -312.000868)
			(xy 408.609801 -311.953084) (xy 408.629092 -311.907808) (xy 408.655395 -311.866212) (xy 408.68803 -311.829375)
			(xy 408.726151 -311.79825) (xy 408.768772 -311.773643) (xy 408.814788 -311.756191) (xy 408.863007 -311.746347)
			(xy 408.912182 -311.744366) (xy 408.961037 -311.750298) (xy 409.008308 -311.76399) (xy 409.05277 -311.785088)
			(xy 409.093273 -311.813044) (xy 409.128766 -311.847136) (xy 409.158331 -311.88648) (xy 409.181202 -311.930057)
			(xy 409.196786 -311.976738) (xy 409.204681 -312.025315) (xy 409.205176 -312.049922) (xy 410.493984 -312.049922)
			(xy 410.497944 -312.000868) (xy 410.509721 -311.953084) (xy 410.529012 -311.907808) (xy 410.555315 -311.866212)
			(xy 410.58795 -311.829375) (xy 410.626071 -311.79825) (xy 410.668692 -311.773643) (xy 410.714708 -311.756191)
			(xy 410.762927 -311.746347) (xy 410.812102 -311.744366) (xy 410.860957 -311.750298) (xy 410.908228 -311.76399)
			(xy 410.95269 -311.785088) (xy 410.993193 -311.813044) (xy 411.028686 -311.847136) (xy 411.058251 -311.88648)
			(xy 411.081122 -311.930057) (xy 411.096706 -311.976738) (xy 411.104601 -312.025315) (xy 411.105096 -312.049922)
			(xy 412.394158 -312.049922) (xy 412.398118 -312.000868) (xy 412.409895 -311.953084) (xy 412.429186 -311.907808)
			(xy 412.455489 -311.866212) (xy 412.488124 -311.829375) (xy 412.526245 -311.79825) (xy 412.568866 -311.773643)
			(xy 412.614882 -311.756191) (xy 412.663101 -311.746347) (xy 412.712276 -311.744366) (xy 412.761131 -311.750298)
			(xy 412.808402 -311.76399) (xy 412.852864 -311.785088) (xy 412.893367 -311.813044) (xy 412.92886 -311.847136)
			(xy 412.958425 -311.88648) (xy 412.981296 -311.930057) (xy 412.99688 -311.976738) (xy 413.004775 -312.025315)
			(xy 413.00527 -312.049922) (xy 414.294078 -312.049922) (xy 414.298038 -312.000868) (xy 414.309815 -311.953084)
			(xy 414.329106 -311.907808) (xy 414.355409 -311.866212) (xy 414.388044 -311.829375) (xy 414.426165 -311.79825)
			(xy 414.468786 -311.773643) (xy 414.514802 -311.756191) (xy 414.563021 -311.746347) (xy 414.612196 -311.744366)
			(xy 414.661051 -311.750298) (xy 414.708322 -311.76399) (xy 414.752784 -311.785088) (xy 414.793287 -311.813044)
			(xy 414.82878 -311.847136) (xy 414.858345 -311.88648) (xy 414.881216 -311.930057) (xy 414.8968 -311.976738)
			(xy 414.904695 -312.025315) (xy 414.90519 -312.049922) (xy 416.193998 -312.049922) (xy 416.197958 -312.000868)
			(xy 416.209735 -311.953084) (xy 416.229026 -311.907808) (xy 416.255329 -311.866212) (xy 416.287964 -311.829375)
			(xy 416.326085 -311.79825) (xy 416.368706 -311.773643) (xy 416.414722 -311.756191) (xy 416.462941 -311.746347)
			(xy 416.512116 -311.744366) (xy 416.560971 -311.750298) (xy 416.608242 -311.76399) (xy 416.652704 -311.785088)
			(xy 416.693207 -311.813044) (xy 416.7287 -311.847136) (xy 416.758265 -311.88648) (xy 416.781136 -311.930057)
			(xy 416.79672 -311.976738) (xy 416.804615 -312.025315) (xy 416.80511 -312.049922) (xy 418.094172 -312.049922)
			(xy 418.098132 -312.000868) (xy 418.109909 -311.953084) (xy 418.1292 -311.907808) (xy 418.155503 -311.866212)
			(xy 418.188138 -311.829375) (xy 418.226259 -311.79825) (xy 418.26888 -311.773643) (xy 418.314896 -311.756191)
			(xy 418.363115 -311.746347) (xy 418.41229 -311.744366) (xy 418.461145 -311.750298) (xy 418.508416 -311.76399)
			(xy 418.552878 -311.785088) (xy 418.593381 -311.813044) (xy 418.628874 -311.847136) (xy 418.658439 -311.88648)
			(xy 418.68131 -311.930057) (xy 418.696894 -311.976738) (xy 418.704789 -312.025315) (xy 418.705284 -312.049922)
			(xy 419.994092 -312.049922) (xy 419.998052 -312.000868) (xy 420.009829 -311.953084) (xy 420.02912 -311.907808)
			(xy 420.055423 -311.866212) (xy 420.088058 -311.829375) (xy 420.126179 -311.79825) (xy 420.1688 -311.773643)
			(xy 420.214816 -311.756191) (xy 420.263035 -311.746347) (xy 420.31221 -311.744366) (xy 420.361065 -311.750298)
			(xy 420.408336 -311.76399) (xy 420.452798 -311.785088) (xy 420.493301 -311.813044) (xy 420.528794 -311.847136)
			(xy 420.558359 -311.88648) (xy 420.58123 -311.930057) (xy 420.596814 -311.976738) (xy 420.604709 -312.025315)
			(xy 420.605204 -312.049922) (xy 421.894012 -312.049922) (xy 421.897972 -312.000868) (xy 421.909749 -311.953084)
			(xy 421.92904 -311.907808) (xy 421.955343 -311.866212) (xy 421.987978 -311.829375) (xy 422.026099 -311.79825)
			(xy 422.06872 -311.773643) (xy 422.114736 -311.756191) (xy 422.162955 -311.746347) (xy 422.21213 -311.744366)
			(xy 422.260985 -311.750298) (xy 422.308256 -311.76399) (xy 422.352718 -311.785088) (xy 422.393221 -311.813044)
			(xy 422.428714 -311.847136) (xy 422.458279 -311.88648) (xy 422.48115 -311.930057) (xy 422.496734 -311.976738)
			(xy 422.504629 -312.025315) (xy 422.505124 -312.049922) (xy 423.794186 -312.049922) (xy 423.798146 -312.000868)
			(xy 423.809923 -311.953084) (xy 423.829214 -311.907808) (xy 423.855517 -311.866212) (xy 423.888152 -311.829375)
			(xy 423.926273 -311.79825) (xy 423.968894 -311.773643) (xy 424.01491 -311.756191) (xy 424.063129 -311.746347)
			(xy 424.112304 -311.744366) (xy 424.161159 -311.750298) (xy 424.20843 -311.76399) (xy 424.252892 -311.785088)
			(xy 424.293395 -311.813044) (xy 424.328888 -311.847136) (xy 424.358453 -311.88648) (xy 424.381324 -311.930057)
			(xy 424.396908 -311.976738) (xy 424.404803 -312.025315) (xy 424.405298 -312.049922) (xy 425.694106 -312.049922)
			(xy 425.698066 -312.000868) (xy 425.709843 -311.953084) (xy 425.729134 -311.907808) (xy 425.755437 -311.866212)
			(xy 425.788072 -311.829375) (xy 425.826193 -311.79825) (xy 425.868814 -311.773643) (xy 425.91483 -311.756191)
			(xy 425.963049 -311.746347) (xy 426.012224 -311.744366) (xy 426.061079 -311.750298) (xy 426.10835 -311.76399)
			(xy 426.152812 -311.785088) (xy 426.193315 -311.813044) (xy 426.228808 -311.847136) (xy 426.258373 -311.88648)
			(xy 426.281244 -311.930057) (xy 426.296828 -311.976738) (xy 426.304723 -312.025315) (xy 426.305218 -312.049922)
			(xy 427.594026 -312.049922) (xy 427.597986 -312.000868) (xy 427.609763 -311.953084) (xy 427.629054 -311.907808)
			(xy 427.655357 -311.866212) (xy 427.687992 -311.829375) (xy 427.726113 -311.79825) (xy 427.768734 -311.773643)
			(xy 427.81475 -311.756191) (xy 427.862969 -311.746347) (xy 427.912144 -311.744366) (xy 427.960999 -311.750298)
			(xy 428.00827 -311.76399) (xy 428.052732 -311.785088) (xy 428.093235 -311.813044) (xy 428.128728 -311.847136)
			(xy 428.158293 -311.88648) (xy 428.181164 -311.930057) (xy 428.196748 -311.976738) (xy 428.204643 -312.025315)
			(xy 428.205138 -312.049922) (xy 429.4942 -312.049922) (xy 429.49816 -312.000868) (xy 429.509937 -311.953084)
			(xy 429.529228 -311.907808) (xy 429.555531 -311.866212) (xy 429.588166 -311.829375) (xy 429.626287 -311.79825)
			(xy 429.668908 -311.773643) (xy 429.714924 -311.756191) (xy 429.763143 -311.746347) (xy 429.812318 -311.744366)
			(xy 429.861173 -311.750298) (xy 429.908444 -311.76399) (xy 429.952906 -311.785088) (xy 429.993409 -311.813044)
			(xy 430.028902 -311.847136) (xy 430.058467 -311.88648) (xy 430.081338 -311.930057) (xy 430.096922 -311.976738)
			(xy 430.104817 -312.025315) (xy 430.105312 -312.049922) (xy 430.44416 -312.049922) (xy 430.44812 -312.000868)
			(xy 430.459897 -311.953084) (xy 430.479188 -311.907808) (xy 430.505491 -311.866212) (xy 430.538126 -311.829375)
			(xy 430.576247 -311.79825) (xy 430.618868 -311.773643) (xy 430.664884 -311.756191) (xy 430.713103 -311.746347)
			(xy 430.762278 -311.744366) (xy 430.811133 -311.750298) (xy 430.858404 -311.76399) (xy 430.902866 -311.785088)
			(xy 430.943369 -311.813044) (xy 430.978862 -311.847136) (xy 431.008427 -311.88648) (xy 431.031298 -311.930057)
			(xy 431.046882 -311.976738) (xy 431.054777 -312.025315) (xy 431.055272 -312.049922) (xy 431.054777 -312.074529)
			(xy 431.046882 -312.123106) (xy 431.031298 -312.169787) (xy 431.008427 -312.213364) (xy 430.978862 -312.252708)
			(xy 430.943369 -312.2868) (xy 430.902866 -312.314756) (xy 430.858404 -312.335854) (xy 430.811133 -312.349546)
			(xy 430.762278 -312.355478) (xy 430.713103 -312.353497) (xy 430.664884 -312.343653) (xy 430.618868 -312.326201)
			(xy 430.576247 -312.301594) (xy 430.538126 -312.270469) (xy 430.505491 -312.233632) (xy 430.479188 -312.192036)
			(xy 430.459897 -312.14676) (xy 430.44812 -312.098976) (xy 430.44416 -312.049922) (xy 430.105312 -312.049922)
			(xy 430.104817 -312.074529) (xy 430.096922 -312.123106) (xy 430.081338 -312.169787) (xy 430.058467 -312.213364)
			(xy 430.028902 -312.252708) (xy 429.993409 -312.2868) (xy 429.952906 -312.314756) (xy 429.908444 -312.335854)
			(xy 429.861173 -312.349546) (xy 429.812318 -312.355478) (xy 429.763143 -312.353497) (xy 429.714924 -312.343653)
			(xy 429.668908 -312.326201) (xy 429.626287 -312.301594) (xy 429.588166 -312.270469) (xy 429.555531 -312.233632)
			(xy 429.529228 -312.192036) (xy 429.509937 -312.14676) (xy 429.49816 -312.098976) (xy 429.4942 -312.049922)
			(xy 428.205138 -312.049922) (xy 428.204643 -312.074529) (xy 428.196748 -312.123106) (xy 428.181164 -312.169787)
			(xy 428.158293 -312.213364) (xy 428.128728 -312.252708) (xy 428.093235 -312.2868) (xy 428.052732 -312.314756)
			(xy 428.00827 -312.335854) (xy 427.960999 -312.349546) (xy 427.912144 -312.355478) (xy 427.862969 -312.353497)
			(xy 427.81475 -312.343653) (xy 427.768734 -312.326201) (xy 427.726113 -312.301594) (xy 427.687992 -312.270469)
			(xy 427.655357 -312.233632) (xy 427.629054 -312.192036) (xy 427.609763 -312.14676) (xy 427.597986 -312.098976)
			(xy 427.594026 -312.049922) (xy 426.305218 -312.049922) (xy 426.304723 -312.074529) (xy 426.296828 -312.123106)
			(xy 426.281244 -312.169787) (xy 426.258373 -312.213364) (xy 426.228808 -312.252708) (xy 426.193315 -312.2868)
			(xy 426.152812 -312.314756) (xy 426.10835 -312.335854) (xy 426.061079 -312.349546) (xy 426.012224 -312.355478)
			(xy 425.963049 -312.353497) (xy 425.91483 -312.343653) (xy 425.868814 -312.326201) (xy 425.826193 -312.301594)
			(xy 425.788072 -312.270469) (xy 425.755437 -312.233632) (xy 425.729134 -312.192036) (xy 425.709843 -312.14676)
			(xy 425.698066 -312.098976) (xy 425.694106 -312.049922) (xy 424.405298 -312.049922) (xy 424.404803 -312.074529)
			(xy 424.396908 -312.123106) (xy 424.381324 -312.169787) (xy 424.358453 -312.213364) (xy 424.328888 -312.252708)
			(xy 424.293395 -312.2868) (xy 424.252892 -312.314756) (xy 424.20843 -312.335854) (xy 424.161159 -312.349546)
			(xy 424.112304 -312.355478) (xy 424.063129 -312.353497) (xy 424.01491 -312.343653) (xy 423.968894 -312.326201)
			(xy 423.926273 -312.301594) (xy 423.888152 -312.270469) (xy 423.855517 -312.233632) (xy 423.829214 -312.192036)
			(xy 423.809923 -312.14676) (xy 423.798146 -312.098976) (xy 423.794186 -312.049922) (xy 422.505124 -312.049922)
			(xy 422.504629 -312.074529) (xy 422.496734 -312.123106) (xy 422.48115 -312.169787) (xy 422.458279 -312.213364)
			(xy 422.428714 -312.252708) (xy 422.393221 -312.2868) (xy 422.352718 -312.314756) (xy 422.308256 -312.335854)
			(xy 422.260985 -312.349546) (xy 422.21213 -312.355478) (xy 422.162955 -312.353497) (xy 422.114736 -312.343653)
			(xy 422.06872 -312.326201) (xy 422.026099 -312.301594) (xy 421.987978 -312.270469) (xy 421.955343 -312.233632)
			(xy 421.92904 -312.192036) (xy 421.909749 -312.14676) (xy 421.897972 -312.098976) (xy 421.894012 -312.049922)
			(xy 420.605204 -312.049922) (xy 420.604709 -312.074529) (xy 420.596814 -312.123106) (xy 420.58123 -312.169787)
			(xy 420.558359 -312.213364) (xy 420.528794 -312.252708) (xy 420.493301 -312.2868) (xy 420.452798 -312.314756)
			(xy 420.408336 -312.335854) (xy 420.361065 -312.349546) (xy 420.31221 -312.355478) (xy 420.263035 -312.353497)
			(xy 420.214816 -312.343653) (xy 420.1688 -312.326201) (xy 420.126179 -312.301594) (xy 420.088058 -312.270469)
			(xy 420.055423 -312.233632) (xy 420.02912 -312.192036) (xy 420.009829 -312.14676) (xy 419.998052 -312.098976)
			(xy 419.994092 -312.049922) (xy 418.705284 -312.049922) (xy 418.704789 -312.074529) (xy 418.696894 -312.123106)
			(xy 418.68131 -312.169787) (xy 418.658439 -312.213364) (xy 418.628874 -312.252708) (xy 418.593381 -312.2868)
			(xy 418.552878 -312.314756) (xy 418.508416 -312.335854) (xy 418.461145 -312.349546) (xy 418.41229 -312.355478)
			(xy 418.363115 -312.353497) (xy 418.314896 -312.343653) (xy 418.26888 -312.326201) (xy 418.226259 -312.301594)
			(xy 418.188138 -312.270469) (xy 418.155503 -312.233632) (xy 418.1292 -312.192036) (xy 418.109909 -312.14676)
			(xy 418.098132 -312.098976) (xy 418.094172 -312.049922) (xy 416.80511 -312.049922) (xy 416.804615 -312.074529)
			(xy 416.79672 -312.123106) (xy 416.781136 -312.169787) (xy 416.758265 -312.213364) (xy 416.7287 -312.252708)
			(xy 416.693207 -312.2868) (xy 416.652704 -312.314756) (xy 416.608242 -312.335854) (xy 416.560971 -312.349546)
			(xy 416.512116 -312.355478) (xy 416.462941 -312.353497) (xy 416.414722 -312.343653) (xy 416.368706 -312.326201)
			(xy 416.326085 -312.301594) (xy 416.287964 -312.270469) (xy 416.255329 -312.233632) (xy 416.229026 -312.192036)
			(xy 416.209735 -312.14676) (xy 416.197958 -312.098976) (xy 416.193998 -312.049922) (xy 414.90519 -312.049922)
			(xy 414.904695 -312.074529) (xy 414.8968 -312.123106) (xy 414.881216 -312.169787) (xy 414.858345 -312.213364)
			(xy 414.82878 -312.252708) (xy 414.793287 -312.2868) (xy 414.752784 -312.314756) (xy 414.708322 -312.335854)
			(xy 414.661051 -312.349546) (xy 414.612196 -312.355478) (xy 414.563021 -312.353497) (xy 414.514802 -312.343653)
			(xy 414.468786 -312.326201) (xy 414.426165 -312.301594) (xy 414.388044 -312.270469) (xy 414.355409 -312.233632)
			(xy 414.329106 -312.192036) (xy 414.309815 -312.14676) (xy 414.298038 -312.098976) (xy 414.294078 -312.049922)
			(xy 413.00527 -312.049922) (xy 413.004775 -312.074529) (xy 412.99688 -312.123106) (xy 412.981296 -312.169787)
			(xy 412.958425 -312.213364) (xy 412.92886 -312.252708) (xy 412.893367 -312.2868) (xy 412.852864 -312.314756)
			(xy 412.808402 -312.335854) (xy 412.761131 -312.349546) (xy 412.712276 -312.355478) (xy 412.663101 -312.353497)
			(xy 412.614882 -312.343653) (xy 412.568866 -312.326201) (xy 412.526245 -312.301594) (xy 412.488124 -312.270469)
			(xy 412.455489 -312.233632) (xy 412.429186 -312.192036) (xy 412.409895 -312.14676) (xy 412.398118 -312.098976)
			(xy 412.394158 -312.049922) (xy 411.105096 -312.049922) (xy 411.104601 -312.074529) (xy 411.096706 -312.123106)
			(xy 411.081122 -312.169787) (xy 411.058251 -312.213364) (xy 411.028686 -312.252708) (xy 410.993193 -312.2868)
			(xy 410.95269 -312.314756) (xy 410.908228 -312.335854) (xy 410.860957 -312.349546) (xy 410.812102 -312.355478)
			(xy 410.762927 -312.353497) (xy 410.714708 -312.343653) (xy 410.668692 -312.326201) (xy 410.626071 -312.301594)
			(xy 410.58795 -312.270469) (xy 410.555315 -312.233632) (xy 410.529012 -312.192036) (xy 410.509721 -312.14676)
			(xy 410.497944 -312.098976) (xy 410.493984 -312.049922) (xy 409.205176 -312.049922) (xy 409.204681 -312.074529)
			(xy 409.196786 -312.123106) (xy 409.181202 -312.169787) (xy 409.158331 -312.213364) (xy 409.128766 -312.252708)
			(xy 409.093273 -312.2868) (xy 409.05277 -312.314756) (xy 409.008308 -312.335854) (xy 408.961037 -312.349546)
			(xy 408.912182 -312.355478) (xy 408.863007 -312.353497) (xy 408.814788 -312.343653) (xy 408.768772 -312.326201)
			(xy 408.726151 -312.301594) (xy 408.68803 -312.270469) (xy 408.655395 -312.233632) (xy 408.629092 -312.192036)
			(xy 408.609801 -312.14676) (xy 408.598024 -312.098976) (xy 408.594064 -312.049922) (xy 407.305256 -312.049922)
			(xy 407.304761 -312.074529) (xy 407.296866 -312.123106) (xy 407.281282 -312.169787) (xy 407.258411 -312.213364)
			(xy 407.228846 -312.252708) (xy 407.193353 -312.2868) (xy 407.15285 -312.314756) (xy 407.108388 -312.335854)
			(xy 407.061117 -312.349546) (xy 407.012262 -312.355478) (xy 406.963087 -312.353497) (xy 406.914868 -312.343653)
			(xy 406.868852 -312.326201) (xy 406.826231 -312.301594) (xy 406.78811 -312.270469) (xy 406.755475 -312.233632)
			(xy 406.729172 -312.192036) (xy 406.709881 -312.14676) (xy 406.698104 -312.098976) (xy 406.694144 -312.049922)
			(xy 405.405336 -312.049922) (xy 405.404841 -312.074529) (xy 405.396946 -312.123106) (xy 405.381362 -312.169787)
			(xy 405.358491 -312.213364) (xy 405.328926 -312.252708) (xy 405.293433 -312.2868) (xy 405.25293 -312.314756)
			(xy 405.208468 -312.335854) (xy 405.161197 -312.349546) (xy 405.112342 -312.355478) (xy 405.063167 -312.353497)
			(xy 405.014948 -312.343653) (xy 404.968932 -312.326201) (xy 404.926311 -312.301594) (xy 404.88819 -312.270469)
			(xy 404.855555 -312.233632) (xy 404.829252 -312.192036) (xy 404.809961 -312.14676) (xy 404.798184 -312.098976)
			(xy 404.794224 -312.049922) (xy 403.505162 -312.049922) (xy 403.504667 -312.074529) (xy 403.496772 -312.123106)
			(xy 403.481188 -312.169787) (xy 403.458317 -312.213364) (xy 403.428752 -312.252708) (xy 403.393259 -312.2868)
			(xy 403.352756 -312.314756) (xy 403.308294 -312.335854) (xy 403.261023 -312.349546) (xy 403.212168 -312.355478)
			(xy 403.162993 -312.353497) (xy 403.114774 -312.343653) (xy 403.068758 -312.326201) (xy 403.026137 -312.301594)
			(xy 402.988016 -312.270469) (xy 402.955381 -312.233632) (xy 402.929078 -312.192036) (xy 402.909787 -312.14676)
			(xy 402.89801 -312.098976) (xy 402.89405 -312.049922) (xy 401.605242 -312.049922) (xy 401.604747 -312.074529)
			(xy 401.596852 -312.123106) (xy 401.581268 -312.169787) (xy 401.558397 -312.213364) (xy 401.528832 -312.252708)
			(xy 401.493339 -312.2868) (xy 401.452836 -312.314756) (xy 401.408374 -312.335854) (xy 401.361103 -312.349546)
			(xy 401.312248 -312.355478) (xy 401.263073 -312.353497) (xy 401.214854 -312.343653) (xy 401.168838 -312.326201)
			(xy 401.126217 -312.301594) (xy 401.088096 -312.270469) (xy 401.055461 -312.233632) (xy 401.029158 -312.192036)
			(xy 401.009867 -312.14676) (xy 400.99809 -312.098976) (xy 400.99413 -312.049922) (xy 399.705322 -312.049922)
			(xy 399.704827 -312.074529) (xy 399.696932 -312.123106) (xy 399.681348 -312.169787) (xy 399.658477 -312.213364)
			(xy 399.628912 -312.252708) (xy 399.593419 -312.2868) (xy 399.552916 -312.314756) (xy 399.508454 -312.335854)
			(xy 399.461183 -312.349546) (xy 399.412328 -312.355478) (xy 399.363153 -312.353497) (xy 399.314934 -312.343653)
			(xy 399.268918 -312.326201) (xy 399.226297 -312.301594) (xy 399.188176 -312.270469) (xy 399.155541 -312.233632)
			(xy 399.129238 -312.192036) (xy 399.109947 -312.14676) (xy 399.09817 -312.098976) (xy 399.09421 -312.049922)
			(xy 397.805148 -312.049922) (xy 397.804653 -312.074529) (xy 397.796758 -312.123106) (xy 397.781174 -312.169787)
			(xy 397.758303 -312.213364) (xy 397.728738 -312.252708) (xy 397.693245 -312.2868) (xy 397.652742 -312.314756)
			(xy 397.60828 -312.335854) (xy 397.561009 -312.349546) (xy 397.512154 -312.355478) (xy 397.462979 -312.353497)
			(xy 397.41476 -312.343653) (xy 397.368744 -312.326201) (xy 397.326123 -312.301594) (xy 397.288002 -312.270469)
			(xy 397.255367 -312.233632) (xy 397.229064 -312.192036) (xy 397.209773 -312.14676) (xy 397.197996 -312.098976)
			(xy 397.194036 -312.049922) (xy 395.905228 -312.049922) (xy 395.904733 -312.074529) (xy 395.896838 -312.123106)
			(xy 395.881254 -312.169787) (xy 395.858383 -312.213364) (xy 395.828818 -312.252708) (xy 395.793325 -312.2868)
			(xy 395.752822 -312.314756) (xy 395.70836 -312.335854) (xy 395.661089 -312.349546) (xy 395.612234 -312.355478)
			(xy 395.563059 -312.353497) (xy 395.51484 -312.343653) (xy 395.468824 -312.326201) (xy 395.426203 -312.301594)
			(xy 395.388082 -312.270469) (xy 395.355447 -312.233632) (xy 395.329144 -312.192036) (xy 395.309853 -312.14676)
			(xy 395.298076 -312.098976) (xy 395.294116 -312.049922) (xy 394.005308 -312.049922) (xy 394.004813 -312.074529)
			(xy 393.996918 -312.123106) (xy 393.981334 -312.169787) (xy 393.958463 -312.213364) (xy 393.928898 -312.252708)
			(xy 393.893405 -312.2868) (xy 393.852902 -312.314756) (xy 393.80844 -312.335854) (xy 393.761169 -312.349546)
			(xy 393.712314 -312.355478) (xy 393.663139 -312.353497) (xy 393.61492 -312.343653) (xy 393.568904 -312.326201)
			(xy 393.526283 -312.301594) (xy 393.488162 -312.270469) (xy 393.455527 -312.233632) (xy 393.429224 -312.192036)
			(xy 393.409933 -312.14676) (xy 393.398156 -312.098976) (xy 393.394196 -312.049922) (xy 392.105134 -312.049922)
			(xy 392.104639 -312.074529) (xy 392.096744 -312.123106) (xy 392.08116 -312.169787) (xy 392.058289 -312.213364)
			(xy 392.028724 -312.252708) (xy 391.993231 -312.2868) (xy 391.952728 -312.314756) (xy 391.908266 -312.335854)
			(xy 391.860995 -312.349546) (xy 391.81214 -312.355478) (xy 391.762965 -312.353497) (xy 391.714746 -312.343653)
			(xy 391.66873 -312.326201) (xy 391.626109 -312.301594) (xy 391.587988 -312.270469) (xy 391.555353 -312.233632)
			(xy 391.52905 -312.192036) (xy 391.509759 -312.14676) (xy 391.497982 -312.098976) (xy 391.494022 -312.049922)
			(xy 390.205214 -312.049922) (xy 390.204719 -312.074529) (xy 390.196824 -312.123106) (xy 390.18124 -312.169787)
			(xy 390.158369 -312.213364) (xy 390.128804 -312.252708) (xy 390.093311 -312.2868) (xy 390.052808 -312.314756)
			(xy 390.008346 -312.335854) (xy 389.961075 -312.349546) (xy 389.91222 -312.355478) (xy 389.863045 -312.353497)
			(xy 389.814826 -312.343653) (xy 389.76881 -312.326201) (xy 389.726189 -312.301594) (xy 389.688068 -312.270469)
			(xy 389.655433 -312.233632) (xy 389.62913 -312.192036) (xy 389.609839 -312.14676) (xy 389.598062 -312.098976)
			(xy 389.594102 -312.049922) (xy 388.305294 -312.049922) (xy 388.304799 -312.074529) (xy 388.296904 -312.123106)
			(xy 388.28132 -312.169787) (xy 388.258449 -312.213364) (xy 388.228884 -312.252708) (xy 388.193391 -312.2868)
			(xy 388.152888 -312.314756) (xy 388.108426 -312.335854) (xy 388.061155 -312.349546) (xy 388.0123 -312.355478)
			(xy 387.963125 -312.353497) (xy 387.914906 -312.343653) (xy 387.86889 -312.326201) (xy 387.826269 -312.301594)
			(xy 387.788148 -312.270469) (xy 387.755513 -312.233632) (xy 387.72921 -312.192036) (xy 387.709919 -312.14676)
			(xy 387.698142 -312.098976) (xy 387.694182 -312.049922) (xy 386.40512 -312.049922) (xy 386.404625 -312.074529)
			(xy 386.39673 -312.123106) (xy 386.381146 -312.169787) (xy 386.358275 -312.213364) (xy 386.32871 -312.252708)
			(xy 386.293217 -312.2868) (xy 386.252714 -312.314756) (xy 386.208252 -312.335854) (xy 386.160981 -312.349546)
			(xy 386.112126 -312.355478) (xy 386.062951 -312.353497) (xy 386.014732 -312.343653) (xy 385.968716 -312.326201)
			(xy 385.926095 -312.301594) (xy 385.887974 -312.270469) (xy 385.855339 -312.233632) (xy 385.829036 -312.192036)
			(xy 385.809745 -312.14676) (xy 385.797968 -312.098976) (xy 385.794008 -312.049922) (xy 385.45516 -312.049922)
			(xy 385.454665 -312.074529) (xy 385.44677 -312.123106) (xy 385.431186 -312.169787) (xy 385.408315 -312.213364)
			(xy 385.37875 -312.252708) (xy 385.343257 -312.2868) (xy 385.302754 -312.314756) (xy 385.258292 -312.335854)
			(xy 385.211021 -312.349546) (xy 385.162166 -312.355478) (xy 385.112991 -312.353497) (xy 385.064772 -312.343653)
			(xy 385.018756 -312.326201) (xy 384.976135 -312.301594) (xy 384.938014 -312.270469) (xy 384.905379 -312.233632)
			(xy 384.879076 -312.192036) (xy 384.859785 -312.14676) (xy 384.848008 -312.098976) (xy 384.844048 -312.049922)
			(xy 314.955174 -312.049922) (xy 314.954679 -312.074529) (xy 314.946784 -312.123106) (xy 314.9312 -312.169787)
			(xy 314.908329 -312.213364) (xy 314.878764 -312.252708) (xy 314.843271 -312.2868) (xy 314.802768 -312.314756)
			(xy 314.758306 -312.335854) (xy 314.711035 -312.349546) (xy 314.66218 -312.355478) (xy 314.613005 -312.353497)
			(xy 314.564786 -312.343653) (xy 314.51877 -312.326201) (xy 314.476149 -312.301594) (xy 314.438028 -312.270469)
			(xy 314.405393 -312.233632) (xy 314.37909 -312.192036) (xy 314.359799 -312.14676) (xy 314.348022 -312.098976)
			(xy 314.344062 -312.049922) (xy 314.005214 -312.049922) (xy 314.004719 -312.074529) (xy 313.996824 -312.123106)
			(xy 313.98124 -312.169787) (xy 313.958369 -312.213364) (xy 313.928804 -312.252708) (xy 313.893311 -312.2868)
			(xy 313.852808 -312.314756) (xy 313.808346 -312.335854) (xy 313.761075 -312.349546) (xy 313.71222 -312.355478)
			(xy 313.663045 -312.353497) (xy 313.614826 -312.343653) (xy 313.56881 -312.326201) (xy 313.526189 -312.301594)
			(xy 313.488068 -312.270469) (xy 313.455433 -312.233632) (xy 313.42913 -312.192036) (xy 313.409839 -312.14676)
			(xy 313.398062 -312.098976) (xy 313.394102 -312.049922) (xy 312.10504 -312.049922) (xy 312.104545 -312.074529)
			(xy 312.09665 -312.123106) (xy 312.081066 -312.169787) (xy 312.058195 -312.213364) (xy 312.02863 -312.252708)
			(xy 311.993137 -312.2868) (xy 311.952634 -312.314756) (xy 311.908172 -312.335854) (xy 311.860901 -312.349546)
			(xy 311.812046 -312.355478) (xy 311.762871 -312.353497) (xy 311.714652 -312.343653) (xy 311.668636 -312.326201)
			(xy 311.626015 -312.301594) (xy 311.587894 -312.270469) (xy 311.555259 -312.233632) (xy 311.528956 -312.192036)
			(xy 311.509665 -312.14676) (xy 311.497888 -312.098976) (xy 311.493928 -312.049922) (xy 310.20512 -312.049922)
			(xy 310.204625 -312.074529) (xy 310.19673 -312.123106) (xy 310.181146 -312.169787) (xy 310.158275 -312.213364)
			(xy 310.12871 -312.252708) (xy 310.093217 -312.2868) (xy 310.052714 -312.314756) (xy 310.008252 -312.335854)
			(xy 309.960981 -312.349546) (xy 309.912126 -312.355478) (xy 309.862951 -312.353497) (xy 309.814732 -312.343653)
			(xy 309.768716 -312.326201) (xy 309.726095 -312.301594) (xy 309.687974 -312.270469) (xy 309.655339 -312.233632)
			(xy 309.629036 -312.192036) (xy 309.609745 -312.14676) (xy 309.597968 -312.098976) (xy 309.594008 -312.049922)
			(xy 308.3052 -312.049922) (xy 308.304705 -312.074529) (xy 308.29681 -312.123106) (xy 308.281226 -312.169787)
			(xy 308.258355 -312.213364) (xy 308.22879 -312.252708) (xy 308.193297 -312.2868) (xy 308.152794 -312.314756)
			(xy 308.108332 -312.335854) (xy 308.061061 -312.349546) (xy 308.012206 -312.355478) (xy 307.963031 -312.353497)
			(xy 307.914812 -312.343653) (xy 307.868796 -312.326201) (xy 307.826175 -312.301594) (xy 307.788054 -312.270469)
			(xy 307.755419 -312.233632) (xy 307.729116 -312.192036) (xy 307.709825 -312.14676) (xy 307.698048 -312.098976)
			(xy 307.694088 -312.049922) (xy 306.405026 -312.049922) (xy 306.404531 -312.074529) (xy 306.396636 -312.123106)
			(xy 306.381052 -312.169787) (xy 306.358181 -312.213364) (xy 306.328616 -312.252708) (xy 306.293123 -312.2868)
			(xy 306.25262 -312.314756) (xy 306.208158 -312.335854) (xy 306.160887 -312.349546) (xy 306.112032 -312.355478)
			(xy 306.062857 -312.353497) (xy 306.014638 -312.343653) (xy 305.968622 -312.326201) (xy 305.926001 -312.301594)
			(xy 305.88788 -312.270469) (xy 305.855245 -312.233632) (xy 305.828942 -312.192036) (xy 305.809651 -312.14676)
			(xy 305.797874 -312.098976) (xy 305.793914 -312.049922) (xy 304.505106 -312.049922) (xy 304.504611 -312.074529)
			(xy 304.496716 -312.123106) (xy 304.481132 -312.169787) (xy 304.458261 -312.213364) (xy 304.428696 -312.252708)
			(xy 304.393203 -312.2868) (xy 304.3527 -312.314756) (xy 304.308238 -312.335854) (xy 304.260967 -312.349546)
			(xy 304.212112 -312.355478) (xy 304.162937 -312.353497) (xy 304.114718 -312.343653) (xy 304.068702 -312.326201)
			(xy 304.026081 -312.301594) (xy 303.98796 -312.270469) (xy 303.955325 -312.233632) (xy 303.929022 -312.192036)
			(xy 303.909731 -312.14676) (xy 303.897954 -312.098976) (xy 303.893994 -312.049922) (xy 302.605186 -312.049922)
			(xy 302.604691 -312.074529) (xy 302.596796 -312.123106) (xy 302.581212 -312.169787) (xy 302.558341 -312.213364)
			(xy 302.528776 -312.252708) (xy 302.493283 -312.2868) (xy 302.45278 -312.314756) (xy 302.408318 -312.335854)
			(xy 302.361047 -312.349546) (xy 302.312192 -312.355478) (xy 302.263017 -312.353497) (xy 302.214798 -312.343653)
			(xy 302.168782 -312.326201) (xy 302.126161 -312.301594) (xy 302.08804 -312.270469) (xy 302.055405 -312.233632)
			(xy 302.029102 -312.192036) (xy 302.009811 -312.14676) (xy 301.998034 -312.098976) (xy 301.994074 -312.049922)
			(xy 300.705012 -312.049922) (xy 300.704517 -312.074529) (xy 300.696622 -312.123106) (xy 300.681038 -312.169787)
			(xy 300.658167 -312.213364) (xy 300.628602 -312.252708) (xy 300.593109 -312.2868) (xy 300.552606 -312.314756)
			(xy 300.508144 -312.335854) (xy 300.460873 -312.349546) (xy 300.412018 -312.355478) (xy 300.362843 -312.353497)
			(xy 300.314624 -312.343653) (xy 300.268608 -312.326201) (xy 300.225987 -312.301594) (xy 300.187866 -312.270469)
			(xy 300.155231 -312.233632) (xy 300.128928 -312.192036) (xy 300.109637 -312.14676) (xy 300.09786 -312.098976)
			(xy 300.0939 -312.049922) (xy 298.805092 -312.049922) (xy 298.804597 -312.074529) (xy 298.796702 -312.123106)
			(xy 298.781118 -312.169787) (xy 298.758247 -312.213364) (xy 298.728682 -312.252708) (xy 298.693189 -312.2868)
			(xy 298.652686 -312.314756) (xy 298.608224 -312.335854) (xy 298.560953 -312.349546) (xy 298.512098 -312.355478)
			(xy 298.462923 -312.353497) (xy 298.414704 -312.343653) (xy 298.368688 -312.326201) (xy 298.326067 -312.301594)
			(xy 298.287946 -312.270469) (xy 298.255311 -312.233632) (xy 298.229008 -312.192036) (xy 298.209717 -312.14676)
			(xy 298.19794 -312.098976) (xy 298.19398 -312.049922) (xy 296.905172 -312.049922) (xy 296.904677 -312.074529)
			(xy 296.896782 -312.123106) (xy 296.881198 -312.169787) (xy 296.858327 -312.213364) (xy 296.828762 -312.252708)
			(xy 296.793269 -312.2868) (xy 296.752766 -312.314756) (xy 296.708304 -312.335854) (xy 296.661033 -312.349546)
			(xy 296.612178 -312.355478) (xy 296.563003 -312.353497) (xy 296.514784 -312.343653) (xy 296.468768 -312.326201)
			(xy 296.426147 -312.301594) (xy 296.388026 -312.270469) (xy 296.355391 -312.233632) (xy 296.329088 -312.192036)
			(xy 296.309797 -312.14676) (xy 296.29802 -312.098976) (xy 296.29406 -312.049922) (xy 295.004998 -312.049922)
			(xy 295.004503 -312.074529) (xy 294.996608 -312.123106) (xy 294.981024 -312.169787) (xy 294.958153 -312.213364)
			(xy 294.928588 -312.252708) (xy 294.893095 -312.2868) (xy 294.852592 -312.314756) (xy 294.80813 -312.335854)
			(xy 294.760859 -312.349546) (xy 294.712004 -312.355478) (xy 294.662829 -312.353497) (xy 294.61461 -312.343653)
			(xy 294.568594 -312.326201) (xy 294.525973 -312.301594) (xy 294.487852 -312.270469) (xy 294.455217 -312.233632)
			(xy 294.428914 -312.192036) (xy 294.409623 -312.14676) (xy 294.397846 -312.098976) (xy 294.393886 -312.049922)
			(xy 293.105078 -312.049922) (xy 293.104583 -312.074529) (xy 293.096688 -312.123106) (xy 293.081104 -312.169787)
			(xy 293.058233 -312.213364) (xy 293.028668 -312.252708) (xy 292.993175 -312.2868) (xy 292.952672 -312.314756)
			(xy 292.90821 -312.335854) (xy 292.860939 -312.349546) (xy 292.812084 -312.355478) (xy 292.762909 -312.353497)
			(xy 292.71469 -312.343653) (xy 292.668674 -312.326201) (xy 292.626053 -312.301594) (xy 292.587932 -312.270469)
			(xy 292.555297 -312.233632) (xy 292.528994 -312.192036) (xy 292.509703 -312.14676) (xy 292.497926 -312.098976)
			(xy 292.493966 -312.049922) (xy 291.205158 -312.049922) (xy 291.204663 -312.074529) (xy 291.196768 -312.123106)
			(xy 291.181184 -312.169787) (xy 291.158313 -312.213364) (xy 291.128748 -312.252708) (xy 291.093255 -312.2868)
			(xy 291.052752 -312.314756) (xy 291.00829 -312.335854) (xy 290.961019 -312.349546) (xy 290.912164 -312.355478)
			(xy 290.862989 -312.353497) (xy 290.81477 -312.343653) (xy 290.768754 -312.326201) (xy 290.726133 -312.301594)
			(xy 290.688012 -312.270469) (xy 290.655377 -312.233632) (xy 290.629074 -312.192036) (xy 290.609783 -312.14676)
			(xy 290.598006 -312.098976) (xy 290.594046 -312.049922) (xy 289.305238 -312.049922) (xy 289.304743 -312.074529)
			(xy 289.296848 -312.123106) (xy 289.281264 -312.169787) (xy 289.258393 -312.213364) (xy 289.228828 -312.252708)
			(xy 289.193335 -312.2868) (xy 289.152832 -312.314756) (xy 289.10837 -312.335854) (xy 289.061099 -312.349546)
			(xy 289.012244 -312.355478) (xy 288.963069 -312.353497) (xy 288.91485 -312.343653) (xy 288.868834 -312.326201)
			(xy 288.826213 -312.301594) (xy 288.788092 -312.270469) (xy 288.755457 -312.233632) (xy 288.729154 -312.192036)
			(xy 288.709863 -312.14676) (xy 288.698086 -312.098976) (xy 288.694126 -312.049922) (xy 287.405064 -312.049922)
			(xy 287.404569 -312.074529) (xy 287.396674 -312.123106) (xy 287.38109 -312.169787) (xy 287.358219 -312.213364)
			(xy 287.328654 -312.252708) (xy 287.293161 -312.2868) (xy 287.252658 -312.314756) (xy 287.208196 -312.335854)
			(xy 287.160925 -312.349546) (xy 287.11207 -312.355478) (xy 287.062895 -312.353497) (xy 287.014676 -312.343653)
			(xy 286.96866 -312.326201) (xy 286.926039 -312.301594) (xy 286.887918 -312.270469) (xy 286.855283 -312.233632)
			(xy 286.82898 -312.192036) (xy 286.809689 -312.14676) (xy 286.797912 -312.098976) (xy 286.793952 -312.049922)
			(xy 285.505144 -312.049922) (xy 285.504649 -312.074529) (xy 285.496754 -312.123106) (xy 285.48117 -312.169787)
			(xy 285.458299 -312.213364) (xy 285.428734 -312.252708) (xy 285.393241 -312.2868) (xy 285.352738 -312.314756)
			(xy 285.308276 -312.335854) (xy 285.261005 -312.349546) (xy 285.21215 -312.355478) (xy 285.162975 -312.353497)
			(xy 285.114756 -312.343653) (xy 285.06874 -312.326201) (xy 285.026119 -312.301594) (xy 284.987998 -312.270469)
			(xy 284.955363 -312.233632) (xy 284.92906 -312.192036) (xy 284.909769 -312.14676) (xy 284.897992 -312.098976)
			(xy 284.894032 -312.049922) (xy 283.605224 -312.049922) (xy 283.604729 -312.074529) (xy 283.596834 -312.123106)
			(xy 283.58125 -312.169787) (xy 283.558379 -312.213364) (xy 283.528814 -312.252708) (xy 283.493321 -312.2868)
			(xy 283.452818 -312.314756) (xy 283.408356 -312.335854) (xy 283.361085 -312.349546) (xy 283.31223 -312.355478)
			(xy 283.263055 -312.353497) (xy 283.214836 -312.343653) (xy 283.16882 -312.326201) (xy 283.126199 -312.301594)
			(xy 283.088078 -312.270469) (xy 283.055443 -312.233632) (xy 283.02914 -312.192036) (xy 283.009849 -312.14676)
			(xy 282.998072 -312.098976) (xy 282.994112 -312.049922) (xy 281.70505 -312.049922) (xy 281.704555 -312.074529)
			(xy 281.69666 -312.123106) (xy 281.681076 -312.169787) (xy 281.658205 -312.213364) (xy 281.62864 -312.252708)
			(xy 281.593147 -312.2868) (xy 281.552644 -312.314756) (xy 281.508182 -312.335854) (xy 281.460911 -312.349546)
			(xy 281.412056 -312.355478) (xy 281.362881 -312.353497) (xy 281.314662 -312.343653) (xy 281.268646 -312.326201)
			(xy 281.226025 -312.301594) (xy 281.187904 -312.270469) (xy 281.155269 -312.233632) (xy 281.128966 -312.192036)
			(xy 281.109675 -312.14676) (xy 281.097898 -312.098976) (xy 281.093938 -312.049922) (xy 279.80513 -312.049922)
			(xy 279.804635 -312.074529) (xy 279.79674 -312.123106) (xy 279.781156 -312.169787) (xy 279.758285 -312.213364)
			(xy 279.72872 -312.252708) (xy 279.693227 -312.2868) (xy 279.652724 -312.314756) (xy 279.608262 -312.335854)
			(xy 279.560991 -312.349546) (xy 279.512136 -312.355478) (xy 279.462961 -312.353497) (xy 279.414742 -312.343653)
			(xy 279.368726 -312.326201) (xy 279.326105 -312.301594) (xy 279.287984 -312.270469) (xy 279.255349 -312.233632)
			(xy 279.229046 -312.192036) (xy 279.209755 -312.14676) (xy 279.197978 -312.098976) (xy 279.194018 -312.049922)
			(xy 277.90521 -312.049922) (xy 277.904715 -312.074529) (xy 277.89682 -312.123106) (xy 277.881236 -312.169787)
			(xy 277.858365 -312.213364) (xy 277.8288 -312.252708) (xy 277.793307 -312.2868) (xy 277.752804 -312.314756)
			(xy 277.708342 -312.335854) (xy 277.661071 -312.349546) (xy 277.612216 -312.355478) (xy 277.563041 -312.353497)
			(xy 277.514822 -312.343653) (xy 277.468806 -312.326201) (xy 277.426185 -312.301594) (xy 277.388064 -312.270469)
			(xy 277.355429 -312.233632) (xy 277.329126 -312.192036) (xy 277.309835 -312.14676) (xy 277.298058 -312.098976)
			(xy 277.294098 -312.049922) (xy 276.005036 -312.049922) (xy 276.004541 -312.074529) (xy 275.996646 -312.123106)
			(xy 275.981062 -312.169787) (xy 275.958191 -312.213364) (xy 275.928626 -312.252708) (xy 275.893133 -312.2868)
			(xy 275.85263 -312.314756) (xy 275.808168 -312.335854) (xy 275.760897 -312.349546) (xy 275.712042 -312.355478)
			(xy 275.662867 -312.353497) (xy 275.614648 -312.343653) (xy 275.568632 -312.326201) (xy 275.526011 -312.301594)
			(xy 275.48789 -312.270469) (xy 275.455255 -312.233632) (xy 275.428952 -312.192036) (xy 275.409661 -312.14676)
			(xy 275.397884 -312.098976) (xy 275.393924 -312.049922) (xy 274.105116 -312.049922) (xy 274.104621 -312.074529)
			(xy 274.096726 -312.123106) (xy 274.081142 -312.169787) (xy 274.058271 -312.213364) (xy 274.028706 -312.252708)
			(xy 273.993213 -312.2868) (xy 273.95271 -312.314756) (xy 273.908248 -312.335854) (xy 273.860977 -312.349546)
			(xy 273.812122 -312.355478) (xy 273.762947 -312.353497) (xy 273.714728 -312.343653) (xy 273.668712 -312.326201)
			(xy 273.626091 -312.301594) (xy 273.58797 -312.270469) (xy 273.555335 -312.233632) (xy 273.529032 -312.192036)
			(xy 273.509741 -312.14676) (xy 273.497964 -312.098976) (xy 273.494004 -312.049922) (xy 272.205196 -312.049922)
			(xy 272.204701 -312.074529) (xy 272.196806 -312.123106) (xy 272.181222 -312.169787) (xy 272.158351 -312.213364)
			(xy 272.128786 -312.252708) (xy 272.093293 -312.2868) (xy 272.05279 -312.314756) (xy 272.008328 -312.335854)
			(xy 271.961057 -312.349546) (xy 271.912202 -312.355478) (xy 271.863027 -312.353497) (xy 271.814808 -312.343653)
			(xy 271.768792 -312.326201) (xy 271.726171 -312.301594) (xy 271.68805 -312.270469) (xy 271.655415 -312.233632)
			(xy 271.629112 -312.192036) (xy 271.609821 -312.14676) (xy 271.598044 -312.098976) (xy 271.594084 -312.049922)
			(xy 270.305022 -312.049922) (xy 270.304527 -312.074529) (xy 270.296632 -312.123106) (xy 270.281048 -312.169787)
			(xy 270.258177 -312.213364) (xy 270.228612 -312.252708) (xy 270.193119 -312.2868) (xy 270.152616 -312.314756)
			(xy 270.108154 -312.335854) (xy 270.060883 -312.349546) (xy 270.012028 -312.355478) (xy 269.962853 -312.353497)
			(xy 269.914634 -312.343653) (xy 269.868618 -312.326201) (xy 269.825997 -312.301594) (xy 269.787876 -312.270469)
			(xy 269.755241 -312.233632) (xy 269.728938 -312.192036) (xy 269.709647 -312.14676) (xy 269.69787 -312.098976)
			(xy 269.69391 -312.049922) (xy 269.355062 -312.049922) (xy 269.354567 -312.074529) (xy 269.346672 -312.123106)
			(xy 269.331088 -312.169787) (xy 269.308217 -312.213364) (xy 269.278652 -312.252708) (xy 269.243159 -312.2868)
			(xy 269.202656 -312.314756) (xy 269.158194 -312.335854) (xy 269.110923 -312.349546) (xy 269.062068 -312.355478)
			(xy 269.012893 -312.353497) (xy 268.964674 -312.343653) (xy 268.918658 -312.326201) (xy 268.876037 -312.301594)
			(xy 268.837916 -312.270469) (xy 268.805281 -312.233632) (xy 268.778978 -312.192036) (xy 268.759687 -312.14676)
			(xy 268.74791 -312.098976) (xy 268.74395 -312.049922) (xy 198.85533 -312.049922) (xy 198.854835 -312.074529)
			(xy 198.84694 -312.123106) (xy 198.831356 -312.169787) (xy 198.808485 -312.213364) (xy 198.77892 -312.252708)
			(xy 198.743427 -312.2868) (xy 198.702924 -312.314756) (xy 198.658462 -312.335854) (xy 198.611191 -312.349546)
			(xy 198.562336 -312.355478) (xy 198.513161 -312.353497) (xy 198.464942 -312.343653) (xy 198.418926 -312.326201)
			(xy 198.376305 -312.301594) (xy 198.338184 -312.270469) (xy 198.305549 -312.233632) (xy 198.279246 -312.192036)
			(xy 198.259955 -312.14676) (xy 198.248178 -312.098976) (xy 198.244218 -312.049922) (xy 197.90537 -312.049922)
			(xy 197.904875 -312.074529) (xy 197.89698 -312.123106) (xy 197.881396 -312.169787) (xy 197.858525 -312.213364)
			(xy 197.82896 -312.252708) (xy 197.793467 -312.2868) (xy 197.752964 -312.314756) (xy 197.708502 -312.335854)
			(xy 197.661231 -312.349546) (xy 197.612376 -312.355478) (xy 197.563201 -312.353497) (xy 197.514982 -312.343653)
			(xy 197.468966 -312.326201) (xy 197.426345 -312.301594) (xy 197.388224 -312.270469) (xy 197.355589 -312.233632)
			(xy 197.329286 -312.192036) (xy 197.309995 -312.14676) (xy 197.298218 -312.098976) (xy 197.294258 -312.049922)
			(xy 196.005196 -312.049922) (xy 196.004701 -312.074529) (xy 195.996806 -312.123106) (xy 195.981222 -312.169787)
			(xy 195.958351 -312.213364) (xy 195.928786 -312.252708) (xy 195.893293 -312.2868) (xy 195.85279 -312.314756)
			(xy 195.808328 -312.335854) (xy 195.761057 -312.349546) (xy 195.712202 -312.355478) (xy 195.663027 -312.353497)
			(xy 195.614808 -312.343653) (xy 195.568792 -312.326201) (xy 195.526171 -312.301594) (xy 195.48805 -312.270469)
			(xy 195.455415 -312.233632) (xy 195.429112 -312.192036) (xy 195.409821 -312.14676) (xy 195.398044 -312.098976)
			(xy 195.394084 -312.049922) (xy 194.105276 -312.049922) (xy 194.104781 -312.074529) (xy 194.096886 -312.123106)
			(xy 194.081302 -312.169787) (xy 194.058431 -312.213364) (xy 194.028866 -312.252708) (xy 193.993373 -312.2868)
			(xy 193.95287 -312.314756) (xy 193.908408 -312.335854) (xy 193.861137 -312.349546) (xy 193.812282 -312.355478)
			(xy 193.763107 -312.353497) (xy 193.714888 -312.343653) (xy 193.668872 -312.326201) (xy 193.626251 -312.301594)
			(xy 193.58813 -312.270469) (xy 193.555495 -312.233632) (xy 193.529192 -312.192036) (xy 193.509901 -312.14676)
			(xy 193.498124 -312.098976) (xy 193.494164 -312.049922) (xy 192.205356 -312.049922) (xy 192.204861 -312.074529)
			(xy 192.196966 -312.123106) (xy 192.181382 -312.169787) (xy 192.158511 -312.213364) (xy 192.128946 -312.252708)
			(xy 192.093453 -312.2868) (xy 192.05295 -312.314756) (xy 192.008488 -312.335854) (xy 191.961217 -312.349546)
			(xy 191.912362 -312.355478) (xy 191.863187 -312.353497) (xy 191.814968 -312.343653) (xy 191.768952 -312.326201)
			(xy 191.726331 -312.301594) (xy 191.68821 -312.270469) (xy 191.655575 -312.233632) (xy 191.629272 -312.192036)
			(xy 191.609981 -312.14676) (xy 191.598204 -312.098976) (xy 191.594244 -312.049922) (xy 190.305182 -312.049922)
			(xy 190.304687 -312.074529) (xy 190.296792 -312.123106) (xy 190.281208 -312.169787) (xy 190.258337 -312.213364)
			(xy 190.228772 -312.252708) (xy 190.193279 -312.2868) (xy 190.152776 -312.314756) (xy 190.108314 -312.335854)
			(xy 190.061043 -312.349546) (xy 190.012188 -312.355478) (xy 189.963013 -312.353497) (xy 189.914794 -312.343653)
			(xy 189.868778 -312.326201) (xy 189.826157 -312.301594) (xy 189.788036 -312.270469) (xy 189.755401 -312.233632)
			(xy 189.729098 -312.192036) (xy 189.709807 -312.14676) (xy 189.69803 -312.098976) (xy 189.69407 -312.049922)
			(xy 188.405262 -312.049922) (xy 188.404767 -312.074529) (xy 188.396872 -312.123106) (xy 188.381288 -312.169787)
			(xy 188.358417 -312.213364) (xy 188.328852 -312.252708) (xy 188.293359 -312.2868) (xy 188.252856 -312.314756)
			(xy 188.208394 -312.335854) (xy 188.161123 -312.349546) (xy 188.112268 -312.355478) (xy 188.063093 -312.353497)
			(xy 188.014874 -312.343653) (xy 187.968858 -312.326201) (xy 187.926237 -312.301594) (xy 187.888116 -312.270469)
			(xy 187.855481 -312.233632) (xy 187.829178 -312.192036) (xy 187.809887 -312.14676) (xy 187.79811 -312.098976)
			(xy 187.79415 -312.049922) (xy 186.505342 -312.049922) (xy 186.504847 -312.074529) (xy 186.496952 -312.123106)
			(xy 186.481368 -312.169787) (xy 186.458497 -312.213364) (xy 186.428932 -312.252708) (xy 186.393439 -312.2868)
			(xy 186.352936 -312.314756) (xy 186.308474 -312.335854) (xy 186.261203 -312.349546) (xy 186.212348 -312.355478)
			(xy 186.163173 -312.353497) (xy 186.114954 -312.343653) (xy 186.068938 -312.326201) (xy 186.026317 -312.301594)
			(xy 185.988196 -312.270469) (xy 185.955561 -312.233632) (xy 185.929258 -312.192036) (xy 185.909967 -312.14676)
			(xy 185.89819 -312.098976) (xy 185.89423 -312.049922) (xy 184.605168 -312.049922) (xy 184.604673 -312.074529)
			(xy 184.596778 -312.123106) (xy 184.581194 -312.169787) (xy 184.558323 -312.213364) (xy 184.528758 -312.252708)
			(xy 184.493265 -312.2868) (xy 184.452762 -312.314756) (xy 184.4083 -312.335854) (xy 184.361029 -312.349546)
			(xy 184.312174 -312.355478) (xy 184.262999 -312.353497) (xy 184.21478 -312.343653) (xy 184.168764 -312.326201)
			(xy 184.126143 -312.301594) (xy 184.088022 -312.270469) (xy 184.055387 -312.233632) (xy 184.029084 -312.192036)
			(xy 184.009793 -312.14676) (xy 183.998016 -312.098976) (xy 183.994056 -312.049922) (xy 182.705248 -312.049922)
			(xy 182.704753 -312.074529) (xy 182.696858 -312.123106) (xy 182.681274 -312.169787) (xy 182.658403 -312.213364)
			(xy 182.628838 -312.252708) (xy 182.593345 -312.2868) (xy 182.552842 -312.314756) (xy 182.50838 -312.335854)
			(xy 182.461109 -312.349546) (xy 182.412254 -312.355478) (xy 182.363079 -312.353497) (xy 182.31486 -312.343653)
			(xy 182.268844 -312.326201) (xy 182.226223 -312.301594) (xy 182.188102 -312.270469) (xy 182.155467 -312.233632)
			(xy 182.129164 -312.192036) (xy 182.109873 -312.14676) (xy 182.098096 -312.098976) (xy 182.094136 -312.049922)
			(xy 180.805328 -312.049922) (xy 180.804833 -312.074529) (xy 180.796938 -312.123106) (xy 180.781354 -312.169787)
			(xy 180.758483 -312.213364) (xy 180.728918 -312.252708) (xy 180.693425 -312.2868) (xy 180.652922 -312.314756)
			(xy 180.60846 -312.335854) (xy 180.561189 -312.349546) (xy 180.512334 -312.355478) (xy 180.463159 -312.353497)
			(xy 180.41494 -312.343653) (xy 180.368924 -312.326201) (xy 180.326303 -312.301594) (xy 180.288182 -312.270469)
			(xy 180.255547 -312.233632) (xy 180.229244 -312.192036) (xy 180.209953 -312.14676) (xy 180.198176 -312.098976)
			(xy 180.194216 -312.049922) (xy 178.905154 -312.049922) (xy 178.904659 -312.074529) (xy 178.896764 -312.123106)
			(xy 178.88118 -312.169787) (xy 178.858309 -312.213364) (xy 178.828744 -312.252708) (xy 178.793251 -312.2868)
			(xy 178.752748 -312.314756) (xy 178.708286 -312.335854) (xy 178.661015 -312.349546) (xy 178.61216 -312.355478)
			(xy 178.562985 -312.353497) (xy 178.514766 -312.343653) (xy 178.46875 -312.326201) (xy 178.426129 -312.301594)
			(xy 178.388008 -312.270469) (xy 178.355373 -312.233632) (xy 178.32907 -312.192036) (xy 178.309779 -312.14676)
			(xy 178.298002 -312.098976) (xy 178.294042 -312.049922) (xy 177.005234 -312.049922) (xy 177.004739 -312.074529)
			(xy 176.996844 -312.123106) (xy 176.98126 -312.169787) (xy 176.958389 -312.213364) (xy 176.928824 -312.252708)
			(xy 176.893331 -312.2868) (xy 176.852828 -312.314756) (xy 176.808366 -312.335854) (xy 176.761095 -312.349546)
			(xy 176.71224 -312.355478) (xy 176.663065 -312.353497) (xy 176.614846 -312.343653) (xy 176.56883 -312.326201)
			(xy 176.526209 -312.301594) (xy 176.488088 -312.270469) (xy 176.455453 -312.233632) (xy 176.42915 -312.192036)
			(xy 176.409859 -312.14676) (xy 176.398082 -312.098976) (xy 176.394122 -312.049922) (xy 175.105314 -312.049922)
			(xy 175.104819 -312.074529) (xy 175.096924 -312.123106) (xy 175.08134 -312.169787) (xy 175.058469 -312.213364)
			(xy 175.028904 -312.252708) (xy 174.993411 -312.2868) (xy 174.952908 -312.314756) (xy 174.908446 -312.335854)
			(xy 174.861175 -312.349546) (xy 174.81232 -312.355478) (xy 174.763145 -312.353497) (xy 174.714926 -312.343653)
			(xy 174.66891 -312.326201) (xy 174.626289 -312.301594) (xy 174.588168 -312.270469) (xy 174.555533 -312.233632)
			(xy 174.52923 -312.192036) (xy 174.509939 -312.14676) (xy 174.498162 -312.098976) (xy 174.494202 -312.049922)
			(xy 173.205394 -312.049922) (xy 173.204899 -312.074529) (xy 173.197004 -312.123106) (xy 173.18142 -312.169787)
			(xy 173.158549 -312.213364) (xy 173.128984 -312.252708) (xy 173.093491 -312.2868) (xy 173.052988 -312.314756)
			(xy 173.008526 -312.335854) (xy 172.961255 -312.349546) (xy 172.9124 -312.355478) (xy 172.863225 -312.353497)
			(xy 172.815006 -312.343653) (xy 172.76899 -312.326201) (xy 172.726369 -312.301594) (xy 172.688248 -312.270469)
			(xy 172.655613 -312.233632) (xy 172.62931 -312.192036) (xy 172.610019 -312.14676) (xy 172.598242 -312.098976)
			(xy 172.594282 -312.049922) (xy 171.30522 -312.049922) (xy 171.304725 -312.074529) (xy 171.29683 -312.123106)
			(xy 171.281246 -312.169787) (xy 171.258375 -312.213364) (xy 171.22881 -312.252708) (xy 171.193317 -312.2868)
			(xy 171.152814 -312.314756) (xy 171.108352 -312.335854) (xy 171.061081 -312.349546) (xy 171.012226 -312.355478)
			(xy 170.963051 -312.353497) (xy 170.914832 -312.343653) (xy 170.868816 -312.326201) (xy 170.826195 -312.301594)
			(xy 170.788074 -312.270469) (xy 170.755439 -312.233632) (xy 170.729136 -312.192036) (xy 170.709845 -312.14676)
			(xy 170.698068 -312.098976) (xy 170.694108 -312.049922) (xy 169.4053 -312.049922) (xy 169.404805 -312.074529)
			(xy 169.39691 -312.123106) (xy 169.381326 -312.169787) (xy 169.358455 -312.213364) (xy 169.32889 -312.252708)
			(xy 169.293397 -312.2868) (xy 169.252894 -312.314756) (xy 169.208432 -312.335854) (xy 169.161161 -312.349546)
			(xy 169.112306 -312.355478) (xy 169.063131 -312.353497) (xy 169.014912 -312.343653) (xy 168.968896 -312.326201)
			(xy 168.926275 -312.301594) (xy 168.888154 -312.270469) (xy 168.855519 -312.233632) (xy 168.829216 -312.192036)
			(xy 168.809925 -312.14676) (xy 168.798148 -312.098976) (xy 168.794188 -312.049922) (xy 167.50538 -312.049922)
			(xy 167.504885 -312.074529) (xy 167.49699 -312.123106) (xy 167.481406 -312.169787) (xy 167.458535 -312.213364)
			(xy 167.42897 -312.252708) (xy 167.393477 -312.2868) (xy 167.352974 -312.314756) (xy 167.308512 -312.335854)
			(xy 167.261241 -312.349546) (xy 167.212386 -312.355478) (xy 167.163211 -312.353497) (xy 167.114992 -312.343653)
			(xy 167.068976 -312.326201) (xy 167.026355 -312.301594) (xy 166.988234 -312.270469) (xy 166.955599 -312.233632)
			(xy 166.929296 -312.192036) (xy 166.910005 -312.14676) (xy 166.898228 -312.098976) (xy 166.894268 -312.049922)
			(xy 165.605206 -312.049922) (xy 165.604711 -312.074529) (xy 165.596816 -312.123106) (xy 165.581232 -312.169787)
			(xy 165.558361 -312.213364) (xy 165.528796 -312.252708) (xy 165.493303 -312.2868) (xy 165.4528 -312.314756)
			(xy 165.408338 -312.335854) (xy 165.361067 -312.349546) (xy 165.312212 -312.355478) (xy 165.263037 -312.353497)
			(xy 165.214818 -312.343653) (xy 165.168802 -312.326201) (xy 165.126181 -312.301594) (xy 165.08806 -312.270469)
			(xy 165.055425 -312.233632) (xy 165.029122 -312.192036) (xy 165.009831 -312.14676) (xy 164.998054 -312.098976)
			(xy 164.994094 -312.049922) (xy 163.705286 -312.049922) (xy 163.704791 -312.074529) (xy 163.696896 -312.123106)
			(xy 163.681312 -312.169787) (xy 163.658441 -312.213364) (xy 163.628876 -312.252708) (xy 163.593383 -312.2868)
			(xy 163.55288 -312.314756) (xy 163.508418 -312.335854) (xy 163.461147 -312.349546) (xy 163.412292 -312.355478)
			(xy 163.363117 -312.353497) (xy 163.314898 -312.343653) (xy 163.268882 -312.326201) (xy 163.226261 -312.301594)
			(xy 163.18814 -312.270469) (xy 163.155505 -312.233632) (xy 163.129202 -312.192036) (xy 163.109911 -312.14676)
			(xy 163.098134 -312.098976) (xy 163.094174 -312.049922) (xy 161.805366 -312.049922) (xy 161.804871 -312.074529)
			(xy 161.796976 -312.123106) (xy 161.781392 -312.169787) (xy 161.758521 -312.213364) (xy 161.728956 -312.252708)
			(xy 161.693463 -312.2868) (xy 161.65296 -312.314756) (xy 161.608498 -312.335854) (xy 161.561227 -312.349546)
			(xy 161.512372 -312.355478) (xy 161.463197 -312.353497) (xy 161.414978 -312.343653) (xy 161.368962 -312.326201)
			(xy 161.326341 -312.301594) (xy 161.28822 -312.270469) (xy 161.255585 -312.233632) (xy 161.229282 -312.192036)
			(xy 161.209991 -312.14676) (xy 161.198214 -312.098976) (xy 161.194254 -312.049922) (xy 159.905192 -312.049922)
			(xy 159.904697 -312.074529) (xy 159.896802 -312.123106) (xy 159.881218 -312.169787) (xy 159.858347 -312.213364)
			(xy 159.828782 -312.252708) (xy 159.793289 -312.2868) (xy 159.752786 -312.314756) (xy 159.708324 -312.335854)
			(xy 159.661053 -312.349546) (xy 159.612198 -312.355478) (xy 159.563023 -312.353497) (xy 159.514804 -312.343653)
			(xy 159.468788 -312.326201) (xy 159.426167 -312.301594) (xy 159.388046 -312.270469) (xy 159.355411 -312.233632)
			(xy 159.329108 -312.192036) (xy 159.309817 -312.14676) (xy 159.29804 -312.098976) (xy 159.29408 -312.049922)
			(xy 158.005272 -312.049922) (xy 158.004777 -312.074529) (xy 157.996882 -312.123106) (xy 157.981298 -312.169787)
			(xy 157.958427 -312.213364) (xy 157.928862 -312.252708) (xy 157.893369 -312.2868) (xy 157.852866 -312.314756)
			(xy 157.808404 -312.335854) (xy 157.761133 -312.349546) (xy 157.712278 -312.355478) (xy 157.663103 -312.353497)
			(xy 157.614884 -312.343653) (xy 157.568868 -312.326201) (xy 157.526247 -312.301594) (xy 157.488126 -312.270469)
			(xy 157.455491 -312.233632) (xy 157.429188 -312.192036) (xy 157.409897 -312.14676) (xy 157.39812 -312.098976)
			(xy 157.39416 -312.049922) (xy 156.105352 -312.049922) (xy 156.104857 -312.074529) (xy 156.096962 -312.123106)
			(xy 156.081378 -312.169787) (xy 156.058507 -312.213364) (xy 156.028942 -312.252708) (xy 155.993449 -312.2868)
			(xy 155.952946 -312.314756) (xy 155.908484 -312.335854) (xy 155.861213 -312.349546) (xy 155.812358 -312.355478)
			(xy 155.763183 -312.353497) (xy 155.714964 -312.343653) (xy 155.668948 -312.326201) (xy 155.626327 -312.301594)
			(xy 155.588206 -312.270469) (xy 155.555571 -312.233632) (xy 155.529268 -312.192036) (xy 155.509977 -312.14676)
			(xy 155.4982 -312.098976) (xy 155.49424 -312.049922) (xy 154.205178 -312.049922) (xy 154.204683 -312.074529)
			(xy 154.196788 -312.123106) (xy 154.181204 -312.169787) (xy 154.158333 -312.213364) (xy 154.128768 -312.252708)
			(xy 154.093275 -312.2868) (xy 154.052772 -312.314756) (xy 154.00831 -312.335854) (xy 153.961039 -312.349546)
			(xy 153.912184 -312.355478) (xy 153.863009 -312.353497) (xy 153.81479 -312.343653) (xy 153.768774 -312.326201)
			(xy 153.726153 -312.301594) (xy 153.688032 -312.270469) (xy 153.655397 -312.233632) (xy 153.629094 -312.192036)
			(xy 153.609803 -312.14676) (xy 153.598026 -312.098976) (xy 153.594066 -312.049922) (xy 153.255218 -312.049922)
			(xy 153.254723 -312.074529) (xy 153.246828 -312.123106) (xy 153.231244 -312.169787) (xy 153.208373 -312.213364)
			(xy 153.178808 -312.252708) (xy 153.143315 -312.2868) (xy 153.102812 -312.314756) (xy 153.05835 -312.335854)
			(xy 153.011079 -312.349546) (xy 152.962224 -312.355478) (xy 152.913049 -312.353497) (xy 152.86483 -312.343653)
			(xy 152.818814 -312.326201) (xy 152.776193 -312.301594) (xy 152.738072 -312.270469) (xy 152.705437 -312.233632)
			(xy 152.679134 -312.192036) (xy 152.659843 -312.14676) (xy 152.648066 -312.098976) (xy 152.644106 -312.049922)
			(xy 82.755232 -312.049922) (xy 82.754737 -312.074529) (xy 82.746842 -312.123106) (xy 82.731258 -312.169787)
			(xy 82.708387 -312.213364) (xy 82.678822 -312.252708) (xy 82.643329 -312.2868) (xy 82.602826 -312.314756)
			(xy 82.558364 -312.335854) (xy 82.511093 -312.349546) (xy 82.462238 -312.355478) (xy 82.413063 -312.353497)
			(xy 82.364844 -312.343653) (xy 82.318828 -312.326201) (xy 82.276207 -312.301594) (xy 82.238086 -312.270469)
			(xy 82.205451 -312.233632) (xy 82.179148 -312.192036) (xy 82.159857 -312.14676) (xy 82.14808 -312.098976)
			(xy 82.14412 -312.049922) (xy 81.805272 -312.049922) (xy 81.804777 -312.074529) (xy 81.796882 -312.123106)
			(xy 81.781298 -312.169787) (xy 81.758427 -312.213364) (xy 81.728862 -312.252708) (xy 81.693369 -312.2868)
			(xy 81.652866 -312.314756) (xy 81.608404 -312.335854) (xy 81.561133 -312.349546) (xy 81.512278 -312.355478)
			(xy 81.463103 -312.353497) (xy 81.414884 -312.343653) (xy 81.368868 -312.326201) (xy 81.326247 -312.301594)
			(xy 81.288126 -312.270469) (xy 81.255491 -312.233632) (xy 81.229188 -312.192036) (xy 81.209897 -312.14676)
			(xy 81.19812 -312.098976) (xy 81.19416 -312.049922) (xy 79.905098 -312.049922) (xy 79.904603 -312.074529)
			(xy 79.896708 -312.123106) (xy 79.881124 -312.169787) (xy 79.858253 -312.213364) (xy 79.828688 -312.252708)
			(xy 79.793195 -312.2868) (xy 79.752692 -312.314756) (xy 79.70823 -312.335854) (xy 79.660959 -312.349546)
			(xy 79.612104 -312.355478) (xy 79.562929 -312.353497) (xy 79.51471 -312.343653) (xy 79.468694 -312.326201)
			(xy 79.426073 -312.301594) (xy 79.387952 -312.270469) (xy 79.355317 -312.233632) (xy 79.329014 -312.192036)
			(xy 79.309723 -312.14676) (xy 79.297946 -312.098976) (xy 79.293986 -312.049922) (xy 78.005178 -312.049922)
			(xy 78.004683 -312.074529) (xy 77.996788 -312.123106) (xy 77.981204 -312.169787) (xy 77.958333 -312.213364)
			(xy 77.928768 -312.252708) (xy 77.893275 -312.2868) (xy 77.852772 -312.314756) (xy 77.80831 -312.335854)
			(xy 77.761039 -312.349546) (xy 77.712184 -312.355478) (xy 77.663009 -312.353497) (xy 77.61479 -312.343653)
			(xy 77.568774 -312.326201) (xy 77.526153 -312.301594) (xy 77.488032 -312.270469) (xy 77.455397 -312.233632)
			(xy 77.429094 -312.192036) (xy 77.409803 -312.14676) (xy 77.398026 -312.098976) (xy 77.394066 -312.049922)
			(xy 76.105258 -312.049922) (xy 76.104763 -312.074529) (xy 76.096868 -312.123106) (xy 76.081284 -312.169787)
			(xy 76.058413 -312.213364) (xy 76.028848 -312.252708) (xy 75.993355 -312.2868) (xy 75.952852 -312.314756)
			(xy 75.90839 -312.335854) (xy 75.861119 -312.349546) (xy 75.812264 -312.355478) (xy 75.763089 -312.353497)
			(xy 75.71487 -312.343653) (xy 75.668854 -312.326201) (xy 75.626233 -312.301594) (xy 75.588112 -312.270469)
			(xy 75.555477 -312.233632) (xy 75.529174 -312.192036) (xy 75.509883 -312.14676) (xy 75.498106 -312.098976)
			(xy 75.494146 -312.049922) (xy 74.205084 -312.049922) (xy 74.204589 -312.074529) (xy 74.196694 -312.123106)
			(xy 74.18111 -312.169787) (xy 74.158239 -312.213364) (xy 74.128674 -312.252708) (xy 74.093181 -312.2868)
			(xy 74.052678 -312.314756) (xy 74.008216 -312.335854) (xy 73.960945 -312.349546) (xy 73.91209 -312.355478)
			(xy 73.862915 -312.353497) (xy 73.814696 -312.343653) (xy 73.76868 -312.326201) (xy 73.726059 -312.301594)
			(xy 73.687938 -312.270469) (xy 73.655303 -312.233632) (xy 73.629 -312.192036) (xy 73.609709 -312.14676)
			(xy 73.597932 -312.098976) (xy 73.593972 -312.049922) (xy 72.305164 -312.049922) (xy 72.304669 -312.074529)
			(xy 72.296774 -312.123106) (xy 72.28119 -312.169787) (xy 72.258319 -312.213364) (xy 72.228754 -312.252708)
			(xy 72.193261 -312.2868) (xy 72.152758 -312.314756) (xy 72.108296 -312.335854) (xy 72.061025 -312.349546)
			(xy 72.01217 -312.355478) (xy 71.962995 -312.353497) (xy 71.914776 -312.343653) (xy 71.86876 -312.326201)
			(xy 71.826139 -312.301594) (xy 71.788018 -312.270469) (xy 71.755383 -312.233632) (xy 71.72908 -312.192036)
			(xy 71.709789 -312.14676) (xy 71.698012 -312.098976) (xy 71.694052 -312.049922) (xy 70.405244 -312.049922)
			(xy 70.404749 -312.074529) (xy 70.396854 -312.123106) (xy 70.38127 -312.169787) (xy 70.358399 -312.213364)
			(xy 70.328834 -312.252708) (xy 70.293341 -312.2868) (xy 70.252838 -312.314756) (xy 70.208376 -312.335854)
			(xy 70.161105 -312.349546) (xy 70.11225 -312.355478) (xy 70.063075 -312.353497) (xy 70.014856 -312.343653)
			(xy 69.96884 -312.326201) (xy 69.926219 -312.301594) (xy 69.888098 -312.270469) (xy 69.855463 -312.233632)
			(xy 69.82916 -312.192036) (xy 69.809869 -312.14676) (xy 69.798092 -312.098976) (xy 69.794132 -312.049922)
			(xy 68.50507 -312.049922) (xy 68.504575 -312.074529) (xy 68.49668 -312.123106) (xy 68.481096 -312.169787)
			(xy 68.458225 -312.213364) (xy 68.42866 -312.252708) (xy 68.393167 -312.2868) (xy 68.352664 -312.314756)
			(xy 68.308202 -312.335854) (xy 68.260931 -312.349546) (xy 68.212076 -312.355478) (xy 68.162901 -312.353497)
			(xy 68.114682 -312.343653) (xy 68.068666 -312.326201) (xy 68.026045 -312.301594) (xy 67.987924 -312.270469)
			(xy 67.955289 -312.233632) (xy 67.928986 -312.192036) (xy 67.909695 -312.14676) (xy 67.897918 -312.098976)
			(xy 67.893958 -312.049922) (xy 66.60515 -312.049922) (xy 66.604655 -312.074529) (xy 66.59676 -312.123106)
			(xy 66.581176 -312.169787) (xy 66.558305 -312.213364) (xy 66.52874 -312.252708) (xy 66.493247 -312.2868)
			(xy 66.452744 -312.314756) (xy 66.408282 -312.335854) (xy 66.361011 -312.349546) (xy 66.312156 -312.355478)
			(xy 66.262981 -312.353497) (xy 66.214762 -312.343653) (xy 66.168746 -312.326201) (xy 66.126125 -312.301594)
			(xy 66.088004 -312.270469) (xy 66.055369 -312.233632) (xy 66.029066 -312.192036) (xy 66.009775 -312.14676)
			(xy 65.997998 -312.098976) (xy 65.994038 -312.049922) (xy 64.70523 -312.049922) (xy 64.704735 -312.074529)
			(xy 64.69684 -312.123106) (xy 64.681256 -312.169787) (xy 64.658385 -312.213364) (xy 64.62882 -312.252708)
			(xy 64.593327 -312.2868) (xy 64.552824 -312.314756) (xy 64.508362 -312.335854) (xy 64.461091 -312.349546)
			(xy 64.412236 -312.355478) (xy 64.363061 -312.353497) (xy 64.314842 -312.343653) (xy 64.268826 -312.326201)
			(xy 64.226205 -312.301594) (xy 64.188084 -312.270469) (xy 64.155449 -312.233632) (xy 64.129146 -312.192036)
			(xy 64.109855 -312.14676) (xy 64.098078 -312.098976) (xy 64.094118 -312.049922) (xy 62.805056 -312.049922)
			(xy 62.804561 -312.074529) (xy 62.796666 -312.123106) (xy 62.781082 -312.169787) (xy 62.758211 -312.213364)
			(xy 62.728646 -312.252708) (xy 62.693153 -312.2868) (xy 62.65265 -312.314756) (xy 62.608188 -312.335854)
			(xy 62.560917 -312.349546) (xy 62.512062 -312.355478) (xy 62.462887 -312.353497) (xy 62.414668 -312.343653)
			(xy 62.368652 -312.326201) (xy 62.326031 -312.301594) (xy 62.28791 -312.270469) (xy 62.255275 -312.233632)
			(xy 62.228972 -312.192036) (xy 62.209681 -312.14676) (xy 62.197904 -312.098976) (xy 62.193944 -312.049922)
			(xy 60.905136 -312.049922) (xy 60.904641 -312.074529) (xy 60.896746 -312.123106) (xy 60.881162 -312.169787)
			(xy 60.858291 -312.213364) (xy 60.828726 -312.252708) (xy 60.793233 -312.2868) (xy 60.75273 -312.314756)
			(xy 60.708268 -312.335854) (xy 60.660997 -312.349546) (xy 60.612142 -312.355478) (xy 60.562967 -312.353497)
			(xy 60.514748 -312.343653) (xy 60.468732 -312.326201) (xy 60.426111 -312.301594) (xy 60.38799 -312.270469)
			(xy 60.355355 -312.233632) (xy 60.329052 -312.192036) (xy 60.309761 -312.14676) (xy 60.297984 -312.098976)
			(xy 60.294024 -312.049922) (xy 59.005216 -312.049922) (xy 59.004721 -312.074529) (xy 58.996826 -312.123106)
			(xy 58.981242 -312.169787) (xy 58.958371 -312.213364) (xy 58.928806 -312.252708) (xy 58.893313 -312.2868)
			(xy 58.85281 -312.314756) (xy 58.808348 -312.335854) (xy 58.761077 -312.349546) (xy 58.712222 -312.355478)
			(xy 58.663047 -312.353497) (xy 58.614828 -312.343653) (xy 58.568812 -312.326201) (xy 58.526191 -312.301594)
			(xy 58.48807 -312.270469) (xy 58.455435 -312.233632) (xy 58.429132 -312.192036) (xy 58.409841 -312.14676)
			(xy 58.398064 -312.098976) (xy 58.394104 -312.049922) (xy 57.105296 -312.049922) (xy 57.104801 -312.074529)
			(xy 57.096906 -312.123106) (xy 57.081322 -312.169787) (xy 57.058451 -312.213364) (xy 57.028886 -312.252708)
			(xy 56.993393 -312.2868) (xy 56.95289 -312.314756) (xy 56.908428 -312.335854) (xy 56.861157 -312.349546)
			(xy 56.812302 -312.355478) (xy 56.763127 -312.353497) (xy 56.714908 -312.343653) (xy 56.668892 -312.326201)
			(xy 56.626271 -312.301594) (xy 56.58815 -312.270469) (xy 56.555515 -312.233632) (xy 56.529212 -312.192036)
			(xy 56.509921 -312.14676) (xy 56.498144 -312.098976) (xy 56.494184 -312.049922) (xy 55.205122 -312.049922)
			(xy 55.204627 -312.074529) (xy 55.196732 -312.123106) (xy 55.181148 -312.169787) (xy 55.158277 -312.213364)
			(xy 55.128712 -312.252708) (xy 55.093219 -312.2868) (xy 55.052716 -312.314756) (xy 55.008254 -312.335854)
			(xy 54.960983 -312.349546) (xy 54.912128 -312.355478) (xy 54.862953 -312.353497) (xy 54.814734 -312.343653)
			(xy 54.768718 -312.326201) (xy 54.726097 -312.301594) (xy 54.687976 -312.270469) (xy 54.655341 -312.233632)
			(xy 54.629038 -312.192036) (xy 54.609747 -312.14676) (xy 54.59797 -312.098976) (xy 54.59401 -312.049922)
			(xy 53.305202 -312.049922) (xy 53.304707 -312.074529) (xy 53.296812 -312.123106) (xy 53.281228 -312.169787)
			(xy 53.258357 -312.213364) (xy 53.228792 -312.252708) (xy 53.193299 -312.2868) (xy 53.152796 -312.314756)
			(xy 53.108334 -312.335854) (xy 53.061063 -312.349546) (xy 53.012208 -312.355478) (xy 52.963033 -312.353497)
			(xy 52.914814 -312.343653) (xy 52.868798 -312.326201) (xy 52.826177 -312.301594) (xy 52.788056 -312.270469)
			(xy 52.755421 -312.233632) (xy 52.729118 -312.192036) (xy 52.709827 -312.14676) (xy 52.69805 -312.098976)
			(xy 52.69409 -312.049922) (xy 51.405282 -312.049922) (xy 51.404787 -312.074529) (xy 51.396892 -312.123106)
			(xy 51.381308 -312.169787) (xy 51.358437 -312.213364) (xy 51.328872 -312.252708) (xy 51.293379 -312.2868)
			(xy 51.252876 -312.314756) (xy 51.208414 -312.335854) (xy 51.161143 -312.349546) (xy 51.112288 -312.355478)
			(xy 51.063113 -312.353497) (xy 51.014894 -312.343653) (xy 50.968878 -312.326201) (xy 50.926257 -312.301594)
			(xy 50.888136 -312.270469) (xy 50.855501 -312.233632) (xy 50.829198 -312.192036) (xy 50.809907 -312.14676)
			(xy 50.79813 -312.098976) (xy 50.79417 -312.049922) (xy 49.505108 -312.049922) (xy 49.504613 -312.074529)
			(xy 49.496718 -312.123106) (xy 49.481134 -312.169787) (xy 49.458263 -312.213364) (xy 49.428698 -312.252708)
			(xy 49.393205 -312.2868) (xy 49.352702 -312.314756) (xy 49.30824 -312.335854) (xy 49.260969 -312.349546)
			(xy 49.212114 -312.355478) (xy 49.162939 -312.353497) (xy 49.11472 -312.343653) (xy 49.068704 -312.326201)
			(xy 49.026083 -312.301594) (xy 48.987962 -312.270469) (xy 48.955327 -312.233632) (xy 48.929024 -312.192036)
			(xy 48.909733 -312.14676) (xy 48.897956 -312.098976) (xy 48.893996 -312.049922) (xy 47.605188 -312.049922)
			(xy 47.604693 -312.074529) (xy 47.596798 -312.123106) (xy 47.581214 -312.169787) (xy 47.558343 -312.213364)
			(xy 47.528778 -312.252708) (xy 47.493285 -312.2868) (xy 47.452782 -312.314756) (xy 47.40832 -312.335854)
			(xy 47.361049 -312.349546) (xy 47.312194 -312.355478) (xy 47.263019 -312.353497) (xy 47.2148 -312.343653)
			(xy 47.168784 -312.326201) (xy 47.126163 -312.301594) (xy 47.088042 -312.270469) (xy 47.055407 -312.233632)
			(xy 47.029104 -312.192036) (xy 47.009813 -312.14676) (xy 46.998036 -312.098976) (xy 46.994076 -312.049922)
			(xy 45.705268 -312.049922) (xy 45.704773 -312.074529) (xy 45.696878 -312.123106) (xy 45.681294 -312.169787)
			(xy 45.658423 -312.213364) (xy 45.628858 -312.252708) (xy 45.593365 -312.2868) (xy 45.552862 -312.314756)
			(xy 45.5084 -312.335854) (xy 45.461129 -312.349546) (xy 45.412274 -312.355478) (xy 45.363099 -312.353497)
			(xy 45.31488 -312.343653) (xy 45.268864 -312.326201) (xy 45.226243 -312.301594) (xy 45.188122 -312.270469)
			(xy 45.155487 -312.233632) (xy 45.129184 -312.192036) (xy 45.109893 -312.14676) (xy 45.098116 -312.098976)
			(xy 45.094156 -312.049922) (xy 43.805094 -312.049922) (xy 43.804599 -312.074529) (xy 43.796704 -312.123106)
			(xy 43.78112 -312.169787) (xy 43.758249 -312.213364) (xy 43.728684 -312.252708) (xy 43.693191 -312.2868)
			(xy 43.652688 -312.314756) (xy 43.608226 -312.335854) (xy 43.560955 -312.349546) (xy 43.5121 -312.355478)
			(xy 43.462925 -312.353497) (xy 43.414706 -312.343653) (xy 43.36869 -312.326201) (xy 43.326069 -312.301594)
			(xy 43.287948 -312.270469) (xy 43.255313 -312.233632) (xy 43.22901 -312.192036) (xy 43.209719 -312.14676)
			(xy 43.197942 -312.098976) (xy 43.193982 -312.049922) (xy 41.905174 -312.049922) (xy 41.904679 -312.074529)
			(xy 41.896784 -312.123106) (xy 41.8812 -312.169787) (xy 41.858329 -312.213364) (xy 41.828764 -312.252708)
			(xy 41.793271 -312.2868) (xy 41.752768 -312.314756) (xy 41.708306 -312.335854) (xy 41.661035 -312.349546)
			(xy 41.61218 -312.355478) (xy 41.563005 -312.353497) (xy 41.514786 -312.343653) (xy 41.46877 -312.326201)
			(xy 41.426149 -312.301594) (xy 41.388028 -312.270469) (xy 41.355393 -312.233632) (xy 41.32909 -312.192036)
			(xy 41.309799 -312.14676) (xy 41.298022 -312.098976) (xy 41.294062 -312.049922) (xy 40.005254 -312.049922)
			(xy 40.004759 -312.074529) (xy 39.996864 -312.123106) (xy 39.98128 -312.169787) (xy 39.958409 -312.213364)
			(xy 39.928844 -312.252708) (xy 39.893351 -312.2868) (xy 39.852848 -312.314756) (xy 39.808386 -312.335854)
			(xy 39.761115 -312.349546) (xy 39.71226 -312.355478) (xy 39.663085 -312.353497) (xy 39.614866 -312.343653)
			(xy 39.56885 -312.326201) (xy 39.526229 -312.301594) (xy 39.488108 -312.270469) (xy 39.455473 -312.233632)
			(xy 39.42917 -312.192036) (xy 39.409879 -312.14676) (xy 39.398102 -312.098976) (xy 39.394142 -312.049922)
			(xy 38.10508 -312.049922) (xy 38.104585 -312.074529) (xy 38.09669 -312.123106) (xy 38.081106 -312.169787)
			(xy 38.058235 -312.213364) (xy 38.02867 -312.252708) (xy 37.993177 -312.2868) (xy 37.952674 -312.314756)
			(xy 37.908212 -312.335854) (xy 37.860941 -312.349546) (xy 37.812086 -312.355478) (xy 37.762911 -312.353497)
			(xy 37.714692 -312.343653) (xy 37.668676 -312.326201) (xy 37.626055 -312.301594) (xy 37.587934 -312.270469)
			(xy 37.555299 -312.233632) (xy 37.528996 -312.192036) (xy 37.509705 -312.14676) (xy 37.497928 -312.098976)
			(xy 37.493968 -312.049922) (xy 37.15512 -312.049922) (xy 37.154625 -312.074529) (xy 37.14673 -312.123106)
			(xy 37.131146 -312.169787) (xy 37.108275 -312.213364) (xy 37.07871 -312.252708) (xy 37.043217 -312.2868)
			(xy 37.002714 -312.314756) (xy 36.958252 -312.335854) (xy 36.910981 -312.349546) (xy 36.862126 -312.355478)
			(xy 36.812951 -312.353497) (xy 36.764732 -312.343653) (xy 36.718716 -312.326201) (xy 36.676095 -312.301594)
			(xy 36.637974 -312.270469) (xy 36.605339 -312.233632) (xy 36.579036 -312.192036) (xy 36.559745 -312.14676)
			(xy 36.547968 -312.098976) (xy 36.544008 -312.049922) (xy 0.508 -312.049922) (xy 0.508 -312.999882)
			(xy 38.444182 -312.999882) (xy 38.448142 -312.950828) (xy 38.459919 -312.903044) (xy 38.47921 -312.857768)
			(xy 38.505513 -312.816172) (xy 38.538148 -312.779335) (xy 38.576269 -312.74821) (xy 38.61889 -312.723603)
			(xy 38.664906 -312.706151) (xy 38.713125 -312.696307) (xy 38.7623 -312.694326) (xy 38.811155 -312.700258)
			(xy 38.858426 -312.71395) (xy 38.902888 -312.735048) (xy 38.943391 -312.763004) (xy 38.978884 -312.797096)
			(xy 39.008449 -312.83644) (xy 39.03132 -312.880017) (xy 39.046904 -312.926698) (xy 39.054799 -312.975275)
			(xy 39.055294 -312.999882) (xy 40.344102 -312.999882) (xy 40.348062 -312.950828) (xy 40.359839 -312.903044)
			(xy 40.37913 -312.857768) (xy 40.405433 -312.816172) (xy 40.438068 -312.779335) (xy 40.476189 -312.74821)
			(xy 40.51881 -312.723603) (xy 40.564826 -312.706151) (xy 40.613045 -312.696307) (xy 40.66222 -312.694326)
			(xy 40.711075 -312.700258) (xy 40.758346 -312.71395) (xy 40.802808 -312.735048) (xy 40.843311 -312.763004)
			(xy 40.878804 -312.797096) (xy 40.908369 -312.83644) (xy 40.93124 -312.880017) (xy 40.946824 -312.926698)
			(xy 40.954719 -312.975275) (xy 40.955214 -312.999882) (xy 42.244022 -312.999882) (xy 42.247982 -312.950828)
			(xy 42.259759 -312.903044) (xy 42.27905 -312.857768) (xy 42.305353 -312.816172) (xy 42.337988 -312.779335)
			(xy 42.376109 -312.74821) (xy 42.41873 -312.723603) (xy 42.464746 -312.706151) (xy 42.512965 -312.696307)
			(xy 42.56214 -312.694326) (xy 42.610995 -312.700258) (xy 42.658266 -312.71395) (xy 42.702728 -312.735048)
			(xy 42.743231 -312.763004) (xy 42.778724 -312.797096) (xy 42.808289 -312.83644) (xy 42.83116 -312.880017)
			(xy 42.846744 -312.926698) (xy 42.854639 -312.975275) (xy 42.855134 -312.999882) (xy 44.143942 -312.999882)
			(xy 44.147902 -312.950828) (xy 44.159679 -312.903044) (xy 44.17897 -312.857768) (xy 44.205273 -312.816172)
			(xy 44.237908 -312.779335) (xy 44.276029 -312.74821) (xy 44.31865 -312.723603) (xy 44.364666 -312.706151)
			(xy 44.412885 -312.696307) (xy 44.46206 -312.694326) (xy 44.510915 -312.700258) (xy 44.558186 -312.71395)
			(xy 44.602648 -312.735048) (xy 44.643151 -312.763004) (xy 44.678644 -312.797096) (xy 44.708209 -312.83644)
			(xy 44.73108 -312.880017) (xy 44.746664 -312.926698) (xy 44.754559 -312.975275) (xy 44.755054 -312.999882)
			(xy 46.044116 -312.999882) (xy 46.048076 -312.950828) (xy 46.059853 -312.903044) (xy 46.079144 -312.857768)
			(xy 46.105447 -312.816172) (xy 46.138082 -312.779335) (xy 46.176203 -312.74821) (xy 46.218824 -312.723603)
			(xy 46.26484 -312.706151) (xy 46.313059 -312.696307) (xy 46.362234 -312.694326) (xy 46.411089 -312.700258)
			(xy 46.45836 -312.71395) (xy 46.502822 -312.735048) (xy 46.543325 -312.763004) (xy 46.578818 -312.797096)
			(xy 46.608383 -312.83644) (xy 46.631254 -312.880017) (xy 46.646838 -312.926698) (xy 46.654733 -312.975275)
			(xy 46.655228 -312.999882) (xy 47.944036 -312.999882) (xy 47.947996 -312.950828) (xy 47.959773 -312.903044)
			(xy 47.979064 -312.857768) (xy 48.005367 -312.816172) (xy 48.038002 -312.779335) (xy 48.076123 -312.74821)
			(xy 48.118744 -312.723603) (xy 48.16476 -312.706151) (xy 48.212979 -312.696307) (xy 48.262154 -312.694326)
			(xy 48.311009 -312.700258) (xy 48.35828 -312.71395) (xy 48.402742 -312.735048) (xy 48.443245 -312.763004)
			(xy 48.478738 -312.797096) (xy 48.508303 -312.83644) (xy 48.531174 -312.880017) (xy 48.546758 -312.926698)
			(xy 48.554653 -312.975275) (xy 48.555148 -312.999882) (xy 49.843956 -312.999882) (xy 49.847916 -312.950828)
			(xy 49.859693 -312.903044) (xy 49.878984 -312.857768) (xy 49.905287 -312.816172) (xy 49.937922 -312.779335)
			(xy 49.976043 -312.74821) (xy 50.018664 -312.723603) (xy 50.06468 -312.706151) (xy 50.112899 -312.696307)
			(xy 50.162074 -312.694326) (xy 50.210929 -312.700258) (xy 50.2582 -312.71395) (xy 50.302662 -312.735048)
			(xy 50.343165 -312.763004) (xy 50.378658 -312.797096) (xy 50.408223 -312.83644) (xy 50.431094 -312.880017)
			(xy 50.446678 -312.926698) (xy 50.454573 -312.975275) (xy 50.455068 -312.999882) (xy 51.74413 -312.999882)
			(xy 51.74809 -312.950828) (xy 51.759867 -312.903044) (xy 51.779158 -312.857768) (xy 51.805461 -312.816172)
			(xy 51.838096 -312.779335) (xy 51.876217 -312.74821) (xy 51.918838 -312.723603) (xy 51.964854 -312.706151)
			(xy 52.013073 -312.696307) (xy 52.062248 -312.694326) (xy 52.111103 -312.700258) (xy 52.158374 -312.71395)
			(xy 52.202836 -312.735048) (xy 52.243339 -312.763004) (xy 52.278832 -312.797096) (xy 52.308397 -312.83644)
			(xy 52.331268 -312.880017) (xy 52.346852 -312.926698) (xy 52.354747 -312.975275) (xy 52.355242 -312.999882)
			(xy 53.64405 -312.999882) (xy 53.64801 -312.950828) (xy 53.659787 -312.903044) (xy 53.679078 -312.857768)
			(xy 53.705381 -312.816172) (xy 53.738016 -312.779335) (xy 53.776137 -312.74821) (xy 53.818758 -312.723603)
			(xy 53.864774 -312.706151) (xy 53.912993 -312.696307) (xy 53.962168 -312.694326) (xy 54.011023 -312.700258)
			(xy 54.058294 -312.71395) (xy 54.102756 -312.735048) (xy 54.143259 -312.763004) (xy 54.178752 -312.797096)
			(xy 54.208317 -312.83644) (xy 54.231188 -312.880017) (xy 54.246772 -312.926698) (xy 54.254667 -312.975275)
			(xy 54.255162 -312.999882) (xy 55.54397 -312.999882) (xy 55.54793 -312.950828) (xy 55.559707 -312.903044)
			(xy 55.578998 -312.857768) (xy 55.605301 -312.816172) (xy 55.637936 -312.779335) (xy 55.676057 -312.74821)
			(xy 55.718678 -312.723603) (xy 55.764694 -312.706151) (xy 55.812913 -312.696307) (xy 55.862088 -312.694326)
			(xy 55.910943 -312.700258) (xy 55.958214 -312.71395) (xy 56.002676 -312.735048) (xy 56.043179 -312.763004)
			(xy 56.078672 -312.797096) (xy 56.108237 -312.83644) (xy 56.131108 -312.880017) (xy 56.146692 -312.926698)
			(xy 56.154587 -312.975275) (xy 56.155082 -312.999882) (xy 57.444144 -312.999882) (xy 57.448104 -312.950828)
			(xy 57.459881 -312.903044) (xy 57.479172 -312.857768) (xy 57.505475 -312.816172) (xy 57.53811 -312.779335)
			(xy 57.576231 -312.74821) (xy 57.618852 -312.723603) (xy 57.664868 -312.706151) (xy 57.713087 -312.696307)
			(xy 57.762262 -312.694326) (xy 57.811117 -312.700258) (xy 57.858388 -312.71395) (xy 57.90285 -312.735048)
			(xy 57.943353 -312.763004) (xy 57.978846 -312.797096) (xy 58.008411 -312.83644) (xy 58.031282 -312.880017)
			(xy 58.046866 -312.926698) (xy 58.054761 -312.975275) (xy 58.055256 -312.999882) (xy 59.344064 -312.999882)
			(xy 59.348024 -312.950828) (xy 59.359801 -312.903044) (xy 59.379092 -312.857768) (xy 59.405395 -312.816172)
			(xy 59.43803 -312.779335) (xy 59.476151 -312.74821) (xy 59.518772 -312.723603) (xy 59.564788 -312.706151)
			(xy 59.613007 -312.696307) (xy 59.662182 -312.694326) (xy 59.711037 -312.700258) (xy 59.758308 -312.71395)
			(xy 59.80277 -312.735048) (xy 59.843273 -312.763004) (xy 59.878766 -312.797096) (xy 59.908331 -312.83644)
			(xy 59.931202 -312.880017) (xy 59.946786 -312.926698) (xy 59.954681 -312.975275) (xy 59.955176 -312.999882)
			(xy 61.243984 -312.999882) (xy 61.247944 -312.950828) (xy 61.259721 -312.903044) (xy 61.279012 -312.857768)
			(xy 61.305315 -312.816172) (xy 61.33795 -312.779335) (xy 61.376071 -312.74821) (xy 61.418692 -312.723603)
			(xy 61.464708 -312.706151) (xy 61.512927 -312.696307) (xy 61.562102 -312.694326) (xy 61.610957 -312.700258)
			(xy 61.658228 -312.71395) (xy 61.70269 -312.735048) (xy 61.743193 -312.763004) (xy 61.778686 -312.797096)
			(xy 61.808251 -312.83644) (xy 61.831122 -312.880017) (xy 61.846706 -312.926698) (xy 61.854601 -312.975275)
			(xy 61.855096 -312.999882) (xy 63.144158 -312.999882) (xy 63.148118 -312.950828) (xy 63.159895 -312.903044)
			(xy 63.179186 -312.857768) (xy 63.205489 -312.816172) (xy 63.238124 -312.779335) (xy 63.276245 -312.74821)
			(xy 63.318866 -312.723603) (xy 63.364882 -312.706151) (xy 63.413101 -312.696307) (xy 63.462276 -312.694326)
			(xy 63.511131 -312.700258) (xy 63.558402 -312.71395) (xy 63.602864 -312.735048) (xy 63.643367 -312.763004)
			(xy 63.67886 -312.797096) (xy 63.708425 -312.83644) (xy 63.731296 -312.880017) (xy 63.74688 -312.926698)
			(xy 63.754775 -312.975275) (xy 63.75527 -312.999882) (xy 65.044078 -312.999882) (xy 65.048038 -312.950828)
			(xy 65.059815 -312.903044) (xy 65.079106 -312.857768) (xy 65.105409 -312.816172) (xy 65.138044 -312.779335)
			(xy 65.176165 -312.74821) (xy 65.218786 -312.723603) (xy 65.264802 -312.706151) (xy 65.313021 -312.696307)
			(xy 65.362196 -312.694326) (xy 65.411051 -312.700258) (xy 65.458322 -312.71395) (xy 65.502784 -312.735048)
			(xy 65.543287 -312.763004) (xy 65.57878 -312.797096) (xy 65.608345 -312.83644) (xy 65.631216 -312.880017)
			(xy 65.6468 -312.926698) (xy 65.654695 -312.975275) (xy 65.65519 -312.999882) (xy 66.943998 -312.999882)
			(xy 66.947958 -312.950828) (xy 66.959735 -312.903044) (xy 66.979026 -312.857768) (xy 67.005329 -312.816172)
			(xy 67.037964 -312.779335) (xy 67.076085 -312.74821) (xy 67.118706 -312.723603) (xy 67.164722 -312.706151)
			(xy 67.212941 -312.696307) (xy 67.262116 -312.694326) (xy 67.310971 -312.700258) (xy 67.358242 -312.71395)
			(xy 67.402704 -312.735048) (xy 67.443207 -312.763004) (xy 67.4787 -312.797096) (xy 67.508265 -312.83644)
			(xy 67.531136 -312.880017) (xy 67.54672 -312.926698) (xy 67.554615 -312.975275) (xy 67.55511 -312.999882)
			(xy 68.844172 -312.999882) (xy 68.848132 -312.950828) (xy 68.859909 -312.903044) (xy 68.8792 -312.857768)
			(xy 68.905503 -312.816172) (xy 68.938138 -312.779335) (xy 68.976259 -312.74821) (xy 69.01888 -312.723603)
			(xy 69.064896 -312.706151) (xy 69.113115 -312.696307) (xy 69.16229 -312.694326) (xy 69.211145 -312.700258)
			(xy 69.258416 -312.71395) (xy 69.302878 -312.735048) (xy 69.343381 -312.763004) (xy 69.378874 -312.797096)
			(xy 69.408439 -312.83644) (xy 69.43131 -312.880017) (xy 69.446894 -312.926698) (xy 69.454789 -312.975275)
			(xy 69.455284 -312.999882) (xy 70.744092 -312.999882) (xy 70.748052 -312.950828) (xy 70.759829 -312.903044)
			(xy 70.77912 -312.857768) (xy 70.805423 -312.816172) (xy 70.838058 -312.779335) (xy 70.876179 -312.74821)
			(xy 70.9188 -312.723603) (xy 70.964816 -312.706151) (xy 71.013035 -312.696307) (xy 71.06221 -312.694326)
			(xy 71.111065 -312.700258) (xy 71.158336 -312.71395) (xy 71.202798 -312.735048) (xy 71.243301 -312.763004)
			(xy 71.278794 -312.797096) (xy 71.308359 -312.83644) (xy 71.33123 -312.880017) (xy 71.346814 -312.926698)
			(xy 71.354709 -312.975275) (xy 71.355204 -312.999882) (xy 72.644012 -312.999882) (xy 72.647972 -312.950828)
			(xy 72.659749 -312.903044) (xy 72.67904 -312.857768) (xy 72.705343 -312.816172) (xy 72.737978 -312.779335)
			(xy 72.776099 -312.74821) (xy 72.81872 -312.723603) (xy 72.864736 -312.706151) (xy 72.912955 -312.696307)
			(xy 72.96213 -312.694326) (xy 73.010985 -312.700258) (xy 73.058256 -312.71395) (xy 73.102718 -312.735048)
			(xy 73.143221 -312.763004) (xy 73.178714 -312.797096) (xy 73.208279 -312.83644) (xy 73.23115 -312.880017)
			(xy 73.246734 -312.926698) (xy 73.254629 -312.975275) (xy 73.255124 -312.999882) (xy 74.544186 -312.999882)
			(xy 74.548146 -312.950828) (xy 74.559923 -312.903044) (xy 74.579214 -312.857768) (xy 74.605517 -312.816172)
			(xy 74.638152 -312.779335) (xy 74.676273 -312.74821) (xy 74.718894 -312.723603) (xy 74.76491 -312.706151)
			(xy 74.813129 -312.696307) (xy 74.862304 -312.694326) (xy 74.911159 -312.700258) (xy 74.95843 -312.71395)
			(xy 75.002892 -312.735048) (xy 75.043395 -312.763004) (xy 75.078888 -312.797096) (xy 75.108453 -312.83644)
			(xy 75.131324 -312.880017) (xy 75.146908 -312.926698) (xy 75.154803 -312.975275) (xy 75.155298 -312.999882)
			(xy 76.444106 -312.999882) (xy 76.448066 -312.950828) (xy 76.459843 -312.903044) (xy 76.479134 -312.857768)
			(xy 76.505437 -312.816172) (xy 76.538072 -312.779335) (xy 76.576193 -312.74821) (xy 76.618814 -312.723603)
			(xy 76.66483 -312.706151) (xy 76.713049 -312.696307) (xy 76.762224 -312.694326) (xy 76.811079 -312.700258)
			(xy 76.85835 -312.71395) (xy 76.902812 -312.735048) (xy 76.943315 -312.763004) (xy 76.978808 -312.797096)
			(xy 77.008373 -312.83644) (xy 77.031244 -312.880017) (xy 77.046828 -312.926698) (xy 77.054723 -312.975275)
			(xy 77.055218 -312.999882) (xy 78.344026 -312.999882) (xy 78.347986 -312.950828) (xy 78.359763 -312.903044)
			(xy 78.379054 -312.857768) (xy 78.405357 -312.816172) (xy 78.437992 -312.779335) (xy 78.476113 -312.74821)
			(xy 78.518734 -312.723603) (xy 78.56475 -312.706151) (xy 78.612969 -312.696307) (xy 78.662144 -312.694326)
			(xy 78.710999 -312.700258) (xy 78.75827 -312.71395) (xy 78.802732 -312.735048) (xy 78.843235 -312.763004)
			(xy 78.878728 -312.797096) (xy 78.908293 -312.83644) (xy 78.931164 -312.880017) (xy 78.946748 -312.926698)
			(xy 78.954643 -312.975275) (xy 78.955138 -312.999882) (xy 80.243946 -312.999882) (xy 80.247906 -312.950828)
			(xy 80.259683 -312.903044) (xy 80.278974 -312.857768) (xy 80.305277 -312.816172) (xy 80.337912 -312.779335)
			(xy 80.376033 -312.74821) (xy 80.418654 -312.723603) (xy 80.46467 -312.706151) (xy 80.512889 -312.696307)
			(xy 80.562064 -312.694326) (xy 80.610919 -312.700258) (xy 80.65819 -312.71395) (xy 80.702652 -312.735048)
			(xy 80.743155 -312.763004) (xy 80.778648 -312.797096) (xy 80.808213 -312.83644) (xy 80.831084 -312.880017)
			(xy 80.846668 -312.926698) (xy 80.854563 -312.975275) (xy 80.855058 -312.999882) (xy 154.54428 -312.999882)
			(xy 154.54824 -312.950828) (xy 154.560017 -312.903044) (xy 154.579308 -312.857768) (xy 154.605611 -312.816172)
			(xy 154.638246 -312.779335) (xy 154.676367 -312.74821) (xy 154.718988 -312.723603) (xy 154.765004 -312.706151)
			(xy 154.813223 -312.696307) (xy 154.862398 -312.694326) (xy 154.911253 -312.700258) (xy 154.958524 -312.71395)
			(xy 155.002986 -312.735048) (xy 155.043489 -312.763004) (xy 155.078982 -312.797096) (xy 155.108547 -312.83644)
			(xy 155.131418 -312.880017) (xy 155.147002 -312.926698) (xy 155.154897 -312.975275) (xy 155.155392 -312.999882)
			(xy 156.4442 -312.999882) (xy 156.44816 -312.950828) (xy 156.459937 -312.903044) (xy 156.479228 -312.857768)
			(xy 156.505531 -312.816172) (xy 156.538166 -312.779335) (xy 156.576287 -312.74821) (xy 156.618908 -312.723603)
			(xy 156.664924 -312.706151) (xy 156.713143 -312.696307) (xy 156.762318 -312.694326) (xy 156.811173 -312.700258)
			(xy 156.858444 -312.71395) (xy 156.902906 -312.735048) (xy 156.943409 -312.763004) (xy 156.978902 -312.797096)
			(xy 157.008467 -312.83644) (xy 157.031338 -312.880017) (xy 157.046922 -312.926698) (xy 157.054817 -312.975275)
			(xy 157.055312 -312.999882) (xy 158.34412 -312.999882) (xy 158.34808 -312.950828) (xy 158.359857 -312.903044)
			(xy 158.379148 -312.857768) (xy 158.405451 -312.816172) (xy 158.438086 -312.779335) (xy 158.476207 -312.74821)
			(xy 158.518828 -312.723603) (xy 158.564844 -312.706151) (xy 158.613063 -312.696307) (xy 158.662238 -312.694326)
			(xy 158.711093 -312.700258) (xy 158.758364 -312.71395) (xy 158.802826 -312.735048) (xy 158.843329 -312.763004)
			(xy 158.878822 -312.797096) (xy 158.908387 -312.83644) (xy 158.931258 -312.880017) (xy 158.946842 -312.926698)
			(xy 158.954737 -312.975275) (xy 158.955232 -312.999882) (xy 160.24404 -312.999882) (xy 160.248 -312.950828)
			(xy 160.259777 -312.903044) (xy 160.279068 -312.857768) (xy 160.305371 -312.816172) (xy 160.338006 -312.779335)
			(xy 160.376127 -312.74821) (xy 160.418748 -312.723603) (xy 160.464764 -312.706151) (xy 160.512983 -312.696307)
			(xy 160.562158 -312.694326) (xy 160.611013 -312.700258) (xy 160.658284 -312.71395) (xy 160.702746 -312.735048)
			(xy 160.743249 -312.763004) (xy 160.778742 -312.797096) (xy 160.808307 -312.83644) (xy 160.831178 -312.880017)
			(xy 160.846762 -312.926698) (xy 160.854657 -312.975275) (xy 160.855152 -312.999882) (xy 162.144214 -312.999882)
			(xy 162.148174 -312.950828) (xy 162.159951 -312.903044) (xy 162.179242 -312.857768) (xy 162.205545 -312.816172)
			(xy 162.23818 -312.779335) (xy 162.276301 -312.74821) (xy 162.318922 -312.723603) (xy 162.364938 -312.706151)
			(xy 162.413157 -312.696307) (xy 162.462332 -312.694326) (xy 162.511187 -312.700258) (xy 162.558458 -312.71395)
			(xy 162.60292 -312.735048) (xy 162.643423 -312.763004) (xy 162.678916 -312.797096) (xy 162.708481 -312.83644)
			(xy 162.731352 -312.880017) (xy 162.746936 -312.926698) (xy 162.754831 -312.975275) (xy 162.755326 -312.999882)
			(xy 164.044134 -312.999882) (xy 164.048094 -312.950828) (xy 164.059871 -312.903044) (xy 164.079162 -312.857768)
			(xy 164.105465 -312.816172) (xy 164.1381 -312.779335) (xy 164.176221 -312.74821) (xy 164.218842 -312.723603)
			(xy 164.264858 -312.706151) (xy 164.313077 -312.696307) (xy 164.362252 -312.694326) (xy 164.411107 -312.700258)
			(xy 164.458378 -312.71395) (xy 164.50284 -312.735048) (xy 164.543343 -312.763004) (xy 164.578836 -312.797096)
			(xy 164.608401 -312.83644) (xy 164.631272 -312.880017) (xy 164.646856 -312.926698) (xy 164.654751 -312.975275)
			(xy 164.655246 -312.999882) (xy 165.944054 -312.999882) (xy 165.948014 -312.950828) (xy 165.959791 -312.903044)
			(xy 165.979082 -312.857768) (xy 166.005385 -312.816172) (xy 166.03802 -312.779335) (xy 166.076141 -312.74821)
			(xy 166.118762 -312.723603) (xy 166.164778 -312.706151) (xy 166.212997 -312.696307) (xy 166.262172 -312.694326)
			(xy 166.311027 -312.700258) (xy 166.358298 -312.71395) (xy 166.40276 -312.735048) (xy 166.443263 -312.763004)
			(xy 166.478756 -312.797096) (xy 166.508321 -312.83644) (xy 166.531192 -312.880017) (xy 166.546776 -312.926698)
			(xy 166.554671 -312.975275) (xy 166.555166 -312.999882) (xy 167.844228 -312.999882) (xy 167.848188 -312.950828)
			(xy 167.859965 -312.903044) (xy 167.879256 -312.857768) (xy 167.905559 -312.816172) (xy 167.938194 -312.779335)
			(xy 167.976315 -312.74821) (xy 168.018936 -312.723603) (xy 168.064952 -312.706151) (xy 168.113171 -312.696307)
			(xy 168.162346 -312.694326) (xy 168.211201 -312.700258) (xy 168.258472 -312.71395) (xy 168.302934 -312.735048)
			(xy 168.343437 -312.763004) (xy 168.37893 -312.797096) (xy 168.408495 -312.83644) (xy 168.431366 -312.880017)
			(xy 168.44695 -312.926698) (xy 168.454845 -312.975275) (xy 168.45534 -312.999882) (xy 169.744148 -312.999882)
			(xy 169.748108 -312.950828) (xy 169.759885 -312.903044) (xy 169.779176 -312.857768) (xy 169.805479 -312.816172)
			(xy 169.838114 -312.779335) (xy 169.876235 -312.74821) (xy 169.918856 -312.723603) (xy 169.964872 -312.706151)
			(xy 170.013091 -312.696307) (xy 170.062266 -312.694326) (xy 170.111121 -312.700258) (xy 170.158392 -312.71395)
			(xy 170.202854 -312.735048) (xy 170.243357 -312.763004) (xy 170.27885 -312.797096) (xy 170.308415 -312.83644)
			(xy 170.331286 -312.880017) (xy 170.34687 -312.926698) (xy 170.354765 -312.975275) (xy 170.35526 -312.999882)
			(xy 171.644068 -312.999882) (xy 171.648028 -312.950828) (xy 171.659805 -312.903044) (xy 171.679096 -312.857768)
			(xy 171.705399 -312.816172) (xy 171.738034 -312.779335) (xy 171.776155 -312.74821) (xy 171.818776 -312.723603)
			(xy 171.864792 -312.706151) (xy 171.913011 -312.696307) (xy 171.962186 -312.694326) (xy 172.011041 -312.700258)
			(xy 172.058312 -312.71395) (xy 172.102774 -312.735048) (xy 172.143277 -312.763004) (xy 172.17877 -312.797096)
			(xy 172.208335 -312.83644) (xy 172.231206 -312.880017) (xy 172.24679 -312.926698) (xy 172.254685 -312.975275)
			(xy 172.25518 -312.999882) (xy 173.544242 -312.999882) (xy 173.548202 -312.950828) (xy 173.559979 -312.903044)
			(xy 173.57927 -312.857768) (xy 173.605573 -312.816172) (xy 173.638208 -312.779335) (xy 173.676329 -312.74821)
			(xy 173.71895 -312.723603) (xy 173.764966 -312.706151) (xy 173.813185 -312.696307) (xy 173.86236 -312.694326)
			(xy 173.911215 -312.700258) (xy 173.958486 -312.71395) (xy 174.002948 -312.735048) (xy 174.043451 -312.763004)
			(xy 174.078944 -312.797096) (xy 174.108509 -312.83644) (xy 174.13138 -312.880017) (xy 174.146964 -312.926698)
			(xy 174.154859 -312.975275) (xy 174.155354 -312.999882) (xy 175.444162 -312.999882) (xy 175.448122 -312.950828)
			(xy 175.459899 -312.903044) (xy 175.47919 -312.857768) (xy 175.505493 -312.816172) (xy 175.538128 -312.779335)
			(xy 175.576249 -312.74821) (xy 175.61887 -312.723603) (xy 175.664886 -312.706151) (xy 175.713105 -312.696307)
			(xy 175.76228 -312.694326) (xy 175.811135 -312.700258) (xy 175.858406 -312.71395) (xy 175.902868 -312.735048)
			(xy 175.943371 -312.763004) (xy 175.978864 -312.797096) (xy 176.008429 -312.83644) (xy 176.0313 -312.880017)
			(xy 176.046884 -312.926698) (xy 176.054779 -312.975275) (xy 176.055274 -312.999882) (xy 177.344082 -312.999882)
			(xy 177.348042 -312.950828) (xy 177.359819 -312.903044) (xy 177.37911 -312.857768) (xy 177.405413 -312.816172)
			(xy 177.438048 -312.779335) (xy 177.476169 -312.74821) (xy 177.51879 -312.723603) (xy 177.564806 -312.706151)
			(xy 177.613025 -312.696307) (xy 177.6622 -312.694326) (xy 177.711055 -312.700258) (xy 177.758326 -312.71395)
			(xy 177.802788 -312.735048) (xy 177.843291 -312.763004) (xy 177.878784 -312.797096) (xy 177.908349 -312.83644)
			(xy 177.93122 -312.880017) (xy 177.946804 -312.926698) (xy 177.954699 -312.975275) (xy 177.955194 -312.999882)
			(xy 179.244256 -312.999882) (xy 179.248216 -312.950828) (xy 179.259993 -312.903044) (xy 179.279284 -312.857768)
			(xy 179.305587 -312.816172) (xy 179.338222 -312.779335) (xy 179.376343 -312.74821) (xy 179.418964 -312.723603)
			(xy 179.46498 -312.706151) (xy 179.513199 -312.696307) (xy 179.562374 -312.694326) (xy 179.611229 -312.700258)
			(xy 179.6585 -312.71395) (xy 179.702962 -312.735048) (xy 179.743465 -312.763004) (xy 179.778958 -312.797096)
			(xy 179.808523 -312.83644) (xy 179.831394 -312.880017) (xy 179.846978 -312.926698) (xy 179.854873 -312.975275)
			(xy 179.855368 -312.999882) (xy 181.144176 -312.999882) (xy 181.148136 -312.950828) (xy 181.159913 -312.903044)
			(xy 181.179204 -312.857768) (xy 181.205507 -312.816172) (xy 181.238142 -312.779335) (xy 181.276263 -312.74821)
			(xy 181.318884 -312.723603) (xy 181.3649 -312.706151) (xy 181.413119 -312.696307) (xy 181.462294 -312.694326)
			(xy 181.511149 -312.700258) (xy 181.55842 -312.71395) (xy 181.602882 -312.735048) (xy 181.643385 -312.763004)
			(xy 181.678878 -312.797096) (xy 181.708443 -312.83644) (xy 181.731314 -312.880017) (xy 181.746898 -312.926698)
			(xy 181.754793 -312.975275) (xy 181.755288 -312.999882) (xy 183.044096 -312.999882) (xy 183.048056 -312.950828)
			(xy 183.059833 -312.903044) (xy 183.079124 -312.857768) (xy 183.105427 -312.816172) (xy 183.138062 -312.779335)
			(xy 183.176183 -312.74821) (xy 183.218804 -312.723603) (xy 183.26482 -312.706151) (xy 183.313039 -312.696307)
			(xy 183.362214 -312.694326) (xy 183.411069 -312.700258) (xy 183.45834 -312.71395) (xy 183.502802 -312.735048)
			(xy 183.543305 -312.763004) (xy 183.578798 -312.797096) (xy 183.608363 -312.83644) (xy 183.631234 -312.880017)
			(xy 183.646818 -312.926698) (xy 183.654713 -312.975275) (xy 183.655208 -312.999882) (xy 184.94427 -312.999882)
			(xy 184.94823 -312.950828) (xy 184.960007 -312.903044) (xy 184.979298 -312.857768) (xy 185.005601 -312.816172)
			(xy 185.038236 -312.779335) (xy 185.076357 -312.74821) (xy 185.118978 -312.723603) (xy 185.164994 -312.706151)
			(xy 185.213213 -312.696307) (xy 185.262388 -312.694326) (xy 185.311243 -312.700258) (xy 185.358514 -312.71395)
			(xy 185.402976 -312.735048) (xy 185.443479 -312.763004) (xy 185.478972 -312.797096) (xy 185.508537 -312.83644)
			(xy 185.531408 -312.880017) (xy 185.546992 -312.926698) (xy 185.554887 -312.975275) (xy 185.555382 -312.999882)
			(xy 186.84419 -312.999882) (xy 186.84815 -312.950828) (xy 186.859927 -312.903044) (xy 186.879218 -312.857768)
			(xy 186.905521 -312.816172) (xy 186.938156 -312.779335) (xy 186.976277 -312.74821) (xy 187.018898 -312.723603)
			(xy 187.064914 -312.706151) (xy 187.113133 -312.696307) (xy 187.162308 -312.694326) (xy 187.211163 -312.700258)
			(xy 187.258434 -312.71395) (xy 187.302896 -312.735048) (xy 187.343399 -312.763004) (xy 187.378892 -312.797096)
			(xy 187.408457 -312.83644) (xy 187.431328 -312.880017) (xy 187.446912 -312.926698) (xy 187.454807 -312.975275)
			(xy 187.455302 -312.999882) (xy 188.74411 -312.999882) (xy 188.74807 -312.950828) (xy 188.759847 -312.903044)
			(xy 188.779138 -312.857768) (xy 188.805441 -312.816172) (xy 188.838076 -312.779335) (xy 188.876197 -312.74821)
			(xy 188.918818 -312.723603) (xy 188.964834 -312.706151) (xy 189.013053 -312.696307) (xy 189.062228 -312.694326)
			(xy 189.111083 -312.700258) (xy 189.158354 -312.71395) (xy 189.202816 -312.735048) (xy 189.243319 -312.763004)
			(xy 189.278812 -312.797096) (xy 189.308377 -312.83644) (xy 189.331248 -312.880017) (xy 189.346832 -312.926698)
			(xy 189.354727 -312.975275) (xy 189.355222 -312.999882) (xy 190.644284 -312.999882) (xy 190.648244 -312.950828)
			(xy 190.660021 -312.903044) (xy 190.679312 -312.857768) (xy 190.705615 -312.816172) (xy 190.73825 -312.779335)
			(xy 190.776371 -312.74821) (xy 190.818992 -312.723603) (xy 190.865008 -312.706151) (xy 190.913227 -312.696307)
			(xy 190.962402 -312.694326) (xy 191.011257 -312.700258) (xy 191.058528 -312.71395) (xy 191.10299 -312.735048)
			(xy 191.143493 -312.763004) (xy 191.178986 -312.797096) (xy 191.208551 -312.83644) (xy 191.231422 -312.880017)
			(xy 191.247006 -312.926698) (xy 191.254901 -312.975275) (xy 191.255396 -312.999882) (xy 192.544204 -312.999882)
			(xy 192.548164 -312.950828) (xy 192.559941 -312.903044) (xy 192.579232 -312.857768) (xy 192.605535 -312.816172)
			(xy 192.63817 -312.779335) (xy 192.676291 -312.74821) (xy 192.718912 -312.723603) (xy 192.764928 -312.706151)
			(xy 192.813147 -312.696307) (xy 192.862322 -312.694326) (xy 192.911177 -312.700258) (xy 192.958448 -312.71395)
			(xy 193.00291 -312.735048) (xy 193.043413 -312.763004) (xy 193.078906 -312.797096) (xy 193.108471 -312.83644)
			(xy 193.131342 -312.880017) (xy 193.146926 -312.926698) (xy 193.154821 -312.975275) (xy 193.155316 -312.999882)
			(xy 194.444124 -312.999882) (xy 194.448084 -312.950828) (xy 194.459861 -312.903044) (xy 194.479152 -312.857768)
			(xy 194.505455 -312.816172) (xy 194.53809 -312.779335) (xy 194.576211 -312.74821) (xy 194.618832 -312.723603)
			(xy 194.664848 -312.706151) (xy 194.713067 -312.696307) (xy 194.762242 -312.694326) (xy 194.811097 -312.700258)
			(xy 194.858368 -312.71395) (xy 194.90283 -312.735048) (xy 194.943333 -312.763004) (xy 194.978826 -312.797096)
			(xy 195.008391 -312.83644) (xy 195.031262 -312.880017) (xy 195.046846 -312.926698) (xy 195.054741 -312.975275)
			(xy 195.055236 -312.999882) (xy 196.344044 -312.999882) (xy 196.348004 -312.950828) (xy 196.359781 -312.903044)
			(xy 196.379072 -312.857768) (xy 196.405375 -312.816172) (xy 196.43801 -312.779335) (xy 196.476131 -312.74821)
			(xy 196.518752 -312.723603) (xy 196.564768 -312.706151) (xy 196.612987 -312.696307) (xy 196.662162 -312.694326)
			(xy 196.711017 -312.700258) (xy 196.758288 -312.71395) (xy 196.80275 -312.735048) (xy 196.843253 -312.763004)
			(xy 196.878746 -312.797096) (xy 196.908311 -312.83644) (xy 196.931182 -312.880017) (xy 196.946766 -312.926698)
			(xy 196.954661 -312.975275) (xy 196.955156 -312.999882) (xy 270.644124 -312.999882) (xy 270.648084 -312.950828)
			(xy 270.659861 -312.903044) (xy 270.679152 -312.857768) (xy 270.705455 -312.816172) (xy 270.73809 -312.779335)
			(xy 270.776211 -312.74821) (xy 270.818832 -312.723603) (xy 270.864848 -312.706151) (xy 270.913067 -312.696307)
			(xy 270.962242 -312.694326) (xy 271.011097 -312.700258) (xy 271.058368 -312.71395) (xy 271.10283 -312.735048)
			(xy 271.143333 -312.763004) (xy 271.178826 -312.797096) (xy 271.208391 -312.83644) (xy 271.231262 -312.880017)
			(xy 271.246846 -312.926698) (xy 271.254741 -312.975275) (xy 271.255236 -312.999882) (xy 272.544044 -312.999882)
			(xy 272.548004 -312.950828) (xy 272.559781 -312.903044) (xy 272.579072 -312.857768) (xy 272.605375 -312.816172)
			(xy 272.63801 -312.779335) (xy 272.676131 -312.74821) (xy 272.718752 -312.723603) (xy 272.764768 -312.706151)
			(xy 272.812987 -312.696307) (xy 272.862162 -312.694326) (xy 272.911017 -312.700258) (xy 272.958288 -312.71395)
			(xy 273.00275 -312.735048) (xy 273.043253 -312.763004) (xy 273.078746 -312.797096) (xy 273.108311 -312.83644)
			(xy 273.131182 -312.880017) (xy 273.146766 -312.926698) (xy 273.154661 -312.975275) (xy 273.155156 -312.999882)
			(xy 274.443964 -312.999882) (xy 274.447924 -312.950828) (xy 274.459701 -312.903044) (xy 274.478992 -312.857768)
			(xy 274.505295 -312.816172) (xy 274.53793 -312.779335) (xy 274.576051 -312.74821) (xy 274.618672 -312.723603)
			(xy 274.664688 -312.706151) (xy 274.712907 -312.696307) (xy 274.762082 -312.694326) (xy 274.810937 -312.700258)
			(xy 274.858208 -312.71395) (xy 274.90267 -312.735048) (xy 274.943173 -312.763004) (xy 274.978666 -312.797096)
			(xy 275.008231 -312.83644) (xy 275.031102 -312.880017) (xy 275.046686 -312.926698) (xy 275.054581 -312.975275)
			(xy 275.055076 -312.999882) (xy 276.343884 -312.999882) (xy 276.347844 -312.950828) (xy 276.359621 -312.903044)
			(xy 276.378912 -312.857768) (xy 276.405215 -312.816172) (xy 276.43785 -312.779335) (xy 276.475971 -312.74821)
			(xy 276.518592 -312.723603) (xy 276.564608 -312.706151) (xy 276.612827 -312.696307) (xy 276.662002 -312.694326)
			(xy 276.710857 -312.700258) (xy 276.758128 -312.71395) (xy 276.80259 -312.735048) (xy 276.843093 -312.763004)
			(xy 276.878586 -312.797096) (xy 276.908151 -312.83644) (xy 276.931022 -312.880017) (xy 276.946606 -312.926698)
			(xy 276.954501 -312.975275) (xy 276.954996 -312.999882) (xy 278.244058 -312.999882) (xy 278.248018 -312.950828)
			(xy 278.259795 -312.903044) (xy 278.279086 -312.857768) (xy 278.305389 -312.816172) (xy 278.338024 -312.779335)
			(xy 278.376145 -312.74821) (xy 278.418766 -312.723603) (xy 278.464782 -312.706151) (xy 278.513001 -312.696307)
			(xy 278.562176 -312.694326) (xy 278.611031 -312.700258) (xy 278.658302 -312.71395) (xy 278.702764 -312.735048)
			(xy 278.743267 -312.763004) (xy 278.77876 -312.797096) (xy 278.808325 -312.83644) (xy 278.831196 -312.880017)
			(xy 278.84678 -312.926698) (xy 278.854675 -312.975275) (xy 278.85517 -312.999882) (xy 280.143978 -312.999882)
			(xy 280.147938 -312.950828) (xy 280.159715 -312.903044) (xy 280.179006 -312.857768) (xy 280.205309 -312.816172)
			(xy 280.237944 -312.779335) (xy 280.276065 -312.74821) (xy 280.318686 -312.723603) (xy 280.364702 -312.706151)
			(xy 280.412921 -312.696307) (xy 280.462096 -312.694326) (xy 280.510951 -312.700258) (xy 280.558222 -312.71395)
			(xy 280.602684 -312.735048) (xy 280.643187 -312.763004) (xy 280.67868 -312.797096) (xy 280.708245 -312.83644)
			(xy 280.731116 -312.880017) (xy 280.7467 -312.926698) (xy 280.754595 -312.975275) (xy 280.75509 -312.999882)
			(xy 282.043898 -312.999882) (xy 282.047858 -312.950828) (xy 282.059635 -312.903044) (xy 282.078926 -312.857768)
			(xy 282.105229 -312.816172) (xy 282.137864 -312.779335) (xy 282.175985 -312.74821) (xy 282.218606 -312.723603)
			(xy 282.264622 -312.706151) (xy 282.312841 -312.696307) (xy 282.362016 -312.694326) (xy 282.410871 -312.700258)
			(xy 282.458142 -312.71395) (xy 282.502604 -312.735048) (xy 282.543107 -312.763004) (xy 282.5786 -312.797096)
			(xy 282.608165 -312.83644) (xy 282.631036 -312.880017) (xy 282.64662 -312.926698) (xy 282.654515 -312.975275)
			(xy 282.65501 -312.999882) (xy 283.944072 -312.999882) (xy 283.948032 -312.950828) (xy 283.959809 -312.903044)
			(xy 283.9791 -312.857768) (xy 284.005403 -312.816172) (xy 284.038038 -312.779335) (xy 284.076159 -312.74821)
			(xy 284.11878 -312.723603) (xy 284.164796 -312.706151) (xy 284.213015 -312.696307) (xy 284.26219 -312.694326)
			(xy 284.311045 -312.700258) (xy 284.358316 -312.71395) (xy 284.402778 -312.735048) (xy 284.443281 -312.763004)
			(xy 284.478774 -312.797096) (xy 284.508339 -312.83644) (xy 284.53121 -312.880017) (xy 284.546794 -312.926698)
			(xy 284.554689 -312.975275) (xy 284.555184 -312.999882) (xy 285.843992 -312.999882) (xy 285.847952 -312.950828)
			(xy 285.859729 -312.903044) (xy 285.87902 -312.857768) (xy 285.905323 -312.816172) (xy 285.937958 -312.779335)
			(xy 285.976079 -312.74821) (xy 286.0187 -312.723603) (xy 286.064716 -312.706151) (xy 286.112935 -312.696307)
			(xy 286.16211 -312.694326) (xy 286.210965 -312.700258) (xy 286.258236 -312.71395) (xy 286.302698 -312.735048)
			(xy 286.343201 -312.763004) (xy 286.378694 -312.797096) (xy 286.408259 -312.83644) (xy 286.43113 -312.880017)
			(xy 286.446714 -312.926698) (xy 286.454609 -312.975275) (xy 286.455104 -312.999882) (xy 287.743912 -312.999882)
			(xy 287.747872 -312.950828) (xy 287.759649 -312.903044) (xy 287.77894 -312.857768) (xy 287.805243 -312.816172)
			(xy 287.837878 -312.779335) (xy 287.875999 -312.74821) (xy 287.91862 -312.723603) (xy 287.964636 -312.706151)
			(xy 288.012855 -312.696307) (xy 288.06203 -312.694326) (xy 288.110885 -312.700258) (xy 288.158156 -312.71395)
			(xy 288.202618 -312.735048) (xy 288.243121 -312.763004) (xy 288.278614 -312.797096) (xy 288.308179 -312.83644)
			(xy 288.33105 -312.880017) (xy 288.346634 -312.926698) (xy 288.354529 -312.975275) (xy 288.355024 -312.999882)
			(xy 289.644086 -312.999882) (xy 289.648046 -312.950828) (xy 289.659823 -312.903044) (xy 289.679114 -312.857768)
			(xy 289.705417 -312.816172) (xy 289.738052 -312.779335) (xy 289.776173 -312.74821) (xy 289.818794 -312.723603)
			(xy 289.86481 -312.706151) (xy 289.913029 -312.696307) (xy 289.962204 -312.694326) (xy 290.011059 -312.700258)
			(xy 290.05833 -312.71395) (xy 290.102792 -312.735048) (xy 290.143295 -312.763004) (xy 290.178788 -312.797096)
			(xy 290.208353 -312.83644) (xy 290.231224 -312.880017) (xy 290.246808 -312.926698) (xy 290.254703 -312.975275)
			(xy 290.255198 -312.999882) (xy 291.544006 -312.999882) (xy 291.547966 -312.950828) (xy 291.559743 -312.903044)
			(xy 291.579034 -312.857768) (xy 291.605337 -312.816172) (xy 291.637972 -312.779335) (xy 291.676093 -312.74821)
			(xy 291.718714 -312.723603) (xy 291.76473 -312.706151) (xy 291.812949 -312.696307) (xy 291.862124 -312.694326)
			(xy 291.910979 -312.700258) (xy 291.95825 -312.71395) (xy 292.002712 -312.735048) (xy 292.043215 -312.763004)
			(xy 292.078708 -312.797096) (xy 292.108273 -312.83644) (xy 292.131144 -312.880017) (xy 292.146728 -312.926698)
			(xy 292.154623 -312.975275) (xy 292.155118 -312.999882) (xy 293.443926 -312.999882) (xy 293.447886 -312.950828)
			(xy 293.459663 -312.903044) (xy 293.478954 -312.857768) (xy 293.505257 -312.816172) (xy 293.537892 -312.779335)
			(xy 293.576013 -312.74821) (xy 293.618634 -312.723603) (xy 293.66465 -312.706151) (xy 293.712869 -312.696307)
			(xy 293.762044 -312.694326) (xy 293.810899 -312.700258) (xy 293.85817 -312.71395) (xy 293.902632 -312.735048)
			(xy 293.943135 -312.763004) (xy 293.978628 -312.797096) (xy 294.008193 -312.83644) (xy 294.031064 -312.880017)
			(xy 294.046648 -312.926698) (xy 294.054543 -312.975275) (xy 294.055038 -312.999882) (xy 295.3441 -312.999882)
			(xy 295.34806 -312.950828) (xy 295.359837 -312.903044) (xy 295.379128 -312.857768) (xy 295.405431 -312.816172)
			(xy 295.438066 -312.779335) (xy 295.476187 -312.74821) (xy 295.518808 -312.723603) (xy 295.564824 -312.706151)
			(xy 295.613043 -312.696307) (xy 295.662218 -312.694326) (xy 295.711073 -312.700258) (xy 295.758344 -312.71395)
			(xy 295.802806 -312.735048) (xy 295.843309 -312.763004) (xy 295.878802 -312.797096) (xy 295.908367 -312.83644)
			(xy 295.931238 -312.880017) (xy 295.946822 -312.926698) (xy 295.954717 -312.975275) (xy 295.955212 -312.999882)
			(xy 297.24402 -312.999882) (xy 297.24798 -312.950828) (xy 297.259757 -312.903044) (xy 297.279048 -312.857768)
			(xy 297.305351 -312.816172) (xy 297.337986 -312.779335) (xy 297.376107 -312.74821) (xy 297.418728 -312.723603)
			(xy 297.464744 -312.706151) (xy 297.512963 -312.696307) (xy 297.562138 -312.694326) (xy 297.610993 -312.700258)
			(xy 297.658264 -312.71395) (xy 297.702726 -312.735048) (xy 297.743229 -312.763004) (xy 297.778722 -312.797096)
			(xy 297.808287 -312.83644) (xy 297.831158 -312.880017) (xy 297.846742 -312.926698) (xy 297.854637 -312.975275)
			(xy 297.855132 -312.999882) (xy 299.14394 -312.999882) (xy 299.1479 -312.950828) (xy 299.159677 -312.903044)
			(xy 299.178968 -312.857768) (xy 299.205271 -312.816172) (xy 299.237906 -312.779335) (xy 299.276027 -312.74821)
			(xy 299.318648 -312.723603) (xy 299.364664 -312.706151) (xy 299.412883 -312.696307) (xy 299.462058 -312.694326)
			(xy 299.510913 -312.700258) (xy 299.558184 -312.71395) (xy 299.602646 -312.735048) (xy 299.643149 -312.763004)
			(xy 299.678642 -312.797096) (xy 299.708207 -312.83644) (xy 299.731078 -312.880017) (xy 299.746662 -312.926698)
			(xy 299.754557 -312.975275) (xy 299.755052 -312.999882) (xy 301.044114 -312.999882) (xy 301.048074 -312.950828)
			(xy 301.059851 -312.903044) (xy 301.079142 -312.857768) (xy 301.105445 -312.816172) (xy 301.13808 -312.779335)
			(xy 301.176201 -312.74821) (xy 301.218822 -312.723603) (xy 301.264838 -312.706151) (xy 301.313057 -312.696307)
			(xy 301.362232 -312.694326) (xy 301.411087 -312.700258) (xy 301.458358 -312.71395) (xy 301.50282 -312.735048)
			(xy 301.543323 -312.763004) (xy 301.578816 -312.797096) (xy 301.608381 -312.83644) (xy 301.631252 -312.880017)
			(xy 301.646836 -312.926698) (xy 301.654731 -312.975275) (xy 301.655226 -312.999882) (xy 302.944034 -312.999882)
			(xy 302.947994 -312.950828) (xy 302.959771 -312.903044) (xy 302.979062 -312.857768) (xy 303.005365 -312.816172)
			(xy 303.038 -312.779335) (xy 303.076121 -312.74821) (xy 303.118742 -312.723603) (xy 303.164758 -312.706151)
			(xy 303.212977 -312.696307) (xy 303.262152 -312.694326) (xy 303.311007 -312.700258) (xy 303.358278 -312.71395)
			(xy 303.40274 -312.735048) (xy 303.443243 -312.763004) (xy 303.478736 -312.797096) (xy 303.508301 -312.83644)
			(xy 303.531172 -312.880017) (xy 303.546756 -312.926698) (xy 303.554651 -312.975275) (xy 303.555146 -312.999882)
			(xy 304.843954 -312.999882) (xy 304.847914 -312.950828) (xy 304.859691 -312.903044) (xy 304.878982 -312.857768)
			(xy 304.905285 -312.816172) (xy 304.93792 -312.779335) (xy 304.976041 -312.74821) (xy 305.018662 -312.723603)
			(xy 305.064678 -312.706151) (xy 305.112897 -312.696307) (xy 305.162072 -312.694326) (xy 305.210927 -312.700258)
			(xy 305.258198 -312.71395) (xy 305.30266 -312.735048) (xy 305.343163 -312.763004) (xy 305.378656 -312.797096)
			(xy 305.408221 -312.83644) (xy 305.431092 -312.880017) (xy 305.446676 -312.926698) (xy 305.454571 -312.975275)
			(xy 305.455066 -312.999882) (xy 306.744128 -312.999882) (xy 306.748088 -312.950828) (xy 306.759865 -312.903044)
			(xy 306.779156 -312.857768) (xy 306.805459 -312.816172) (xy 306.838094 -312.779335) (xy 306.876215 -312.74821)
			(xy 306.918836 -312.723603) (xy 306.964852 -312.706151) (xy 307.013071 -312.696307) (xy 307.062246 -312.694326)
			(xy 307.111101 -312.700258) (xy 307.158372 -312.71395) (xy 307.202834 -312.735048) (xy 307.243337 -312.763004)
			(xy 307.27883 -312.797096) (xy 307.308395 -312.83644) (xy 307.331266 -312.880017) (xy 307.34685 -312.926698)
			(xy 307.354745 -312.975275) (xy 307.35524 -312.999882) (xy 308.644048 -312.999882) (xy 308.648008 -312.950828)
			(xy 308.659785 -312.903044) (xy 308.679076 -312.857768) (xy 308.705379 -312.816172) (xy 308.738014 -312.779335)
			(xy 308.776135 -312.74821) (xy 308.818756 -312.723603) (xy 308.864772 -312.706151) (xy 308.912991 -312.696307)
			(xy 308.962166 -312.694326) (xy 309.011021 -312.700258) (xy 309.058292 -312.71395) (xy 309.102754 -312.735048)
			(xy 309.143257 -312.763004) (xy 309.17875 -312.797096) (xy 309.208315 -312.83644) (xy 309.231186 -312.880017)
			(xy 309.24677 -312.926698) (xy 309.254665 -312.975275) (xy 309.25516 -312.999882) (xy 310.543968 -312.999882)
			(xy 310.547928 -312.950828) (xy 310.559705 -312.903044) (xy 310.578996 -312.857768) (xy 310.605299 -312.816172)
			(xy 310.637934 -312.779335) (xy 310.676055 -312.74821) (xy 310.718676 -312.723603) (xy 310.764692 -312.706151)
			(xy 310.812911 -312.696307) (xy 310.862086 -312.694326) (xy 310.910941 -312.700258) (xy 310.958212 -312.71395)
			(xy 311.002674 -312.735048) (xy 311.043177 -312.763004) (xy 311.07867 -312.797096) (xy 311.108235 -312.83644)
			(xy 311.131106 -312.880017) (xy 311.14669 -312.926698) (xy 311.154585 -312.975275) (xy 311.15508 -312.999882)
			(xy 312.443888 -312.999882) (xy 312.447848 -312.950828) (xy 312.459625 -312.903044) (xy 312.478916 -312.857768)
			(xy 312.505219 -312.816172) (xy 312.537854 -312.779335) (xy 312.575975 -312.74821) (xy 312.618596 -312.723603)
			(xy 312.664612 -312.706151) (xy 312.712831 -312.696307) (xy 312.762006 -312.694326) (xy 312.810861 -312.700258)
			(xy 312.858132 -312.71395) (xy 312.902594 -312.735048) (xy 312.943097 -312.763004) (xy 312.97859 -312.797096)
			(xy 313.008155 -312.83644) (xy 313.031026 -312.880017) (xy 313.04661 -312.926698) (xy 313.054505 -312.975275)
			(xy 313.055 -312.999882) (xy 386.744222 -312.999882) (xy 386.748182 -312.950828) (xy 386.759959 -312.903044)
			(xy 386.77925 -312.857768) (xy 386.805553 -312.816172) (xy 386.838188 -312.779335) (xy 386.876309 -312.74821)
			(xy 386.91893 -312.723603) (xy 386.964946 -312.706151) (xy 387.013165 -312.696307) (xy 387.06234 -312.694326)
			(xy 387.111195 -312.700258) (xy 387.158466 -312.71395) (xy 387.202928 -312.735048) (xy 387.243431 -312.763004)
			(xy 387.278924 -312.797096) (xy 387.308489 -312.83644) (xy 387.33136 -312.880017) (xy 387.346944 -312.926698)
			(xy 387.354839 -312.975275) (xy 387.355334 -312.999882) (xy 388.644142 -312.999882) (xy 388.648102 -312.950828)
			(xy 388.659879 -312.903044) (xy 388.67917 -312.857768) (xy 388.705473 -312.816172) (xy 388.738108 -312.779335)
			(xy 388.776229 -312.74821) (xy 388.81885 -312.723603) (xy 388.864866 -312.706151) (xy 388.913085 -312.696307)
			(xy 388.96226 -312.694326) (xy 389.011115 -312.700258) (xy 389.058386 -312.71395) (xy 389.102848 -312.735048)
			(xy 389.143351 -312.763004) (xy 389.178844 -312.797096) (xy 389.208409 -312.83644) (xy 389.23128 -312.880017)
			(xy 389.246864 -312.926698) (xy 389.254759 -312.975275) (xy 389.255254 -312.999882) (xy 390.544062 -312.999882)
			(xy 390.548022 -312.950828) (xy 390.559799 -312.903044) (xy 390.57909 -312.857768) (xy 390.605393 -312.816172)
			(xy 390.638028 -312.779335) (xy 390.676149 -312.74821) (xy 390.71877 -312.723603) (xy 390.764786 -312.706151)
			(xy 390.813005 -312.696307) (xy 390.86218 -312.694326) (xy 390.911035 -312.700258) (xy 390.958306 -312.71395)
			(xy 391.002768 -312.735048) (xy 391.043271 -312.763004) (xy 391.078764 -312.797096) (xy 391.108329 -312.83644)
			(xy 391.1312 -312.880017) (xy 391.146784 -312.926698) (xy 391.154679 -312.975275) (xy 391.155174 -312.999882)
			(xy 392.443982 -312.999882) (xy 392.447942 -312.950828) (xy 392.459719 -312.903044) (xy 392.47901 -312.857768)
			(xy 392.505313 -312.816172) (xy 392.537948 -312.779335) (xy 392.576069 -312.74821) (xy 392.61869 -312.723603)
			(xy 392.664706 -312.706151) (xy 392.712925 -312.696307) (xy 392.7621 -312.694326) (xy 392.810955 -312.700258)
			(xy 392.858226 -312.71395) (xy 392.902688 -312.735048) (xy 392.943191 -312.763004) (xy 392.978684 -312.797096)
			(xy 393.008249 -312.83644) (xy 393.03112 -312.880017) (xy 393.046704 -312.926698) (xy 393.054599 -312.975275)
			(xy 393.055094 -312.999882) (xy 394.344156 -312.999882) (xy 394.348116 -312.950828) (xy 394.359893 -312.903044)
			(xy 394.379184 -312.857768) (xy 394.405487 -312.816172) (xy 394.438122 -312.779335) (xy 394.476243 -312.74821)
			(xy 394.518864 -312.723603) (xy 394.56488 -312.706151) (xy 394.613099 -312.696307) (xy 394.662274 -312.694326)
			(xy 394.711129 -312.700258) (xy 394.7584 -312.71395) (xy 394.802862 -312.735048) (xy 394.843365 -312.763004)
			(xy 394.878858 -312.797096) (xy 394.908423 -312.83644) (xy 394.931294 -312.880017) (xy 394.946878 -312.926698)
			(xy 394.954773 -312.975275) (xy 394.955268 -312.999882) (xy 396.244076 -312.999882) (xy 396.248036 -312.950828)
			(xy 396.259813 -312.903044) (xy 396.279104 -312.857768) (xy 396.305407 -312.816172) (xy 396.338042 -312.779335)
			(xy 396.376163 -312.74821) (xy 396.418784 -312.723603) (xy 396.4648 -312.706151) (xy 396.513019 -312.696307)
			(xy 396.562194 -312.694326) (xy 396.611049 -312.700258) (xy 396.65832 -312.71395) (xy 396.702782 -312.735048)
			(xy 396.743285 -312.763004) (xy 396.778778 -312.797096) (xy 396.808343 -312.83644) (xy 396.831214 -312.880017)
			(xy 396.846798 -312.926698) (xy 396.854693 -312.975275) (xy 396.855188 -312.999882) (xy 398.143996 -312.999882)
			(xy 398.147956 -312.950828) (xy 398.159733 -312.903044) (xy 398.179024 -312.857768) (xy 398.205327 -312.816172)
			(xy 398.237962 -312.779335) (xy 398.276083 -312.74821) (xy 398.318704 -312.723603) (xy 398.36472 -312.706151)
			(xy 398.412939 -312.696307) (xy 398.462114 -312.694326) (xy 398.510969 -312.700258) (xy 398.55824 -312.71395)
			(xy 398.602702 -312.735048) (xy 398.643205 -312.763004) (xy 398.678698 -312.797096) (xy 398.708263 -312.83644)
			(xy 398.731134 -312.880017) (xy 398.746718 -312.926698) (xy 398.754613 -312.975275) (xy 398.755108 -312.999882)
			(xy 400.04417 -312.999882) (xy 400.04813 -312.950828) (xy 400.059907 -312.903044) (xy 400.079198 -312.857768)
			(xy 400.105501 -312.816172) (xy 400.138136 -312.779335) (xy 400.176257 -312.74821) (xy 400.218878 -312.723603)
			(xy 400.264894 -312.706151) (xy 400.313113 -312.696307) (xy 400.362288 -312.694326) (xy 400.411143 -312.700258)
			(xy 400.458414 -312.71395) (xy 400.502876 -312.735048) (xy 400.543379 -312.763004) (xy 400.578872 -312.797096)
			(xy 400.608437 -312.83644) (xy 400.631308 -312.880017) (xy 400.646892 -312.926698) (xy 400.654787 -312.975275)
			(xy 400.655282 -312.999882) (xy 401.94409 -312.999882) (xy 401.94805 -312.950828) (xy 401.959827 -312.903044)
			(xy 401.979118 -312.857768) (xy 402.005421 -312.816172) (xy 402.038056 -312.779335) (xy 402.076177 -312.74821)
			(xy 402.118798 -312.723603) (xy 402.164814 -312.706151) (xy 402.213033 -312.696307) (xy 402.262208 -312.694326)
			(xy 402.311063 -312.700258) (xy 402.358334 -312.71395) (xy 402.402796 -312.735048) (xy 402.443299 -312.763004)
			(xy 402.478792 -312.797096) (xy 402.508357 -312.83644) (xy 402.531228 -312.880017) (xy 402.546812 -312.926698)
			(xy 402.554707 -312.975275) (xy 402.555202 -312.999882) (xy 403.84401 -312.999882) (xy 403.84797 -312.950828)
			(xy 403.859747 -312.903044) (xy 403.879038 -312.857768) (xy 403.905341 -312.816172) (xy 403.937976 -312.779335)
			(xy 403.976097 -312.74821) (xy 404.018718 -312.723603) (xy 404.064734 -312.706151) (xy 404.112953 -312.696307)
			(xy 404.162128 -312.694326) (xy 404.210983 -312.700258) (xy 404.258254 -312.71395) (xy 404.302716 -312.735048)
			(xy 404.343219 -312.763004) (xy 404.378712 -312.797096) (xy 404.408277 -312.83644) (xy 404.431148 -312.880017)
			(xy 404.446732 -312.926698) (xy 404.454627 -312.975275) (xy 404.455122 -312.999882) (xy 405.744184 -312.999882)
			(xy 405.748144 -312.950828) (xy 405.759921 -312.903044) (xy 405.779212 -312.857768) (xy 405.805515 -312.816172)
			(xy 405.83815 -312.779335) (xy 405.876271 -312.74821) (xy 405.918892 -312.723603) (xy 405.964908 -312.706151)
			(xy 406.013127 -312.696307) (xy 406.062302 -312.694326) (xy 406.111157 -312.700258) (xy 406.158428 -312.71395)
			(xy 406.20289 -312.735048) (xy 406.243393 -312.763004) (xy 406.278886 -312.797096) (xy 406.308451 -312.83644)
			(xy 406.331322 -312.880017) (xy 406.346906 -312.926698) (xy 406.354801 -312.975275) (xy 406.355296 -312.999882)
			(xy 407.644104 -312.999882) (xy 407.648064 -312.950828) (xy 407.659841 -312.903044) (xy 407.679132 -312.857768)
			(xy 407.705435 -312.816172) (xy 407.73807 -312.779335) (xy 407.776191 -312.74821) (xy 407.818812 -312.723603)
			(xy 407.864828 -312.706151) (xy 407.913047 -312.696307) (xy 407.962222 -312.694326) (xy 408.011077 -312.700258)
			(xy 408.058348 -312.71395) (xy 408.10281 -312.735048) (xy 408.143313 -312.763004) (xy 408.178806 -312.797096)
			(xy 408.208371 -312.83644) (xy 408.231242 -312.880017) (xy 408.246826 -312.926698) (xy 408.254721 -312.975275)
			(xy 408.255216 -312.999882) (xy 409.544024 -312.999882) (xy 409.547984 -312.950828) (xy 409.559761 -312.903044)
			(xy 409.579052 -312.857768) (xy 409.605355 -312.816172) (xy 409.63799 -312.779335) (xy 409.676111 -312.74821)
			(xy 409.718732 -312.723603) (xy 409.764748 -312.706151) (xy 409.812967 -312.696307) (xy 409.862142 -312.694326)
			(xy 409.910997 -312.700258) (xy 409.958268 -312.71395) (xy 410.00273 -312.735048) (xy 410.043233 -312.763004)
			(xy 410.078726 -312.797096) (xy 410.108291 -312.83644) (xy 410.131162 -312.880017) (xy 410.146746 -312.926698)
			(xy 410.154641 -312.975275) (xy 410.155136 -312.999882) (xy 411.444198 -312.999882) (xy 411.448158 -312.950828)
			(xy 411.459935 -312.903044) (xy 411.479226 -312.857768) (xy 411.505529 -312.816172) (xy 411.538164 -312.779335)
			(xy 411.576285 -312.74821) (xy 411.618906 -312.723603) (xy 411.664922 -312.706151) (xy 411.713141 -312.696307)
			(xy 411.762316 -312.694326) (xy 411.811171 -312.700258) (xy 411.858442 -312.71395) (xy 411.902904 -312.735048)
			(xy 411.943407 -312.763004) (xy 411.9789 -312.797096) (xy 412.008465 -312.83644) (xy 412.031336 -312.880017)
			(xy 412.04692 -312.926698) (xy 412.054815 -312.975275) (xy 412.05531 -312.999882) (xy 413.344118 -312.999882)
			(xy 413.348078 -312.950828) (xy 413.359855 -312.903044) (xy 413.379146 -312.857768) (xy 413.405449 -312.816172)
			(xy 413.438084 -312.779335) (xy 413.476205 -312.74821) (xy 413.518826 -312.723603) (xy 413.564842 -312.706151)
			(xy 413.613061 -312.696307) (xy 413.662236 -312.694326) (xy 413.711091 -312.700258) (xy 413.758362 -312.71395)
			(xy 413.802824 -312.735048) (xy 413.843327 -312.763004) (xy 413.87882 -312.797096) (xy 413.908385 -312.83644)
			(xy 413.931256 -312.880017) (xy 413.94684 -312.926698) (xy 413.954735 -312.975275) (xy 413.95523 -312.999882)
			(xy 415.244038 -312.999882) (xy 415.247998 -312.950828) (xy 415.259775 -312.903044) (xy 415.279066 -312.857768)
			(xy 415.305369 -312.816172) (xy 415.338004 -312.779335) (xy 415.376125 -312.74821) (xy 415.418746 -312.723603)
			(xy 415.464762 -312.706151) (xy 415.512981 -312.696307) (xy 415.562156 -312.694326) (xy 415.611011 -312.700258)
			(xy 415.658282 -312.71395) (xy 415.702744 -312.735048) (xy 415.743247 -312.763004) (xy 415.77874 -312.797096)
			(xy 415.808305 -312.83644) (xy 415.831176 -312.880017) (xy 415.84676 -312.926698) (xy 415.854655 -312.975275)
			(xy 415.85515 -312.999882) (xy 417.144212 -312.999882) (xy 417.148172 -312.950828) (xy 417.159949 -312.903044)
			(xy 417.17924 -312.857768) (xy 417.205543 -312.816172) (xy 417.238178 -312.779335) (xy 417.276299 -312.74821)
			(xy 417.31892 -312.723603) (xy 417.364936 -312.706151) (xy 417.413155 -312.696307) (xy 417.46233 -312.694326)
			(xy 417.511185 -312.700258) (xy 417.558456 -312.71395) (xy 417.602918 -312.735048) (xy 417.643421 -312.763004)
			(xy 417.678914 -312.797096) (xy 417.708479 -312.83644) (xy 417.73135 -312.880017) (xy 417.746934 -312.926698)
			(xy 417.754829 -312.975275) (xy 417.755324 -312.999882) (xy 419.044132 -312.999882) (xy 419.048092 -312.950828)
			(xy 419.059869 -312.903044) (xy 419.07916 -312.857768) (xy 419.105463 -312.816172) (xy 419.138098 -312.779335)
			(xy 419.176219 -312.74821) (xy 419.21884 -312.723603) (xy 419.264856 -312.706151) (xy 419.313075 -312.696307)
			(xy 419.36225 -312.694326) (xy 419.411105 -312.700258) (xy 419.458376 -312.71395) (xy 419.502838 -312.735048)
			(xy 419.543341 -312.763004) (xy 419.578834 -312.797096) (xy 419.608399 -312.83644) (xy 419.63127 -312.880017)
			(xy 419.646854 -312.926698) (xy 419.654749 -312.975275) (xy 419.655244 -312.999882) (xy 420.944052 -312.999882)
			(xy 420.948012 -312.950828) (xy 420.959789 -312.903044) (xy 420.97908 -312.857768) (xy 421.005383 -312.816172)
			(xy 421.038018 -312.779335) (xy 421.076139 -312.74821) (xy 421.11876 -312.723603) (xy 421.164776 -312.706151)
			(xy 421.212995 -312.696307) (xy 421.26217 -312.694326) (xy 421.311025 -312.700258) (xy 421.358296 -312.71395)
			(xy 421.402758 -312.735048) (xy 421.443261 -312.763004) (xy 421.478754 -312.797096) (xy 421.508319 -312.83644)
			(xy 421.53119 -312.880017) (xy 421.546774 -312.926698) (xy 421.554669 -312.975275) (xy 421.555164 -312.999882)
			(xy 422.844226 -312.999882) (xy 422.848186 -312.950828) (xy 422.859963 -312.903044) (xy 422.879254 -312.857768)
			(xy 422.905557 -312.816172) (xy 422.938192 -312.779335) (xy 422.976313 -312.74821) (xy 423.018934 -312.723603)
			(xy 423.06495 -312.706151) (xy 423.113169 -312.696307) (xy 423.162344 -312.694326) (xy 423.211199 -312.700258)
			(xy 423.25847 -312.71395) (xy 423.302932 -312.735048) (xy 423.343435 -312.763004) (xy 423.378928 -312.797096)
			(xy 423.408493 -312.83644) (xy 423.431364 -312.880017) (xy 423.446948 -312.926698) (xy 423.454843 -312.975275)
			(xy 423.455338 -312.999882) (xy 424.744146 -312.999882) (xy 424.748106 -312.950828) (xy 424.759883 -312.903044)
			(xy 424.779174 -312.857768) (xy 424.805477 -312.816172) (xy 424.838112 -312.779335) (xy 424.876233 -312.74821)
			(xy 424.918854 -312.723603) (xy 424.96487 -312.706151) (xy 425.013089 -312.696307) (xy 425.062264 -312.694326)
			(xy 425.111119 -312.700258) (xy 425.15839 -312.71395) (xy 425.202852 -312.735048) (xy 425.243355 -312.763004)
			(xy 425.278848 -312.797096) (xy 425.308413 -312.83644) (xy 425.331284 -312.880017) (xy 425.346868 -312.926698)
			(xy 425.354763 -312.975275) (xy 425.355258 -312.999882) (xy 426.644066 -312.999882) (xy 426.648026 -312.950828)
			(xy 426.659803 -312.903044) (xy 426.679094 -312.857768) (xy 426.705397 -312.816172) (xy 426.738032 -312.779335)
			(xy 426.776153 -312.74821) (xy 426.818774 -312.723603) (xy 426.86479 -312.706151) (xy 426.913009 -312.696307)
			(xy 426.962184 -312.694326) (xy 427.011039 -312.700258) (xy 427.05831 -312.71395) (xy 427.102772 -312.735048)
			(xy 427.143275 -312.763004) (xy 427.178768 -312.797096) (xy 427.208333 -312.83644) (xy 427.231204 -312.880017)
			(xy 427.246788 -312.926698) (xy 427.254683 -312.975275) (xy 427.255178 -312.999882) (xy 428.543986 -312.999882)
			(xy 428.547946 -312.950828) (xy 428.559723 -312.903044) (xy 428.579014 -312.857768) (xy 428.605317 -312.816172)
			(xy 428.637952 -312.779335) (xy 428.676073 -312.74821) (xy 428.718694 -312.723603) (xy 428.76471 -312.706151)
			(xy 428.812929 -312.696307) (xy 428.862104 -312.694326) (xy 428.910959 -312.700258) (xy 428.95823 -312.71395)
			(xy 429.002692 -312.735048) (xy 429.043195 -312.763004) (xy 429.078688 -312.797096) (xy 429.108253 -312.83644)
			(xy 429.131124 -312.880017) (xy 429.146708 -312.926698) (xy 429.154603 -312.975275) (xy 429.155098 -312.999882)
			(xy 429.154603 -313.024489) (xy 429.146708 -313.073066) (xy 429.131124 -313.119747) (xy 429.108253 -313.163324)
			(xy 429.078688 -313.202668) (xy 429.043195 -313.23676) (xy 429.002692 -313.264716) (xy 428.95823 -313.285814)
			(xy 428.910959 -313.299506) (xy 428.862104 -313.305438) (xy 428.812929 -313.303457) (xy 428.76471 -313.293613)
			(xy 428.718694 -313.276161) (xy 428.676073 -313.251554) (xy 428.637952 -313.220429) (xy 428.605317 -313.183592)
			(xy 428.579014 -313.141996) (xy 428.559723 -313.09672) (xy 428.547946 -313.048936) (xy 428.543986 -312.999882)
			(xy 427.255178 -312.999882) (xy 427.254683 -313.024489) (xy 427.246788 -313.073066) (xy 427.231204 -313.119747)
			(xy 427.208333 -313.163324) (xy 427.178768 -313.202668) (xy 427.143275 -313.23676) (xy 427.102772 -313.264716)
			(xy 427.05831 -313.285814) (xy 427.011039 -313.299506) (xy 426.962184 -313.305438) (xy 426.913009 -313.303457)
			(xy 426.86479 -313.293613) (xy 426.818774 -313.276161) (xy 426.776153 -313.251554) (xy 426.738032 -313.220429)
			(xy 426.705397 -313.183592) (xy 426.679094 -313.141996) (xy 426.659803 -313.09672) (xy 426.648026 -313.048936)
			(xy 426.644066 -312.999882) (xy 425.355258 -312.999882) (xy 425.354763 -313.024489) (xy 425.346868 -313.073066)
			(xy 425.331284 -313.119747) (xy 425.308413 -313.163324) (xy 425.278848 -313.202668) (xy 425.243355 -313.23676)
			(xy 425.202852 -313.264716) (xy 425.15839 -313.285814) (xy 425.111119 -313.299506) (xy 425.062264 -313.305438)
			(xy 425.013089 -313.303457) (xy 424.96487 -313.293613) (xy 424.918854 -313.276161) (xy 424.876233 -313.251554)
			(xy 424.838112 -313.220429) (xy 424.805477 -313.183592) (xy 424.779174 -313.141996) (xy 424.759883 -313.09672)
			(xy 424.748106 -313.048936) (xy 424.744146 -312.999882) (xy 423.455338 -312.999882) (xy 423.454843 -313.024489)
			(xy 423.446948 -313.073066) (xy 423.431364 -313.119747) (xy 423.408493 -313.163324) (xy 423.378928 -313.202668)
			(xy 423.343435 -313.23676) (xy 423.302932 -313.264716) (xy 423.25847 -313.285814) (xy 423.211199 -313.299506)
			(xy 423.162344 -313.305438) (xy 423.113169 -313.303457) (xy 423.06495 -313.293613) (xy 423.018934 -313.276161)
			(xy 422.976313 -313.251554) (xy 422.938192 -313.220429) (xy 422.905557 -313.183592) (xy 422.879254 -313.141996)
			(xy 422.859963 -313.09672) (xy 422.848186 -313.048936) (xy 422.844226 -312.999882) (xy 421.555164 -312.999882)
			(xy 421.554669 -313.024489) (xy 421.546774 -313.073066) (xy 421.53119 -313.119747) (xy 421.508319 -313.163324)
			(xy 421.478754 -313.202668) (xy 421.443261 -313.23676) (xy 421.402758 -313.264716) (xy 421.358296 -313.285814)
			(xy 421.311025 -313.299506) (xy 421.26217 -313.305438) (xy 421.212995 -313.303457) (xy 421.164776 -313.293613)
			(xy 421.11876 -313.276161) (xy 421.076139 -313.251554) (xy 421.038018 -313.220429) (xy 421.005383 -313.183592)
			(xy 420.97908 -313.141996) (xy 420.959789 -313.09672) (xy 420.948012 -313.048936) (xy 420.944052 -312.999882)
			(xy 419.655244 -312.999882) (xy 419.654749 -313.024489) (xy 419.646854 -313.073066) (xy 419.63127 -313.119747)
			(xy 419.608399 -313.163324) (xy 419.578834 -313.202668) (xy 419.543341 -313.23676) (xy 419.502838 -313.264716)
			(xy 419.458376 -313.285814) (xy 419.411105 -313.299506) (xy 419.36225 -313.305438) (xy 419.313075 -313.303457)
			(xy 419.264856 -313.293613) (xy 419.21884 -313.276161) (xy 419.176219 -313.251554) (xy 419.138098 -313.220429)
			(xy 419.105463 -313.183592) (xy 419.07916 -313.141996) (xy 419.059869 -313.09672) (xy 419.048092 -313.048936)
			(xy 419.044132 -312.999882) (xy 417.755324 -312.999882) (xy 417.754829 -313.024489) (xy 417.746934 -313.073066)
			(xy 417.73135 -313.119747) (xy 417.708479 -313.163324) (xy 417.678914 -313.202668) (xy 417.643421 -313.23676)
			(xy 417.602918 -313.264716) (xy 417.558456 -313.285814) (xy 417.511185 -313.299506) (xy 417.46233 -313.305438)
			(xy 417.413155 -313.303457) (xy 417.364936 -313.293613) (xy 417.31892 -313.276161) (xy 417.276299 -313.251554)
			(xy 417.238178 -313.220429) (xy 417.205543 -313.183592) (xy 417.17924 -313.141996) (xy 417.159949 -313.09672)
			(xy 417.148172 -313.048936) (xy 417.144212 -312.999882) (xy 415.85515 -312.999882) (xy 415.854655 -313.024489)
			(xy 415.84676 -313.073066) (xy 415.831176 -313.119747) (xy 415.808305 -313.163324) (xy 415.77874 -313.202668)
			(xy 415.743247 -313.23676) (xy 415.702744 -313.264716) (xy 415.658282 -313.285814) (xy 415.611011 -313.299506)
			(xy 415.562156 -313.305438) (xy 415.512981 -313.303457) (xy 415.464762 -313.293613) (xy 415.418746 -313.276161)
			(xy 415.376125 -313.251554) (xy 415.338004 -313.220429) (xy 415.305369 -313.183592) (xy 415.279066 -313.141996)
			(xy 415.259775 -313.09672) (xy 415.247998 -313.048936) (xy 415.244038 -312.999882) (xy 413.95523 -312.999882)
			(xy 413.954735 -313.024489) (xy 413.94684 -313.073066) (xy 413.931256 -313.119747) (xy 413.908385 -313.163324)
			(xy 413.87882 -313.202668) (xy 413.843327 -313.23676) (xy 413.802824 -313.264716) (xy 413.758362 -313.285814)
			(xy 413.711091 -313.299506) (xy 413.662236 -313.305438) (xy 413.613061 -313.303457) (xy 413.564842 -313.293613)
			(xy 413.518826 -313.276161) (xy 413.476205 -313.251554) (xy 413.438084 -313.220429) (xy 413.405449 -313.183592)
			(xy 413.379146 -313.141996) (xy 413.359855 -313.09672) (xy 413.348078 -313.048936) (xy 413.344118 -312.999882)
			(xy 412.05531 -312.999882) (xy 412.054815 -313.024489) (xy 412.04692 -313.073066) (xy 412.031336 -313.119747)
			(xy 412.008465 -313.163324) (xy 411.9789 -313.202668) (xy 411.943407 -313.23676) (xy 411.902904 -313.264716)
			(xy 411.858442 -313.285814) (xy 411.811171 -313.299506) (xy 411.762316 -313.305438) (xy 411.713141 -313.303457)
			(xy 411.664922 -313.293613) (xy 411.618906 -313.276161) (xy 411.576285 -313.251554) (xy 411.538164 -313.220429)
			(xy 411.505529 -313.183592) (xy 411.479226 -313.141996) (xy 411.459935 -313.09672) (xy 411.448158 -313.048936)
			(xy 411.444198 -312.999882) (xy 410.155136 -312.999882) (xy 410.154641 -313.024489) (xy 410.146746 -313.073066)
			(xy 410.131162 -313.119747) (xy 410.108291 -313.163324) (xy 410.078726 -313.202668) (xy 410.043233 -313.23676)
			(xy 410.00273 -313.264716) (xy 409.958268 -313.285814) (xy 409.910997 -313.299506) (xy 409.862142 -313.305438)
			(xy 409.812967 -313.303457) (xy 409.764748 -313.293613) (xy 409.718732 -313.276161) (xy 409.676111 -313.251554)
			(xy 409.63799 -313.220429) (xy 409.605355 -313.183592) (xy 409.579052 -313.141996) (xy 409.559761 -313.09672)
			(xy 409.547984 -313.048936) (xy 409.544024 -312.999882) (xy 408.255216 -312.999882) (xy 408.254721 -313.024489)
			(xy 408.246826 -313.073066) (xy 408.231242 -313.119747) (xy 408.208371 -313.163324) (xy 408.178806 -313.202668)
			(xy 408.143313 -313.23676) (xy 408.10281 -313.264716) (xy 408.058348 -313.285814) (xy 408.011077 -313.299506)
			(xy 407.962222 -313.305438) (xy 407.913047 -313.303457) (xy 407.864828 -313.293613) (xy 407.818812 -313.276161)
			(xy 407.776191 -313.251554) (xy 407.73807 -313.220429) (xy 407.705435 -313.183592) (xy 407.679132 -313.141996)
			(xy 407.659841 -313.09672) (xy 407.648064 -313.048936) (xy 407.644104 -312.999882) (xy 406.355296 -312.999882)
			(xy 406.354801 -313.024489) (xy 406.346906 -313.073066) (xy 406.331322 -313.119747) (xy 406.308451 -313.163324)
			(xy 406.278886 -313.202668) (xy 406.243393 -313.23676) (xy 406.20289 -313.264716) (xy 406.158428 -313.285814)
			(xy 406.111157 -313.299506) (xy 406.062302 -313.305438) (xy 406.013127 -313.303457) (xy 405.964908 -313.293613)
			(xy 405.918892 -313.276161) (xy 405.876271 -313.251554) (xy 405.83815 -313.220429) (xy 405.805515 -313.183592)
			(xy 405.779212 -313.141996) (xy 405.759921 -313.09672) (xy 405.748144 -313.048936) (xy 405.744184 -312.999882)
			(xy 404.455122 -312.999882) (xy 404.454627 -313.024489) (xy 404.446732 -313.073066) (xy 404.431148 -313.119747)
			(xy 404.408277 -313.163324) (xy 404.378712 -313.202668) (xy 404.343219 -313.23676) (xy 404.302716 -313.264716)
			(xy 404.258254 -313.285814) (xy 404.210983 -313.299506) (xy 404.162128 -313.305438) (xy 404.112953 -313.303457)
			(xy 404.064734 -313.293613) (xy 404.018718 -313.276161) (xy 403.976097 -313.251554) (xy 403.937976 -313.220429)
			(xy 403.905341 -313.183592) (xy 403.879038 -313.141996) (xy 403.859747 -313.09672) (xy 403.84797 -313.048936)
			(xy 403.84401 -312.999882) (xy 402.555202 -312.999882) (xy 402.554707 -313.024489) (xy 402.546812 -313.073066)
			(xy 402.531228 -313.119747) (xy 402.508357 -313.163324) (xy 402.478792 -313.202668) (xy 402.443299 -313.23676)
			(xy 402.402796 -313.264716) (xy 402.358334 -313.285814) (xy 402.311063 -313.299506) (xy 402.262208 -313.305438)
			(xy 402.213033 -313.303457) (xy 402.164814 -313.293613) (xy 402.118798 -313.276161) (xy 402.076177 -313.251554)
			(xy 402.038056 -313.220429) (xy 402.005421 -313.183592) (xy 401.979118 -313.141996) (xy 401.959827 -313.09672)
			(xy 401.94805 -313.048936) (xy 401.94409 -312.999882) (xy 400.655282 -312.999882) (xy 400.654787 -313.024489)
			(xy 400.646892 -313.073066) (xy 400.631308 -313.119747) (xy 400.608437 -313.163324) (xy 400.578872 -313.202668)
			(xy 400.543379 -313.23676) (xy 400.502876 -313.264716) (xy 400.458414 -313.285814) (xy 400.411143 -313.299506)
			(xy 400.362288 -313.305438) (xy 400.313113 -313.303457) (xy 400.264894 -313.293613) (xy 400.218878 -313.276161)
			(xy 400.176257 -313.251554) (xy 400.138136 -313.220429) (xy 400.105501 -313.183592) (xy 400.079198 -313.141996)
			(xy 400.059907 -313.09672) (xy 400.04813 -313.048936) (xy 400.04417 -312.999882) (xy 398.755108 -312.999882)
			(xy 398.754613 -313.024489) (xy 398.746718 -313.073066) (xy 398.731134 -313.119747) (xy 398.708263 -313.163324)
			(xy 398.678698 -313.202668) (xy 398.643205 -313.23676) (xy 398.602702 -313.264716) (xy 398.55824 -313.285814)
			(xy 398.510969 -313.299506) (xy 398.462114 -313.305438) (xy 398.412939 -313.303457) (xy 398.36472 -313.293613)
			(xy 398.318704 -313.276161) (xy 398.276083 -313.251554) (xy 398.237962 -313.220429) (xy 398.205327 -313.183592)
			(xy 398.179024 -313.141996) (xy 398.159733 -313.09672) (xy 398.147956 -313.048936) (xy 398.143996 -312.999882)
			(xy 396.855188 -312.999882) (xy 396.854693 -313.024489) (xy 396.846798 -313.073066) (xy 396.831214 -313.119747)
			(xy 396.808343 -313.163324) (xy 396.778778 -313.202668) (xy 396.743285 -313.23676) (xy 396.702782 -313.264716)
			(xy 396.65832 -313.285814) (xy 396.611049 -313.299506) (xy 396.562194 -313.305438) (xy 396.513019 -313.303457)
			(xy 396.4648 -313.293613) (xy 396.418784 -313.276161) (xy 396.376163 -313.251554) (xy 396.338042 -313.220429)
			(xy 396.305407 -313.183592) (xy 396.279104 -313.141996) (xy 396.259813 -313.09672) (xy 396.248036 -313.048936)
			(xy 396.244076 -312.999882) (xy 394.955268 -312.999882) (xy 394.954773 -313.024489) (xy 394.946878 -313.073066)
			(xy 394.931294 -313.119747) (xy 394.908423 -313.163324) (xy 394.878858 -313.202668) (xy 394.843365 -313.23676)
			(xy 394.802862 -313.264716) (xy 394.7584 -313.285814) (xy 394.711129 -313.299506) (xy 394.662274 -313.305438)
			(xy 394.613099 -313.303457) (xy 394.56488 -313.293613) (xy 394.518864 -313.276161) (xy 394.476243 -313.251554)
			(xy 394.438122 -313.220429) (xy 394.405487 -313.183592) (xy 394.379184 -313.141996) (xy 394.359893 -313.09672)
			(xy 394.348116 -313.048936) (xy 394.344156 -312.999882) (xy 393.055094 -312.999882) (xy 393.054599 -313.024489)
			(xy 393.046704 -313.073066) (xy 393.03112 -313.119747) (xy 393.008249 -313.163324) (xy 392.978684 -313.202668)
			(xy 392.943191 -313.23676) (xy 392.902688 -313.264716) (xy 392.858226 -313.285814) (xy 392.810955 -313.299506)
			(xy 392.7621 -313.305438) (xy 392.712925 -313.303457) (xy 392.664706 -313.293613) (xy 392.61869 -313.276161)
			(xy 392.576069 -313.251554) (xy 392.537948 -313.220429) (xy 392.505313 -313.183592) (xy 392.47901 -313.141996)
			(xy 392.459719 -313.09672) (xy 392.447942 -313.048936) (xy 392.443982 -312.999882) (xy 391.155174 -312.999882)
			(xy 391.154679 -313.024489) (xy 391.146784 -313.073066) (xy 391.1312 -313.119747) (xy 391.108329 -313.163324)
			(xy 391.078764 -313.202668) (xy 391.043271 -313.23676) (xy 391.002768 -313.264716) (xy 390.958306 -313.285814)
			(xy 390.911035 -313.299506) (xy 390.86218 -313.305438) (xy 390.813005 -313.303457) (xy 390.764786 -313.293613)
			(xy 390.71877 -313.276161) (xy 390.676149 -313.251554) (xy 390.638028 -313.220429) (xy 390.605393 -313.183592)
			(xy 390.57909 -313.141996) (xy 390.559799 -313.09672) (xy 390.548022 -313.048936) (xy 390.544062 -312.999882)
			(xy 389.255254 -312.999882) (xy 389.254759 -313.024489) (xy 389.246864 -313.073066) (xy 389.23128 -313.119747)
			(xy 389.208409 -313.163324) (xy 389.178844 -313.202668) (xy 389.143351 -313.23676) (xy 389.102848 -313.264716)
			(xy 389.058386 -313.285814) (xy 389.011115 -313.299506) (xy 388.96226 -313.305438) (xy 388.913085 -313.303457)
			(xy 388.864866 -313.293613) (xy 388.81885 -313.276161) (xy 388.776229 -313.251554) (xy 388.738108 -313.220429)
			(xy 388.705473 -313.183592) (xy 388.67917 -313.141996) (xy 388.659879 -313.09672) (xy 388.648102 -313.048936)
			(xy 388.644142 -312.999882) (xy 387.355334 -312.999882) (xy 387.354839 -313.024489) (xy 387.346944 -313.073066)
			(xy 387.33136 -313.119747) (xy 387.308489 -313.163324) (xy 387.278924 -313.202668) (xy 387.243431 -313.23676)
			(xy 387.202928 -313.264716) (xy 387.158466 -313.285814) (xy 387.111195 -313.299506) (xy 387.06234 -313.305438)
			(xy 387.013165 -313.303457) (xy 386.964946 -313.293613) (xy 386.91893 -313.276161) (xy 386.876309 -313.251554)
			(xy 386.838188 -313.220429) (xy 386.805553 -313.183592) (xy 386.77925 -313.141996) (xy 386.759959 -313.09672)
			(xy 386.748182 -313.048936) (xy 386.744222 -312.999882) (xy 313.055 -312.999882) (xy 313.054505 -313.024489)
			(xy 313.04661 -313.073066) (xy 313.031026 -313.119747) (xy 313.008155 -313.163324) (xy 312.97859 -313.202668)
			(xy 312.943097 -313.23676) (xy 312.902594 -313.264716) (xy 312.858132 -313.285814) (xy 312.810861 -313.299506)
			(xy 312.762006 -313.305438) (xy 312.712831 -313.303457) (xy 312.664612 -313.293613) (xy 312.618596 -313.276161)
			(xy 312.575975 -313.251554) (xy 312.537854 -313.220429) (xy 312.505219 -313.183592) (xy 312.478916 -313.141996)
			(xy 312.459625 -313.09672) (xy 312.447848 -313.048936) (xy 312.443888 -312.999882) (xy 311.15508 -312.999882)
			(xy 311.154585 -313.024489) (xy 311.14669 -313.073066) (xy 311.131106 -313.119747) (xy 311.108235 -313.163324)
			(xy 311.07867 -313.202668) (xy 311.043177 -313.23676) (xy 311.002674 -313.264716) (xy 310.958212 -313.285814)
			(xy 310.910941 -313.299506) (xy 310.862086 -313.305438) (xy 310.812911 -313.303457) (xy 310.764692 -313.293613)
			(xy 310.718676 -313.276161) (xy 310.676055 -313.251554) (xy 310.637934 -313.220429) (xy 310.605299 -313.183592)
			(xy 310.578996 -313.141996) (xy 310.559705 -313.09672) (xy 310.547928 -313.048936) (xy 310.543968 -312.999882)
			(xy 309.25516 -312.999882) (xy 309.254665 -313.024489) (xy 309.24677 -313.073066) (xy 309.231186 -313.119747)
			(xy 309.208315 -313.163324) (xy 309.17875 -313.202668) (xy 309.143257 -313.23676) (xy 309.102754 -313.264716)
			(xy 309.058292 -313.285814) (xy 309.011021 -313.299506) (xy 308.962166 -313.305438) (xy 308.912991 -313.303457)
			(xy 308.864772 -313.293613) (xy 308.818756 -313.276161) (xy 308.776135 -313.251554) (xy 308.738014 -313.220429)
			(xy 308.705379 -313.183592) (xy 308.679076 -313.141996) (xy 308.659785 -313.09672) (xy 308.648008 -313.048936)
			(xy 308.644048 -312.999882) (xy 307.35524 -312.999882) (xy 307.354745 -313.024489) (xy 307.34685 -313.073066)
			(xy 307.331266 -313.119747) (xy 307.308395 -313.163324) (xy 307.27883 -313.202668) (xy 307.243337 -313.23676)
			(xy 307.202834 -313.264716) (xy 307.158372 -313.285814) (xy 307.111101 -313.299506) (xy 307.062246 -313.305438)
			(xy 307.013071 -313.303457) (xy 306.964852 -313.293613) (xy 306.918836 -313.276161) (xy 306.876215 -313.251554)
			(xy 306.838094 -313.220429) (xy 306.805459 -313.183592) (xy 306.779156 -313.141996) (xy 306.759865 -313.09672)
			(xy 306.748088 -313.048936) (xy 306.744128 -312.999882) (xy 305.455066 -312.999882) (xy 305.454571 -313.024489)
			(xy 305.446676 -313.073066) (xy 305.431092 -313.119747) (xy 305.408221 -313.163324) (xy 305.378656 -313.202668)
			(xy 305.343163 -313.23676) (xy 305.30266 -313.264716) (xy 305.258198 -313.285814) (xy 305.210927 -313.299506)
			(xy 305.162072 -313.305438) (xy 305.112897 -313.303457) (xy 305.064678 -313.293613) (xy 305.018662 -313.276161)
			(xy 304.976041 -313.251554) (xy 304.93792 -313.220429) (xy 304.905285 -313.183592) (xy 304.878982 -313.141996)
			(xy 304.859691 -313.09672) (xy 304.847914 -313.048936) (xy 304.843954 -312.999882) (xy 303.555146 -312.999882)
			(xy 303.554651 -313.024489) (xy 303.546756 -313.073066) (xy 303.531172 -313.119747) (xy 303.508301 -313.163324)
			(xy 303.478736 -313.202668) (xy 303.443243 -313.23676) (xy 303.40274 -313.264716) (xy 303.358278 -313.285814)
			(xy 303.311007 -313.299506) (xy 303.262152 -313.305438) (xy 303.212977 -313.303457) (xy 303.164758 -313.293613)
			(xy 303.118742 -313.276161) (xy 303.076121 -313.251554) (xy 303.038 -313.220429) (xy 303.005365 -313.183592)
			(xy 302.979062 -313.141996) (xy 302.959771 -313.09672) (xy 302.947994 -313.048936) (xy 302.944034 -312.999882)
			(xy 301.655226 -312.999882) (xy 301.654731 -313.024489) (xy 301.646836 -313.073066) (xy 301.631252 -313.119747)
			(xy 301.608381 -313.163324) (xy 301.578816 -313.202668) (xy 301.543323 -313.23676) (xy 301.50282 -313.264716)
			(xy 301.458358 -313.285814) (xy 301.411087 -313.299506) (xy 301.362232 -313.305438) (xy 301.313057 -313.303457)
			(xy 301.264838 -313.293613) (xy 301.218822 -313.276161) (xy 301.176201 -313.251554) (xy 301.13808 -313.220429)
			(xy 301.105445 -313.183592) (xy 301.079142 -313.141996) (xy 301.059851 -313.09672) (xy 301.048074 -313.048936)
			(xy 301.044114 -312.999882) (xy 299.755052 -312.999882) (xy 299.754557 -313.024489) (xy 299.746662 -313.073066)
			(xy 299.731078 -313.119747) (xy 299.708207 -313.163324) (xy 299.678642 -313.202668) (xy 299.643149 -313.23676)
			(xy 299.602646 -313.264716) (xy 299.558184 -313.285814) (xy 299.510913 -313.299506) (xy 299.462058 -313.305438)
			(xy 299.412883 -313.303457) (xy 299.364664 -313.293613) (xy 299.318648 -313.276161) (xy 299.276027 -313.251554)
			(xy 299.237906 -313.220429) (xy 299.205271 -313.183592) (xy 299.178968 -313.141996) (xy 299.159677 -313.09672)
			(xy 299.1479 -313.048936) (xy 299.14394 -312.999882) (xy 297.855132 -312.999882) (xy 297.854637 -313.024489)
			(xy 297.846742 -313.073066) (xy 297.831158 -313.119747) (xy 297.808287 -313.163324) (xy 297.778722 -313.202668)
			(xy 297.743229 -313.23676) (xy 297.702726 -313.264716) (xy 297.658264 -313.285814) (xy 297.610993 -313.299506)
			(xy 297.562138 -313.305438) (xy 297.512963 -313.303457) (xy 297.464744 -313.293613) (xy 297.418728 -313.276161)
			(xy 297.376107 -313.251554) (xy 297.337986 -313.220429) (xy 297.305351 -313.183592) (xy 297.279048 -313.141996)
			(xy 297.259757 -313.09672) (xy 297.24798 -313.048936) (xy 297.24402 -312.999882) (xy 295.955212 -312.999882)
			(xy 295.954717 -313.024489) (xy 295.946822 -313.073066) (xy 295.931238 -313.119747) (xy 295.908367 -313.163324)
			(xy 295.878802 -313.202668) (xy 295.843309 -313.23676) (xy 295.802806 -313.264716) (xy 295.758344 -313.285814)
			(xy 295.711073 -313.299506) (xy 295.662218 -313.305438) (xy 295.613043 -313.303457) (xy 295.564824 -313.293613)
			(xy 295.518808 -313.276161) (xy 295.476187 -313.251554) (xy 295.438066 -313.220429) (xy 295.405431 -313.183592)
			(xy 295.379128 -313.141996) (xy 295.359837 -313.09672) (xy 295.34806 -313.048936) (xy 295.3441 -312.999882)
			(xy 294.055038 -312.999882) (xy 294.054543 -313.024489) (xy 294.046648 -313.073066) (xy 294.031064 -313.119747)
			(xy 294.008193 -313.163324) (xy 293.978628 -313.202668) (xy 293.943135 -313.23676) (xy 293.902632 -313.264716)
			(xy 293.85817 -313.285814) (xy 293.810899 -313.299506) (xy 293.762044 -313.305438) (xy 293.712869 -313.303457)
			(xy 293.66465 -313.293613) (xy 293.618634 -313.276161) (xy 293.576013 -313.251554) (xy 293.537892 -313.220429)
			(xy 293.505257 -313.183592) (xy 293.478954 -313.141996) (xy 293.459663 -313.09672) (xy 293.447886 -313.048936)
			(xy 293.443926 -312.999882) (xy 292.155118 -312.999882) (xy 292.154623 -313.024489) (xy 292.146728 -313.073066)
			(xy 292.131144 -313.119747) (xy 292.108273 -313.163324) (xy 292.078708 -313.202668) (xy 292.043215 -313.23676)
			(xy 292.002712 -313.264716) (xy 291.95825 -313.285814) (xy 291.910979 -313.299506) (xy 291.862124 -313.305438)
			(xy 291.812949 -313.303457) (xy 291.76473 -313.293613) (xy 291.718714 -313.276161) (xy 291.676093 -313.251554)
			(xy 291.637972 -313.220429) (xy 291.605337 -313.183592) (xy 291.579034 -313.141996) (xy 291.559743 -313.09672)
			(xy 291.547966 -313.048936) (xy 291.544006 -312.999882) (xy 290.255198 -312.999882) (xy 290.254703 -313.024489)
			(xy 290.246808 -313.073066) (xy 290.231224 -313.119747) (xy 290.208353 -313.163324) (xy 290.178788 -313.202668)
			(xy 290.143295 -313.23676) (xy 290.102792 -313.264716) (xy 290.05833 -313.285814) (xy 290.011059 -313.299506)
			(xy 289.962204 -313.305438) (xy 289.913029 -313.303457) (xy 289.86481 -313.293613) (xy 289.818794 -313.276161)
			(xy 289.776173 -313.251554) (xy 289.738052 -313.220429) (xy 289.705417 -313.183592) (xy 289.679114 -313.141996)
			(xy 289.659823 -313.09672) (xy 289.648046 -313.048936) (xy 289.644086 -312.999882) (xy 288.355024 -312.999882)
			(xy 288.354529 -313.024489) (xy 288.346634 -313.073066) (xy 288.33105 -313.119747) (xy 288.308179 -313.163324)
			(xy 288.278614 -313.202668) (xy 288.243121 -313.23676) (xy 288.202618 -313.264716) (xy 288.158156 -313.285814)
			(xy 288.110885 -313.299506) (xy 288.06203 -313.305438) (xy 288.012855 -313.303457) (xy 287.964636 -313.293613)
			(xy 287.91862 -313.276161) (xy 287.875999 -313.251554) (xy 287.837878 -313.220429) (xy 287.805243 -313.183592)
			(xy 287.77894 -313.141996) (xy 287.759649 -313.09672) (xy 287.747872 -313.048936) (xy 287.743912 -312.999882)
			(xy 286.455104 -312.999882) (xy 286.454609 -313.024489) (xy 286.446714 -313.073066) (xy 286.43113 -313.119747)
			(xy 286.408259 -313.163324) (xy 286.378694 -313.202668) (xy 286.343201 -313.23676) (xy 286.302698 -313.264716)
			(xy 286.258236 -313.285814) (xy 286.210965 -313.299506) (xy 286.16211 -313.305438) (xy 286.112935 -313.303457)
			(xy 286.064716 -313.293613) (xy 286.0187 -313.276161) (xy 285.976079 -313.251554) (xy 285.937958 -313.220429)
			(xy 285.905323 -313.183592) (xy 285.87902 -313.141996) (xy 285.859729 -313.09672) (xy 285.847952 -313.048936)
			(xy 285.843992 -312.999882) (xy 284.555184 -312.999882) (xy 284.554689 -313.024489) (xy 284.546794 -313.073066)
			(xy 284.53121 -313.119747) (xy 284.508339 -313.163324) (xy 284.478774 -313.202668) (xy 284.443281 -313.23676)
			(xy 284.402778 -313.264716) (xy 284.358316 -313.285814) (xy 284.311045 -313.299506) (xy 284.26219 -313.305438)
			(xy 284.213015 -313.303457) (xy 284.164796 -313.293613) (xy 284.11878 -313.276161) (xy 284.076159 -313.251554)
			(xy 284.038038 -313.220429) (xy 284.005403 -313.183592) (xy 283.9791 -313.141996) (xy 283.959809 -313.09672)
			(xy 283.948032 -313.048936) (xy 283.944072 -312.999882) (xy 282.65501 -312.999882) (xy 282.654515 -313.024489)
			(xy 282.64662 -313.073066) (xy 282.631036 -313.119747) (xy 282.608165 -313.163324) (xy 282.5786 -313.202668)
			(xy 282.543107 -313.23676) (xy 282.502604 -313.264716) (xy 282.458142 -313.285814) (xy 282.410871 -313.299506)
			(xy 282.362016 -313.305438) (xy 282.312841 -313.303457) (xy 282.264622 -313.293613) (xy 282.218606 -313.276161)
			(xy 282.175985 -313.251554) (xy 282.137864 -313.220429) (xy 282.105229 -313.183592) (xy 282.078926 -313.141996)
			(xy 282.059635 -313.09672) (xy 282.047858 -313.048936) (xy 282.043898 -312.999882) (xy 280.75509 -312.999882)
			(xy 280.754595 -313.024489) (xy 280.7467 -313.073066) (xy 280.731116 -313.119747) (xy 280.708245 -313.163324)
			(xy 280.67868 -313.202668) (xy 280.643187 -313.23676) (xy 280.602684 -313.264716) (xy 280.558222 -313.285814)
			(xy 280.510951 -313.299506) (xy 280.462096 -313.305438) (xy 280.412921 -313.303457) (xy 280.364702 -313.293613)
			(xy 280.318686 -313.276161) (xy 280.276065 -313.251554) (xy 280.237944 -313.220429) (xy 280.205309 -313.183592)
			(xy 280.179006 -313.141996) (xy 280.159715 -313.09672) (xy 280.147938 -313.048936) (xy 280.143978 -312.999882)
			(xy 278.85517 -312.999882) (xy 278.854675 -313.024489) (xy 278.84678 -313.073066) (xy 278.831196 -313.119747)
			(xy 278.808325 -313.163324) (xy 278.77876 -313.202668) (xy 278.743267 -313.23676) (xy 278.702764 -313.264716)
			(xy 278.658302 -313.285814) (xy 278.611031 -313.299506) (xy 278.562176 -313.305438) (xy 278.513001 -313.303457)
			(xy 278.464782 -313.293613) (xy 278.418766 -313.276161) (xy 278.376145 -313.251554) (xy 278.338024 -313.220429)
			(xy 278.305389 -313.183592) (xy 278.279086 -313.141996) (xy 278.259795 -313.09672) (xy 278.248018 -313.048936)
			(xy 278.244058 -312.999882) (xy 276.954996 -312.999882) (xy 276.954501 -313.024489) (xy 276.946606 -313.073066)
			(xy 276.931022 -313.119747) (xy 276.908151 -313.163324) (xy 276.878586 -313.202668) (xy 276.843093 -313.23676)
			(xy 276.80259 -313.264716) (xy 276.758128 -313.285814) (xy 276.710857 -313.299506) (xy 276.662002 -313.305438)
			(xy 276.612827 -313.303457) (xy 276.564608 -313.293613) (xy 276.518592 -313.276161) (xy 276.475971 -313.251554)
			(xy 276.43785 -313.220429) (xy 276.405215 -313.183592) (xy 276.378912 -313.141996) (xy 276.359621 -313.09672)
			(xy 276.347844 -313.048936) (xy 276.343884 -312.999882) (xy 275.055076 -312.999882) (xy 275.054581 -313.024489)
			(xy 275.046686 -313.073066) (xy 275.031102 -313.119747) (xy 275.008231 -313.163324) (xy 274.978666 -313.202668)
			(xy 274.943173 -313.23676) (xy 274.90267 -313.264716) (xy 274.858208 -313.285814) (xy 274.810937 -313.299506)
			(xy 274.762082 -313.305438) (xy 274.712907 -313.303457) (xy 274.664688 -313.293613) (xy 274.618672 -313.276161)
			(xy 274.576051 -313.251554) (xy 274.53793 -313.220429) (xy 274.505295 -313.183592) (xy 274.478992 -313.141996)
			(xy 274.459701 -313.09672) (xy 274.447924 -313.048936) (xy 274.443964 -312.999882) (xy 273.155156 -312.999882)
			(xy 273.154661 -313.024489) (xy 273.146766 -313.073066) (xy 273.131182 -313.119747) (xy 273.108311 -313.163324)
			(xy 273.078746 -313.202668) (xy 273.043253 -313.23676) (xy 273.00275 -313.264716) (xy 272.958288 -313.285814)
			(xy 272.911017 -313.299506) (xy 272.862162 -313.305438) (xy 272.812987 -313.303457) (xy 272.764768 -313.293613)
			(xy 272.718752 -313.276161) (xy 272.676131 -313.251554) (xy 272.63801 -313.220429) (xy 272.605375 -313.183592)
			(xy 272.579072 -313.141996) (xy 272.559781 -313.09672) (xy 272.548004 -313.048936) (xy 272.544044 -312.999882)
			(xy 271.255236 -312.999882) (xy 271.254741 -313.024489) (xy 271.246846 -313.073066) (xy 271.231262 -313.119747)
			(xy 271.208391 -313.163324) (xy 271.178826 -313.202668) (xy 271.143333 -313.23676) (xy 271.10283 -313.264716)
			(xy 271.058368 -313.285814) (xy 271.011097 -313.299506) (xy 270.962242 -313.305438) (xy 270.913067 -313.303457)
			(xy 270.864848 -313.293613) (xy 270.818832 -313.276161) (xy 270.776211 -313.251554) (xy 270.73809 -313.220429)
			(xy 270.705455 -313.183592) (xy 270.679152 -313.141996) (xy 270.659861 -313.09672) (xy 270.648084 -313.048936)
			(xy 270.644124 -312.999882) (xy 196.955156 -312.999882) (xy 196.954661 -313.024489) (xy 196.946766 -313.073066)
			(xy 196.931182 -313.119747) (xy 196.908311 -313.163324) (xy 196.878746 -313.202668) (xy 196.843253 -313.23676)
			(xy 196.80275 -313.264716) (xy 196.758288 -313.285814) (xy 196.711017 -313.299506) (xy 196.662162 -313.305438)
			(xy 196.612987 -313.303457) (xy 196.564768 -313.293613) (xy 196.518752 -313.276161) (xy 196.476131 -313.251554)
			(xy 196.43801 -313.220429) (xy 196.405375 -313.183592) (xy 196.379072 -313.141996) (xy 196.359781 -313.09672)
			(xy 196.348004 -313.048936) (xy 196.344044 -312.999882) (xy 195.055236 -312.999882) (xy 195.054741 -313.024489)
			(xy 195.046846 -313.073066) (xy 195.031262 -313.119747) (xy 195.008391 -313.163324) (xy 194.978826 -313.202668)
			(xy 194.943333 -313.23676) (xy 194.90283 -313.264716) (xy 194.858368 -313.285814) (xy 194.811097 -313.299506)
			(xy 194.762242 -313.305438) (xy 194.713067 -313.303457) (xy 194.664848 -313.293613) (xy 194.618832 -313.276161)
			(xy 194.576211 -313.251554) (xy 194.53809 -313.220429) (xy 194.505455 -313.183592) (xy 194.479152 -313.141996)
			(xy 194.459861 -313.09672) (xy 194.448084 -313.048936) (xy 194.444124 -312.999882) (xy 193.155316 -312.999882)
			(xy 193.154821 -313.024489) (xy 193.146926 -313.073066) (xy 193.131342 -313.119747) (xy 193.108471 -313.163324)
			(xy 193.078906 -313.202668) (xy 193.043413 -313.23676) (xy 193.00291 -313.264716) (xy 192.958448 -313.285814)
			(xy 192.911177 -313.299506) (xy 192.862322 -313.305438) (xy 192.813147 -313.303457) (xy 192.764928 -313.293613)
			(xy 192.718912 -313.276161) (xy 192.676291 -313.251554) (xy 192.63817 -313.220429) (xy 192.605535 -313.183592)
			(xy 192.579232 -313.141996) (xy 192.559941 -313.09672) (xy 192.548164 -313.048936) (xy 192.544204 -312.999882)
			(xy 191.255396 -312.999882) (xy 191.254901 -313.024489) (xy 191.247006 -313.073066) (xy 191.231422 -313.119747)
			(xy 191.208551 -313.163324) (xy 191.178986 -313.202668) (xy 191.143493 -313.23676) (xy 191.10299 -313.264716)
			(xy 191.058528 -313.285814) (xy 191.011257 -313.299506) (xy 190.962402 -313.305438) (xy 190.913227 -313.303457)
			(xy 190.865008 -313.293613) (xy 190.818992 -313.276161) (xy 190.776371 -313.251554) (xy 190.73825 -313.220429)
			(xy 190.705615 -313.183592) (xy 190.679312 -313.141996) (xy 190.660021 -313.09672) (xy 190.648244 -313.048936)
			(xy 190.644284 -312.999882) (xy 189.355222 -312.999882) (xy 189.354727 -313.024489) (xy 189.346832 -313.073066)
			(xy 189.331248 -313.119747) (xy 189.308377 -313.163324) (xy 189.278812 -313.202668) (xy 189.243319 -313.23676)
			(xy 189.202816 -313.264716) (xy 189.158354 -313.285814) (xy 189.111083 -313.299506) (xy 189.062228 -313.305438)
			(xy 189.013053 -313.303457) (xy 188.964834 -313.293613) (xy 188.918818 -313.276161) (xy 188.876197 -313.251554)
			(xy 188.838076 -313.220429) (xy 188.805441 -313.183592) (xy 188.779138 -313.141996) (xy 188.759847 -313.09672)
			(xy 188.74807 -313.048936) (xy 188.74411 -312.999882) (xy 187.455302 -312.999882) (xy 187.454807 -313.024489)
			(xy 187.446912 -313.073066) (xy 187.431328 -313.119747) (xy 187.408457 -313.163324) (xy 187.378892 -313.202668)
			(xy 187.343399 -313.23676) (xy 187.302896 -313.264716) (xy 187.258434 -313.285814) (xy 187.211163 -313.299506)
			(xy 187.162308 -313.305438) (xy 187.113133 -313.303457) (xy 187.064914 -313.293613) (xy 187.018898 -313.276161)
			(xy 186.976277 -313.251554) (xy 186.938156 -313.220429) (xy 186.905521 -313.183592) (xy 186.879218 -313.141996)
			(xy 186.859927 -313.09672) (xy 186.84815 -313.048936) (xy 186.84419 -312.999882) (xy 185.555382 -312.999882)
			(xy 185.554887 -313.024489) (xy 185.546992 -313.073066) (xy 185.531408 -313.119747) (xy 185.508537 -313.163324)
			(xy 185.478972 -313.202668) (xy 185.443479 -313.23676) (xy 185.402976 -313.264716) (xy 185.358514 -313.285814)
			(xy 185.311243 -313.299506) (xy 185.262388 -313.305438) (xy 185.213213 -313.303457) (xy 185.164994 -313.293613)
			(xy 185.118978 -313.276161) (xy 185.076357 -313.251554) (xy 185.038236 -313.220429) (xy 185.005601 -313.183592)
			(xy 184.979298 -313.141996) (xy 184.960007 -313.09672) (xy 184.94823 -313.048936) (xy 184.94427 -312.999882)
			(xy 183.655208 -312.999882) (xy 183.654713 -313.024489) (xy 183.646818 -313.073066) (xy 183.631234 -313.119747)
			(xy 183.608363 -313.163324) (xy 183.578798 -313.202668) (xy 183.543305 -313.23676) (xy 183.502802 -313.264716)
			(xy 183.45834 -313.285814) (xy 183.411069 -313.299506) (xy 183.362214 -313.305438) (xy 183.313039 -313.303457)
			(xy 183.26482 -313.293613) (xy 183.218804 -313.276161) (xy 183.176183 -313.251554) (xy 183.138062 -313.220429)
			(xy 183.105427 -313.183592) (xy 183.079124 -313.141996) (xy 183.059833 -313.09672) (xy 183.048056 -313.048936)
			(xy 183.044096 -312.999882) (xy 181.755288 -312.999882) (xy 181.754793 -313.024489) (xy 181.746898 -313.073066)
			(xy 181.731314 -313.119747) (xy 181.708443 -313.163324) (xy 181.678878 -313.202668) (xy 181.643385 -313.23676)
			(xy 181.602882 -313.264716) (xy 181.55842 -313.285814) (xy 181.511149 -313.299506) (xy 181.462294 -313.305438)
			(xy 181.413119 -313.303457) (xy 181.3649 -313.293613) (xy 181.318884 -313.276161) (xy 181.276263 -313.251554)
			(xy 181.238142 -313.220429) (xy 181.205507 -313.183592) (xy 181.179204 -313.141996) (xy 181.159913 -313.09672)
			(xy 181.148136 -313.048936) (xy 181.144176 -312.999882) (xy 179.855368 -312.999882) (xy 179.854873 -313.024489)
			(xy 179.846978 -313.073066) (xy 179.831394 -313.119747) (xy 179.808523 -313.163324) (xy 179.778958 -313.202668)
			(xy 179.743465 -313.23676) (xy 179.702962 -313.264716) (xy 179.6585 -313.285814) (xy 179.611229 -313.299506)
			(xy 179.562374 -313.305438) (xy 179.513199 -313.303457) (xy 179.46498 -313.293613) (xy 179.418964 -313.276161)
			(xy 179.376343 -313.251554) (xy 179.338222 -313.220429) (xy 179.305587 -313.183592) (xy 179.279284 -313.141996)
			(xy 179.259993 -313.09672) (xy 179.248216 -313.048936) (xy 179.244256 -312.999882) (xy 177.955194 -312.999882)
			(xy 177.954699 -313.024489) (xy 177.946804 -313.073066) (xy 177.93122 -313.119747) (xy 177.908349 -313.163324)
			(xy 177.878784 -313.202668) (xy 177.843291 -313.23676) (xy 177.802788 -313.264716) (xy 177.758326 -313.285814)
			(xy 177.711055 -313.299506) (xy 177.6622 -313.305438) (xy 177.613025 -313.303457) (xy 177.564806 -313.293613)
			(xy 177.51879 -313.276161) (xy 177.476169 -313.251554) (xy 177.438048 -313.220429) (xy 177.405413 -313.183592)
			(xy 177.37911 -313.141996) (xy 177.359819 -313.09672) (xy 177.348042 -313.048936) (xy 177.344082 -312.999882)
			(xy 176.055274 -312.999882) (xy 176.054779 -313.024489) (xy 176.046884 -313.073066) (xy 176.0313 -313.119747)
			(xy 176.008429 -313.163324) (xy 175.978864 -313.202668) (xy 175.943371 -313.23676) (xy 175.902868 -313.264716)
			(xy 175.858406 -313.285814) (xy 175.811135 -313.299506) (xy 175.76228 -313.305438) (xy 175.713105 -313.303457)
			(xy 175.664886 -313.293613) (xy 175.61887 -313.276161) (xy 175.576249 -313.251554) (xy 175.538128 -313.220429)
			(xy 175.505493 -313.183592) (xy 175.47919 -313.141996) (xy 175.459899 -313.09672) (xy 175.448122 -313.048936)
			(xy 175.444162 -312.999882) (xy 174.155354 -312.999882) (xy 174.154859 -313.024489) (xy 174.146964 -313.073066)
			(xy 174.13138 -313.119747) (xy 174.108509 -313.163324) (xy 174.078944 -313.202668) (xy 174.043451 -313.23676)
			(xy 174.002948 -313.264716) (xy 173.958486 -313.285814) (xy 173.911215 -313.299506) (xy 173.86236 -313.305438)
			(xy 173.813185 -313.303457) (xy 173.764966 -313.293613) (xy 173.71895 -313.276161) (xy 173.676329 -313.251554)
			(xy 173.638208 -313.220429) (xy 173.605573 -313.183592) (xy 173.57927 -313.141996) (xy 173.559979 -313.09672)
			(xy 173.548202 -313.048936) (xy 173.544242 -312.999882) (xy 172.25518 -312.999882) (xy 172.254685 -313.024489)
			(xy 172.24679 -313.073066) (xy 172.231206 -313.119747) (xy 172.208335 -313.163324) (xy 172.17877 -313.202668)
			(xy 172.143277 -313.23676) (xy 172.102774 -313.264716) (xy 172.058312 -313.285814) (xy 172.011041 -313.299506)
			(xy 171.962186 -313.305438) (xy 171.913011 -313.303457) (xy 171.864792 -313.293613) (xy 171.818776 -313.276161)
			(xy 171.776155 -313.251554) (xy 171.738034 -313.220429) (xy 171.705399 -313.183592) (xy 171.679096 -313.141996)
			(xy 171.659805 -313.09672) (xy 171.648028 -313.048936) (xy 171.644068 -312.999882) (xy 170.35526 -312.999882)
			(xy 170.354765 -313.024489) (xy 170.34687 -313.073066) (xy 170.331286 -313.119747) (xy 170.308415 -313.163324)
			(xy 170.27885 -313.202668) (xy 170.243357 -313.23676) (xy 170.202854 -313.264716) (xy 170.158392 -313.285814)
			(xy 170.111121 -313.299506) (xy 170.062266 -313.305438) (xy 170.013091 -313.303457) (xy 169.964872 -313.293613)
			(xy 169.918856 -313.276161) (xy 169.876235 -313.251554) (xy 169.838114 -313.220429) (xy 169.805479 -313.183592)
			(xy 169.779176 -313.141996) (xy 169.759885 -313.09672) (xy 169.748108 -313.048936) (xy 169.744148 -312.999882)
			(xy 168.45534 -312.999882) (xy 168.454845 -313.024489) (xy 168.44695 -313.073066) (xy 168.431366 -313.119747)
			(xy 168.408495 -313.163324) (xy 168.37893 -313.202668) (xy 168.343437 -313.23676) (xy 168.302934 -313.264716)
			(xy 168.258472 -313.285814) (xy 168.211201 -313.299506) (xy 168.162346 -313.305438) (xy 168.113171 -313.303457)
			(xy 168.064952 -313.293613) (xy 168.018936 -313.276161) (xy 167.976315 -313.251554) (xy 167.938194 -313.220429)
			(xy 167.905559 -313.183592) (xy 167.879256 -313.141996) (xy 167.859965 -313.09672) (xy 167.848188 -313.048936)
			(xy 167.844228 -312.999882) (xy 166.555166 -312.999882) (xy 166.554671 -313.024489) (xy 166.546776 -313.073066)
			(xy 166.531192 -313.119747) (xy 166.508321 -313.163324) (xy 166.478756 -313.202668) (xy 166.443263 -313.23676)
			(xy 166.40276 -313.264716) (xy 166.358298 -313.285814) (xy 166.311027 -313.299506) (xy 166.262172 -313.305438)
			(xy 166.212997 -313.303457) (xy 166.164778 -313.293613) (xy 166.118762 -313.276161) (xy 166.076141 -313.251554)
			(xy 166.03802 -313.220429) (xy 166.005385 -313.183592) (xy 165.979082 -313.141996) (xy 165.959791 -313.09672)
			(xy 165.948014 -313.048936) (xy 165.944054 -312.999882) (xy 164.655246 -312.999882) (xy 164.654751 -313.024489)
			(xy 164.646856 -313.073066) (xy 164.631272 -313.119747) (xy 164.608401 -313.163324) (xy 164.578836 -313.202668)
			(xy 164.543343 -313.23676) (xy 164.50284 -313.264716) (xy 164.458378 -313.285814) (xy 164.411107 -313.299506)
			(xy 164.362252 -313.305438) (xy 164.313077 -313.303457) (xy 164.264858 -313.293613) (xy 164.218842 -313.276161)
			(xy 164.176221 -313.251554) (xy 164.1381 -313.220429) (xy 164.105465 -313.183592) (xy 164.079162 -313.141996)
			(xy 164.059871 -313.09672) (xy 164.048094 -313.048936) (xy 164.044134 -312.999882) (xy 162.755326 -312.999882)
			(xy 162.754831 -313.024489) (xy 162.746936 -313.073066) (xy 162.731352 -313.119747) (xy 162.708481 -313.163324)
			(xy 162.678916 -313.202668) (xy 162.643423 -313.23676) (xy 162.60292 -313.264716) (xy 162.558458 -313.285814)
			(xy 162.511187 -313.299506) (xy 162.462332 -313.305438) (xy 162.413157 -313.303457) (xy 162.364938 -313.293613)
			(xy 162.318922 -313.276161) (xy 162.276301 -313.251554) (xy 162.23818 -313.220429) (xy 162.205545 -313.183592)
			(xy 162.179242 -313.141996) (xy 162.159951 -313.09672) (xy 162.148174 -313.048936) (xy 162.144214 -312.999882)
			(xy 160.855152 -312.999882) (xy 160.854657 -313.024489) (xy 160.846762 -313.073066) (xy 160.831178 -313.119747)
			(xy 160.808307 -313.163324) (xy 160.778742 -313.202668) (xy 160.743249 -313.23676) (xy 160.702746 -313.264716)
			(xy 160.658284 -313.285814) (xy 160.611013 -313.299506) (xy 160.562158 -313.305438) (xy 160.512983 -313.303457)
			(xy 160.464764 -313.293613) (xy 160.418748 -313.276161) (xy 160.376127 -313.251554) (xy 160.338006 -313.220429)
			(xy 160.305371 -313.183592) (xy 160.279068 -313.141996) (xy 160.259777 -313.09672) (xy 160.248 -313.048936)
			(xy 160.24404 -312.999882) (xy 158.955232 -312.999882) (xy 158.954737 -313.024489) (xy 158.946842 -313.073066)
			(xy 158.931258 -313.119747) (xy 158.908387 -313.163324) (xy 158.878822 -313.202668) (xy 158.843329 -313.23676)
			(xy 158.802826 -313.264716) (xy 158.758364 -313.285814) (xy 158.711093 -313.299506) (xy 158.662238 -313.305438)
			(xy 158.613063 -313.303457) (xy 158.564844 -313.293613) (xy 158.518828 -313.276161) (xy 158.476207 -313.251554)
			(xy 158.438086 -313.220429) (xy 158.405451 -313.183592) (xy 158.379148 -313.141996) (xy 158.359857 -313.09672)
			(xy 158.34808 -313.048936) (xy 158.34412 -312.999882) (xy 157.055312 -312.999882) (xy 157.054817 -313.024489)
			(xy 157.046922 -313.073066) (xy 157.031338 -313.119747) (xy 157.008467 -313.163324) (xy 156.978902 -313.202668)
			(xy 156.943409 -313.23676) (xy 156.902906 -313.264716) (xy 156.858444 -313.285814) (xy 156.811173 -313.299506)
			(xy 156.762318 -313.305438) (xy 156.713143 -313.303457) (xy 156.664924 -313.293613) (xy 156.618908 -313.276161)
			(xy 156.576287 -313.251554) (xy 156.538166 -313.220429) (xy 156.505531 -313.183592) (xy 156.479228 -313.141996)
			(xy 156.459937 -313.09672) (xy 156.44816 -313.048936) (xy 156.4442 -312.999882) (xy 155.155392 -312.999882)
			(xy 155.154897 -313.024489) (xy 155.147002 -313.073066) (xy 155.131418 -313.119747) (xy 155.108547 -313.163324)
			(xy 155.078982 -313.202668) (xy 155.043489 -313.23676) (xy 155.002986 -313.264716) (xy 154.958524 -313.285814)
			(xy 154.911253 -313.299506) (xy 154.862398 -313.305438) (xy 154.813223 -313.303457) (xy 154.765004 -313.293613)
			(xy 154.718988 -313.276161) (xy 154.676367 -313.251554) (xy 154.638246 -313.220429) (xy 154.605611 -313.183592)
			(xy 154.579308 -313.141996) (xy 154.560017 -313.09672) (xy 154.54824 -313.048936) (xy 154.54428 -312.999882)
			(xy 80.855058 -312.999882) (xy 80.854563 -313.024489) (xy 80.846668 -313.073066) (xy 80.831084 -313.119747)
			(xy 80.808213 -313.163324) (xy 80.778648 -313.202668) (xy 80.743155 -313.23676) (xy 80.702652 -313.264716)
			(xy 80.65819 -313.285814) (xy 80.610919 -313.299506) (xy 80.562064 -313.305438) (xy 80.512889 -313.303457)
			(xy 80.46467 -313.293613) (xy 80.418654 -313.276161) (xy 80.376033 -313.251554) (xy 80.337912 -313.220429)
			(xy 80.305277 -313.183592) (xy 80.278974 -313.141996) (xy 80.259683 -313.09672) (xy 80.247906 -313.048936)
			(xy 80.243946 -312.999882) (xy 78.955138 -312.999882) (xy 78.954643 -313.024489) (xy 78.946748 -313.073066)
			(xy 78.931164 -313.119747) (xy 78.908293 -313.163324) (xy 78.878728 -313.202668) (xy 78.843235 -313.23676)
			(xy 78.802732 -313.264716) (xy 78.75827 -313.285814) (xy 78.710999 -313.299506) (xy 78.662144 -313.305438)
			(xy 78.612969 -313.303457) (xy 78.56475 -313.293613) (xy 78.518734 -313.276161) (xy 78.476113 -313.251554)
			(xy 78.437992 -313.220429) (xy 78.405357 -313.183592) (xy 78.379054 -313.141996) (xy 78.359763 -313.09672)
			(xy 78.347986 -313.048936) (xy 78.344026 -312.999882) (xy 77.055218 -312.999882) (xy 77.054723 -313.024489)
			(xy 77.046828 -313.073066) (xy 77.031244 -313.119747) (xy 77.008373 -313.163324) (xy 76.978808 -313.202668)
			(xy 76.943315 -313.23676) (xy 76.902812 -313.264716) (xy 76.85835 -313.285814) (xy 76.811079 -313.299506)
			(xy 76.762224 -313.305438) (xy 76.713049 -313.303457) (xy 76.66483 -313.293613) (xy 76.618814 -313.276161)
			(xy 76.576193 -313.251554) (xy 76.538072 -313.220429) (xy 76.505437 -313.183592) (xy 76.479134 -313.141996)
			(xy 76.459843 -313.09672) (xy 76.448066 -313.048936) (xy 76.444106 -312.999882) (xy 75.155298 -312.999882)
			(xy 75.154803 -313.024489) (xy 75.146908 -313.073066) (xy 75.131324 -313.119747) (xy 75.108453 -313.163324)
			(xy 75.078888 -313.202668) (xy 75.043395 -313.23676) (xy 75.002892 -313.264716) (xy 74.95843 -313.285814)
			(xy 74.911159 -313.299506) (xy 74.862304 -313.305438) (xy 74.813129 -313.303457) (xy 74.76491 -313.293613)
			(xy 74.718894 -313.276161) (xy 74.676273 -313.251554) (xy 74.638152 -313.220429) (xy 74.605517 -313.183592)
			(xy 74.579214 -313.141996) (xy 74.559923 -313.09672) (xy 74.548146 -313.048936) (xy 74.544186 -312.999882)
			(xy 73.255124 -312.999882) (xy 73.254629 -313.024489) (xy 73.246734 -313.073066) (xy 73.23115 -313.119747)
			(xy 73.208279 -313.163324) (xy 73.178714 -313.202668) (xy 73.143221 -313.23676) (xy 73.102718 -313.264716)
			(xy 73.058256 -313.285814) (xy 73.010985 -313.299506) (xy 72.96213 -313.305438) (xy 72.912955 -313.303457)
			(xy 72.864736 -313.293613) (xy 72.81872 -313.276161) (xy 72.776099 -313.251554) (xy 72.737978 -313.220429)
			(xy 72.705343 -313.183592) (xy 72.67904 -313.141996) (xy 72.659749 -313.09672) (xy 72.647972 -313.048936)
			(xy 72.644012 -312.999882) (xy 71.355204 -312.999882) (xy 71.354709 -313.024489) (xy 71.346814 -313.073066)
			(xy 71.33123 -313.119747) (xy 71.308359 -313.163324) (xy 71.278794 -313.202668) (xy 71.243301 -313.23676)
			(xy 71.202798 -313.264716) (xy 71.158336 -313.285814) (xy 71.111065 -313.299506) (xy 71.06221 -313.305438)
			(xy 71.013035 -313.303457) (xy 70.964816 -313.293613) (xy 70.9188 -313.276161) (xy 70.876179 -313.251554)
			(xy 70.838058 -313.220429) (xy 70.805423 -313.183592) (xy 70.77912 -313.141996) (xy 70.759829 -313.09672)
			(xy 70.748052 -313.048936) (xy 70.744092 -312.999882) (xy 69.455284 -312.999882) (xy 69.454789 -313.024489)
			(xy 69.446894 -313.073066) (xy 69.43131 -313.119747) (xy 69.408439 -313.163324) (xy 69.378874 -313.202668)
			(xy 69.343381 -313.23676) (xy 69.302878 -313.264716) (xy 69.258416 -313.285814) (xy 69.211145 -313.299506)
			(xy 69.16229 -313.305438) (xy 69.113115 -313.303457) (xy 69.064896 -313.293613) (xy 69.01888 -313.276161)
			(xy 68.976259 -313.251554) (xy 68.938138 -313.220429) (xy 68.905503 -313.183592) (xy 68.8792 -313.141996)
			(xy 68.859909 -313.09672) (xy 68.848132 -313.048936) (xy 68.844172 -312.999882) (xy 67.55511 -312.999882)
			(xy 67.554615 -313.024489) (xy 67.54672 -313.073066) (xy 67.531136 -313.119747) (xy 67.508265 -313.163324)
			(xy 67.4787 -313.202668) (xy 67.443207 -313.23676) (xy 67.402704 -313.264716) (xy 67.358242 -313.285814)
			(xy 67.310971 -313.299506) (xy 67.262116 -313.305438) (xy 67.212941 -313.303457) (xy 67.164722 -313.293613)
			(xy 67.118706 -313.276161) (xy 67.076085 -313.251554) (xy 67.037964 -313.220429) (xy 67.005329 -313.183592)
			(xy 66.979026 -313.141996) (xy 66.959735 -313.09672) (xy 66.947958 -313.048936) (xy 66.943998 -312.999882)
			(xy 65.65519 -312.999882) (xy 65.654695 -313.024489) (xy 65.6468 -313.073066) (xy 65.631216 -313.119747)
			(xy 65.608345 -313.163324) (xy 65.57878 -313.202668) (xy 65.543287 -313.23676) (xy 65.502784 -313.264716)
			(xy 65.458322 -313.285814) (xy 65.411051 -313.299506) (xy 65.362196 -313.305438) (xy 65.313021 -313.303457)
			(xy 65.264802 -313.293613) (xy 65.218786 -313.276161) (xy 65.176165 -313.251554) (xy 65.138044 -313.220429)
			(xy 65.105409 -313.183592) (xy 65.079106 -313.141996) (xy 65.059815 -313.09672) (xy 65.048038 -313.048936)
			(xy 65.044078 -312.999882) (xy 63.75527 -312.999882) (xy 63.754775 -313.024489) (xy 63.74688 -313.073066)
			(xy 63.731296 -313.119747) (xy 63.708425 -313.163324) (xy 63.67886 -313.202668) (xy 63.643367 -313.23676)
			(xy 63.602864 -313.264716) (xy 63.558402 -313.285814) (xy 63.511131 -313.299506) (xy 63.462276 -313.305438)
			(xy 63.413101 -313.303457) (xy 63.364882 -313.293613) (xy 63.318866 -313.276161) (xy 63.276245 -313.251554)
			(xy 63.238124 -313.220429) (xy 63.205489 -313.183592) (xy 63.179186 -313.141996) (xy 63.159895 -313.09672)
			(xy 63.148118 -313.048936) (xy 63.144158 -312.999882) (xy 61.855096 -312.999882) (xy 61.854601 -313.024489)
			(xy 61.846706 -313.073066) (xy 61.831122 -313.119747) (xy 61.808251 -313.163324) (xy 61.778686 -313.202668)
			(xy 61.743193 -313.23676) (xy 61.70269 -313.264716) (xy 61.658228 -313.285814) (xy 61.610957 -313.299506)
			(xy 61.562102 -313.305438) (xy 61.512927 -313.303457) (xy 61.464708 -313.293613) (xy 61.418692 -313.276161)
			(xy 61.376071 -313.251554) (xy 61.33795 -313.220429) (xy 61.305315 -313.183592) (xy 61.279012 -313.141996)
			(xy 61.259721 -313.09672) (xy 61.247944 -313.048936) (xy 61.243984 -312.999882) (xy 59.955176 -312.999882)
			(xy 59.954681 -313.024489) (xy 59.946786 -313.073066) (xy 59.931202 -313.119747) (xy 59.908331 -313.163324)
			(xy 59.878766 -313.202668) (xy 59.843273 -313.23676) (xy 59.80277 -313.264716) (xy 59.758308 -313.285814)
			(xy 59.711037 -313.299506) (xy 59.662182 -313.305438) (xy 59.613007 -313.303457) (xy 59.564788 -313.293613)
			(xy 59.518772 -313.276161) (xy 59.476151 -313.251554) (xy 59.43803 -313.220429) (xy 59.405395 -313.183592)
			(xy 59.379092 -313.141996) (xy 59.359801 -313.09672) (xy 59.348024 -313.048936) (xy 59.344064 -312.999882)
			(xy 58.055256 -312.999882) (xy 58.054761 -313.024489) (xy 58.046866 -313.073066) (xy 58.031282 -313.119747)
			(xy 58.008411 -313.163324) (xy 57.978846 -313.202668) (xy 57.943353 -313.23676) (xy 57.90285 -313.264716)
			(xy 57.858388 -313.285814) (xy 57.811117 -313.299506) (xy 57.762262 -313.305438) (xy 57.713087 -313.303457)
			(xy 57.664868 -313.293613) (xy 57.618852 -313.276161) (xy 57.576231 -313.251554) (xy 57.53811 -313.220429)
			(xy 57.505475 -313.183592) (xy 57.479172 -313.141996) (xy 57.459881 -313.09672) (xy 57.448104 -313.048936)
			(xy 57.444144 -312.999882) (xy 56.155082 -312.999882) (xy 56.154587 -313.024489) (xy 56.146692 -313.073066)
			(xy 56.131108 -313.119747) (xy 56.108237 -313.163324) (xy 56.078672 -313.202668) (xy 56.043179 -313.23676)
			(xy 56.002676 -313.264716) (xy 55.958214 -313.285814) (xy 55.910943 -313.299506) (xy 55.862088 -313.305438)
			(xy 55.812913 -313.303457) (xy 55.764694 -313.293613) (xy 55.718678 -313.276161) (xy 55.676057 -313.251554)
			(xy 55.637936 -313.220429) (xy 55.605301 -313.183592) (xy 55.578998 -313.141996) (xy 55.559707 -313.09672)
			(xy 55.54793 -313.048936) (xy 55.54397 -312.999882) (xy 54.255162 -312.999882) (xy 54.254667 -313.024489)
			(xy 54.246772 -313.073066) (xy 54.231188 -313.119747) (xy 54.208317 -313.163324) (xy 54.178752 -313.202668)
			(xy 54.143259 -313.23676) (xy 54.102756 -313.264716) (xy 54.058294 -313.285814) (xy 54.011023 -313.299506)
			(xy 53.962168 -313.305438) (xy 53.912993 -313.303457) (xy 53.864774 -313.293613) (xy 53.818758 -313.276161)
			(xy 53.776137 -313.251554) (xy 53.738016 -313.220429) (xy 53.705381 -313.183592) (xy 53.679078 -313.141996)
			(xy 53.659787 -313.09672) (xy 53.64801 -313.048936) (xy 53.64405 -312.999882) (xy 52.355242 -312.999882)
			(xy 52.354747 -313.024489) (xy 52.346852 -313.073066) (xy 52.331268 -313.119747) (xy 52.308397 -313.163324)
			(xy 52.278832 -313.202668) (xy 52.243339 -313.23676) (xy 52.202836 -313.264716) (xy 52.158374 -313.285814)
			(xy 52.111103 -313.299506) (xy 52.062248 -313.305438) (xy 52.013073 -313.303457) (xy 51.964854 -313.293613)
			(xy 51.918838 -313.276161) (xy 51.876217 -313.251554) (xy 51.838096 -313.220429) (xy 51.805461 -313.183592)
			(xy 51.779158 -313.141996) (xy 51.759867 -313.09672) (xy 51.74809 -313.048936) (xy 51.74413 -312.999882)
			(xy 50.455068 -312.999882) (xy 50.454573 -313.024489) (xy 50.446678 -313.073066) (xy 50.431094 -313.119747)
			(xy 50.408223 -313.163324) (xy 50.378658 -313.202668) (xy 50.343165 -313.23676) (xy 50.302662 -313.264716)
			(xy 50.2582 -313.285814) (xy 50.210929 -313.299506) (xy 50.162074 -313.305438) (xy 50.112899 -313.303457)
			(xy 50.06468 -313.293613) (xy 50.018664 -313.276161) (xy 49.976043 -313.251554) (xy 49.937922 -313.220429)
			(xy 49.905287 -313.183592) (xy 49.878984 -313.141996) (xy 49.859693 -313.09672) (xy 49.847916 -313.048936)
			(xy 49.843956 -312.999882) (xy 48.555148 -312.999882) (xy 48.554653 -313.024489) (xy 48.546758 -313.073066)
			(xy 48.531174 -313.119747) (xy 48.508303 -313.163324) (xy 48.478738 -313.202668) (xy 48.443245 -313.23676)
			(xy 48.402742 -313.264716) (xy 48.35828 -313.285814) (xy 48.311009 -313.299506) (xy 48.262154 -313.305438)
			(xy 48.212979 -313.303457) (xy 48.16476 -313.293613) (xy 48.118744 -313.276161) (xy 48.076123 -313.251554)
			(xy 48.038002 -313.220429) (xy 48.005367 -313.183592) (xy 47.979064 -313.141996) (xy 47.959773 -313.09672)
			(xy 47.947996 -313.048936) (xy 47.944036 -312.999882) (xy 46.655228 -312.999882) (xy 46.654733 -313.024489)
			(xy 46.646838 -313.073066) (xy 46.631254 -313.119747) (xy 46.608383 -313.163324) (xy 46.578818 -313.202668)
			(xy 46.543325 -313.23676) (xy 46.502822 -313.264716) (xy 46.45836 -313.285814) (xy 46.411089 -313.299506)
			(xy 46.362234 -313.305438) (xy 46.313059 -313.303457) (xy 46.26484 -313.293613) (xy 46.218824 -313.276161)
			(xy 46.176203 -313.251554) (xy 46.138082 -313.220429) (xy 46.105447 -313.183592) (xy 46.079144 -313.141996)
			(xy 46.059853 -313.09672) (xy 46.048076 -313.048936) (xy 46.044116 -312.999882) (xy 44.755054 -312.999882)
			(xy 44.754559 -313.024489) (xy 44.746664 -313.073066) (xy 44.73108 -313.119747) (xy 44.708209 -313.163324)
			(xy 44.678644 -313.202668) (xy 44.643151 -313.23676) (xy 44.602648 -313.264716) (xy 44.558186 -313.285814)
			(xy 44.510915 -313.299506) (xy 44.46206 -313.305438) (xy 44.412885 -313.303457) (xy 44.364666 -313.293613)
			(xy 44.31865 -313.276161) (xy 44.276029 -313.251554) (xy 44.237908 -313.220429) (xy 44.205273 -313.183592)
			(xy 44.17897 -313.141996) (xy 44.159679 -313.09672) (xy 44.147902 -313.048936) (xy 44.143942 -312.999882)
			(xy 42.855134 -312.999882) (xy 42.854639 -313.024489) (xy 42.846744 -313.073066) (xy 42.83116 -313.119747)
			(xy 42.808289 -313.163324) (xy 42.778724 -313.202668) (xy 42.743231 -313.23676) (xy 42.702728 -313.264716)
			(xy 42.658266 -313.285814) (xy 42.610995 -313.299506) (xy 42.56214 -313.305438) (xy 42.512965 -313.303457)
			(xy 42.464746 -313.293613) (xy 42.41873 -313.276161) (xy 42.376109 -313.251554) (xy 42.337988 -313.220429)
			(xy 42.305353 -313.183592) (xy 42.27905 -313.141996) (xy 42.259759 -313.09672) (xy 42.247982 -313.048936)
			(xy 42.244022 -312.999882) (xy 40.955214 -312.999882) (xy 40.954719 -313.024489) (xy 40.946824 -313.073066)
			(xy 40.93124 -313.119747) (xy 40.908369 -313.163324) (xy 40.878804 -313.202668) (xy 40.843311 -313.23676)
			(xy 40.802808 -313.264716) (xy 40.758346 -313.285814) (xy 40.711075 -313.299506) (xy 40.66222 -313.305438)
			(xy 40.613045 -313.303457) (xy 40.564826 -313.293613) (xy 40.51881 -313.276161) (xy 40.476189 -313.251554)
			(xy 40.438068 -313.220429) (xy 40.405433 -313.183592) (xy 40.37913 -313.141996) (xy 40.359839 -313.09672)
			(xy 40.348062 -313.048936) (xy 40.344102 -312.999882) (xy 39.055294 -312.999882) (xy 39.054799 -313.024489)
			(xy 39.046904 -313.073066) (xy 39.03132 -313.119747) (xy 39.008449 -313.163324) (xy 38.978884 -313.202668)
			(xy 38.943391 -313.23676) (xy 38.902888 -313.264716) (xy 38.858426 -313.285814) (xy 38.811155 -313.299506)
			(xy 38.7623 -313.305438) (xy 38.713125 -313.303457) (xy 38.664906 -313.293613) (xy 38.61889 -313.276161)
			(xy 38.576269 -313.251554) (xy 38.538148 -313.220429) (xy 38.505513 -313.183592) (xy 38.47921 -313.141996)
			(xy 38.459919 -313.09672) (xy 38.448142 -313.048936) (xy 38.444182 -312.999882) (xy 0.508 -312.999882)
			(xy 0.508 -313.949842) (xy 38.444182 -313.949842) (xy 38.448142 -313.900788) (xy 38.459919 -313.853004)
			(xy 38.47921 -313.807728) (xy 38.505513 -313.766132) (xy 38.538148 -313.729295) (xy 38.576269 -313.69817)
			(xy 38.61889 -313.673563) (xy 38.664906 -313.656111) (xy 38.713125 -313.646267) (xy 38.7623 -313.644286)
			(xy 38.811155 -313.650218) (xy 38.858426 -313.66391) (xy 38.902888 -313.685008) (xy 38.943391 -313.712964)
			(xy 38.978884 -313.747056) (xy 39.008449 -313.7864) (xy 39.03132 -313.829977) (xy 39.046904 -313.876658)
			(xy 39.054799 -313.925235) (xy 39.055294 -313.949842) (xy 40.344102 -313.949842) (xy 40.348062 -313.900788)
			(xy 40.359839 -313.853004) (xy 40.37913 -313.807728) (xy 40.405433 -313.766132) (xy 40.438068 -313.729295)
			(xy 40.476189 -313.69817) (xy 40.51881 -313.673563) (xy 40.564826 -313.656111) (xy 40.613045 -313.646267)
			(xy 40.66222 -313.644286) (xy 40.711075 -313.650218) (xy 40.758346 -313.66391) (xy 40.802808 -313.685008)
			(xy 40.843311 -313.712964) (xy 40.878804 -313.747056) (xy 40.908369 -313.7864) (xy 40.93124 -313.829977)
			(xy 40.946824 -313.876658) (xy 40.954719 -313.925235) (xy 40.955214 -313.949842) (xy 42.244022 -313.949842)
			(xy 42.247982 -313.900788) (xy 42.259759 -313.853004) (xy 42.27905 -313.807728) (xy 42.305353 -313.766132)
			(xy 42.337988 -313.729295) (xy 42.376109 -313.69817) (xy 42.41873 -313.673563) (xy 42.464746 -313.656111)
			(xy 42.512965 -313.646267) (xy 42.56214 -313.644286) (xy 42.610995 -313.650218) (xy 42.658266 -313.66391)
			(xy 42.702728 -313.685008) (xy 42.743231 -313.712964) (xy 42.778724 -313.747056) (xy 42.808289 -313.7864)
			(xy 42.83116 -313.829977) (xy 42.846744 -313.876658) (xy 42.854639 -313.925235) (xy 42.855134 -313.949842)
			(xy 44.143942 -313.949842) (xy 44.147902 -313.900788) (xy 44.159679 -313.853004) (xy 44.17897 -313.807728)
			(xy 44.205273 -313.766132) (xy 44.237908 -313.729295) (xy 44.276029 -313.69817) (xy 44.31865 -313.673563)
			(xy 44.364666 -313.656111) (xy 44.412885 -313.646267) (xy 44.46206 -313.644286) (xy 44.510915 -313.650218)
			(xy 44.558186 -313.66391) (xy 44.602648 -313.685008) (xy 44.643151 -313.712964) (xy 44.678644 -313.747056)
			(xy 44.708209 -313.7864) (xy 44.73108 -313.829977) (xy 44.746664 -313.876658) (xy 44.754559 -313.925235)
			(xy 44.755054 -313.949842) (xy 46.044116 -313.949842) (xy 46.048076 -313.900788) (xy 46.059853 -313.853004)
			(xy 46.079144 -313.807728) (xy 46.105447 -313.766132) (xy 46.138082 -313.729295) (xy 46.176203 -313.69817)
			(xy 46.218824 -313.673563) (xy 46.26484 -313.656111) (xy 46.313059 -313.646267) (xy 46.362234 -313.644286)
			(xy 46.411089 -313.650218) (xy 46.45836 -313.66391) (xy 46.502822 -313.685008) (xy 46.543325 -313.712964)
			(xy 46.578818 -313.747056) (xy 46.608383 -313.7864) (xy 46.631254 -313.829977) (xy 46.646838 -313.876658)
			(xy 46.654733 -313.925235) (xy 46.655228 -313.949842) (xy 47.944036 -313.949842) (xy 47.947996 -313.900788)
			(xy 47.959773 -313.853004) (xy 47.979064 -313.807728) (xy 48.005367 -313.766132) (xy 48.038002 -313.729295)
			(xy 48.076123 -313.69817) (xy 48.118744 -313.673563) (xy 48.16476 -313.656111) (xy 48.212979 -313.646267)
			(xy 48.262154 -313.644286) (xy 48.311009 -313.650218) (xy 48.35828 -313.66391) (xy 48.402742 -313.685008)
			(xy 48.443245 -313.712964) (xy 48.478738 -313.747056) (xy 48.508303 -313.7864) (xy 48.531174 -313.829977)
			(xy 48.546758 -313.876658) (xy 48.554653 -313.925235) (xy 48.555148 -313.949842) (xy 49.843956 -313.949842)
			(xy 49.847916 -313.900788) (xy 49.859693 -313.853004) (xy 49.878984 -313.807728) (xy 49.905287 -313.766132)
			(xy 49.937922 -313.729295) (xy 49.976043 -313.69817) (xy 50.018664 -313.673563) (xy 50.06468 -313.656111)
			(xy 50.112899 -313.646267) (xy 50.162074 -313.644286) (xy 50.210929 -313.650218) (xy 50.2582 -313.66391)
			(xy 50.302662 -313.685008) (xy 50.343165 -313.712964) (xy 50.378658 -313.747056) (xy 50.408223 -313.7864)
			(xy 50.431094 -313.829977) (xy 50.446678 -313.876658) (xy 50.454573 -313.925235) (xy 50.455068 -313.949842)
			(xy 51.74413 -313.949842) (xy 51.74809 -313.900788) (xy 51.759867 -313.853004) (xy 51.779158 -313.807728)
			(xy 51.805461 -313.766132) (xy 51.838096 -313.729295) (xy 51.876217 -313.69817) (xy 51.918838 -313.673563)
			(xy 51.964854 -313.656111) (xy 52.013073 -313.646267) (xy 52.062248 -313.644286) (xy 52.111103 -313.650218)
			(xy 52.158374 -313.66391) (xy 52.202836 -313.685008) (xy 52.243339 -313.712964) (xy 52.278832 -313.747056)
			(xy 52.308397 -313.7864) (xy 52.331268 -313.829977) (xy 52.346852 -313.876658) (xy 52.354747 -313.925235)
			(xy 52.355242 -313.949842) (xy 53.64405 -313.949842) (xy 53.64801 -313.900788) (xy 53.659787 -313.853004)
			(xy 53.679078 -313.807728) (xy 53.705381 -313.766132) (xy 53.738016 -313.729295) (xy 53.776137 -313.69817)
			(xy 53.818758 -313.673563) (xy 53.864774 -313.656111) (xy 53.912993 -313.646267) (xy 53.962168 -313.644286)
			(xy 54.011023 -313.650218) (xy 54.058294 -313.66391) (xy 54.102756 -313.685008) (xy 54.143259 -313.712964)
			(xy 54.178752 -313.747056) (xy 54.208317 -313.7864) (xy 54.231188 -313.829977) (xy 54.246772 -313.876658)
			(xy 54.254667 -313.925235) (xy 54.255162 -313.949842) (xy 55.54397 -313.949842) (xy 55.54793 -313.900788)
			(xy 55.559707 -313.853004) (xy 55.578998 -313.807728) (xy 55.605301 -313.766132) (xy 55.637936 -313.729295)
			(xy 55.676057 -313.69817) (xy 55.718678 -313.673563) (xy 55.764694 -313.656111) (xy 55.812913 -313.646267)
			(xy 55.862088 -313.644286) (xy 55.910943 -313.650218) (xy 55.958214 -313.66391) (xy 56.002676 -313.685008)
			(xy 56.043179 -313.712964) (xy 56.078672 -313.747056) (xy 56.108237 -313.7864) (xy 56.131108 -313.829977)
			(xy 56.146692 -313.876658) (xy 56.154587 -313.925235) (xy 56.155082 -313.949842) (xy 57.444144 -313.949842)
			(xy 57.448104 -313.900788) (xy 57.459881 -313.853004) (xy 57.479172 -313.807728) (xy 57.505475 -313.766132)
			(xy 57.53811 -313.729295) (xy 57.576231 -313.69817) (xy 57.618852 -313.673563) (xy 57.664868 -313.656111)
			(xy 57.713087 -313.646267) (xy 57.762262 -313.644286) (xy 57.811117 -313.650218) (xy 57.858388 -313.66391)
			(xy 57.90285 -313.685008) (xy 57.943353 -313.712964) (xy 57.978846 -313.747056) (xy 58.008411 -313.7864)
			(xy 58.031282 -313.829977) (xy 58.046866 -313.876658) (xy 58.054761 -313.925235) (xy 58.055256 -313.949842)
			(xy 59.344064 -313.949842) (xy 59.348024 -313.900788) (xy 59.359801 -313.853004) (xy 59.379092 -313.807728)
			(xy 59.405395 -313.766132) (xy 59.43803 -313.729295) (xy 59.476151 -313.69817) (xy 59.518772 -313.673563)
			(xy 59.564788 -313.656111) (xy 59.613007 -313.646267) (xy 59.662182 -313.644286) (xy 59.711037 -313.650218)
			(xy 59.758308 -313.66391) (xy 59.80277 -313.685008) (xy 59.843273 -313.712964) (xy 59.878766 -313.747056)
			(xy 59.908331 -313.7864) (xy 59.931202 -313.829977) (xy 59.946786 -313.876658) (xy 59.954681 -313.925235)
			(xy 59.955176 -313.949842) (xy 61.243984 -313.949842) (xy 61.247944 -313.900788) (xy 61.259721 -313.853004)
			(xy 61.279012 -313.807728) (xy 61.305315 -313.766132) (xy 61.33795 -313.729295) (xy 61.376071 -313.69817)
			(xy 61.418692 -313.673563) (xy 61.464708 -313.656111) (xy 61.512927 -313.646267) (xy 61.562102 -313.644286)
			(xy 61.610957 -313.650218) (xy 61.658228 -313.66391) (xy 61.70269 -313.685008) (xy 61.743193 -313.712964)
			(xy 61.778686 -313.747056) (xy 61.808251 -313.7864) (xy 61.831122 -313.829977) (xy 61.846706 -313.876658)
			(xy 61.854601 -313.925235) (xy 61.855096 -313.949842) (xy 63.144158 -313.949842) (xy 63.148118 -313.900788)
			(xy 63.159895 -313.853004) (xy 63.179186 -313.807728) (xy 63.205489 -313.766132) (xy 63.238124 -313.729295)
			(xy 63.276245 -313.69817) (xy 63.318866 -313.673563) (xy 63.364882 -313.656111) (xy 63.413101 -313.646267)
			(xy 63.462276 -313.644286) (xy 63.511131 -313.650218) (xy 63.558402 -313.66391) (xy 63.602864 -313.685008)
			(xy 63.643367 -313.712964) (xy 63.67886 -313.747056) (xy 63.708425 -313.7864) (xy 63.731296 -313.829977)
			(xy 63.74688 -313.876658) (xy 63.754775 -313.925235) (xy 63.75527 -313.949842) (xy 65.044078 -313.949842)
			(xy 65.048038 -313.900788) (xy 65.059815 -313.853004) (xy 65.079106 -313.807728) (xy 65.105409 -313.766132)
			(xy 65.138044 -313.729295) (xy 65.176165 -313.69817) (xy 65.218786 -313.673563) (xy 65.264802 -313.656111)
			(xy 65.313021 -313.646267) (xy 65.362196 -313.644286) (xy 65.411051 -313.650218) (xy 65.458322 -313.66391)
			(xy 65.502784 -313.685008) (xy 65.543287 -313.712964) (xy 65.57878 -313.747056) (xy 65.608345 -313.7864)
			(xy 65.631216 -313.829977) (xy 65.6468 -313.876658) (xy 65.654695 -313.925235) (xy 65.65519 -313.949842)
			(xy 66.943998 -313.949842) (xy 66.947958 -313.900788) (xy 66.959735 -313.853004) (xy 66.979026 -313.807728)
			(xy 67.005329 -313.766132) (xy 67.037964 -313.729295) (xy 67.076085 -313.69817) (xy 67.118706 -313.673563)
			(xy 67.164722 -313.656111) (xy 67.212941 -313.646267) (xy 67.262116 -313.644286) (xy 67.310971 -313.650218)
			(xy 67.358242 -313.66391) (xy 67.402704 -313.685008) (xy 67.443207 -313.712964) (xy 67.4787 -313.747056)
			(xy 67.508265 -313.7864) (xy 67.531136 -313.829977) (xy 67.54672 -313.876658) (xy 67.554615 -313.925235)
			(xy 67.55511 -313.949842) (xy 68.844172 -313.949842) (xy 68.848132 -313.900788) (xy 68.859909 -313.853004)
			(xy 68.8792 -313.807728) (xy 68.905503 -313.766132) (xy 68.938138 -313.729295) (xy 68.976259 -313.69817)
			(xy 69.01888 -313.673563) (xy 69.064896 -313.656111) (xy 69.113115 -313.646267) (xy 69.16229 -313.644286)
			(xy 69.211145 -313.650218) (xy 69.258416 -313.66391) (xy 69.302878 -313.685008) (xy 69.343381 -313.712964)
			(xy 69.378874 -313.747056) (xy 69.408439 -313.7864) (xy 69.43131 -313.829977) (xy 69.446894 -313.876658)
			(xy 69.454789 -313.925235) (xy 69.455284 -313.949842) (xy 70.744092 -313.949842) (xy 70.748052 -313.900788)
			(xy 70.759829 -313.853004) (xy 70.77912 -313.807728) (xy 70.805423 -313.766132) (xy 70.838058 -313.729295)
			(xy 70.876179 -313.69817) (xy 70.9188 -313.673563) (xy 70.964816 -313.656111) (xy 71.013035 -313.646267)
			(xy 71.06221 -313.644286) (xy 71.111065 -313.650218) (xy 71.158336 -313.66391) (xy 71.202798 -313.685008)
			(xy 71.243301 -313.712964) (xy 71.278794 -313.747056) (xy 71.308359 -313.7864) (xy 71.33123 -313.829977)
			(xy 71.346814 -313.876658) (xy 71.354709 -313.925235) (xy 71.355204 -313.949842) (xy 72.644012 -313.949842)
			(xy 72.647972 -313.900788) (xy 72.659749 -313.853004) (xy 72.67904 -313.807728) (xy 72.705343 -313.766132)
			(xy 72.737978 -313.729295) (xy 72.776099 -313.69817) (xy 72.81872 -313.673563) (xy 72.864736 -313.656111)
			(xy 72.912955 -313.646267) (xy 72.96213 -313.644286) (xy 73.010985 -313.650218) (xy 73.058256 -313.66391)
			(xy 73.102718 -313.685008) (xy 73.143221 -313.712964) (xy 73.178714 -313.747056) (xy 73.208279 -313.7864)
			(xy 73.23115 -313.829977) (xy 73.246734 -313.876658) (xy 73.254629 -313.925235) (xy 73.255124 -313.949842)
			(xy 74.544186 -313.949842) (xy 74.548146 -313.900788) (xy 74.559923 -313.853004) (xy 74.579214 -313.807728)
			(xy 74.605517 -313.766132) (xy 74.638152 -313.729295) (xy 74.676273 -313.69817) (xy 74.718894 -313.673563)
			(xy 74.76491 -313.656111) (xy 74.813129 -313.646267) (xy 74.862304 -313.644286) (xy 74.911159 -313.650218)
			(xy 74.95843 -313.66391) (xy 75.002892 -313.685008) (xy 75.043395 -313.712964) (xy 75.078888 -313.747056)
			(xy 75.108453 -313.7864) (xy 75.131324 -313.829977) (xy 75.146908 -313.876658) (xy 75.154803 -313.925235)
			(xy 75.155298 -313.949842) (xy 76.444106 -313.949842) (xy 76.448066 -313.900788) (xy 76.459843 -313.853004)
			(xy 76.479134 -313.807728) (xy 76.505437 -313.766132) (xy 76.538072 -313.729295) (xy 76.576193 -313.69817)
			(xy 76.618814 -313.673563) (xy 76.66483 -313.656111) (xy 76.713049 -313.646267) (xy 76.762224 -313.644286)
			(xy 76.811079 -313.650218) (xy 76.85835 -313.66391) (xy 76.902812 -313.685008) (xy 76.943315 -313.712964)
			(xy 76.978808 -313.747056) (xy 77.008373 -313.7864) (xy 77.031244 -313.829977) (xy 77.046828 -313.876658)
			(xy 77.054723 -313.925235) (xy 77.055218 -313.949842) (xy 78.344026 -313.949842) (xy 78.347986 -313.900788)
			(xy 78.359763 -313.853004) (xy 78.379054 -313.807728) (xy 78.405357 -313.766132) (xy 78.437992 -313.729295)
			(xy 78.476113 -313.69817) (xy 78.518734 -313.673563) (xy 78.56475 -313.656111) (xy 78.612969 -313.646267)
			(xy 78.662144 -313.644286) (xy 78.710999 -313.650218) (xy 78.75827 -313.66391) (xy 78.802732 -313.685008)
			(xy 78.843235 -313.712964) (xy 78.878728 -313.747056) (xy 78.908293 -313.7864) (xy 78.931164 -313.829977)
			(xy 78.946748 -313.876658) (xy 78.954643 -313.925235) (xy 78.955138 -313.949842) (xy 80.243946 -313.949842)
			(xy 80.247906 -313.900788) (xy 80.259683 -313.853004) (xy 80.278974 -313.807728) (xy 80.305277 -313.766132)
			(xy 80.337912 -313.729295) (xy 80.376033 -313.69817) (xy 80.418654 -313.673563) (xy 80.46467 -313.656111)
			(xy 80.512889 -313.646267) (xy 80.562064 -313.644286) (xy 80.610919 -313.650218) (xy 80.65819 -313.66391)
			(xy 80.702652 -313.685008) (xy 80.743155 -313.712964) (xy 80.778648 -313.747056) (xy 80.808213 -313.7864)
			(xy 80.831084 -313.829977) (xy 80.846668 -313.876658) (xy 80.854563 -313.925235) (xy 80.855058 -313.949842)
			(xy 154.54428 -313.949842) (xy 154.54824 -313.900788) (xy 154.560017 -313.853004) (xy 154.579308 -313.807728)
			(xy 154.605611 -313.766132) (xy 154.638246 -313.729295) (xy 154.676367 -313.69817) (xy 154.718988 -313.673563)
			(xy 154.765004 -313.656111) (xy 154.813223 -313.646267) (xy 154.862398 -313.644286) (xy 154.911253 -313.650218)
			(xy 154.958524 -313.66391) (xy 155.002986 -313.685008) (xy 155.043489 -313.712964) (xy 155.078982 -313.747056)
			(xy 155.108547 -313.7864) (xy 155.131418 -313.829977) (xy 155.147002 -313.876658) (xy 155.154897 -313.925235)
			(xy 155.155392 -313.949842) (xy 156.4442 -313.949842) (xy 156.44816 -313.900788) (xy 156.459937 -313.853004)
			(xy 156.479228 -313.807728) (xy 156.505531 -313.766132) (xy 156.538166 -313.729295) (xy 156.576287 -313.69817)
			(xy 156.618908 -313.673563) (xy 156.664924 -313.656111) (xy 156.713143 -313.646267) (xy 156.762318 -313.644286)
			(xy 156.811173 -313.650218) (xy 156.858444 -313.66391) (xy 156.902906 -313.685008) (xy 156.943409 -313.712964)
			(xy 156.978902 -313.747056) (xy 157.008467 -313.7864) (xy 157.031338 -313.829977) (xy 157.046922 -313.876658)
			(xy 157.054817 -313.925235) (xy 157.055312 -313.949842) (xy 158.34412 -313.949842) (xy 158.34808 -313.900788)
			(xy 158.359857 -313.853004) (xy 158.379148 -313.807728) (xy 158.405451 -313.766132) (xy 158.438086 -313.729295)
			(xy 158.476207 -313.69817) (xy 158.518828 -313.673563) (xy 158.564844 -313.656111) (xy 158.613063 -313.646267)
			(xy 158.662238 -313.644286) (xy 158.711093 -313.650218) (xy 158.758364 -313.66391) (xy 158.802826 -313.685008)
			(xy 158.843329 -313.712964) (xy 158.878822 -313.747056) (xy 158.908387 -313.7864) (xy 158.931258 -313.829977)
			(xy 158.946842 -313.876658) (xy 158.954737 -313.925235) (xy 158.955232 -313.949842) (xy 160.24404 -313.949842)
			(xy 160.248 -313.900788) (xy 160.259777 -313.853004) (xy 160.279068 -313.807728) (xy 160.305371 -313.766132)
			(xy 160.338006 -313.729295) (xy 160.376127 -313.69817) (xy 160.418748 -313.673563) (xy 160.464764 -313.656111)
			(xy 160.512983 -313.646267) (xy 160.562158 -313.644286) (xy 160.611013 -313.650218) (xy 160.658284 -313.66391)
			(xy 160.702746 -313.685008) (xy 160.743249 -313.712964) (xy 160.778742 -313.747056) (xy 160.808307 -313.7864)
			(xy 160.831178 -313.829977) (xy 160.846762 -313.876658) (xy 160.854657 -313.925235) (xy 160.855152 -313.949842)
			(xy 162.144214 -313.949842) (xy 162.148174 -313.900788) (xy 162.159951 -313.853004) (xy 162.179242 -313.807728)
			(xy 162.205545 -313.766132) (xy 162.23818 -313.729295) (xy 162.276301 -313.69817) (xy 162.318922 -313.673563)
			(xy 162.364938 -313.656111) (xy 162.413157 -313.646267) (xy 162.462332 -313.644286) (xy 162.511187 -313.650218)
			(xy 162.558458 -313.66391) (xy 162.60292 -313.685008) (xy 162.643423 -313.712964) (xy 162.678916 -313.747056)
			(xy 162.708481 -313.7864) (xy 162.731352 -313.829977) (xy 162.746936 -313.876658) (xy 162.754831 -313.925235)
			(xy 162.755326 -313.949842) (xy 164.044134 -313.949842) (xy 164.048094 -313.900788) (xy 164.059871 -313.853004)
			(xy 164.079162 -313.807728) (xy 164.105465 -313.766132) (xy 164.1381 -313.729295) (xy 164.176221 -313.69817)
			(xy 164.218842 -313.673563) (xy 164.264858 -313.656111) (xy 164.313077 -313.646267) (xy 164.362252 -313.644286)
			(xy 164.411107 -313.650218) (xy 164.458378 -313.66391) (xy 164.50284 -313.685008) (xy 164.543343 -313.712964)
			(xy 164.578836 -313.747056) (xy 164.608401 -313.7864) (xy 164.631272 -313.829977) (xy 164.646856 -313.876658)
			(xy 164.654751 -313.925235) (xy 164.655246 -313.949842) (xy 165.944054 -313.949842) (xy 165.948014 -313.900788)
			(xy 165.959791 -313.853004) (xy 165.979082 -313.807728) (xy 166.005385 -313.766132) (xy 166.03802 -313.729295)
			(xy 166.076141 -313.69817) (xy 166.118762 -313.673563) (xy 166.164778 -313.656111) (xy 166.212997 -313.646267)
			(xy 166.262172 -313.644286) (xy 166.311027 -313.650218) (xy 166.358298 -313.66391) (xy 166.40276 -313.685008)
			(xy 166.443263 -313.712964) (xy 166.478756 -313.747056) (xy 166.508321 -313.7864) (xy 166.531192 -313.829977)
			(xy 166.546776 -313.876658) (xy 166.554671 -313.925235) (xy 166.555166 -313.949842) (xy 167.844228 -313.949842)
			(xy 167.848188 -313.900788) (xy 167.859965 -313.853004) (xy 167.879256 -313.807728) (xy 167.905559 -313.766132)
			(xy 167.938194 -313.729295) (xy 167.976315 -313.69817) (xy 168.018936 -313.673563) (xy 168.064952 -313.656111)
			(xy 168.113171 -313.646267) (xy 168.162346 -313.644286) (xy 168.211201 -313.650218) (xy 168.258472 -313.66391)
			(xy 168.302934 -313.685008) (xy 168.343437 -313.712964) (xy 168.37893 -313.747056) (xy 168.408495 -313.7864)
			(xy 168.431366 -313.829977) (xy 168.44695 -313.876658) (xy 168.454845 -313.925235) (xy 168.45534 -313.949842)
			(xy 169.744148 -313.949842) (xy 169.748108 -313.900788) (xy 169.759885 -313.853004) (xy 169.779176 -313.807728)
			(xy 169.805479 -313.766132) (xy 169.838114 -313.729295) (xy 169.876235 -313.69817) (xy 169.918856 -313.673563)
			(xy 169.964872 -313.656111) (xy 170.013091 -313.646267) (xy 170.062266 -313.644286) (xy 170.111121 -313.650218)
			(xy 170.158392 -313.66391) (xy 170.202854 -313.685008) (xy 170.243357 -313.712964) (xy 170.27885 -313.747056)
			(xy 170.308415 -313.7864) (xy 170.331286 -313.829977) (xy 170.34687 -313.876658) (xy 170.354765 -313.925235)
			(xy 170.35526 -313.949842) (xy 171.644068 -313.949842) (xy 171.648028 -313.900788) (xy 171.659805 -313.853004)
			(xy 171.679096 -313.807728) (xy 171.705399 -313.766132) (xy 171.738034 -313.729295) (xy 171.776155 -313.69817)
			(xy 171.818776 -313.673563) (xy 171.864792 -313.656111) (xy 171.913011 -313.646267) (xy 171.962186 -313.644286)
			(xy 172.011041 -313.650218) (xy 172.058312 -313.66391) (xy 172.102774 -313.685008) (xy 172.143277 -313.712964)
			(xy 172.17877 -313.747056) (xy 172.208335 -313.7864) (xy 172.231206 -313.829977) (xy 172.24679 -313.876658)
			(xy 172.254685 -313.925235) (xy 172.25518 -313.949842) (xy 173.544242 -313.949842) (xy 173.548202 -313.900788)
			(xy 173.559979 -313.853004) (xy 173.57927 -313.807728) (xy 173.605573 -313.766132) (xy 173.638208 -313.729295)
			(xy 173.676329 -313.69817) (xy 173.71895 -313.673563) (xy 173.764966 -313.656111) (xy 173.813185 -313.646267)
			(xy 173.86236 -313.644286) (xy 173.911215 -313.650218) (xy 173.958486 -313.66391) (xy 174.002948 -313.685008)
			(xy 174.043451 -313.712964) (xy 174.078944 -313.747056) (xy 174.108509 -313.7864) (xy 174.13138 -313.829977)
			(xy 174.146964 -313.876658) (xy 174.154859 -313.925235) (xy 174.155354 -313.949842) (xy 175.444162 -313.949842)
			(xy 175.448122 -313.900788) (xy 175.459899 -313.853004) (xy 175.47919 -313.807728) (xy 175.505493 -313.766132)
			(xy 175.538128 -313.729295) (xy 175.576249 -313.69817) (xy 175.61887 -313.673563) (xy 175.664886 -313.656111)
			(xy 175.713105 -313.646267) (xy 175.76228 -313.644286) (xy 175.811135 -313.650218) (xy 175.858406 -313.66391)
			(xy 175.902868 -313.685008) (xy 175.943371 -313.712964) (xy 175.978864 -313.747056) (xy 176.008429 -313.7864)
			(xy 176.0313 -313.829977) (xy 176.046884 -313.876658) (xy 176.054779 -313.925235) (xy 176.055274 -313.949842)
			(xy 177.344082 -313.949842) (xy 177.348042 -313.900788) (xy 177.359819 -313.853004) (xy 177.37911 -313.807728)
			(xy 177.405413 -313.766132) (xy 177.438048 -313.729295) (xy 177.476169 -313.69817) (xy 177.51879 -313.673563)
			(xy 177.564806 -313.656111) (xy 177.613025 -313.646267) (xy 177.6622 -313.644286) (xy 177.711055 -313.650218)
			(xy 177.758326 -313.66391) (xy 177.802788 -313.685008) (xy 177.843291 -313.712964) (xy 177.878784 -313.747056)
			(xy 177.908349 -313.7864) (xy 177.93122 -313.829977) (xy 177.946804 -313.876658) (xy 177.954699 -313.925235)
			(xy 177.955194 -313.949842) (xy 179.244256 -313.949842) (xy 179.248216 -313.900788) (xy 179.259993 -313.853004)
			(xy 179.279284 -313.807728) (xy 179.305587 -313.766132) (xy 179.338222 -313.729295) (xy 179.376343 -313.69817)
			(xy 179.418964 -313.673563) (xy 179.46498 -313.656111) (xy 179.513199 -313.646267) (xy 179.562374 -313.644286)
			(xy 179.611229 -313.650218) (xy 179.6585 -313.66391) (xy 179.702962 -313.685008) (xy 179.743465 -313.712964)
			(xy 179.778958 -313.747056) (xy 179.808523 -313.7864) (xy 179.831394 -313.829977) (xy 179.846978 -313.876658)
			(xy 179.854873 -313.925235) (xy 179.855368 -313.949842) (xy 181.144176 -313.949842) (xy 181.148136 -313.900788)
			(xy 181.159913 -313.853004) (xy 181.179204 -313.807728) (xy 181.205507 -313.766132) (xy 181.238142 -313.729295)
			(xy 181.276263 -313.69817) (xy 181.318884 -313.673563) (xy 181.3649 -313.656111) (xy 181.413119 -313.646267)
			(xy 181.462294 -313.644286) (xy 181.511149 -313.650218) (xy 181.55842 -313.66391) (xy 181.602882 -313.685008)
			(xy 181.643385 -313.712964) (xy 181.678878 -313.747056) (xy 181.708443 -313.7864) (xy 181.731314 -313.829977)
			(xy 181.746898 -313.876658) (xy 181.754793 -313.925235) (xy 181.755288 -313.949842) (xy 183.044096 -313.949842)
			(xy 183.048056 -313.900788) (xy 183.059833 -313.853004) (xy 183.079124 -313.807728) (xy 183.105427 -313.766132)
			(xy 183.138062 -313.729295) (xy 183.176183 -313.69817) (xy 183.218804 -313.673563) (xy 183.26482 -313.656111)
			(xy 183.313039 -313.646267) (xy 183.362214 -313.644286) (xy 183.411069 -313.650218) (xy 183.45834 -313.66391)
			(xy 183.502802 -313.685008) (xy 183.543305 -313.712964) (xy 183.578798 -313.747056) (xy 183.608363 -313.7864)
			(xy 183.631234 -313.829977) (xy 183.646818 -313.876658) (xy 183.654713 -313.925235) (xy 183.655208 -313.949842)
			(xy 184.94427 -313.949842) (xy 184.94823 -313.900788) (xy 184.960007 -313.853004) (xy 184.979298 -313.807728)
			(xy 185.005601 -313.766132) (xy 185.038236 -313.729295) (xy 185.076357 -313.69817) (xy 185.118978 -313.673563)
			(xy 185.164994 -313.656111) (xy 185.213213 -313.646267) (xy 185.262388 -313.644286) (xy 185.311243 -313.650218)
			(xy 185.358514 -313.66391) (xy 185.402976 -313.685008) (xy 185.443479 -313.712964) (xy 185.478972 -313.747056)
			(xy 185.508537 -313.7864) (xy 185.531408 -313.829977) (xy 185.546992 -313.876658) (xy 185.554887 -313.925235)
			(xy 185.555382 -313.949842) (xy 186.84419 -313.949842) (xy 186.84815 -313.900788) (xy 186.859927 -313.853004)
			(xy 186.879218 -313.807728) (xy 186.905521 -313.766132) (xy 186.938156 -313.729295) (xy 186.976277 -313.69817)
			(xy 187.018898 -313.673563) (xy 187.064914 -313.656111) (xy 187.113133 -313.646267) (xy 187.162308 -313.644286)
			(xy 187.211163 -313.650218) (xy 187.258434 -313.66391) (xy 187.302896 -313.685008) (xy 187.343399 -313.712964)
			(xy 187.378892 -313.747056) (xy 187.408457 -313.7864) (xy 187.431328 -313.829977) (xy 187.446912 -313.876658)
			(xy 187.454807 -313.925235) (xy 187.455302 -313.949842) (xy 188.74411 -313.949842) (xy 188.74807 -313.900788)
			(xy 188.759847 -313.853004) (xy 188.779138 -313.807728) (xy 188.805441 -313.766132) (xy 188.838076 -313.729295)
			(xy 188.876197 -313.69817) (xy 188.918818 -313.673563) (xy 188.964834 -313.656111) (xy 189.013053 -313.646267)
			(xy 189.062228 -313.644286) (xy 189.111083 -313.650218) (xy 189.158354 -313.66391) (xy 189.202816 -313.685008)
			(xy 189.243319 -313.712964) (xy 189.278812 -313.747056) (xy 189.308377 -313.7864) (xy 189.331248 -313.829977)
			(xy 189.346832 -313.876658) (xy 189.354727 -313.925235) (xy 189.355222 -313.949842) (xy 190.644284 -313.949842)
			(xy 190.648244 -313.900788) (xy 190.660021 -313.853004) (xy 190.679312 -313.807728) (xy 190.705615 -313.766132)
			(xy 190.73825 -313.729295) (xy 190.776371 -313.69817) (xy 190.818992 -313.673563) (xy 190.865008 -313.656111)
			(xy 190.913227 -313.646267) (xy 190.962402 -313.644286) (xy 191.011257 -313.650218) (xy 191.058528 -313.66391)
			(xy 191.10299 -313.685008) (xy 191.143493 -313.712964) (xy 191.178986 -313.747056) (xy 191.208551 -313.7864)
			(xy 191.231422 -313.829977) (xy 191.247006 -313.876658) (xy 191.254901 -313.925235) (xy 191.255396 -313.949842)
			(xy 192.544204 -313.949842) (xy 192.548164 -313.900788) (xy 192.559941 -313.853004) (xy 192.579232 -313.807728)
			(xy 192.605535 -313.766132) (xy 192.63817 -313.729295) (xy 192.676291 -313.69817) (xy 192.718912 -313.673563)
			(xy 192.764928 -313.656111) (xy 192.813147 -313.646267) (xy 192.862322 -313.644286) (xy 192.911177 -313.650218)
			(xy 192.958448 -313.66391) (xy 193.00291 -313.685008) (xy 193.043413 -313.712964) (xy 193.078906 -313.747056)
			(xy 193.108471 -313.7864) (xy 193.131342 -313.829977) (xy 193.146926 -313.876658) (xy 193.154821 -313.925235)
			(xy 193.155316 -313.949842) (xy 194.444124 -313.949842) (xy 194.448084 -313.900788) (xy 194.459861 -313.853004)
			(xy 194.479152 -313.807728) (xy 194.505455 -313.766132) (xy 194.53809 -313.729295) (xy 194.576211 -313.69817)
			(xy 194.618832 -313.673563) (xy 194.664848 -313.656111) (xy 194.713067 -313.646267) (xy 194.762242 -313.644286)
			(xy 194.811097 -313.650218) (xy 194.858368 -313.66391) (xy 194.90283 -313.685008) (xy 194.943333 -313.712964)
			(xy 194.978826 -313.747056) (xy 195.008391 -313.7864) (xy 195.031262 -313.829977) (xy 195.046846 -313.876658)
			(xy 195.054741 -313.925235) (xy 195.055236 -313.949842) (xy 196.344044 -313.949842) (xy 196.348004 -313.900788)
			(xy 196.359781 -313.853004) (xy 196.379072 -313.807728) (xy 196.405375 -313.766132) (xy 196.43801 -313.729295)
			(xy 196.476131 -313.69817) (xy 196.518752 -313.673563) (xy 196.564768 -313.656111) (xy 196.612987 -313.646267)
			(xy 196.662162 -313.644286) (xy 196.711017 -313.650218) (xy 196.758288 -313.66391) (xy 196.80275 -313.685008)
			(xy 196.843253 -313.712964) (xy 196.878746 -313.747056) (xy 196.908311 -313.7864) (xy 196.931182 -313.829977)
			(xy 196.946766 -313.876658) (xy 196.954661 -313.925235) (xy 196.955156 -313.949842) (xy 270.644124 -313.949842)
			(xy 270.648084 -313.900788) (xy 270.659861 -313.853004) (xy 270.679152 -313.807728) (xy 270.705455 -313.766132)
			(xy 270.73809 -313.729295) (xy 270.776211 -313.69817) (xy 270.818832 -313.673563) (xy 270.864848 -313.656111)
			(xy 270.913067 -313.646267) (xy 270.962242 -313.644286) (xy 271.011097 -313.650218) (xy 271.058368 -313.66391)
			(xy 271.10283 -313.685008) (xy 271.143333 -313.712964) (xy 271.178826 -313.747056) (xy 271.208391 -313.7864)
			(xy 271.231262 -313.829977) (xy 271.246846 -313.876658) (xy 271.254741 -313.925235) (xy 271.255236 -313.949842)
			(xy 272.544044 -313.949842) (xy 272.548004 -313.900788) (xy 272.559781 -313.853004) (xy 272.579072 -313.807728)
			(xy 272.605375 -313.766132) (xy 272.63801 -313.729295) (xy 272.676131 -313.69817) (xy 272.718752 -313.673563)
			(xy 272.764768 -313.656111) (xy 272.812987 -313.646267) (xy 272.862162 -313.644286) (xy 272.911017 -313.650218)
			(xy 272.958288 -313.66391) (xy 273.00275 -313.685008) (xy 273.043253 -313.712964) (xy 273.078746 -313.747056)
			(xy 273.108311 -313.7864) (xy 273.131182 -313.829977) (xy 273.146766 -313.876658) (xy 273.154661 -313.925235)
			(xy 273.155156 -313.949842) (xy 274.443964 -313.949842) (xy 274.447924 -313.900788) (xy 274.459701 -313.853004)
			(xy 274.478992 -313.807728) (xy 274.505295 -313.766132) (xy 274.53793 -313.729295) (xy 274.576051 -313.69817)
			(xy 274.618672 -313.673563) (xy 274.664688 -313.656111) (xy 274.712907 -313.646267) (xy 274.762082 -313.644286)
			(xy 274.810937 -313.650218) (xy 274.858208 -313.66391) (xy 274.90267 -313.685008) (xy 274.943173 -313.712964)
			(xy 274.978666 -313.747056) (xy 275.008231 -313.7864) (xy 275.031102 -313.829977) (xy 275.046686 -313.876658)
			(xy 275.054581 -313.925235) (xy 275.055076 -313.949842) (xy 276.343884 -313.949842) (xy 276.347844 -313.900788)
			(xy 276.359621 -313.853004) (xy 276.378912 -313.807728) (xy 276.405215 -313.766132) (xy 276.43785 -313.729295)
			(xy 276.475971 -313.69817) (xy 276.518592 -313.673563) (xy 276.564608 -313.656111) (xy 276.612827 -313.646267)
			(xy 276.662002 -313.644286) (xy 276.710857 -313.650218) (xy 276.758128 -313.66391) (xy 276.80259 -313.685008)
			(xy 276.843093 -313.712964) (xy 276.878586 -313.747056) (xy 276.908151 -313.7864) (xy 276.931022 -313.829977)
			(xy 276.946606 -313.876658) (xy 276.954501 -313.925235) (xy 276.954996 -313.949842) (xy 278.244058 -313.949842)
			(xy 278.248018 -313.900788) (xy 278.259795 -313.853004) (xy 278.279086 -313.807728) (xy 278.305389 -313.766132)
			(xy 278.338024 -313.729295) (xy 278.376145 -313.69817) (xy 278.418766 -313.673563) (xy 278.464782 -313.656111)
			(xy 278.513001 -313.646267) (xy 278.562176 -313.644286) (xy 278.611031 -313.650218) (xy 278.658302 -313.66391)
			(xy 278.702764 -313.685008) (xy 278.743267 -313.712964) (xy 278.77876 -313.747056) (xy 278.808325 -313.7864)
			(xy 278.831196 -313.829977) (xy 278.84678 -313.876658) (xy 278.854675 -313.925235) (xy 278.85517 -313.949842)
			(xy 280.143978 -313.949842) (xy 280.147938 -313.900788) (xy 280.159715 -313.853004) (xy 280.179006 -313.807728)
			(xy 280.205309 -313.766132) (xy 280.237944 -313.729295) (xy 280.276065 -313.69817) (xy 280.318686 -313.673563)
			(xy 280.364702 -313.656111) (xy 280.412921 -313.646267) (xy 280.462096 -313.644286) (xy 280.510951 -313.650218)
			(xy 280.558222 -313.66391) (xy 280.602684 -313.685008) (xy 280.643187 -313.712964) (xy 280.67868 -313.747056)
			(xy 280.708245 -313.7864) (xy 280.731116 -313.829977) (xy 280.7467 -313.876658) (xy 280.754595 -313.925235)
			(xy 280.75509 -313.949842) (xy 282.043898 -313.949842) (xy 282.047858 -313.900788) (xy 282.059635 -313.853004)
			(xy 282.078926 -313.807728) (xy 282.105229 -313.766132) (xy 282.137864 -313.729295) (xy 282.175985 -313.69817)
			(xy 282.218606 -313.673563) (xy 282.264622 -313.656111) (xy 282.312841 -313.646267) (xy 282.362016 -313.644286)
			(xy 282.410871 -313.650218) (xy 282.458142 -313.66391) (xy 282.502604 -313.685008) (xy 282.543107 -313.712964)
			(xy 282.5786 -313.747056) (xy 282.608165 -313.7864) (xy 282.631036 -313.829977) (xy 282.64662 -313.876658)
			(xy 282.654515 -313.925235) (xy 282.65501 -313.949842) (xy 283.944072 -313.949842) (xy 283.948032 -313.900788)
			(xy 283.959809 -313.853004) (xy 283.9791 -313.807728) (xy 284.005403 -313.766132) (xy 284.038038 -313.729295)
			(xy 284.076159 -313.69817) (xy 284.11878 -313.673563) (xy 284.164796 -313.656111) (xy 284.213015 -313.646267)
			(xy 284.26219 -313.644286) (xy 284.311045 -313.650218) (xy 284.358316 -313.66391) (xy 284.402778 -313.685008)
			(xy 284.443281 -313.712964) (xy 284.478774 -313.747056) (xy 284.508339 -313.7864) (xy 284.53121 -313.829977)
			(xy 284.546794 -313.876658) (xy 284.554689 -313.925235) (xy 284.555184 -313.949842) (xy 285.843992 -313.949842)
			(xy 285.847952 -313.900788) (xy 285.859729 -313.853004) (xy 285.87902 -313.807728) (xy 285.905323 -313.766132)
			(xy 285.937958 -313.729295) (xy 285.976079 -313.69817) (xy 286.0187 -313.673563) (xy 286.064716 -313.656111)
			(xy 286.112935 -313.646267) (xy 286.16211 -313.644286) (xy 286.210965 -313.650218) (xy 286.258236 -313.66391)
			(xy 286.302698 -313.685008) (xy 286.343201 -313.712964) (xy 286.378694 -313.747056) (xy 286.408259 -313.7864)
			(xy 286.43113 -313.829977) (xy 286.446714 -313.876658) (xy 286.454609 -313.925235) (xy 286.455104 -313.949842)
			(xy 287.743912 -313.949842) (xy 287.747872 -313.900788) (xy 287.759649 -313.853004) (xy 287.77894 -313.807728)
			(xy 287.805243 -313.766132) (xy 287.837878 -313.729295) (xy 287.875999 -313.69817) (xy 287.91862 -313.673563)
			(xy 287.964636 -313.656111) (xy 288.012855 -313.646267) (xy 288.06203 -313.644286) (xy 288.110885 -313.650218)
			(xy 288.158156 -313.66391) (xy 288.202618 -313.685008) (xy 288.243121 -313.712964) (xy 288.278614 -313.747056)
			(xy 288.308179 -313.7864) (xy 288.33105 -313.829977) (xy 288.346634 -313.876658) (xy 288.354529 -313.925235)
			(xy 288.355024 -313.949842) (xy 289.644086 -313.949842) (xy 289.648046 -313.900788) (xy 289.659823 -313.853004)
			(xy 289.679114 -313.807728) (xy 289.705417 -313.766132) (xy 289.738052 -313.729295) (xy 289.776173 -313.69817)
			(xy 289.818794 -313.673563) (xy 289.86481 -313.656111) (xy 289.913029 -313.646267) (xy 289.962204 -313.644286)
			(xy 290.011059 -313.650218) (xy 290.05833 -313.66391) (xy 290.102792 -313.685008) (xy 290.143295 -313.712964)
			(xy 290.178788 -313.747056) (xy 290.208353 -313.7864) (xy 290.231224 -313.829977) (xy 290.246808 -313.876658)
			(xy 290.254703 -313.925235) (xy 290.255198 -313.949842) (xy 291.544006 -313.949842) (xy 291.547966 -313.900788)
			(xy 291.559743 -313.853004) (xy 291.579034 -313.807728) (xy 291.605337 -313.766132) (xy 291.637972 -313.729295)
			(xy 291.676093 -313.69817) (xy 291.718714 -313.673563) (xy 291.76473 -313.656111) (xy 291.812949 -313.646267)
			(xy 291.862124 -313.644286) (xy 291.910979 -313.650218) (xy 291.95825 -313.66391) (xy 292.002712 -313.685008)
			(xy 292.043215 -313.712964) (xy 292.078708 -313.747056) (xy 292.108273 -313.7864) (xy 292.131144 -313.829977)
			(xy 292.146728 -313.876658) (xy 292.154623 -313.925235) (xy 292.155118 -313.949842) (xy 293.443926 -313.949842)
			(xy 293.447886 -313.900788) (xy 293.459663 -313.853004) (xy 293.478954 -313.807728) (xy 293.505257 -313.766132)
			(xy 293.537892 -313.729295) (xy 293.576013 -313.69817) (xy 293.618634 -313.673563) (xy 293.66465 -313.656111)
			(xy 293.712869 -313.646267) (xy 293.762044 -313.644286) (xy 293.810899 -313.650218) (xy 293.85817 -313.66391)
			(xy 293.902632 -313.685008) (xy 293.943135 -313.712964) (xy 293.978628 -313.747056) (xy 294.008193 -313.7864)
			(xy 294.031064 -313.829977) (xy 294.046648 -313.876658) (xy 294.054543 -313.925235) (xy 294.055038 -313.949842)
			(xy 295.3441 -313.949842) (xy 295.34806 -313.900788) (xy 295.359837 -313.853004) (xy 295.379128 -313.807728)
			(xy 295.405431 -313.766132) (xy 295.438066 -313.729295) (xy 295.476187 -313.69817) (xy 295.518808 -313.673563)
			(xy 295.564824 -313.656111) (xy 295.613043 -313.646267) (xy 295.662218 -313.644286) (xy 295.711073 -313.650218)
			(xy 295.758344 -313.66391) (xy 295.802806 -313.685008) (xy 295.843309 -313.712964) (xy 295.878802 -313.747056)
			(xy 295.908367 -313.7864) (xy 295.931238 -313.829977) (xy 295.946822 -313.876658) (xy 295.954717 -313.925235)
			(xy 295.955212 -313.949842) (xy 297.24402 -313.949842) (xy 297.24798 -313.900788) (xy 297.259757 -313.853004)
			(xy 297.279048 -313.807728) (xy 297.305351 -313.766132) (xy 297.337986 -313.729295) (xy 297.376107 -313.69817)
			(xy 297.418728 -313.673563) (xy 297.464744 -313.656111) (xy 297.512963 -313.646267) (xy 297.562138 -313.644286)
			(xy 297.610993 -313.650218) (xy 297.658264 -313.66391) (xy 297.702726 -313.685008) (xy 297.743229 -313.712964)
			(xy 297.778722 -313.747056) (xy 297.808287 -313.7864) (xy 297.831158 -313.829977) (xy 297.846742 -313.876658)
			(xy 297.854637 -313.925235) (xy 297.855132 -313.949842) (xy 299.14394 -313.949842) (xy 299.1479 -313.900788)
			(xy 299.159677 -313.853004) (xy 299.178968 -313.807728) (xy 299.205271 -313.766132) (xy 299.237906 -313.729295)
			(xy 299.276027 -313.69817) (xy 299.318648 -313.673563) (xy 299.364664 -313.656111) (xy 299.412883 -313.646267)
			(xy 299.462058 -313.644286) (xy 299.510913 -313.650218) (xy 299.558184 -313.66391) (xy 299.602646 -313.685008)
			(xy 299.643149 -313.712964) (xy 299.678642 -313.747056) (xy 299.708207 -313.7864) (xy 299.731078 -313.829977)
			(xy 299.746662 -313.876658) (xy 299.754557 -313.925235) (xy 299.755052 -313.949842) (xy 301.044114 -313.949842)
			(xy 301.048074 -313.900788) (xy 301.059851 -313.853004) (xy 301.079142 -313.807728) (xy 301.105445 -313.766132)
			(xy 301.13808 -313.729295) (xy 301.176201 -313.69817) (xy 301.218822 -313.673563) (xy 301.264838 -313.656111)
			(xy 301.313057 -313.646267) (xy 301.362232 -313.644286) (xy 301.411087 -313.650218) (xy 301.458358 -313.66391)
			(xy 301.50282 -313.685008) (xy 301.543323 -313.712964) (xy 301.578816 -313.747056) (xy 301.608381 -313.7864)
			(xy 301.631252 -313.829977) (xy 301.646836 -313.876658) (xy 301.654731 -313.925235) (xy 301.655226 -313.949842)
			(xy 302.944034 -313.949842) (xy 302.947994 -313.900788) (xy 302.959771 -313.853004) (xy 302.979062 -313.807728)
			(xy 303.005365 -313.766132) (xy 303.038 -313.729295) (xy 303.076121 -313.69817) (xy 303.118742 -313.673563)
			(xy 303.164758 -313.656111) (xy 303.212977 -313.646267) (xy 303.262152 -313.644286) (xy 303.311007 -313.650218)
			(xy 303.358278 -313.66391) (xy 303.40274 -313.685008) (xy 303.443243 -313.712964) (xy 303.478736 -313.747056)
			(xy 303.508301 -313.7864) (xy 303.531172 -313.829977) (xy 303.546756 -313.876658) (xy 303.554651 -313.925235)
			(xy 303.555146 -313.949842) (xy 304.843954 -313.949842) (xy 304.847914 -313.900788) (xy 304.859691 -313.853004)
			(xy 304.878982 -313.807728) (xy 304.905285 -313.766132) (xy 304.93792 -313.729295) (xy 304.976041 -313.69817)
			(xy 305.018662 -313.673563) (xy 305.064678 -313.656111) (xy 305.112897 -313.646267) (xy 305.162072 -313.644286)
			(xy 305.210927 -313.650218) (xy 305.258198 -313.66391) (xy 305.30266 -313.685008) (xy 305.343163 -313.712964)
			(xy 305.378656 -313.747056) (xy 305.408221 -313.7864) (xy 305.431092 -313.829977) (xy 305.446676 -313.876658)
			(xy 305.454571 -313.925235) (xy 305.455066 -313.949842) (xy 306.744128 -313.949842) (xy 306.748088 -313.900788)
			(xy 306.759865 -313.853004) (xy 306.779156 -313.807728) (xy 306.805459 -313.766132) (xy 306.838094 -313.729295)
			(xy 306.876215 -313.69817) (xy 306.918836 -313.673563) (xy 306.964852 -313.656111) (xy 307.013071 -313.646267)
			(xy 307.062246 -313.644286) (xy 307.111101 -313.650218) (xy 307.158372 -313.66391) (xy 307.202834 -313.685008)
			(xy 307.243337 -313.712964) (xy 307.27883 -313.747056) (xy 307.308395 -313.7864) (xy 307.331266 -313.829977)
			(xy 307.34685 -313.876658) (xy 307.354745 -313.925235) (xy 307.35524 -313.949842) (xy 308.644048 -313.949842)
			(xy 308.648008 -313.900788) (xy 308.659785 -313.853004) (xy 308.679076 -313.807728) (xy 308.705379 -313.766132)
			(xy 308.738014 -313.729295) (xy 308.776135 -313.69817) (xy 308.818756 -313.673563) (xy 308.864772 -313.656111)
			(xy 308.912991 -313.646267) (xy 308.962166 -313.644286) (xy 309.011021 -313.650218) (xy 309.058292 -313.66391)
			(xy 309.102754 -313.685008) (xy 309.143257 -313.712964) (xy 309.17875 -313.747056) (xy 309.208315 -313.7864)
			(xy 309.231186 -313.829977) (xy 309.24677 -313.876658) (xy 309.254665 -313.925235) (xy 309.25516 -313.949842)
			(xy 310.543968 -313.949842) (xy 310.547928 -313.900788) (xy 310.559705 -313.853004) (xy 310.578996 -313.807728)
			(xy 310.605299 -313.766132) (xy 310.637934 -313.729295) (xy 310.676055 -313.69817) (xy 310.718676 -313.673563)
			(xy 310.764692 -313.656111) (xy 310.812911 -313.646267) (xy 310.862086 -313.644286) (xy 310.910941 -313.650218)
			(xy 310.958212 -313.66391) (xy 311.002674 -313.685008) (xy 311.043177 -313.712964) (xy 311.07867 -313.747056)
			(xy 311.108235 -313.7864) (xy 311.131106 -313.829977) (xy 311.14669 -313.876658) (xy 311.154585 -313.925235)
			(xy 311.15508 -313.949842) (xy 312.443888 -313.949842) (xy 312.447848 -313.900788) (xy 312.459625 -313.853004)
			(xy 312.478916 -313.807728) (xy 312.505219 -313.766132) (xy 312.537854 -313.729295) (xy 312.575975 -313.69817)
			(xy 312.618596 -313.673563) (xy 312.664612 -313.656111) (xy 312.712831 -313.646267) (xy 312.762006 -313.644286)
			(xy 312.810861 -313.650218) (xy 312.858132 -313.66391) (xy 312.902594 -313.685008) (xy 312.943097 -313.712964)
			(xy 312.97859 -313.747056) (xy 313.008155 -313.7864) (xy 313.031026 -313.829977) (xy 313.04661 -313.876658)
			(xy 313.054505 -313.925235) (xy 313.055 -313.949842) (xy 386.744222 -313.949842) (xy 386.748182 -313.900788)
			(xy 386.759959 -313.853004) (xy 386.77925 -313.807728) (xy 386.805553 -313.766132) (xy 386.838188 -313.729295)
			(xy 386.876309 -313.69817) (xy 386.91893 -313.673563) (xy 386.964946 -313.656111) (xy 387.013165 -313.646267)
			(xy 387.06234 -313.644286) (xy 387.111195 -313.650218) (xy 387.158466 -313.66391) (xy 387.202928 -313.685008)
			(xy 387.243431 -313.712964) (xy 387.278924 -313.747056) (xy 387.308489 -313.7864) (xy 387.33136 -313.829977)
			(xy 387.346944 -313.876658) (xy 387.354839 -313.925235) (xy 387.355334 -313.949842) (xy 388.644142 -313.949842)
			(xy 388.648102 -313.900788) (xy 388.659879 -313.853004) (xy 388.67917 -313.807728) (xy 388.705473 -313.766132)
			(xy 388.738108 -313.729295) (xy 388.776229 -313.69817) (xy 388.81885 -313.673563) (xy 388.864866 -313.656111)
			(xy 388.913085 -313.646267) (xy 388.96226 -313.644286) (xy 389.011115 -313.650218) (xy 389.058386 -313.66391)
			(xy 389.102848 -313.685008) (xy 389.143351 -313.712964) (xy 389.178844 -313.747056) (xy 389.208409 -313.7864)
			(xy 389.23128 -313.829977) (xy 389.246864 -313.876658) (xy 389.254759 -313.925235) (xy 389.255254 -313.949842)
			(xy 390.544062 -313.949842) (xy 390.548022 -313.900788) (xy 390.559799 -313.853004) (xy 390.57909 -313.807728)
			(xy 390.605393 -313.766132) (xy 390.638028 -313.729295) (xy 390.676149 -313.69817) (xy 390.71877 -313.673563)
			(xy 390.764786 -313.656111) (xy 390.813005 -313.646267) (xy 390.86218 -313.644286) (xy 390.911035 -313.650218)
			(xy 390.958306 -313.66391) (xy 391.002768 -313.685008) (xy 391.043271 -313.712964) (xy 391.078764 -313.747056)
			(xy 391.108329 -313.7864) (xy 391.1312 -313.829977) (xy 391.146784 -313.876658) (xy 391.154679 -313.925235)
			(xy 391.155174 -313.949842) (xy 392.443982 -313.949842) (xy 392.447942 -313.900788) (xy 392.459719 -313.853004)
			(xy 392.47901 -313.807728) (xy 392.505313 -313.766132) (xy 392.537948 -313.729295) (xy 392.576069 -313.69817)
			(xy 392.61869 -313.673563) (xy 392.664706 -313.656111) (xy 392.712925 -313.646267) (xy 392.7621 -313.644286)
			(xy 392.810955 -313.650218) (xy 392.858226 -313.66391) (xy 392.902688 -313.685008) (xy 392.943191 -313.712964)
			(xy 392.978684 -313.747056) (xy 393.008249 -313.7864) (xy 393.03112 -313.829977) (xy 393.046704 -313.876658)
			(xy 393.054599 -313.925235) (xy 393.055094 -313.949842) (xy 394.344156 -313.949842) (xy 394.348116 -313.900788)
			(xy 394.359893 -313.853004) (xy 394.379184 -313.807728) (xy 394.405487 -313.766132) (xy 394.438122 -313.729295)
			(xy 394.476243 -313.69817) (xy 394.518864 -313.673563) (xy 394.56488 -313.656111) (xy 394.613099 -313.646267)
			(xy 394.662274 -313.644286) (xy 394.711129 -313.650218) (xy 394.7584 -313.66391) (xy 394.802862 -313.685008)
			(xy 394.843365 -313.712964) (xy 394.878858 -313.747056) (xy 394.908423 -313.7864) (xy 394.931294 -313.829977)
			(xy 394.946878 -313.876658) (xy 394.954773 -313.925235) (xy 394.955268 -313.949842) (xy 396.244076 -313.949842)
			(xy 396.248036 -313.900788) (xy 396.259813 -313.853004) (xy 396.279104 -313.807728) (xy 396.305407 -313.766132)
			(xy 396.338042 -313.729295) (xy 396.376163 -313.69817) (xy 396.418784 -313.673563) (xy 396.4648 -313.656111)
			(xy 396.513019 -313.646267) (xy 396.562194 -313.644286) (xy 396.611049 -313.650218) (xy 396.65832 -313.66391)
			(xy 396.702782 -313.685008) (xy 396.743285 -313.712964) (xy 396.778778 -313.747056) (xy 396.808343 -313.7864)
			(xy 396.831214 -313.829977) (xy 396.846798 -313.876658) (xy 396.854693 -313.925235) (xy 396.855188 -313.949842)
			(xy 398.143996 -313.949842) (xy 398.147956 -313.900788) (xy 398.159733 -313.853004) (xy 398.179024 -313.807728)
			(xy 398.205327 -313.766132) (xy 398.237962 -313.729295) (xy 398.276083 -313.69817) (xy 398.318704 -313.673563)
			(xy 398.36472 -313.656111) (xy 398.412939 -313.646267) (xy 398.462114 -313.644286) (xy 398.510969 -313.650218)
			(xy 398.55824 -313.66391) (xy 398.602702 -313.685008) (xy 398.643205 -313.712964) (xy 398.678698 -313.747056)
			(xy 398.708263 -313.7864) (xy 398.731134 -313.829977) (xy 398.746718 -313.876658) (xy 398.754613 -313.925235)
			(xy 398.755108 -313.949842) (xy 400.04417 -313.949842) (xy 400.04813 -313.900788) (xy 400.059907 -313.853004)
			(xy 400.079198 -313.807728) (xy 400.105501 -313.766132) (xy 400.138136 -313.729295) (xy 400.176257 -313.69817)
			(xy 400.218878 -313.673563) (xy 400.264894 -313.656111) (xy 400.313113 -313.646267) (xy 400.362288 -313.644286)
			(xy 400.411143 -313.650218) (xy 400.458414 -313.66391) (xy 400.502876 -313.685008) (xy 400.543379 -313.712964)
			(xy 400.578872 -313.747056) (xy 400.608437 -313.7864) (xy 400.631308 -313.829977) (xy 400.646892 -313.876658)
			(xy 400.654787 -313.925235) (xy 400.655282 -313.949842) (xy 401.94409 -313.949842) (xy 401.94805 -313.900788)
			(xy 401.959827 -313.853004) (xy 401.979118 -313.807728) (xy 402.005421 -313.766132) (xy 402.038056 -313.729295)
			(xy 402.076177 -313.69817) (xy 402.118798 -313.673563) (xy 402.164814 -313.656111) (xy 402.213033 -313.646267)
			(xy 402.262208 -313.644286) (xy 402.311063 -313.650218) (xy 402.358334 -313.66391) (xy 402.402796 -313.685008)
			(xy 402.443299 -313.712964) (xy 402.478792 -313.747056) (xy 402.508357 -313.7864) (xy 402.531228 -313.829977)
			(xy 402.546812 -313.876658) (xy 402.554707 -313.925235) (xy 402.555202 -313.949842) (xy 403.84401 -313.949842)
			(xy 403.84797 -313.900788) (xy 403.859747 -313.853004) (xy 403.879038 -313.807728) (xy 403.905341 -313.766132)
			(xy 403.937976 -313.729295) (xy 403.976097 -313.69817) (xy 404.018718 -313.673563) (xy 404.064734 -313.656111)
			(xy 404.112953 -313.646267) (xy 404.162128 -313.644286) (xy 404.210983 -313.650218) (xy 404.258254 -313.66391)
			(xy 404.302716 -313.685008) (xy 404.343219 -313.712964) (xy 404.378712 -313.747056) (xy 404.408277 -313.7864)
			(xy 404.431148 -313.829977) (xy 404.446732 -313.876658) (xy 404.454627 -313.925235) (xy 404.455122 -313.949842)
			(xy 405.744184 -313.949842) (xy 405.748144 -313.900788) (xy 405.759921 -313.853004) (xy 405.779212 -313.807728)
			(xy 405.805515 -313.766132) (xy 405.83815 -313.729295) (xy 405.876271 -313.69817) (xy 405.918892 -313.673563)
			(xy 405.964908 -313.656111) (xy 406.013127 -313.646267) (xy 406.062302 -313.644286) (xy 406.111157 -313.650218)
			(xy 406.158428 -313.66391) (xy 406.20289 -313.685008) (xy 406.243393 -313.712964) (xy 406.278886 -313.747056)
			(xy 406.308451 -313.7864) (xy 406.331322 -313.829977) (xy 406.346906 -313.876658) (xy 406.354801 -313.925235)
			(xy 406.355296 -313.949842) (xy 407.644104 -313.949842) (xy 407.648064 -313.900788) (xy 407.659841 -313.853004)
			(xy 407.679132 -313.807728) (xy 407.705435 -313.766132) (xy 407.73807 -313.729295) (xy 407.776191 -313.69817)
			(xy 407.818812 -313.673563) (xy 407.864828 -313.656111) (xy 407.913047 -313.646267) (xy 407.962222 -313.644286)
			(xy 408.011077 -313.650218) (xy 408.058348 -313.66391) (xy 408.10281 -313.685008) (xy 408.143313 -313.712964)
			(xy 408.178806 -313.747056) (xy 408.208371 -313.7864) (xy 408.231242 -313.829977) (xy 408.246826 -313.876658)
			(xy 408.254721 -313.925235) (xy 408.255216 -313.949842) (xy 409.544024 -313.949842) (xy 409.547984 -313.900788)
			(xy 409.559761 -313.853004) (xy 409.579052 -313.807728) (xy 409.605355 -313.766132) (xy 409.63799 -313.729295)
			(xy 409.676111 -313.69817) (xy 409.718732 -313.673563) (xy 409.764748 -313.656111) (xy 409.812967 -313.646267)
			(xy 409.862142 -313.644286) (xy 409.910997 -313.650218) (xy 409.958268 -313.66391) (xy 410.00273 -313.685008)
			(xy 410.043233 -313.712964) (xy 410.078726 -313.747056) (xy 410.108291 -313.7864) (xy 410.131162 -313.829977)
			(xy 410.146746 -313.876658) (xy 410.154641 -313.925235) (xy 410.155136 -313.949842) (xy 411.444198 -313.949842)
			(xy 411.448158 -313.900788) (xy 411.459935 -313.853004) (xy 411.479226 -313.807728) (xy 411.505529 -313.766132)
			(xy 411.538164 -313.729295) (xy 411.576285 -313.69817) (xy 411.618906 -313.673563) (xy 411.664922 -313.656111)
			(xy 411.713141 -313.646267) (xy 411.762316 -313.644286) (xy 411.811171 -313.650218) (xy 411.858442 -313.66391)
			(xy 411.902904 -313.685008) (xy 411.943407 -313.712964) (xy 411.9789 -313.747056) (xy 412.008465 -313.7864)
			(xy 412.031336 -313.829977) (xy 412.04692 -313.876658) (xy 412.054815 -313.925235) (xy 412.05531 -313.949842)
			(xy 413.344118 -313.949842) (xy 413.348078 -313.900788) (xy 413.359855 -313.853004) (xy 413.379146 -313.807728)
			(xy 413.405449 -313.766132) (xy 413.438084 -313.729295) (xy 413.476205 -313.69817) (xy 413.518826 -313.673563)
			(xy 413.564842 -313.656111) (xy 413.613061 -313.646267) (xy 413.662236 -313.644286) (xy 413.711091 -313.650218)
			(xy 413.758362 -313.66391) (xy 413.802824 -313.685008) (xy 413.843327 -313.712964) (xy 413.87882 -313.747056)
			(xy 413.908385 -313.7864) (xy 413.931256 -313.829977) (xy 413.94684 -313.876658) (xy 413.954735 -313.925235)
			(xy 413.95523 -313.949842) (xy 415.244038 -313.949842) (xy 415.247998 -313.900788) (xy 415.259775 -313.853004)
			(xy 415.279066 -313.807728) (xy 415.305369 -313.766132) (xy 415.338004 -313.729295) (xy 415.376125 -313.69817)
			(xy 415.418746 -313.673563) (xy 415.464762 -313.656111) (xy 415.512981 -313.646267) (xy 415.562156 -313.644286)
			(xy 415.611011 -313.650218) (xy 415.658282 -313.66391) (xy 415.702744 -313.685008) (xy 415.743247 -313.712964)
			(xy 415.77874 -313.747056) (xy 415.808305 -313.7864) (xy 415.831176 -313.829977) (xy 415.84676 -313.876658)
			(xy 415.854655 -313.925235) (xy 415.85515 -313.949842) (xy 417.144212 -313.949842) (xy 417.148172 -313.900788)
			(xy 417.159949 -313.853004) (xy 417.17924 -313.807728) (xy 417.205543 -313.766132) (xy 417.238178 -313.729295)
			(xy 417.276299 -313.69817) (xy 417.31892 -313.673563) (xy 417.364936 -313.656111) (xy 417.413155 -313.646267)
			(xy 417.46233 -313.644286) (xy 417.511185 -313.650218) (xy 417.558456 -313.66391) (xy 417.602918 -313.685008)
			(xy 417.643421 -313.712964) (xy 417.678914 -313.747056) (xy 417.708479 -313.7864) (xy 417.73135 -313.829977)
			(xy 417.746934 -313.876658) (xy 417.754829 -313.925235) (xy 417.755324 -313.949842) (xy 419.044132 -313.949842)
			(xy 419.048092 -313.900788) (xy 419.059869 -313.853004) (xy 419.07916 -313.807728) (xy 419.105463 -313.766132)
			(xy 419.138098 -313.729295) (xy 419.176219 -313.69817) (xy 419.21884 -313.673563) (xy 419.264856 -313.656111)
			(xy 419.313075 -313.646267) (xy 419.36225 -313.644286) (xy 419.411105 -313.650218) (xy 419.458376 -313.66391)
			(xy 419.502838 -313.685008) (xy 419.543341 -313.712964) (xy 419.578834 -313.747056) (xy 419.608399 -313.7864)
			(xy 419.63127 -313.829977) (xy 419.646854 -313.876658) (xy 419.654749 -313.925235) (xy 419.655244 -313.949842)
			(xy 420.944052 -313.949842) (xy 420.948012 -313.900788) (xy 420.959789 -313.853004) (xy 420.97908 -313.807728)
			(xy 421.005383 -313.766132) (xy 421.038018 -313.729295) (xy 421.076139 -313.69817) (xy 421.11876 -313.673563)
			(xy 421.164776 -313.656111) (xy 421.212995 -313.646267) (xy 421.26217 -313.644286) (xy 421.311025 -313.650218)
			(xy 421.358296 -313.66391) (xy 421.402758 -313.685008) (xy 421.443261 -313.712964) (xy 421.478754 -313.747056)
			(xy 421.508319 -313.7864) (xy 421.53119 -313.829977) (xy 421.546774 -313.876658) (xy 421.554669 -313.925235)
			(xy 421.555164 -313.949842) (xy 422.844226 -313.949842) (xy 422.848186 -313.900788) (xy 422.859963 -313.853004)
			(xy 422.879254 -313.807728) (xy 422.905557 -313.766132) (xy 422.938192 -313.729295) (xy 422.976313 -313.69817)
			(xy 423.018934 -313.673563) (xy 423.06495 -313.656111) (xy 423.113169 -313.646267) (xy 423.162344 -313.644286)
			(xy 423.211199 -313.650218) (xy 423.25847 -313.66391) (xy 423.302932 -313.685008) (xy 423.343435 -313.712964)
			(xy 423.378928 -313.747056) (xy 423.408493 -313.7864) (xy 423.431364 -313.829977) (xy 423.446948 -313.876658)
			(xy 423.454843 -313.925235) (xy 423.455338 -313.949842) (xy 424.744146 -313.949842) (xy 424.748106 -313.900788)
			(xy 424.759883 -313.853004) (xy 424.779174 -313.807728) (xy 424.805477 -313.766132) (xy 424.838112 -313.729295)
			(xy 424.876233 -313.69817) (xy 424.918854 -313.673563) (xy 424.96487 -313.656111) (xy 425.013089 -313.646267)
			(xy 425.062264 -313.644286) (xy 425.111119 -313.650218) (xy 425.15839 -313.66391) (xy 425.202852 -313.685008)
			(xy 425.243355 -313.712964) (xy 425.278848 -313.747056) (xy 425.308413 -313.7864) (xy 425.331284 -313.829977)
			(xy 425.346868 -313.876658) (xy 425.354763 -313.925235) (xy 425.355258 -313.949842) (xy 426.644066 -313.949842)
			(xy 426.648026 -313.900788) (xy 426.659803 -313.853004) (xy 426.679094 -313.807728) (xy 426.705397 -313.766132)
			(xy 426.738032 -313.729295) (xy 426.776153 -313.69817) (xy 426.818774 -313.673563) (xy 426.86479 -313.656111)
			(xy 426.913009 -313.646267) (xy 426.962184 -313.644286) (xy 427.011039 -313.650218) (xy 427.05831 -313.66391)
			(xy 427.102772 -313.685008) (xy 427.143275 -313.712964) (xy 427.178768 -313.747056) (xy 427.208333 -313.7864)
			(xy 427.231204 -313.829977) (xy 427.246788 -313.876658) (xy 427.254683 -313.925235) (xy 427.255178 -313.949842)
			(xy 428.543986 -313.949842) (xy 428.547946 -313.900788) (xy 428.559723 -313.853004) (xy 428.579014 -313.807728)
			(xy 428.605317 -313.766132) (xy 428.637952 -313.729295) (xy 428.676073 -313.69817) (xy 428.718694 -313.673563)
			(xy 428.76471 -313.656111) (xy 428.812929 -313.646267) (xy 428.862104 -313.644286) (xy 428.910959 -313.650218)
			(xy 428.95823 -313.66391) (xy 429.002692 -313.685008) (xy 429.043195 -313.712964) (xy 429.078688 -313.747056)
			(xy 429.108253 -313.7864) (xy 429.131124 -313.829977) (xy 429.146708 -313.876658) (xy 429.154603 -313.925235)
			(xy 429.155098 -313.949842) (xy 429.154603 -313.974449) (xy 429.146708 -314.023026) (xy 429.131124 -314.069707)
			(xy 429.108253 -314.113284) (xy 429.078688 -314.152628) (xy 429.043195 -314.18672) (xy 429.002692 -314.214676)
			(xy 428.95823 -314.235774) (xy 428.910959 -314.249466) (xy 428.862104 -314.255398) (xy 428.812929 -314.253417)
			(xy 428.76471 -314.243573) (xy 428.718694 -314.226121) (xy 428.676073 -314.201514) (xy 428.637952 -314.170389)
			(xy 428.605317 -314.133552) (xy 428.579014 -314.091956) (xy 428.559723 -314.04668) (xy 428.547946 -313.998896)
			(xy 428.543986 -313.949842) (xy 427.255178 -313.949842) (xy 427.254683 -313.974449) (xy 427.246788 -314.023026)
			(xy 427.231204 -314.069707) (xy 427.208333 -314.113284) (xy 427.178768 -314.152628) (xy 427.143275 -314.18672)
			(xy 427.102772 -314.214676) (xy 427.05831 -314.235774) (xy 427.011039 -314.249466) (xy 426.962184 -314.255398)
			(xy 426.913009 -314.253417) (xy 426.86479 -314.243573) (xy 426.818774 -314.226121) (xy 426.776153 -314.201514)
			(xy 426.738032 -314.170389) (xy 426.705397 -314.133552) (xy 426.679094 -314.091956) (xy 426.659803 -314.04668)
			(xy 426.648026 -313.998896) (xy 426.644066 -313.949842) (xy 425.355258 -313.949842) (xy 425.354763 -313.974449)
			(xy 425.346868 -314.023026) (xy 425.331284 -314.069707) (xy 425.308413 -314.113284) (xy 425.278848 -314.152628)
			(xy 425.243355 -314.18672) (xy 425.202852 -314.214676) (xy 425.15839 -314.235774) (xy 425.111119 -314.249466)
			(xy 425.062264 -314.255398) (xy 425.013089 -314.253417) (xy 424.96487 -314.243573) (xy 424.918854 -314.226121)
			(xy 424.876233 -314.201514) (xy 424.838112 -314.170389) (xy 424.805477 -314.133552) (xy 424.779174 -314.091956)
			(xy 424.759883 -314.04668) (xy 424.748106 -313.998896) (xy 424.744146 -313.949842) (xy 423.455338 -313.949842)
			(xy 423.454843 -313.974449) (xy 423.446948 -314.023026) (xy 423.431364 -314.069707) (xy 423.408493 -314.113284)
			(xy 423.378928 -314.152628) (xy 423.343435 -314.18672) (xy 423.302932 -314.214676) (xy 423.25847 -314.235774)
			(xy 423.211199 -314.249466) (xy 423.162344 -314.255398) (xy 423.113169 -314.253417) (xy 423.06495 -314.243573)
			(xy 423.018934 -314.226121) (xy 422.976313 -314.201514) (xy 422.938192 -314.170389) (xy 422.905557 -314.133552)
			(xy 422.879254 -314.091956) (xy 422.859963 -314.04668) (xy 422.848186 -313.998896) (xy 422.844226 -313.949842)
			(xy 421.555164 -313.949842) (xy 421.554669 -313.974449) (xy 421.546774 -314.023026) (xy 421.53119 -314.069707)
			(xy 421.508319 -314.113284) (xy 421.478754 -314.152628) (xy 421.443261 -314.18672) (xy 421.402758 -314.214676)
			(xy 421.358296 -314.235774) (xy 421.311025 -314.249466) (xy 421.26217 -314.255398) (xy 421.212995 -314.253417)
			(xy 421.164776 -314.243573) (xy 421.11876 -314.226121) (xy 421.076139 -314.201514) (xy 421.038018 -314.170389)
			(xy 421.005383 -314.133552) (xy 420.97908 -314.091956) (xy 420.959789 -314.04668) (xy 420.948012 -313.998896)
			(xy 420.944052 -313.949842) (xy 419.655244 -313.949842) (xy 419.654749 -313.974449) (xy 419.646854 -314.023026)
			(xy 419.63127 -314.069707) (xy 419.608399 -314.113284) (xy 419.578834 -314.152628) (xy 419.543341 -314.18672)
			(xy 419.502838 -314.214676) (xy 419.458376 -314.235774) (xy 419.411105 -314.249466) (xy 419.36225 -314.255398)
			(xy 419.313075 -314.253417) (xy 419.264856 -314.243573) (xy 419.21884 -314.226121) (xy 419.176219 -314.201514)
			(xy 419.138098 -314.170389) (xy 419.105463 -314.133552) (xy 419.07916 -314.091956) (xy 419.059869 -314.04668)
			(xy 419.048092 -313.998896) (xy 419.044132 -313.949842) (xy 417.755324 -313.949842) (xy 417.754829 -313.974449)
			(xy 417.746934 -314.023026) (xy 417.73135 -314.069707) (xy 417.708479 -314.113284) (xy 417.678914 -314.152628)
			(xy 417.643421 -314.18672) (xy 417.602918 -314.214676) (xy 417.558456 -314.235774) (xy 417.511185 -314.249466)
			(xy 417.46233 -314.255398) (xy 417.413155 -314.253417) (xy 417.364936 -314.243573) (xy 417.31892 -314.226121)
			(xy 417.276299 -314.201514) (xy 417.238178 -314.170389) (xy 417.205543 -314.133552) (xy 417.17924 -314.091956)
			(xy 417.159949 -314.04668) (xy 417.148172 -313.998896) (xy 417.144212 -313.949842) (xy 415.85515 -313.949842)
			(xy 415.854655 -313.974449) (xy 415.84676 -314.023026) (xy 415.831176 -314.069707) (xy 415.808305 -314.113284)
			(xy 415.77874 -314.152628) (xy 415.743247 -314.18672) (xy 415.702744 -314.214676) (xy 415.658282 -314.235774)
			(xy 415.611011 -314.249466) (xy 415.562156 -314.255398) (xy 415.512981 -314.253417) (xy 415.464762 -314.243573)
			(xy 415.418746 -314.226121) (xy 415.376125 -314.201514) (xy 415.338004 -314.170389) (xy 415.305369 -314.133552)
			(xy 415.279066 -314.091956) (xy 415.259775 -314.04668) (xy 415.247998 -313.998896) (xy 415.244038 -313.949842)
			(xy 413.95523 -313.949842) (xy 413.954735 -313.974449) (xy 413.94684 -314.023026) (xy 413.931256 -314.069707)
			(xy 413.908385 -314.113284) (xy 413.87882 -314.152628) (xy 413.843327 -314.18672) (xy 413.802824 -314.214676)
			(xy 413.758362 -314.235774) (xy 413.711091 -314.249466) (xy 413.662236 -314.255398) (xy 413.613061 -314.253417)
			(xy 413.564842 -314.243573) (xy 413.518826 -314.226121) (xy 413.476205 -314.201514) (xy 413.438084 -314.170389)
			(xy 413.405449 -314.133552) (xy 413.379146 -314.091956) (xy 413.359855 -314.04668) (xy 413.348078 -313.998896)
			(xy 413.344118 -313.949842) (xy 412.05531 -313.949842) (xy 412.054815 -313.974449) (xy 412.04692 -314.023026)
			(xy 412.031336 -314.069707) (xy 412.008465 -314.113284) (xy 411.9789 -314.152628) (xy 411.943407 -314.18672)
			(xy 411.902904 -314.214676) (xy 411.858442 -314.235774) (xy 411.811171 -314.249466) (xy 411.762316 -314.255398)
			(xy 411.713141 -314.253417) (xy 411.664922 -314.243573) (xy 411.618906 -314.226121) (xy 411.576285 -314.201514)
			(xy 411.538164 -314.170389) (xy 411.505529 -314.133552) (xy 411.479226 -314.091956) (xy 411.459935 -314.04668)
			(xy 411.448158 -313.998896) (xy 411.444198 -313.949842) (xy 410.155136 -313.949842) (xy 410.154641 -313.974449)
			(xy 410.146746 -314.023026) (xy 410.131162 -314.069707) (xy 410.108291 -314.113284) (xy 410.078726 -314.152628)
			(xy 410.043233 -314.18672) (xy 410.00273 -314.214676) (xy 409.958268 -314.235774) (xy 409.910997 -314.249466)
			(xy 409.862142 -314.255398) (xy 409.812967 -314.253417) (xy 409.764748 -314.243573) (xy 409.718732 -314.226121)
			(xy 409.676111 -314.201514) (xy 409.63799 -314.170389) (xy 409.605355 -314.133552) (xy 409.579052 -314.091956)
			(xy 409.559761 -314.04668) (xy 409.547984 -313.998896) (xy 409.544024 -313.949842) (xy 408.255216 -313.949842)
			(xy 408.254721 -313.974449) (xy 408.246826 -314.023026) (xy 408.231242 -314.069707) (xy 408.208371 -314.113284)
			(xy 408.178806 -314.152628) (xy 408.143313 -314.18672) (xy 408.10281 -314.214676) (xy 408.058348 -314.235774)
			(xy 408.011077 -314.249466) (xy 407.962222 -314.255398) (xy 407.913047 -314.253417) (xy 407.864828 -314.243573)
			(xy 407.818812 -314.226121) (xy 407.776191 -314.201514) (xy 407.73807 -314.170389) (xy 407.705435 -314.133552)
			(xy 407.679132 -314.091956) (xy 407.659841 -314.04668) (xy 407.648064 -313.998896) (xy 407.644104 -313.949842)
			(xy 406.355296 -313.949842) (xy 406.354801 -313.974449) (xy 406.346906 -314.023026) (xy 406.331322 -314.069707)
			(xy 406.308451 -314.113284) (xy 406.278886 -314.152628) (xy 406.243393 -314.18672) (xy 406.20289 -314.214676)
			(xy 406.158428 -314.235774) (xy 406.111157 -314.249466) (xy 406.062302 -314.255398) (xy 406.013127 -314.253417)
			(xy 405.964908 -314.243573) (xy 405.918892 -314.226121) (xy 405.876271 -314.201514) (xy 405.83815 -314.170389)
			(xy 405.805515 -314.133552) (xy 405.779212 -314.091956) (xy 405.759921 -314.04668) (xy 405.748144 -313.998896)
			(xy 405.744184 -313.949842) (xy 404.455122 -313.949842) (xy 404.454627 -313.974449) (xy 404.446732 -314.023026)
			(xy 404.431148 -314.069707) (xy 404.408277 -314.113284) (xy 404.378712 -314.152628) (xy 404.343219 -314.18672)
			(xy 404.302716 -314.214676) (xy 404.258254 -314.235774) (xy 404.210983 -314.249466) (xy 404.162128 -314.255398)
			(xy 404.112953 -314.253417) (xy 404.064734 -314.243573) (xy 404.018718 -314.226121) (xy 403.976097 -314.201514)
			(xy 403.937976 -314.170389) (xy 403.905341 -314.133552) (xy 403.879038 -314.091956) (xy 403.859747 -314.04668)
			(xy 403.84797 -313.998896) (xy 403.84401 -313.949842) (xy 402.555202 -313.949842) (xy 402.554707 -313.974449)
			(xy 402.546812 -314.023026) (xy 402.531228 -314.069707) (xy 402.508357 -314.113284) (xy 402.478792 -314.152628)
			(xy 402.443299 -314.18672) (xy 402.402796 -314.214676) (xy 402.358334 -314.235774) (xy 402.311063 -314.249466)
			(xy 402.262208 -314.255398) (xy 402.213033 -314.253417) (xy 402.164814 -314.243573) (xy 402.118798 -314.226121)
			(xy 402.076177 -314.201514) (xy 402.038056 -314.170389) (xy 402.005421 -314.133552) (xy 401.979118 -314.091956)
			(xy 401.959827 -314.04668) (xy 401.94805 -313.998896) (xy 401.94409 -313.949842) (xy 400.655282 -313.949842)
			(xy 400.654787 -313.974449) (xy 400.646892 -314.023026) (xy 400.631308 -314.069707) (xy 400.608437 -314.113284)
			(xy 400.578872 -314.152628) (xy 400.543379 -314.18672) (xy 400.502876 -314.214676) (xy 400.458414 -314.235774)
			(xy 400.411143 -314.249466) (xy 400.362288 -314.255398) (xy 400.313113 -314.253417) (xy 400.264894 -314.243573)
			(xy 400.218878 -314.226121) (xy 400.176257 -314.201514) (xy 400.138136 -314.170389) (xy 400.105501 -314.133552)
			(xy 400.079198 -314.091956) (xy 400.059907 -314.04668) (xy 400.04813 -313.998896) (xy 400.04417 -313.949842)
			(xy 398.755108 -313.949842) (xy 398.754613 -313.974449) (xy 398.746718 -314.023026) (xy 398.731134 -314.069707)
			(xy 398.708263 -314.113284) (xy 398.678698 -314.152628) (xy 398.643205 -314.18672) (xy 398.602702 -314.214676)
			(xy 398.55824 -314.235774) (xy 398.510969 -314.249466) (xy 398.462114 -314.255398) (xy 398.412939 -314.253417)
			(xy 398.36472 -314.243573) (xy 398.318704 -314.226121) (xy 398.276083 -314.201514) (xy 398.237962 -314.170389)
			(xy 398.205327 -314.133552) (xy 398.179024 -314.091956) (xy 398.159733 -314.04668) (xy 398.147956 -313.998896)
			(xy 398.143996 -313.949842) (xy 396.855188 -313.949842) (xy 396.854693 -313.974449) (xy 396.846798 -314.023026)
			(xy 396.831214 -314.069707) (xy 396.808343 -314.113284) (xy 396.778778 -314.152628) (xy 396.743285 -314.18672)
			(xy 396.702782 -314.214676) (xy 396.65832 -314.235774) (xy 396.611049 -314.249466) (xy 396.562194 -314.255398)
			(xy 396.513019 -314.253417) (xy 396.4648 -314.243573) (xy 396.418784 -314.226121) (xy 396.376163 -314.201514)
			(xy 396.338042 -314.170389) (xy 396.305407 -314.133552) (xy 396.279104 -314.091956) (xy 396.259813 -314.04668)
			(xy 396.248036 -313.998896) (xy 396.244076 -313.949842) (xy 394.955268 -313.949842) (xy 394.954773 -313.974449)
			(xy 394.946878 -314.023026) (xy 394.931294 -314.069707) (xy 394.908423 -314.113284) (xy 394.878858 -314.152628)
			(xy 394.843365 -314.18672) (xy 394.802862 -314.214676) (xy 394.7584 -314.235774) (xy 394.711129 -314.249466)
			(xy 394.662274 -314.255398) (xy 394.613099 -314.253417) (xy 394.56488 -314.243573) (xy 394.518864 -314.226121)
			(xy 394.476243 -314.201514) (xy 394.438122 -314.170389) (xy 394.405487 -314.133552) (xy 394.379184 -314.091956)
			(xy 394.359893 -314.04668) (xy 394.348116 -313.998896) (xy 394.344156 -313.949842) (xy 393.055094 -313.949842)
			(xy 393.054599 -313.974449) (xy 393.046704 -314.023026) (xy 393.03112 -314.069707) (xy 393.008249 -314.113284)
			(xy 392.978684 -314.152628) (xy 392.943191 -314.18672) (xy 392.902688 -314.214676) (xy 392.858226 -314.235774)
			(xy 392.810955 -314.249466) (xy 392.7621 -314.255398) (xy 392.712925 -314.253417) (xy 392.664706 -314.243573)
			(xy 392.61869 -314.226121) (xy 392.576069 -314.201514) (xy 392.537948 -314.170389) (xy 392.505313 -314.133552)
			(xy 392.47901 -314.091956) (xy 392.459719 -314.04668) (xy 392.447942 -313.998896) (xy 392.443982 -313.949842)
			(xy 391.155174 -313.949842) (xy 391.154679 -313.974449) (xy 391.146784 -314.023026) (xy 391.1312 -314.069707)
			(xy 391.108329 -314.113284) (xy 391.078764 -314.152628) (xy 391.043271 -314.18672) (xy 391.002768 -314.214676)
			(xy 390.958306 -314.235774) (xy 390.911035 -314.249466) (xy 390.86218 -314.255398) (xy 390.813005 -314.253417)
			(xy 390.764786 -314.243573) (xy 390.71877 -314.226121) (xy 390.676149 -314.201514) (xy 390.638028 -314.170389)
			(xy 390.605393 -314.133552) (xy 390.57909 -314.091956) (xy 390.559799 -314.04668) (xy 390.548022 -313.998896)
			(xy 390.544062 -313.949842) (xy 389.255254 -313.949842) (xy 389.254759 -313.974449) (xy 389.246864 -314.023026)
			(xy 389.23128 -314.069707) (xy 389.208409 -314.113284) (xy 389.178844 -314.152628) (xy 389.143351 -314.18672)
			(xy 389.102848 -314.214676) (xy 389.058386 -314.235774) (xy 389.011115 -314.249466) (xy 388.96226 -314.255398)
			(xy 388.913085 -314.253417) (xy 388.864866 -314.243573) (xy 388.81885 -314.226121) (xy 388.776229 -314.201514)
			(xy 388.738108 -314.170389) (xy 388.705473 -314.133552) (xy 388.67917 -314.091956) (xy 388.659879 -314.04668)
			(xy 388.648102 -313.998896) (xy 388.644142 -313.949842) (xy 387.355334 -313.949842) (xy 387.354839 -313.974449)
			(xy 387.346944 -314.023026) (xy 387.33136 -314.069707) (xy 387.308489 -314.113284) (xy 387.278924 -314.152628)
			(xy 387.243431 -314.18672) (xy 387.202928 -314.214676) (xy 387.158466 -314.235774) (xy 387.111195 -314.249466)
			(xy 387.06234 -314.255398) (xy 387.013165 -314.253417) (xy 386.964946 -314.243573) (xy 386.91893 -314.226121)
			(xy 386.876309 -314.201514) (xy 386.838188 -314.170389) (xy 386.805553 -314.133552) (xy 386.77925 -314.091956)
			(xy 386.759959 -314.04668) (xy 386.748182 -313.998896) (xy 386.744222 -313.949842) (xy 313.055 -313.949842)
			(xy 313.054505 -313.974449) (xy 313.04661 -314.023026) (xy 313.031026 -314.069707) (xy 313.008155 -314.113284)
			(xy 312.97859 -314.152628) (xy 312.943097 -314.18672) (xy 312.902594 -314.214676) (xy 312.858132 -314.235774)
			(xy 312.810861 -314.249466) (xy 312.762006 -314.255398) (xy 312.712831 -314.253417) (xy 312.664612 -314.243573)
			(xy 312.618596 -314.226121) (xy 312.575975 -314.201514) (xy 312.537854 -314.170389) (xy 312.505219 -314.133552)
			(xy 312.478916 -314.091956) (xy 312.459625 -314.04668) (xy 312.447848 -313.998896) (xy 312.443888 -313.949842)
			(xy 311.15508 -313.949842) (xy 311.154585 -313.974449) (xy 311.14669 -314.023026) (xy 311.131106 -314.069707)
			(xy 311.108235 -314.113284) (xy 311.07867 -314.152628) (xy 311.043177 -314.18672) (xy 311.002674 -314.214676)
			(xy 310.958212 -314.235774) (xy 310.910941 -314.249466) (xy 310.862086 -314.255398) (xy 310.812911 -314.253417)
			(xy 310.764692 -314.243573) (xy 310.718676 -314.226121) (xy 310.676055 -314.201514) (xy 310.637934 -314.170389)
			(xy 310.605299 -314.133552) (xy 310.578996 -314.091956) (xy 310.559705 -314.04668) (xy 310.547928 -313.998896)
			(xy 310.543968 -313.949842) (xy 309.25516 -313.949842) (xy 309.254665 -313.974449) (xy 309.24677 -314.023026)
			(xy 309.231186 -314.069707) (xy 309.208315 -314.113284) (xy 309.17875 -314.152628) (xy 309.143257 -314.18672)
			(xy 309.102754 -314.214676) (xy 309.058292 -314.235774) (xy 309.011021 -314.249466) (xy 308.962166 -314.255398)
			(xy 308.912991 -314.253417) (xy 308.864772 -314.243573) (xy 308.818756 -314.226121) (xy 308.776135 -314.201514)
			(xy 308.738014 -314.170389) (xy 308.705379 -314.133552) (xy 308.679076 -314.091956) (xy 308.659785 -314.04668)
			(xy 308.648008 -313.998896) (xy 308.644048 -313.949842) (xy 307.35524 -313.949842) (xy 307.354745 -313.974449)
			(xy 307.34685 -314.023026) (xy 307.331266 -314.069707) (xy 307.308395 -314.113284) (xy 307.27883 -314.152628)
			(xy 307.243337 -314.18672) (xy 307.202834 -314.214676) (xy 307.158372 -314.235774) (xy 307.111101 -314.249466)
			(xy 307.062246 -314.255398) (xy 307.013071 -314.253417) (xy 306.964852 -314.243573) (xy 306.918836 -314.226121)
			(xy 306.876215 -314.201514) (xy 306.838094 -314.170389) (xy 306.805459 -314.133552) (xy 306.779156 -314.091956)
			(xy 306.759865 -314.04668) (xy 306.748088 -313.998896) (xy 306.744128 -313.949842) (xy 305.455066 -313.949842)
			(xy 305.454571 -313.974449) (xy 305.446676 -314.023026) (xy 305.431092 -314.069707) (xy 305.408221 -314.113284)
			(xy 305.378656 -314.152628) (xy 305.343163 -314.18672) (xy 305.30266 -314.214676) (xy 305.258198 -314.235774)
			(xy 305.210927 -314.249466) (xy 305.162072 -314.255398) (xy 305.112897 -314.253417) (xy 305.064678 -314.243573)
			(xy 305.018662 -314.226121) (xy 304.976041 -314.201514) (xy 304.93792 -314.170389) (xy 304.905285 -314.133552)
			(xy 304.878982 -314.091956) (xy 304.859691 -314.04668) (xy 304.847914 -313.998896) (xy 304.843954 -313.949842)
			(xy 303.555146 -313.949842) (xy 303.554651 -313.974449) (xy 303.546756 -314.023026) (xy 303.531172 -314.069707)
			(xy 303.508301 -314.113284) (xy 303.478736 -314.152628) (xy 303.443243 -314.18672) (xy 303.40274 -314.214676)
			(xy 303.358278 -314.235774) (xy 303.311007 -314.249466) (xy 303.262152 -314.255398) (xy 303.212977 -314.253417)
			(xy 303.164758 -314.243573) (xy 303.118742 -314.226121) (xy 303.076121 -314.201514) (xy 303.038 -314.170389)
			(xy 303.005365 -314.133552) (xy 302.979062 -314.091956) (xy 302.959771 -314.04668) (xy 302.947994 -313.998896)
			(xy 302.944034 -313.949842) (xy 301.655226 -313.949842) (xy 301.654731 -313.974449) (xy 301.646836 -314.023026)
			(xy 301.631252 -314.069707) (xy 301.608381 -314.113284) (xy 301.578816 -314.152628) (xy 301.543323 -314.18672)
			(xy 301.50282 -314.214676) (xy 301.458358 -314.235774) (xy 301.411087 -314.249466) (xy 301.362232 -314.255398)
			(xy 301.313057 -314.253417) (xy 301.264838 -314.243573) (xy 301.218822 -314.226121) (xy 301.176201 -314.201514)
			(xy 301.13808 -314.170389) (xy 301.105445 -314.133552) (xy 301.079142 -314.091956) (xy 301.059851 -314.04668)
			(xy 301.048074 -313.998896) (xy 301.044114 -313.949842) (xy 299.755052 -313.949842) (xy 299.754557 -313.974449)
			(xy 299.746662 -314.023026) (xy 299.731078 -314.069707) (xy 299.708207 -314.113284) (xy 299.678642 -314.152628)
			(xy 299.643149 -314.18672) (xy 299.602646 -314.214676) (xy 299.558184 -314.235774) (xy 299.510913 -314.249466)
			(xy 299.462058 -314.255398) (xy 299.412883 -314.253417) (xy 299.364664 -314.243573) (xy 299.318648 -314.226121)
			(xy 299.276027 -314.201514) (xy 299.237906 -314.170389) (xy 299.205271 -314.133552) (xy 299.178968 -314.091956)
			(xy 299.159677 -314.04668) (xy 299.1479 -313.998896) (xy 299.14394 -313.949842) (xy 297.855132 -313.949842)
			(xy 297.854637 -313.974449) (xy 297.846742 -314.023026) (xy 297.831158 -314.069707) (xy 297.808287 -314.113284)
			(xy 297.778722 -314.152628) (xy 297.743229 -314.18672) (xy 297.702726 -314.214676) (xy 297.658264 -314.235774)
			(xy 297.610993 -314.249466) (xy 297.562138 -314.255398) (xy 297.512963 -314.253417) (xy 297.464744 -314.243573)
			(xy 297.418728 -314.226121) (xy 297.376107 -314.201514) (xy 297.337986 -314.170389) (xy 297.305351 -314.133552)
			(xy 297.279048 -314.091956) (xy 297.259757 -314.04668) (xy 297.24798 -313.998896) (xy 297.24402 -313.949842)
			(xy 295.955212 -313.949842) (xy 295.954717 -313.974449) (xy 295.946822 -314.023026) (xy 295.931238 -314.069707)
			(xy 295.908367 -314.113284) (xy 295.878802 -314.152628) (xy 295.843309 -314.18672) (xy 295.802806 -314.214676)
			(xy 295.758344 -314.235774) (xy 295.711073 -314.249466) (xy 295.662218 -314.255398) (xy 295.613043 -314.253417)
			(xy 295.564824 -314.243573) (xy 295.518808 -314.226121) (xy 295.476187 -314.201514) (xy 295.438066 -314.170389)
			(xy 295.405431 -314.133552) (xy 295.379128 -314.091956) (xy 295.359837 -314.04668) (xy 295.34806 -313.998896)
			(xy 295.3441 -313.949842) (xy 294.055038 -313.949842) (xy 294.054543 -313.974449) (xy 294.046648 -314.023026)
			(xy 294.031064 -314.069707) (xy 294.008193 -314.113284) (xy 293.978628 -314.152628) (xy 293.943135 -314.18672)
			(xy 293.902632 -314.214676) (xy 293.85817 -314.235774) (xy 293.810899 -314.249466) (xy 293.762044 -314.255398)
			(xy 293.712869 -314.253417) (xy 293.66465 -314.243573) (xy 293.618634 -314.226121) (xy 293.576013 -314.201514)
			(xy 293.537892 -314.170389) (xy 293.505257 -314.133552) (xy 293.478954 -314.091956) (xy 293.459663 -314.04668)
			(xy 293.447886 -313.998896) (xy 293.443926 -313.949842) (xy 292.155118 -313.949842) (xy 292.154623 -313.974449)
			(xy 292.146728 -314.023026) (xy 292.131144 -314.069707) (xy 292.108273 -314.113284) (xy 292.078708 -314.152628)
			(xy 292.043215 -314.18672) (xy 292.002712 -314.214676) (xy 291.95825 -314.235774) (xy 291.910979 -314.249466)
			(xy 291.862124 -314.255398) (xy 291.812949 -314.253417) (xy 291.76473 -314.243573) (xy 291.718714 -314.226121)
			(xy 291.676093 -314.201514) (xy 291.637972 -314.170389) (xy 291.605337 -314.133552) (xy 291.579034 -314.091956)
			(xy 291.559743 -314.04668) (xy 291.547966 -313.998896) (xy 291.544006 -313.949842) (xy 290.255198 -313.949842)
			(xy 290.254703 -313.974449) (xy 290.246808 -314.023026) (xy 290.231224 -314.069707) (xy 290.208353 -314.113284)
			(xy 290.178788 -314.152628) (xy 290.143295 -314.18672) (xy 290.102792 -314.214676) (xy 290.05833 -314.235774)
			(xy 290.011059 -314.249466) (xy 289.962204 -314.255398) (xy 289.913029 -314.253417) (xy 289.86481 -314.243573)
			(xy 289.818794 -314.226121) (xy 289.776173 -314.201514) (xy 289.738052 -314.170389) (xy 289.705417 -314.133552)
			(xy 289.679114 -314.091956) (xy 289.659823 -314.04668) (xy 289.648046 -313.998896) (xy 289.644086 -313.949842)
			(xy 288.355024 -313.949842) (xy 288.354529 -313.974449) (xy 288.346634 -314.023026) (xy 288.33105 -314.069707)
			(xy 288.308179 -314.113284) (xy 288.278614 -314.152628) (xy 288.243121 -314.18672) (xy 288.202618 -314.214676)
			(xy 288.158156 -314.235774) (xy 288.110885 -314.249466) (xy 288.06203 -314.255398) (xy 288.012855 -314.253417)
			(xy 287.964636 -314.243573) (xy 287.91862 -314.226121) (xy 287.875999 -314.201514) (xy 287.837878 -314.170389)
			(xy 287.805243 -314.133552) (xy 287.77894 -314.091956) (xy 287.759649 -314.04668) (xy 287.747872 -313.998896)
			(xy 287.743912 -313.949842) (xy 286.455104 -313.949842) (xy 286.454609 -313.974449) (xy 286.446714 -314.023026)
			(xy 286.43113 -314.069707) (xy 286.408259 -314.113284) (xy 286.378694 -314.152628) (xy 286.343201 -314.18672)
			(xy 286.302698 -314.214676) (xy 286.258236 -314.235774) (xy 286.210965 -314.249466) (xy 286.16211 -314.255398)
			(xy 286.112935 -314.253417) (xy 286.064716 -314.243573) (xy 286.0187 -314.226121) (xy 285.976079 -314.201514)
			(xy 285.937958 -314.170389) (xy 285.905323 -314.133552) (xy 285.87902 -314.091956) (xy 285.859729 -314.04668)
			(xy 285.847952 -313.998896) (xy 285.843992 -313.949842) (xy 284.555184 -313.949842) (xy 284.554689 -313.974449)
			(xy 284.546794 -314.023026) (xy 284.53121 -314.069707) (xy 284.508339 -314.113284) (xy 284.478774 -314.152628)
			(xy 284.443281 -314.18672) (xy 284.402778 -314.214676) (xy 284.358316 -314.235774) (xy 284.311045 -314.249466)
			(xy 284.26219 -314.255398) (xy 284.213015 -314.253417) (xy 284.164796 -314.243573) (xy 284.11878 -314.226121)
			(xy 284.076159 -314.201514) (xy 284.038038 -314.170389) (xy 284.005403 -314.133552) (xy 283.9791 -314.091956)
			(xy 283.959809 -314.04668) (xy 283.948032 -313.998896) (xy 283.944072 -313.949842) (xy 282.65501 -313.949842)
			(xy 282.654515 -313.974449) (xy 282.64662 -314.023026) (xy 282.631036 -314.069707) (xy 282.608165 -314.113284)
			(xy 282.5786 -314.152628) (xy 282.543107 -314.18672) (xy 282.502604 -314.214676) (xy 282.458142 -314.235774)
			(xy 282.410871 -314.249466) (xy 282.362016 -314.255398) (xy 282.312841 -314.253417) (xy 282.264622 -314.243573)
			(xy 282.218606 -314.226121) (xy 282.175985 -314.201514) (xy 282.137864 -314.170389) (xy 282.105229 -314.133552)
			(xy 282.078926 -314.091956) (xy 282.059635 -314.04668) (xy 282.047858 -313.998896) (xy 282.043898 -313.949842)
			(xy 280.75509 -313.949842) (xy 280.754595 -313.974449) (xy 280.7467 -314.023026) (xy 280.731116 -314.069707)
			(xy 280.708245 -314.113284) (xy 280.67868 -314.152628) (xy 280.643187 -314.18672) (xy 280.602684 -314.214676)
			(xy 280.558222 -314.235774) (xy 280.510951 -314.249466) (xy 280.462096 -314.255398) (xy 280.412921 -314.253417)
			(xy 280.364702 -314.243573) (xy 280.318686 -314.226121) (xy 280.276065 -314.201514) (xy 280.237944 -314.170389)
			(xy 280.205309 -314.133552) (xy 280.179006 -314.091956) (xy 280.159715 -314.04668) (xy 280.147938 -313.998896)
			(xy 280.143978 -313.949842) (xy 278.85517 -313.949842) (xy 278.854675 -313.974449) (xy 278.84678 -314.023026)
			(xy 278.831196 -314.069707) (xy 278.808325 -314.113284) (xy 278.77876 -314.152628) (xy 278.743267 -314.18672)
			(xy 278.702764 -314.214676) (xy 278.658302 -314.235774) (xy 278.611031 -314.249466) (xy 278.562176 -314.255398)
			(xy 278.513001 -314.253417) (xy 278.464782 -314.243573) (xy 278.418766 -314.226121) (xy 278.376145 -314.201514)
			(xy 278.338024 -314.170389) (xy 278.305389 -314.133552) (xy 278.279086 -314.091956) (xy 278.259795 -314.04668)
			(xy 278.248018 -313.998896) (xy 278.244058 -313.949842) (xy 276.954996 -313.949842) (xy 276.954501 -313.974449)
			(xy 276.946606 -314.023026) (xy 276.931022 -314.069707) (xy 276.908151 -314.113284) (xy 276.878586 -314.152628)
			(xy 276.843093 -314.18672) (xy 276.80259 -314.214676) (xy 276.758128 -314.235774) (xy 276.710857 -314.249466)
			(xy 276.662002 -314.255398) (xy 276.612827 -314.253417) (xy 276.564608 -314.243573) (xy 276.518592 -314.226121)
			(xy 276.475971 -314.201514) (xy 276.43785 -314.170389) (xy 276.405215 -314.133552) (xy 276.378912 -314.091956)
			(xy 276.359621 -314.04668) (xy 276.347844 -313.998896) (xy 276.343884 -313.949842) (xy 275.055076 -313.949842)
			(xy 275.054581 -313.974449) (xy 275.046686 -314.023026) (xy 275.031102 -314.069707) (xy 275.008231 -314.113284)
			(xy 274.978666 -314.152628) (xy 274.943173 -314.18672) (xy 274.90267 -314.214676) (xy 274.858208 -314.235774)
			(xy 274.810937 -314.249466) (xy 274.762082 -314.255398) (xy 274.712907 -314.253417) (xy 274.664688 -314.243573)
			(xy 274.618672 -314.226121) (xy 274.576051 -314.201514) (xy 274.53793 -314.170389) (xy 274.505295 -314.133552)
			(xy 274.478992 -314.091956) (xy 274.459701 -314.04668) (xy 274.447924 -313.998896) (xy 274.443964 -313.949842)
			(xy 273.155156 -313.949842) (xy 273.154661 -313.974449) (xy 273.146766 -314.023026) (xy 273.131182 -314.069707)
			(xy 273.108311 -314.113284) (xy 273.078746 -314.152628) (xy 273.043253 -314.18672) (xy 273.00275 -314.214676)
			(xy 272.958288 -314.235774) (xy 272.911017 -314.249466) (xy 272.862162 -314.255398) (xy 272.812987 -314.253417)
			(xy 272.764768 -314.243573) (xy 272.718752 -314.226121) (xy 272.676131 -314.201514) (xy 272.63801 -314.170389)
			(xy 272.605375 -314.133552) (xy 272.579072 -314.091956) (xy 272.559781 -314.04668) (xy 272.548004 -313.998896)
			(xy 272.544044 -313.949842) (xy 271.255236 -313.949842) (xy 271.254741 -313.974449) (xy 271.246846 -314.023026)
			(xy 271.231262 -314.069707) (xy 271.208391 -314.113284) (xy 271.178826 -314.152628) (xy 271.143333 -314.18672)
			(xy 271.10283 -314.214676) (xy 271.058368 -314.235774) (xy 271.011097 -314.249466) (xy 270.962242 -314.255398)
			(xy 270.913067 -314.253417) (xy 270.864848 -314.243573) (xy 270.818832 -314.226121) (xy 270.776211 -314.201514)
			(xy 270.73809 -314.170389) (xy 270.705455 -314.133552) (xy 270.679152 -314.091956) (xy 270.659861 -314.04668)
			(xy 270.648084 -313.998896) (xy 270.644124 -313.949842) (xy 196.955156 -313.949842) (xy 196.954661 -313.974449)
			(xy 196.946766 -314.023026) (xy 196.931182 -314.069707) (xy 196.908311 -314.113284) (xy 196.878746 -314.152628)
			(xy 196.843253 -314.18672) (xy 196.80275 -314.214676) (xy 196.758288 -314.235774) (xy 196.711017 -314.249466)
			(xy 196.662162 -314.255398) (xy 196.612987 -314.253417) (xy 196.564768 -314.243573) (xy 196.518752 -314.226121)
			(xy 196.476131 -314.201514) (xy 196.43801 -314.170389) (xy 196.405375 -314.133552) (xy 196.379072 -314.091956)
			(xy 196.359781 -314.04668) (xy 196.348004 -313.998896) (xy 196.344044 -313.949842) (xy 195.055236 -313.949842)
			(xy 195.054741 -313.974449) (xy 195.046846 -314.023026) (xy 195.031262 -314.069707) (xy 195.008391 -314.113284)
			(xy 194.978826 -314.152628) (xy 194.943333 -314.18672) (xy 194.90283 -314.214676) (xy 194.858368 -314.235774)
			(xy 194.811097 -314.249466) (xy 194.762242 -314.255398) (xy 194.713067 -314.253417) (xy 194.664848 -314.243573)
			(xy 194.618832 -314.226121) (xy 194.576211 -314.201514) (xy 194.53809 -314.170389) (xy 194.505455 -314.133552)
			(xy 194.479152 -314.091956) (xy 194.459861 -314.04668) (xy 194.448084 -313.998896) (xy 194.444124 -313.949842)
			(xy 193.155316 -313.949842) (xy 193.154821 -313.974449) (xy 193.146926 -314.023026) (xy 193.131342 -314.069707)
			(xy 193.108471 -314.113284) (xy 193.078906 -314.152628) (xy 193.043413 -314.18672) (xy 193.00291 -314.214676)
			(xy 192.958448 -314.235774) (xy 192.911177 -314.249466) (xy 192.862322 -314.255398) (xy 192.813147 -314.253417)
			(xy 192.764928 -314.243573) (xy 192.718912 -314.226121) (xy 192.676291 -314.201514) (xy 192.63817 -314.170389)
			(xy 192.605535 -314.133552) (xy 192.579232 -314.091956) (xy 192.559941 -314.04668) (xy 192.548164 -313.998896)
			(xy 192.544204 -313.949842) (xy 191.255396 -313.949842) (xy 191.254901 -313.974449) (xy 191.247006 -314.023026)
			(xy 191.231422 -314.069707) (xy 191.208551 -314.113284) (xy 191.178986 -314.152628) (xy 191.143493 -314.18672)
			(xy 191.10299 -314.214676) (xy 191.058528 -314.235774) (xy 191.011257 -314.249466) (xy 190.962402 -314.255398)
			(xy 190.913227 -314.253417) (xy 190.865008 -314.243573) (xy 190.818992 -314.226121) (xy 190.776371 -314.201514)
			(xy 190.73825 -314.170389) (xy 190.705615 -314.133552) (xy 190.679312 -314.091956) (xy 190.660021 -314.04668)
			(xy 190.648244 -313.998896) (xy 190.644284 -313.949842) (xy 189.355222 -313.949842) (xy 189.354727 -313.974449)
			(xy 189.346832 -314.023026) (xy 189.331248 -314.069707) (xy 189.308377 -314.113284) (xy 189.278812 -314.152628)
			(xy 189.243319 -314.18672) (xy 189.202816 -314.214676) (xy 189.158354 -314.235774) (xy 189.111083 -314.249466)
			(xy 189.062228 -314.255398) (xy 189.013053 -314.253417) (xy 188.964834 -314.243573) (xy 188.918818 -314.226121)
			(xy 188.876197 -314.201514) (xy 188.838076 -314.170389) (xy 188.805441 -314.133552) (xy 188.779138 -314.091956)
			(xy 188.759847 -314.04668) (xy 188.74807 -313.998896) (xy 188.74411 -313.949842) (xy 187.455302 -313.949842)
			(xy 187.454807 -313.974449) (xy 187.446912 -314.023026) (xy 187.431328 -314.069707) (xy 187.408457 -314.113284)
			(xy 187.378892 -314.152628) (xy 187.343399 -314.18672) (xy 187.302896 -314.214676) (xy 187.258434 -314.235774)
			(xy 187.211163 -314.249466) (xy 187.162308 -314.255398) (xy 187.113133 -314.253417) (xy 187.064914 -314.243573)
			(xy 187.018898 -314.226121) (xy 186.976277 -314.201514) (xy 186.938156 -314.170389) (xy 186.905521 -314.133552)
			(xy 186.879218 -314.091956) (xy 186.859927 -314.04668) (xy 186.84815 -313.998896) (xy 186.84419 -313.949842)
			(xy 185.555382 -313.949842) (xy 185.554887 -313.974449) (xy 185.546992 -314.023026) (xy 185.531408 -314.069707)
			(xy 185.508537 -314.113284) (xy 185.478972 -314.152628) (xy 185.443479 -314.18672) (xy 185.402976 -314.214676)
			(xy 185.358514 -314.235774) (xy 185.311243 -314.249466) (xy 185.262388 -314.255398) (xy 185.213213 -314.253417)
			(xy 185.164994 -314.243573) (xy 185.118978 -314.226121) (xy 185.076357 -314.201514) (xy 185.038236 -314.170389)
			(xy 185.005601 -314.133552) (xy 184.979298 -314.091956) (xy 184.960007 -314.04668) (xy 184.94823 -313.998896)
			(xy 184.94427 -313.949842) (xy 183.655208 -313.949842) (xy 183.654713 -313.974449) (xy 183.646818 -314.023026)
			(xy 183.631234 -314.069707) (xy 183.608363 -314.113284) (xy 183.578798 -314.152628) (xy 183.543305 -314.18672)
			(xy 183.502802 -314.214676) (xy 183.45834 -314.235774) (xy 183.411069 -314.249466) (xy 183.362214 -314.255398)
			(xy 183.313039 -314.253417) (xy 183.26482 -314.243573) (xy 183.218804 -314.226121) (xy 183.176183 -314.201514)
			(xy 183.138062 -314.170389) (xy 183.105427 -314.133552) (xy 183.079124 -314.091956) (xy 183.059833 -314.04668)
			(xy 183.048056 -313.998896) (xy 183.044096 -313.949842) (xy 181.755288 -313.949842) (xy 181.754793 -313.974449)
			(xy 181.746898 -314.023026) (xy 181.731314 -314.069707) (xy 181.708443 -314.113284) (xy 181.678878 -314.152628)
			(xy 181.643385 -314.18672) (xy 181.602882 -314.214676) (xy 181.55842 -314.235774) (xy 181.511149 -314.249466)
			(xy 181.462294 -314.255398) (xy 181.413119 -314.253417) (xy 181.3649 -314.243573) (xy 181.318884 -314.226121)
			(xy 181.276263 -314.201514) (xy 181.238142 -314.170389) (xy 181.205507 -314.133552) (xy 181.179204 -314.091956)
			(xy 181.159913 -314.04668) (xy 181.148136 -313.998896) (xy 181.144176 -313.949842) (xy 179.855368 -313.949842)
			(xy 179.854873 -313.974449) (xy 179.846978 -314.023026) (xy 179.831394 -314.069707) (xy 179.808523 -314.113284)
			(xy 179.778958 -314.152628) (xy 179.743465 -314.18672) (xy 179.702962 -314.214676) (xy 179.6585 -314.235774)
			(xy 179.611229 -314.249466) (xy 179.562374 -314.255398) (xy 179.513199 -314.253417) (xy 179.46498 -314.243573)
			(xy 179.418964 -314.226121) (xy 179.376343 -314.201514) (xy 179.338222 -314.170389) (xy 179.305587 -314.133552)
			(xy 179.279284 -314.091956) (xy 179.259993 -314.04668) (xy 179.248216 -313.998896) (xy 179.244256 -313.949842)
			(xy 177.955194 -313.949842) (xy 177.954699 -313.974449) (xy 177.946804 -314.023026) (xy 177.93122 -314.069707)
			(xy 177.908349 -314.113284) (xy 177.878784 -314.152628) (xy 177.843291 -314.18672) (xy 177.802788 -314.214676)
			(xy 177.758326 -314.235774) (xy 177.711055 -314.249466) (xy 177.6622 -314.255398) (xy 177.613025 -314.253417)
			(xy 177.564806 -314.243573) (xy 177.51879 -314.226121) (xy 177.476169 -314.201514) (xy 177.438048 -314.170389)
			(xy 177.405413 -314.133552) (xy 177.37911 -314.091956) (xy 177.359819 -314.04668) (xy 177.348042 -313.998896)
			(xy 177.344082 -313.949842) (xy 176.055274 -313.949842) (xy 176.054779 -313.974449) (xy 176.046884 -314.023026)
			(xy 176.0313 -314.069707) (xy 176.008429 -314.113284) (xy 175.978864 -314.152628) (xy 175.943371 -314.18672)
			(xy 175.902868 -314.214676) (xy 175.858406 -314.235774) (xy 175.811135 -314.249466) (xy 175.76228 -314.255398)
			(xy 175.713105 -314.253417) (xy 175.664886 -314.243573) (xy 175.61887 -314.226121) (xy 175.576249 -314.201514)
			(xy 175.538128 -314.170389) (xy 175.505493 -314.133552) (xy 175.47919 -314.091956) (xy 175.459899 -314.04668)
			(xy 175.448122 -313.998896) (xy 175.444162 -313.949842) (xy 174.155354 -313.949842) (xy 174.154859 -313.974449)
			(xy 174.146964 -314.023026) (xy 174.13138 -314.069707) (xy 174.108509 -314.113284) (xy 174.078944 -314.152628)
			(xy 174.043451 -314.18672) (xy 174.002948 -314.214676) (xy 173.958486 -314.235774) (xy 173.911215 -314.249466)
			(xy 173.86236 -314.255398) (xy 173.813185 -314.253417) (xy 173.764966 -314.243573) (xy 173.71895 -314.226121)
			(xy 173.676329 -314.201514) (xy 173.638208 -314.170389) (xy 173.605573 -314.133552) (xy 173.57927 -314.091956)
			(xy 173.559979 -314.04668) (xy 173.548202 -313.998896) (xy 173.544242 -313.949842) (xy 172.25518 -313.949842)
			(xy 172.254685 -313.974449) (xy 172.24679 -314.023026) (xy 172.231206 -314.069707) (xy 172.208335 -314.113284)
			(xy 172.17877 -314.152628) (xy 172.143277 -314.18672) (xy 172.102774 -314.214676) (xy 172.058312 -314.235774)
			(xy 172.011041 -314.249466) (xy 171.962186 -314.255398) (xy 171.913011 -314.253417) (xy 171.864792 -314.243573)
			(xy 171.818776 -314.226121) (xy 171.776155 -314.201514) (xy 171.738034 -314.170389) (xy 171.705399 -314.133552)
			(xy 171.679096 -314.091956) (xy 171.659805 -314.04668) (xy 171.648028 -313.998896) (xy 171.644068 -313.949842)
			(xy 170.35526 -313.949842) (xy 170.354765 -313.974449) (xy 170.34687 -314.023026) (xy 170.331286 -314.069707)
			(xy 170.308415 -314.113284) (xy 170.27885 -314.152628) (xy 170.243357 -314.18672) (xy 170.202854 -314.214676)
			(xy 170.158392 -314.235774) (xy 170.111121 -314.249466) (xy 170.062266 -314.255398) (xy 170.013091 -314.253417)
			(xy 169.964872 -314.243573) (xy 169.918856 -314.226121) (xy 169.876235 -314.201514) (xy 169.838114 -314.170389)
			(xy 169.805479 -314.133552) (xy 169.779176 -314.091956) (xy 169.759885 -314.04668) (xy 169.748108 -313.998896)
			(xy 169.744148 -313.949842) (xy 168.45534 -313.949842) (xy 168.454845 -313.974449) (xy 168.44695 -314.023026)
			(xy 168.431366 -314.069707) (xy 168.408495 -314.113284) (xy 168.37893 -314.152628) (xy 168.343437 -314.18672)
			(xy 168.302934 -314.214676) (xy 168.258472 -314.235774) (xy 168.211201 -314.249466) (xy 168.162346 -314.255398)
			(xy 168.113171 -314.253417) (xy 168.064952 -314.243573) (xy 168.018936 -314.226121) (xy 167.976315 -314.201514)
			(xy 167.938194 -314.170389) (xy 167.905559 -314.133552) (xy 167.879256 -314.091956) (xy 167.859965 -314.04668)
			(xy 167.848188 -313.998896) (xy 167.844228 -313.949842) (xy 166.555166 -313.949842) (xy 166.554671 -313.974449)
			(xy 166.546776 -314.023026) (xy 166.531192 -314.069707) (xy 166.508321 -314.113284) (xy 166.478756 -314.152628)
			(xy 166.443263 -314.18672) (xy 166.40276 -314.214676) (xy 166.358298 -314.235774) (xy 166.311027 -314.249466)
			(xy 166.262172 -314.255398) (xy 166.212997 -314.253417) (xy 166.164778 -314.243573) (xy 166.118762 -314.226121)
			(xy 166.076141 -314.201514) (xy 166.03802 -314.170389) (xy 166.005385 -314.133552) (xy 165.979082 -314.091956)
			(xy 165.959791 -314.04668) (xy 165.948014 -313.998896) (xy 165.944054 -313.949842) (xy 164.655246 -313.949842)
			(xy 164.654751 -313.974449) (xy 164.646856 -314.023026) (xy 164.631272 -314.069707) (xy 164.608401 -314.113284)
			(xy 164.578836 -314.152628) (xy 164.543343 -314.18672) (xy 164.50284 -314.214676) (xy 164.458378 -314.235774)
			(xy 164.411107 -314.249466) (xy 164.362252 -314.255398) (xy 164.313077 -314.253417) (xy 164.264858 -314.243573)
			(xy 164.218842 -314.226121) (xy 164.176221 -314.201514) (xy 164.1381 -314.170389) (xy 164.105465 -314.133552)
			(xy 164.079162 -314.091956) (xy 164.059871 -314.04668) (xy 164.048094 -313.998896) (xy 164.044134 -313.949842)
			(xy 162.755326 -313.949842) (xy 162.754831 -313.974449) (xy 162.746936 -314.023026) (xy 162.731352 -314.069707)
			(xy 162.708481 -314.113284) (xy 162.678916 -314.152628) (xy 162.643423 -314.18672) (xy 162.60292 -314.214676)
			(xy 162.558458 -314.235774) (xy 162.511187 -314.249466) (xy 162.462332 -314.255398) (xy 162.413157 -314.253417)
			(xy 162.364938 -314.243573) (xy 162.318922 -314.226121) (xy 162.276301 -314.201514) (xy 162.23818 -314.170389)
			(xy 162.205545 -314.133552) (xy 162.179242 -314.091956) (xy 162.159951 -314.04668) (xy 162.148174 -313.998896)
			(xy 162.144214 -313.949842) (xy 160.855152 -313.949842) (xy 160.854657 -313.974449) (xy 160.846762 -314.023026)
			(xy 160.831178 -314.069707) (xy 160.808307 -314.113284) (xy 160.778742 -314.152628) (xy 160.743249 -314.18672)
			(xy 160.702746 -314.214676) (xy 160.658284 -314.235774) (xy 160.611013 -314.249466) (xy 160.562158 -314.255398)
			(xy 160.512983 -314.253417) (xy 160.464764 -314.243573) (xy 160.418748 -314.226121) (xy 160.376127 -314.201514)
			(xy 160.338006 -314.170389) (xy 160.305371 -314.133552) (xy 160.279068 -314.091956) (xy 160.259777 -314.04668)
			(xy 160.248 -313.998896) (xy 160.24404 -313.949842) (xy 158.955232 -313.949842) (xy 158.954737 -313.974449)
			(xy 158.946842 -314.023026) (xy 158.931258 -314.069707) (xy 158.908387 -314.113284) (xy 158.878822 -314.152628)
			(xy 158.843329 -314.18672) (xy 158.802826 -314.214676) (xy 158.758364 -314.235774) (xy 158.711093 -314.249466)
			(xy 158.662238 -314.255398) (xy 158.613063 -314.253417) (xy 158.564844 -314.243573) (xy 158.518828 -314.226121)
			(xy 158.476207 -314.201514) (xy 158.438086 -314.170389) (xy 158.405451 -314.133552) (xy 158.379148 -314.091956)
			(xy 158.359857 -314.04668) (xy 158.34808 -313.998896) (xy 158.34412 -313.949842) (xy 157.055312 -313.949842)
			(xy 157.054817 -313.974449) (xy 157.046922 -314.023026) (xy 157.031338 -314.069707) (xy 157.008467 -314.113284)
			(xy 156.978902 -314.152628) (xy 156.943409 -314.18672) (xy 156.902906 -314.214676) (xy 156.858444 -314.235774)
			(xy 156.811173 -314.249466) (xy 156.762318 -314.255398) (xy 156.713143 -314.253417) (xy 156.664924 -314.243573)
			(xy 156.618908 -314.226121) (xy 156.576287 -314.201514) (xy 156.538166 -314.170389) (xy 156.505531 -314.133552)
			(xy 156.479228 -314.091956) (xy 156.459937 -314.04668) (xy 156.44816 -313.998896) (xy 156.4442 -313.949842)
			(xy 155.155392 -313.949842) (xy 155.154897 -313.974449) (xy 155.147002 -314.023026) (xy 155.131418 -314.069707)
			(xy 155.108547 -314.113284) (xy 155.078982 -314.152628) (xy 155.043489 -314.18672) (xy 155.002986 -314.214676)
			(xy 154.958524 -314.235774) (xy 154.911253 -314.249466) (xy 154.862398 -314.255398) (xy 154.813223 -314.253417)
			(xy 154.765004 -314.243573) (xy 154.718988 -314.226121) (xy 154.676367 -314.201514) (xy 154.638246 -314.170389)
			(xy 154.605611 -314.133552) (xy 154.579308 -314.091956) (xy 154.560017 -314.04668) (xy 154.54824 -313.998896)
			(xy 154.54428 -313.949842) (xy 80.855058 -313.949842) (xy 80.854563 -313.974449) (xy 80.846668 -314.023026)
			(xy 80.831084 -314.069707) (xy 80.808213 -314.113284) (xy 80.778648 -314.152628) (xy 80.743155 -314.18672)
			(xy 80.702652 -314.214676) (xy 80.65819 -314.235774) (xy 80.610919 -314.249466) (xy 80.562064 -314.255398)
			(xy 80.512889 -314.253417) (xy 80.46467 -314.243573) (xy 80.418654 -314.226121) (xy 80.376033 -314.201514)
			(xy 80.337912 -314.170389) (xy 80.305277 -314.133552) (xy 80.278974 -314.091956) (xy 80.259683 -314.04668)
			(xy 80.247906 -313.998896) (xy 80.243946 -313.949842) (xy 78.955138 -313.949842) (xy 78.954643 -313.974449)
			(xy 78.946748 -314.023026) (xy 78.931164 -314.069707) (xy 78.908293 -314.113284) (xy 78.878728 -314.152628)
			(xy 78.843235 -314.18672) (xy 78.802732 -314.214676) (xy 78.75827 -314.235774) (xy 78.710999 -314.249466)
			(xy 78.662144 -314.255398) (xy 78.612969 -314.253417) (xy 78.56475 -314.243573) (xy 78.518734 -314.226121)
			(xy 78.476113 -314.201514) (xy 78.437992 -314.170389) (xy 78.405357 -314.133552) (xy 78.379054 -314.091956)
			(xy 78.359763 -314.04668) (xy 78.347986 -313.998896) (xy 78.344026 -313.949842) (xy 77.055218 -313.949842)
			(xy 77.054723 -313.974449) (xy 77.046828 -314.023026) (xy 77.031244 -314.069707) (xy 77.008373 -314.113284)
			(xy 76.978808 -314.152628) (xy 76.943315 -314.18672) (xy 76.902812 -314.214676) (xy 76.85835 -314.235774)
			(xy 76.811079 -314.249466) (xy 76.762224 -314.255398) (xy 76.713049 -314.253417) (xy 76.66483 -314.243573)
			(xy 76.618814 -314.226121) (xy 76.576193 -314.201514) (xy 76.538072 -314.170389) (xy 76.505437 -314.133552)
			(xy 76.479134 -314.091956) (xy 76.459843 -314.04668) (xy 76.448066 -313.998896) (xy 76.444106 -313.949842)
			(xy 75.155298 -313.949842) (xy 75.154803 -313.974449) (xy 75.146908 -314.023026) (xy 75.131324 -314.069707)
			(xy 75.108453 -314.113284) (xy 75.078888 -314.152628) (xy 75.043395 -314.18672) (xy 75.002892 -314.214676)
			(xy 74.95843 -314.235774) (xy 74.911159 -314.249466) (xy 74.862304 -314.255398) (xy 74.813129 -314.253417)
			(xy 74.76491 -314.243573) (xy 74.718894 -314.226121) (xy 74.676273 -314.201514) (xy 74.638152 -314.170389)
			(xy 74.605517 -314.133552) (xy 74.579214 -314.091956) (xy 74.559923 -314.04668) (xy 74.548146 -313.998896)
			(xy 74.544186 -313.949842) (xy 73.255124 -313.949842) (xy 73.254629 -313.974449) (xy 73.246734 -314.023026)
			(xy 73.23115 -314.069707) (xy 73.208279 -314.113284) (xy 73.178714 -314.152628) (xy 73.143221 -314.18672)
			(xy 73.102718 -314.214676) (xy 73.058256 -314.235774) (xy 73.010985 -314.249466) (xy 72.96213 -314.255398)
			(xy 72.912955 -314.253417) (xy 72.864736 -314.243573) (xy 72.81872 -314.226121) (xy 72.776099 -314.201514)
			(xy 72.737978 -314.170389) (xy 72.705343 -314.133552) (xy 72.67904 -314.091956) (xy 72.659749 -314.04668)
			(xy 72.647972 -313.998896) (xy 72.644012 -313.949842) (xy 71.355204 -313.949842) (xy 71.354709 -313.974449)
			(xy 71.346814 -314.023026) (xy 71.33123 -314.069707) (xy 71.308359 -314.113284) (xy 71.278794 -314.152628)
			(xy 71.243301 -314.18672) (xy 71.202798 -314.214676) (xy 71.158336 -314.235774) (xy 71.111065 -314.249466)
			(xy 71.06221 -314.255398) (xy 71.013035 -314.253417) (xy 70.964816 -314.243573) (xy 70.9188 -314.226121)
			(xy 70.876179 -314.201514) (xy 70.838058 -314.170389) (xy 70.805423 -314.133552) (xy 70.77912 -314.091956)
			(xy 70.759829 -314.04668) (xy 70.748052 -313.998896) (xy 70.744092 -313.949842) (xy 69.455284 -313.949842)
			(xy 69.454789 -313.974449) (xy 69.446894 -314.023026) (xy 69.43131 -314.069707) (xy 69.408439 -314.113284)
			(xy 69.378874 -314.152628) (xy 69.343381 -314.18672) (xy 69.302878 -314.214676) (xy 69.258416 -314.235774)
			(xy 69.211145 -314.249466) (xy 69.16229 -314.255398) (xy 69.113115 -314.253417) (xy 69.064896 -314.243573)
			(xy 69.01888 -314.226121) (xy 68.976259 -314.201514) (xy 68.938138 -314.170389) (xy 68.905503 -314.133552)
			(xy 68.8792 -314.091956) (xy 68.859909 -314.04668) (xy 68.848132 -313.998896) (xy 68.844172 -313.949842)
			(xy 67.55511 -313.949842) (xy 67.554615 -313.974449) (xy 67.54672 -314.023026) (xy 67.531136 -314.069707)
			(xy 67.508265 -314.113284) (xy 67.4787 -314.152628) (xy 67.443207 -314.18672) (xy 67.402704 -314.214676)
			(xy 67.358242 -314.235774) (xy 67.310971 -314.249466) (xy 67.262116 -314.255398) (xy 67.212941 -314.253417)
			(xy 67.164722 -314.243573) (xy 67.118706 -314.226121) (xy 67.076085 -314.201514) (xy 67.037964 -314.170389)
			(xy 67.005329 -314.133552) (xy 66.979026 -314.091956) (xy 66.959735 -314.04668) (xy 66.947958 -313.998896)
			(xy 66.943998 -313.949842) (xy 65.65519 -313.949842) (xy 65.654695 -313.974449) (xy 65.6468 -314.023026)
			(xy 65.631216 -314.069707) (xy 65.608345 -314.113284) (xy 65.57878 -314.152628) (xy 65.543287 -314.18672)
			(xy 65.502784 -314.214676) (xy 65.458322 -314.235774) (xy 65.411051 -314.249466) (xy 65.362196 -314.255398)
			(xy 65.313021 -314.253417) (xy 65.264802 -314.243573) (xy 65.218786 -314.226121) (xy 65.176165 -314.201514)
			(xy 65.138044 -314.170389) (xy 65.105409 -314.133552) (xy 65.079106 -314.091956) (xy 65.059815 -314.04668)
			(xy 65.048038 -313.998896) (xy 65.044078 -313.949842) (xy 63.75527 -313.949842) (xy 63.754775 -313.974449)
			(xy 63.74688 -314.023026) (xy 63.731296 -314.069707) (xy 63.708425 -314.113284) (xy 63.67886 -314.152628)
			(xy 63.643367 -314.18672) (xy 63.602864 -314.214676) (xy 63.558402 -314.235774) (xy 63.511131 -314.249466)
			(xy 63.462276 -314.255398) (xy 63.413101 -314.253417) (xy 63.364882 -314.243573) (xy 63.318866 -314.226121)
			(xy 63.276245 -314.201514) (xy 63.238124 -314.170389) (xy 63.205489 -314.133552) (xy 63.179186 -314.091956)
			(xy 63.159895 -314.04668) (xy 63.148118 -313.998896) (xy 63.144158 -313.949842) (xy 61.855096 -313.949842)
			(xy 61.854601 -313.974449) (xy 61.846706 -314.023026) (xy 61.831122 -314.069707) (xy 61.808251 -314.113284)
			(xy 61.778686 -314.152628) (xy 61.743193 -314.18672) (xy 61.70269 -314.214676) (xy 61.658228 -314.235774)
			(xy 61.610957 -314.249466) (xy 61.562102 -314.255398) (xy 61.512927 -314.253417) (xy 61.464708 -314.243573)
			(xy 61.418692 -314.226121) (xy 61.376071 -314.201514) (xy 61.33795 -314.170389) (xy 61.305315 -314.133552)
			(xy 61.279012 -314.091956) (xy 61.259721 -314.04668) (xy 61.247944 -313.998896) (xy 61.243984 -313.949842)
			(xy 59.955176 -313.949842) (xy 59.954681 -313.974449) (xy 59.946786 -314.023026) (xy 59.931202 -314.069707)
			(xy 59.908331 -314.113284) (xy 59.878766 -314.152628) (xy 59.843273 -314.18672) (xy 59.80277 -314.214676)
			(xy 59.758308 -314.235774) (xy 59.711037 -314.249466) (xy 59.662182 -314.255398) (xy 59.613007 -314.253417)
			(xy 59.564788 -314.243573) (xy 59.518772 -314.226121) (xy 59.476151 -314.201514) (xy 59.43803 -314.170389)
			(xy 59.405395 -314.133552) (xy 59.379092 -314.091956) (xy 59.359801 -314.04668) (xy 59.348024 -313.998896)
			(xy 59.344064 -313.949842) (xy 58.055256 -313.949842) (xy 58.054761 -313.974449) (xy 58.046866 -314.023026)
			(xy 58.031282 -314.069707) (xy 58.008411 -314.113284) (xy 57.978846 -314.152628) (xy 57.943353 -314.18672)
			(xy 57.90285 -314.214676) (xy 57.858388 -314.235774) (xy 57.811117 -314.249466) (xy 57.762262 -314.255398)
			(xy 57.713087 -314.253417) (xy 57.664868 -314.243573) (xy 57.618852 -314.226121) (xy 57.576231 -314.201514)
			(xy 57.53811 -314.170389) (xy 57.505475 -314.133552) (xy 57.479172 -314.091956) (xy 57.459881 -314.04668)
			(xy 57.448104 -313.998896) (xy 57.444144 -313.949842) (xy 56.155082 -313.949842) (xy 56.154587 -313.974449)
			(xy 56.146692 -314.023026) (xy 56.131108 -314.069707) (xy 56.108237 -314.113284) (xy 56.078672 -314.152628)
			(xy 56.043179 -314.18672) (xy 56.002676 -314.214676) (xy 55.958214 -314.235774) (xy 55.910943 -314.249466)
			(xy 55.862088 -314.255398) (xy 55.812913 -314.253417) (xy 55.764694 -314.243573) (xy 55.718678 -314.226121)
			(xy 55.676057 -314.201514) (xy 55.637936 -314.170389) (xy 55.605301 -314.133552) (xy 55.578998 -314.091956)
			(xy 55.559707 -314.04668) (xy 55.54793 -313.998896) (xy 55.54397 -313.949842) (xy 54.255162 -313.949842)
			(xy 54.254667 -313.974449) (xy 54.246772 -314.023026) (xy 54.231188 -314.069707) (xy 54.208317 -314.113284)
			(xy 54.178752 -314.152628) (xy 54.143259 -314.18672) (xy 54.102756 -314.214676) (xy 54.058294 -314.235774)
			(xy 54.011023 -314.249466) (xy 53.962168 -314.255398) (xy 53.912993 -314.253417) (xy 53.864774 -314.243573)
			(xy 53.818758 -314.226121) (xy 53.776137 -314.201514) (xy 53.738016 -314.170389) (xy 53.705381 -314.133552)
			(xy 53.679078 -314.091956) (xy 53.659787 -314.04668) (xy 53.64801 -313.998896) (xy 53.64405 -313.949842)
			(xy 52.355242 -313.949842) (xy 52.354747 -313.974449) (xy 52.346852 -314.023026) (xy 52.331268 -314.069707)
			(xy 52.308397 -314.113284) (xy 52.278832 -314.152628) (xy 52.243339 -314.18672) (xy 52.202836 -314.214676)
			(xy 52.158374 -314.235774) (xy 52.111103 -314.249466) (xy 52.062248 -314.255398) (xy 52.013073 -314.253417)
			(xy 51.964854 -314.243573) (xy 51.918838 -314.226121) (xy 51.876217 -314.201514) (xy 51.838096 -314.170389)
			(xy 51.805461 -314.133552) (xy 51.779158 -314.091956) (xy 51.759867 -314.04668) (xy 51.74809 -313.998896)
			(xy 51.74413 -313.949842) (xy 50.455068 -313.949842) (xy 50.454573 -313.974449) (xy 50.446678 -314.023026)
			(xy 50.431094 -314.069707) (xy 50.408223 -314.113284) (xy 50.378658 -314.152628) (xy 50.343165 -314.18672)
			(xy 50.302662 -314.214676) (xy 50.2582 -314.235774) (xy 50.210929 -314.249466) (xy 50.162074 -314.255398)
			(xy 50.112899 -314.253417) (xy 50.06468 -314.243573) (xy 50.018664 -314.226121) (xy 49.976043 -314.201514)
			(xy 49.937922 -314.170389) (xy 49.905287 -314.133552) (xy 49.878984 -314.091956) (xy 49.859693 -314.04668)
			(xy 49.847916 -313.998896) (xy 49.843956 -313.949842) (xy 48.555148 -313.949842) (xy 48.554653 -313.974449)
			(xy 48.546758 -314.023026) (xy 48.531174 -314.069707) (xy 48.508303 -314.113284) (xy 48.478738 -314.152628)
			(xy 48.443245 -314.18672) (xy 48.402742 -314.214676) (xy 48.35828 -314.235774) (xy 48.311009 -314.249466)
			(xy 48.262154 -314.255398) (xy 48.212979 -314.253417) (xy 48.16476 -314.243573) (xy 48.118744 -314.226121)
			(xy 48.076123 -314.201514) (xy 48.038002 -314.170389) (xy 48.005367 -314.133552) (xy 47.979064 -314.091956)
			(xy 47.959773 -314.04668) (xy 47.947996 -313.998896) (xy 47.944036 -313.949842) (xy 46.655228 -313.949842)
			(xy 46.654733 -313.974449) (xy 46.646838 -314.023026) (xy 46.631254 -314.069707) (xy 46.608383 -314.113284)
			(xy 46.578818 -314.152628) (xy 46.543325 -314.18672) (xy 46.502822 -314.214676) (xy 46.45836 -314.235774)
			(xy 46.411089 -314.249466) (xy 46.362234 -314.255398) (xy 46.313059 -314.253417) (xy 46.26484 -314.243573)
			(xy 46.218824 -314.226121) (xy 46.176203 -314.201514) (xy 46.138082 -314.170389) (xy 46.105447 -314.133552)
			(xy 46.079144 -314.091956) (xy 46.059853 -314.04668) (xy 46.048076 -313.998896) (xy 46.044116 -313.949842)
			(xy 44.755054 -313.949842) (xy 44.754559 -313.974449) (xy 44.746664 -314.023026) (xy 44.73108 -314.069707)
			(xy 44.708209 -314.113284) (xy 44.678644 -314.152628) (xy 44.643151 -314.18672) (xy 44.602648 -314.214676)
			(xy 44.558186 -314.235774) (xy 44.510915 -314.249466) (xy 44.46206 -314.255398) (xy 44.412885 -314.253417)
			(xy 44.364666 -314.243573) (xy 44.31865 -314.226121) (xy 44.276029 -314.201514) (xy 44.237908 -314.170389)
			(xy 44.205273 -314.133552) (xy 44.17897 -314.091956) (xy 44.159679 -314.04668) (xy 44.147902 -313.998896)
			(xy 44.143942 -313.949842) (xy 42.855134 -313.949842) (xy 42.854639 -313.974449) (xy 42.846744 -314.023026)
			(xy 42.83116 -314.069707) (xy 42.808289 -314.113284) (xy 42.778724 -314.152628) (xy 42.743231 -314.18672)
			(xy 42.702728 -314.214676) (xy 42.658266 -314.235774) (xy 42.610995 -314.249466) (xy 42.56214 -314.255398)
			(xy 42.512965 -314.253417) (xy 42.464746 -314.243573) (xy 42.41873 -314.226121) (xy 42.376109 -314.201514)
			(xy 42.337988 -314.170389) (xy 42.305353 -314.133552) (xy 42.27905 -314.091956) (xy 42.259759 -314.04668)
			(xy 42.247982 -313.998896) (xy 42.244022 -313.949842) (xy 40.955214 -313.949842) (xy 40.954719 -313.974449)
			(xy 40.946824 -314.023026) (xy 40.93124 -314.069707) (xy 40.908369 -314.113284) (xy 40.878804 -314.152628)
			(xy 40.843311 -314.18672) (xy 40.802808 -314.214676) (xy 40.758346 -314.235774) (xy 40.711075 -314.249466)
			(xy 40.66222 -314.255398) (xy 40.613045 -314.253417) (xy 40.564826 -314.243573) (xy 40.51881 -314.226121)
			(xy 40.476189 -314.201514) (xy 40.438068 -314.170389) (xy 40.405433 -314.133552) (xy 40.37913 -314.091956)
			(xy 40.359839 -314.04668) (xy 40.348062 -313.998896) (xy 40.344102 -313.949842) (xy 39.055294 -313.949842)
			(xy 39.054799 -313.974449) (xy 39.046904 -314.023026) (xy 39.03132 -314.069707) (xy 39.008449 -314.113284)
			(xy 38.978884 -314.152628) (xy 38.943391 -314.18672) (xy 38.902888 -314.214676) (xy 38.858426 -314.235774)
			(xy 38.811155 -314.249466) (xy 38.7623 -314.255398) (xy 38.713125 -314.253417) (xy 38.664906 -314.243573)
			(xy 38.61889 -314.226121) (xy 38.576269 -314.201514) (xy 38.538148 -314.170389) (xy 38.505513 -314.133552)
			(xy 38.47921 -314.091956) (xy 38.459919 -314.04668) (xy 38.448142 -313.998896) (xy 38.444182 -313.949842)
			(xy 0.508 -313.949842) (xy 0.508 -314.899802) (xy 36.544008 -314.899802) (xy 36.547968 -314.850748)
			(xy 36.559745 -314.802964) (xy 36.579036 -314.757688) (xy 36.605339 -314.716092) (xy 36.637974 -314.679255)
			(xy 36.676095 -314.64813) (xy 36.718716 -314.623523) (xy 36.764732 -314.606071) (xy 36.812951 -314.596227)
			(xy 36.862126 -314.594246) (xy 36.910981 -314.600178) (xy 36.958252 -314.61387) (xy 37.002714 -314.634968)
			(xy 37.043217 -314.662924) (xy 37.07871 -314.697016) (xy 37.108275 -314.73636) (xy 37.131146 -314.779937)
			(xy 37.14673 -314.826618) (xy 37.154625 -314.875195) (xy 37.15512 -314.899802) (xy 37.493968 -314.899802)
			(xy 37.497928 -314.850748) (xy 37.509705 -314.802964) (xy 37.528996 -314.757688) (xy 37.555299 -314.716092)
			(xy 37.587934 -314.679255) (xy 37.626055 -314.64813) (xy 37.668676 -314.623523) (xy 37.714692 -314.606071)
			(xy 37.762911 -314.596227) (xy 37.812086 -314.594246) (xy 37.860941 -314.600178) (xy 37.908212 -314.61387)
			(xy 37.952674 -314.634968) (xy 37.993177 -314.662924) (xy 38.02867 -314.697016) (xy 38.058235 -314.73636)
			(xy 38.081106 -314.779937) (xy 38.09669 -314.826618) (xy 38.104585 -314.875195) (xy 38.10508 -314.899802)
			(xy 81.19416 -314.899802) (xy 81.19812 -314.850748) (xy 81.209897 -314.802964) (xy 81.229188 -314.757688)
			(xy 81.255491 -314.716092) (xy 81.288126 -314.679255) (xy 81.326247 -314.64813) (xy 81.368868 -314.623523)
			(xy 81.414884 -314.606071) (xy 81.463103 -314.596227) (xy 81.512278 -314.594246) (xy 81.561133 -314.600178)
			(xy 81.608404 -314.61387) (xy 81.652866 -314.634968) (xy 81.693369 -314.662924) (xy 81.728862 -314.697016)
			(xy 81.758427 -314.73636) (xy 81.781298 -314.779937) (xy 81.796882 -314.826618) (xy 81.804777 -314.875195)
			(xy 81.805272 -314.899802) (xy 82.14412 -314.899802) (xy 82.14808 -314.850748) (xy 82.159857 -314.802964)
			(xy 82.179148 -314.757688) (xy 82.205451 -314.716092) (xy 82.238086 -314.679255) (xy 82.276207 -314.64813)
			(xy 82.318828 -314.623523) (xy 82.364844 -314.606071) (xy 82.413063 -314.596227) (xy 82.462238 -314.594246)
			(xy 82.511093 -314.600178) (xy 82.558364 -314.61387) (xy 82.602826 -314.634968) (xy 82.643329 -314.662924)
			(xy 82.678822 -314.697016) (xy 82.708387 -314.73636) (xy 82.731258 -314.779937) (xy 82.746842 -314.826618)
			(xy 82.754737 -314.875195) (xy 82.755232 -314.899802) (xy 152.644106 -314.899802) (xy 152.648066 -314.850748)
			(xy 152.659843 -314.802964) (xy 152.679134 -314.757688) (xy 152.705437 -314.716092) (xy 152.738072 -314.679255)
			(xy 152.776193 -314.64813) (xy 152.818814 -314.623523) (xy 152.86483 -314.606071) (xy 152.913049 -314.596227)
			(xy 152.962224 -314.594246) (xy 153.011079 -314.600178) (xy 153.05835 -314.61387) (xy 153.102812 -314.634968)
			(xy 153.143315 -314.662924) (xy 153.178808 -314.697016) (xy 153.208373 -314.73636) (xy 153.231244 -314.779937)
			(xy 153.246828 -314.826618) (xy 153.254723 -314.875195) (xy 153.255218 -314.899802) (xy 153.594066 -314.899802)
			(xy 153.598026 -314.850748) (xy 153.609803 -314.802964) (xy 153.629094 -314.757688) (xy 153.655397 -314.716092)
			(xy 153.688032 -314.679255) (xy 153.726153 -314.64813) (xy 153.768774 -314.623523) (xy 153.81479 -314.606071)
			(xy 153.863009 -314.596227) (xy 153.912184 -314.594246) (xy 153.961039 -314.600178) (xy 154.00831 -314.61387)
			(xy 154.052772 -314.634968) (xy 154.093275 -314.662924) (xy 154.128768 -314.697016) (xy 154.158333 -314.73636)
			(xy 154.181204 -314.779937) (xy 154.196788 -314.826618) (xy 154.204683 -314.875195) (xy 154.205178 -314.899802)
			(xy 197.294258 -314.899802) (xy 197.298218 -314.850748) (xy 197.309995 -314.802964) (xy 197.329286 -314.757688)
			(xy 197.355589 -314.716092) (xy 197.388224 -314.679255) (xy 197.426345 -314.64813) (xy 197.468966 -314.623523)
			(xy 197.514982 -314.606071) (xy 197.563201 -314.596227) (xy 197.612376 -314.594246) (xy 197.661231 -314.600178)
			(xy 197.708502 -314.61387) (xy 197.752964 -314.634968) (xy 197.793467 -314.662924) (xy 197.82896 -314.697016)
			(xy 197.858525 -314.73636) (xy 197.881396 -314.779937) (xy 197.89698 -314.826618) (xy 197.904875 -314.875195)
			(xy 197.90537 -314.899802) (xy 198.244218 -314.899802) (xy 198.248178 -314.850748) (xy 198.259955 -314.802964)
			(xy 198.279246 -314.757688) (xy 198.305549 -314.716092) (xy 198.338184 -314.679255) (xy 198.376305 -314.64813)
			(xy 198.418926 -314.623523) (xy 198.464942 -314.606071) (xy 198.513161 -314.596227) (xy 198.562336 -314.594246)
			(xy 198.611191 -314.600178) (xy 198.658462 -314.61387) (xy 198.702924 -314.634968) (xy 198.743427 -314.662924)
			(xy 198.77892 -314.697016) (xy 198.808485 -314.73636) (xy 198.831356 -314.779937) (xy 198.84694 -314.826618)
			(xy 198.854835 -314.875195) (xy 198.85533 -314.899802) (xy 268.74395 -314.899802) (xy 268.74791 -314.850748)
			(xy 268.759687 -314.802964) (xy 268.778978 -314.757688) (xy 268.805281 -314.716092) (xy 268.837916 -314.679255)
			(xy 268.876037 -314.64813) (xy 268.918658 -314.623523) (xy 268.964674 -314.606071) (xy 269.012893 -314.596227)
			(xy 269.062068 -314.594246) (xy 269.110923 -314.600178) (xy 269.158194 -314.61387) (xy 269.202656 -314.634968)
			(xy 269.243159 -314.662924) (xy 269.278652 -314.697016) (xy 269.308217 -314.73636) (xy 269.331088 -314.779937)
			(xy 269.346672 -314.826618) (xy 269.354567 -314.875195) (xy 269.355062 -314.899802) (xy 269.69391 -314.899802)
			(xy 269.69787 -314.850748) (xy 269.709647 -314.802964) (xy 269.728938 -314.757688) (xy 269.755241 -314.716092)
			(xy 269.787876 -314.679255) (xy 269.825997 -314.64813) (xy 269.868618 -314.623523) (xy 269.914634 -314.606071)
			(xy 269.962853 -314.596227) (xy 270.012028 -314.594246) (xy 270.060883 -314.600178) (xy 270.108154 -314.61387)
			(xy 270.152616 -314.634968) (xy 270.193119 -314.662924) (xy 270.228612 -314.697016) (xy 270.258177 -314.73636)
			(xy 270.281048 -314.779937) (xy 270.296632 -314.826618) (xy 270.304527 -314.875195) (xy 270.305022 -314.899802)
			(xy 313.394102 -314.899802) (xy 313.398062 -314.850748) (xy 313.409839 -314.802964) (xy 313.42913 -314.757688)
			(xy 313.455433 -314.716092) (xy 313.488068 -314.679255) (xy 313.526189 -314.64813) (xy 313.56881 -314.623523)
			(xy 313.614826 -314.606071) (xy 313.663045 -314.596227) (xy 313.71222 -314.594246) (xy 313.761075 -314.600178)
			(xy 313.808346 -314.61387) (xy 313.852808 -314.634968) (xy 313.893311 -314.662924) (xy 313.928804 -314.697016)
			(xy 313.958369 -314.73636) (xy 313.98124 -314.779937) (xy 313.996824 -314.826618) (xy 314.004719 -314.875195)
			(xy 314.005214 -314.899802) (xy 314.344062 -314.899802) (xy 314.348022 -314.850748) (xy 314.359799 -314.802964)
			(xy 314.37909 -314.757688) (xy 314.405393 -314.716092) (xy 314.438028 -314.679255) (xy 314.476149 -314.64813)
			(xy 314.51877 -314.623523) (xy 314.564786 -314.606071) (xy 314.613005 -314.596227) (xy 314.66218 -314.594246)
			(xy 314.711035 -314.600178) (xy 314.758306 -314.61387) (xy 314.802768 -314.634968) (xy 314.843271 -314.662924)
			(xy 314.878764 -314.697016) (xy 314.908329 -314.73636) (xy 314.9312 -314.779937) (xy 314.946784 -314.826618)
			(xy 314.954679 -314.875195) (xy 314.955174 -314.899802) (xy 384.844048 -314.899802) (xy 384.848008 -314.850748)
			(xy 384.859785 -314.802964) (xy 384.879076 -314.757688) (xy 384.905379 -314.716092) (xy 384.938014 -314.679255)
			(xy 384.976135 -314.64813) (xy 385.018756 -314.623523) (xy 385.064772 -314.606071) (xy 385.112991 -314.596227)
			(xy 385.162166 -314.594246) (xy 385.211021 -314.600178) (xy 385.258292 -314.61387) (xy 385.302754 -314.634968)
			(xy 385.343257 -314.662924) (xy 385.37875 -314.697016) (xy 385.408315 -314.73636) (xy 385.431186 -314.779937)
			(xy 385.44677 -314.826618) (xy 385.454665 -314.875195) (xy 385.45516 -314.899802) (xy 385.794008 -314.899802)
			(xy 385.797968 -314.850748) (xy 385.809745 -314.802964) (xy 385.829036 -314.757688) (xy 385.855339 -314.716092)
			(xy 385.887974 -314.679255) (xy 385.926095 -314.64813) (xy 385.968716 -314.623523) (xy 386.014732 -314.606071)
			(xy 386.062951 -314.596227) (xy 386.112126 -314.594246) (xy 386.160981 -314.600178) (xy 386.208252 -314.61387)
			(xy 386.252714 -314.634968) (xy 386.293217 -314.662924) (xy 386.32871 -314.697016) (xy 386.358275 -314.73636)
			(xy 386.381146 -314.779937) (xy 386.39673 -314.826618) (xy 386.404625 -314.875195) (xy 386.40512 -314.899802)
			(xy 429.4942 -314.899802) (xy 429.49816 -314.850748) (xy 429.509937 -314.802964) (xy 429.529228 -314.757688)
			(xy 429.555531 -314.716092) (xy 429.588166 -314.679255) (xy 429.626287 -314.64813) (xy 429.668908 -314.623523)
			(xy 429.714924 -314.606071) (xy 429.763143 -314.596227) (xy 429.812318 -314.594246) (xy 429.861173 -314.600178)
			(xy 429.908444 -314.61387) (xy 429.952906 -314.634968) (xy 429.993409 -314.662924) (xy 430.028902 -314.697016)
			(xy 430.058467 -314.73636) (xy 430.081338 -314.779937) (xy 430.096922 -314.826618) (xy 430.104817 -314.875195)
			(xy 430.105312 -314.899802) (xy 430.44416 -314.899802) (xy 430.44812 -314.850748) (xy 430.459897 -314.802964)
			(xy 430.479188 -314.757688) (xy 430.505491 -314.716092) (xy 430.538126 -314.679255) (xy 430.576247 -314.64813)
			(xy 430.618868 -314.623523) (xy 430.664884 -314.606071) (xy 430.713103 -314.596227) (xy 430.762278 -314.594246)
			(xy 430.811133 -314.600178) (xy 430.858404 -314.61387) (xy 430.902866 -314.634968) (xy 430.943369 -314.662924)
			(xy 430.978862 -314.697016) (xy 431.008427 -314.73636) (xy 431.031298 -314.779937) (xy 431.046882 -314.826618)
			(xy 431.054777 -314.875195) (xy 431.055272 -314.899802) (xy 431.054777 -314.924409) (xy 431.046882 -314.972986)
			(xy 431.031298 -315.019667) (xy 431.008427 -315.063244) (xy 430.978862 -315.102588) (xy 430.943369 -315.13668)
			(xy 430.902866 -315.164636) (xy 430.858404 -315.185734) (xy 430.811133 -315.199426) (xy 430.762278 -315.205358)
			(xy 430.713103 -315.203377) (xy 430.664884 -315.193533) (xy 430.618868 -315.176081) (xy 430.576247 -315.151474)
			(xy 430.538126 -315.120349) (xy 430.505491 -315.083512) (xy 430.479188 -315.041916) (xy 430.459897 -314.99664)
			(xy 430.44812 -314.948856) (xy 430.44416 -314.899802) (xy 430.105312 -314.899802) (xy 430.104817 -314.924409)
			(xy 430.096922 -314.972986) (xy 430.081338 -315.019667) (xy 430.058467 -315.063244) (xy 430.028902 -315.102588)
			(xy 429.993409 -315.13668) (xy 429.952906 -315.164636) (xy 429.908444 -315.185734) (xy 429.861173 -315.199426)
			(xy 429.812318 -315.205358) (xy 429.763143 -315.203377) (xy 429.714924 -315.193533) (xy 429.668908 -315.176081)
			(xy 429.626287 -315.151474) (xy 429.588166 -315.120349) (xy 429.555531 -315.083512) (xy 429.529228 -315.041916)
			(xy 429.509937 -314.99664) (xy 429.49816 -314.948856) (xy 429.4942 -314.899802) (xy 386.40512 -314.899802)
			(xy 386.404625 -314.924409) (xy 386.39673 -314.972986) (xy 386.381146 -315.019667) (xy 386.358275 -315.063244)
			(xy 386.32871 -315.102588) (xy 386.293217 -315.13668) (xy 386.252714 -315.164636) (xy 386.208252 -315.185734)
			(xy 386.160981 -315.199426) (xy 386.112126 -315.205358) (xy 386.062951 -315.203377) (xy 386.014732 -315.193533)
			(xy 385.968716 -315.176081) (xy 385.926095 -315.151474) (xy 385.887974 -315.120349) (xy 385.855339 -315.083512)
			(xy 385.829036 -315.041916) (xy 385.809745 -314.99664) (xy 385.797968 -314.948856) (xy 385.794008 -314.899802)
			(xy 385.45516 -314.899802) (xy 385.454665 -314.924409) (xy 385.44677 -314.972986) (xy 385.431186 -315.019667)
			(xy 385.408315 -315.063244) (xy 385.37875 -315.102588) (xy 385.343257 -315.13668) (xy 385.302754 -315.164636)
			(xy 385.258292 -315.185734) (xy 385.211021 -315.199426) (xy 385.162166 -315.205358) (xy 385.112991 -315.203377)
			(xy 385.064772 -315.193533) (xy 385.018756 -315.176081) (xy 384.976135 -315.151474) (xy 384.938014 -315.120349)
			(xy 384.905379 -315.083512) (xy 384.879076 -315.041916) (xy 384.859785 -314.99664) (xy 384.848008 -314.948856)
			(xy 384.844048 -314.899802) (xy 314.955174 -314.899802) (xy 314.954679 -314.924409) (xy 314.946784 -314.972986)
			(xy 314.9312 -315.019667) (xy 314.908329 -315.063244) (xy 314.878764 -315.102588) (xy 314.843271 -315.13668)
			(xy 314.802768 -315.164636) (xy 314.758306 -315.185734) (xy 314.711035 -315.199426) (xy 314.66218 -315.205358)
			(xy 314.613005 -315.203377) (xy 314.564786 -315.193533) (xy 314.51877 -315.176081) (xy 314.476149 -315.151474)
			(xy 314.438028 -315.120349) (xy 314.405393 -315.083512) (xy 314.37909 -315.041916) (xy 314.359799 -314.99664)
			(xy 314.348022 -314.948856) (xy 314.344062 -314.899802) (xy 314.005214 -314.899802) (xy 314.004719 -314.924409)
			(xy 313.996824 -314.972986) (xy 313.98124 -315.019667) (xy 313.958369 -315.063244) (xy 313.928804 -315.102588)
			(xy 313.893311 -315.13668) (xy 313.852808 -315.164636) (xy 313.808346 -315.185734) (xy 313.761075 -315.199426)
			(xy 313.71222 -315.205358) (xy 313.663045 -315.203377) (xy 313.614826 -315.193533) (xy 313.56881 -315.176081)
			(xy 313.526189 -315.151474) (xy 313.488068 -315.120349) (xy 313.455433 -315.083512) (xy 313.42913 -315.041916)
			(xy 313.409839 -314.99664) (xy 313.398062 -314.948856) (xy 313.394102 -314.899802) (xy 270.305022 -314.899802)
			(xy 270.304527 -314.924409) (xy 270.296632 -314.972986) (xy 270.281048 -315.019667) (xy 270.258177 -315.063244)
			(xy 270.228612 -315.102588) (xy 270.193119 -315.13668) (xy 270.152616 -315.164636) (xy 270.108154 -315.185734)
			(xy 270.060883 -315.199426) (xy 270.012028 -315.205358) (xy 269.962853 -315.203377) (xy 269.914634 -315.193533)
			(xy 269.868618 -315.176081) (xy 269.825997 -315.151474) (xy 269.787876 -315.120349) (xy 269.755241 -315.083512)
			(xy 269.728938 -315.041916) (xy 269.709647 -314.99664) (xy 269.69787 -314.948856) (xy 269.69391 -314.899802)
			(xy 269.355062 -314.899802) (xy 269.354567 -314.924409) (xy 269.346672 -314.972986) (xy 269.331088 -315.019667)
			(xy 269.308217 -315.063244) (xy 269.278652 -315.102588) (xy 269.243159 -315.13668) (xy 269.202656 -315.164636)
			(xy 269.158194 -315.185734) (xy 269.110923 -315.199426) (xy 269.062068 -315.205358) (xy 269.012893 -315.203377)
			(xy 268.964674 -315.193533) (xy 268.918658 -315.176081) (xy 268.876037 -315.151474) (xy 268.837916 -315.120349)
			(xy 268.805281 -315.083512) (xy 268.778978 -315.041916) (xy 268.759687 -314.99664) (xy 268.74791 -314.948856)
			(xy 268.74395 -314.899802) (xy 198.85533 -314.899802) (xy 198.854835 -314.924409) (xy 198.84694 -314.972986)
			(xy 198.831356 -315.019667) (xy 198.808485 -315.063244) (xy 198.77892 -315.102588) (xy 198.743427 -315.13668)
			(xy 198.702924 -315.164636) (xy 198.658462 -315.185734) (xy 198.611191 -315.199426) (xy 198.562336 -315.205358)
			(xy 198.513161 -315.203377) (xy 198.464942 -315.193533) (xy 198.418926 -315.176081) (xy 198.376305 -315.151474)
			(xy 198.338184 -315.120349) (xy 198.305549 -315.083512) (xy 198.279246 -315.041916) (xy 198.259955 -314.99664)
			(xy 198.248178 -314.948856) (xy 198.244218 -314.899802) (xy 197.90537 -314.899802) (xy 197.904875 -314.924409)
			(xy 197.89698 -314.972986) (xy 197.881396 -315.019667) (xy 197.858525 -315.063244) (xy 197.82896 -315.102588)
			(xy 197.793467 -315.13668) (xy 197.752964 -315.164636) (xy 197.708502 -315.185734) (xy 197.661231 -315.199426)
			(xy 197.612376 -315.205358) (xy 197.563201 -315.203377) (xy 197.514982 -315.193533) (xy 197.468966 -315.176081)
			(xy 197.426345 -315.151474) (xy 197.388224 -315.120349) (xy 197.355589 -315.083512) (xy 197.329286 -315.041916)
			(xy 197.309995 -314.99664) (xy 197.298218 -314.948856) (xy 197.294258 -314.899802) (xy 154.205178 -314.899802)
			(xy 154.204683 -314.924409) (xy 154.196788 -314.972986) (xy 154.181204 -315.019667) (xy 154.158333 -315.063244)
			(xy 154.128768 -315.102588) (xy 154.093275 -315.13668) (xy 154.052772 -315.164636) (xy 154.00831 -315.185734)
			(xy 153.961039 -315.199426) (xy 153.912184 -315.205358) (xy 153.863009 -315.203377) (xy 153.81479 -315.193533)
			(xy 153.768774 -315.176081) (xy 153.726153 -315.151474) (xy 153.688032 -315.120349) (xy 153.655397 -315.083512)
			(xy 153.629094 -315.041916) (xy 153.609803 -314.99664) (xy 153.598026 -314.948856) (xy 153.594066 -314.899802)
			(xy 153.255218 -314.899802) (xy 153.254723 -314.924409) (xy 153.246828 -314.972986) (xy 153.231244 -315.019667)
			(xy 153.208373 -315.063244) (xy 153.178808 -315.102588) (xy 153.143315 -315.13668) (xy 153.102812 -315.164636)
			(xy 153.05835 -315.185734) (xy 153.011079 -315.199426) (xy 152.962224 -315.205358) (xy 152.913049 -315.203377)
			(xy 152.86483 -315.193533) (xy 152.818814 -315.176081) (xy 152.776193 -315.151474) (xy 152.738072 -315.120349)
			(xy 152.705437 -315.083512) (xy 152.679134 -315.041916) (xy 152.659843 -314.99664) (xy 152.648066 -314.948856)
			(xy 152.644106 -314.899802) (xy 82.755232 -314.899802) (xy 82.754737 -314.924409) (xy 82.746842 -314.972986)
			(xy 82.731258 -315.019667) (xy 82.708387 -315.063244) (xy 82.678822 -315.102588) (xy 82.643329 -315.13668)
			(xy 82.602826 -315.164636) (xy 82.558364 -315.185734) (xy 82.511093 -315.199426) (xy 82.462238 -315.205358)
			(xy 82.413063 -315.203377) (xy 82.364844 -315.193533) (xy 82.318828 -315.176081) (xy 82.276207 -315.151474)
			(xy 82.238086 -315.120349) (xy 82.205451 -315.083512) (xy 82.179148 -315.041916) (xy 82.159857 -314.99664)
			(xy 82.14808 -314.948856) (xy 82.14412 -314.899802) (xy 81.805272 -314.899802) (xy 81.804777 -314.924409)
			(xy 81.796882 -314.972986) (xy 81.781298 -315.019667) (xy 81.758427 -315.063244) (xy 81.728862 -315.102588)
			(xy 81.693369 -315.13668) (xy 81.652866 -315.164636) (xy 81.608404 -315.185734) (xy 81.561133 -315.199426)
			(xy 81.512278 -315.205358) (xy 81.463103 -315.203377) (xy 81.414884 -315.193533) (xy 81.368868 -315.176081)
			(xy 81.326247 -315.151474) (xy 81.288126 -315.120349) (xy 81.255491 -315.083512) (xy 81.229188 -315.041916)
			(xy 81.209897 -314.99664) (xy 81.19812 -314.948856) (xy 81.19416 -314.899802) (xy 38.10508 -314.899802)
			(xy 38.104585 -314.924409) (xy 38.09669 -314.972986) (xy 38.081106 -315.019667) (xy 38.058235 -315.063244)
			(xy 38.02867 -315.102588) (xy 37.993177 -315.13668) (xy 37.952674 -315.164636) (xy 37.908212 -315.185734)
			(xy 37.860941 -315.199426) (xy 37.812086 -315.205358) (xy 37.762911 -315.203377) (xy 37.714692 -315.193533)
			(xy 37.668676 -315.176081) (xy 37.626055 -315.151474) (xy 37.587934 -315.120349) (xy 37.555299 -315.083512)
			(xy 37.528996 -315.041916) (xy 37.509705 -314.99664) (xy 37.497928 -314.948856) (xy 37.493968 -314.899802)
			(xy 37.15512 -314.899802) (xy 37.154625 -314.924409) (xy 37.14673 -314.972986) (xy 37.131146 -315.019667)
			(xy 37.108275 -315.063244) (xy 37.07871 -315.102588) (xy 37.043217 -315.13668) (xy 37.002714 -315.164636)
			(xy 36.958252 -315.185734) (xy 36.910981 -315.199426) (xy 36.862126 -315.205358) (xy 36.812951 -315.203377)
			(xy 36.764732 -315.193533) (xy 36.718716 -315.176081) (xy 36.676095 -315.151474) (xy 36.637974 -315.120349)
			(xy 36.605339 -315.083512) (xy 36.579036 -315.041916) (xy 36.559745 -314.99664) (xy 36.547968 -314.948856)
			(xy 36.544008 -314.899802) (xy 0.508 -314.899802) (xy 0.508 -315.849762) (xy 39.394142 -315.849762)
			(xy 39.398102 -315.800708) (xy 39.409879 -315.752924) (xy 39.42917 -315.707648) (xy 39.455473 -315.666052)
			(xy 39.488108 -315.629215) (xy 39.526229 -315.59809) (xy 39.56885 -315.573483) (xy 39.614866 -315.556031)
			(xy 39.663085 -315.546187) (xy 39.71226 -315.544206) (xy 39.761115 -315.550138) (xy 39.808386 -315.56383)
			(xy 39.852848 -315.584928) (xy 39.893351 -315.612884) (xy 39.928844 -315.646976) (xy 39.958409 -315.68632)
			(xy 39.98128 -315.729897) (xy 39.996864 -315.776578) (xy 40.004759 -315.825155) (xy 40.005254 -315.849762)
			(xy 41.294062 -315.849762) (xy 41.298022 -315.800708) (xy 41.309799 -315.752924) (xy 41.32909 -315.707648)
			(xy 41.355393 -315.666052) (xy 41.388028 -315.629215) (xy 41.426149 -315.59809) (xy 41.46877 -315.573483)
			(xy 41.514786 -315.556031) (xy 41.563005 -315.546187) (xy 41.61218 -315.544206) (xy 41.661035 -315.550138)
			(xy 41.708306 -315.56383) (xy 41.752768 -315.584928) (xy 41.793271 -315.612884) (xy 41.828764 -315.646976)
			(xy 41.858329 -315.68632) (xy 41.8812 -315.729897) (xy 41.896784 -315.776578) (xy 41.904679 -315.825155)
			(xy 41.905174 -315.849762) (xy 43.193982 -315.849762) (xy 43.197942 -315.800708) (xy 43.209719 -315.752924)
			(xy 43.22901 -315.707648) (xy 43.255313 -315.666052) (xy 43.287948 -315.629215) (xy 43.326069 -315.59809)
			(xy 43.36869 -315.573483) (xy 43.414706 -315.556031) (xy 43.462925 -315.546187) (xy 43.5121 -315.544206)
			(xy 43.560955 -315.550138) (xy 43.608226 -315.56383) (xy 43.652688 -315.584928) (xy 43.693191 -315.612884)
			(xy 43.728684 -315.646976) (xy 43.758249 -315.68632) (xy 43.78112 -315.729897) (xy 43.796704 -315.776578)
			(xy 43.804599 -315.825155) (xy 43.805094 -315.849762) (xy 45.094156 -315.849762) (xy 45.098116 -315.800708)
			(xy 45.109893 -315.752924) (xy 45.129184 -315.707648) (xy 45.155487 -315.666052) (xy 45.188122 -315.629215)
			(xy 45.226243 -315.59809) (xy 45.268864 -315.573483) (xy 45.31488 -315.556031) (xy 45.363099 -315.546187)
			(xy 45.412274 -315.544206) (xy 45.461129 -315.550138) (xy 45.5084 -315.56383) (xy 45.552862 -315.584928)
			(xy 45.593365 -315.612884) (xy 45.628858 -315.646976) (xy 45.658423 -315.68632) (xy 45.681294 -315.729897)
			(xy 45.696878 -315.776578) (xy 45.704773 -315.825155) (xy 45.705268 -315.849762) (xy 46.994076 -315.849762)
			(xy 46.998036 -315.800708) (xy 47.009813 -315.752924) (xy 47.029104 -315.707648) (xy 47.055407 -315.666052)
			(xy 47.088042 -315.629215) (xy 47.126163 -315.59809) (xy 47.168784 -315.573483) (xy 47.2148 -315.556031)
			(xy 47.263019 -315.546187) (xy 47.312194 -315.544206) (xy 47.361049 -315.550138) (xy 47.40832 -315.56383)
			(xy 47.452782 -315.584928) (xy 47.493285 -315.612884) (xy 47.528778 -315.646976) (xy 47.558343 -315.68632)
			(xy 47.581214 -315.729897) (xy 47.596798 -315.776578) (xy 47.604693 -315.825155) (xy 47.605188 -315.849762)
			(xy 48.893996 -315.849762) (xy 48.897956 -315.800708) (xy 48.909733 -315.752924) (xy 48.929024 -315.707648)
			(xy 48.955327 -315.666052) (xy 48.987962 -315.629215) (xy 49.026083 -315.59809) (xy 49.068704 -315.573483)
			(xy 49.11472 -315.556031) (xy 49.162939 -315.546187) (xy 49.212114 -315.544206) (xy 49.260969 -315.550138)
			(xy 49.30824 -315.56383) (xy 49.352702 -315.584928) (xy 49.393205 -315.612884) (xy 49.428698 -315.646976)
			(xy 49.458263 -315.68632) (xy 49.481134 -315.729897) (xy 49.496718 -315.776578) (xy 49.504613 -315.825155)
			(xy 49.505108 -315.849762) (xy 50.79417 -315.849762) (xy 50.79813 -315.800708) (xy 50.809907 -315.752924)
			(xy 50.829198 -315.707648) (xy 50.855501 -315.666052) (xy 50.888136 -315.629215) (xy 50.926257 -315.59809)
			(xy 50.968878 -315.573483) (xy 51.014894 -315.556031) (xy 51.063113 -315.546187) (xy 51.112288 -315.544206)
			(xy 51.161143 -315.550138) (xy 51.208414 -315.56383) (xy 51.252876 -315.584928) (xy 51.293379 -315.612884)
			(xy 51.328872 -315.646976) (xy 51.358437 -315.68632) (xy 51.381308 -315.729897) (xy 51.396892 -315.776578)
			(xy 51.404787 -315.825155) (xy 51.405282 -315.849762) (xy 52.69409 -315.849762) (xy 52.69805 -315.800708)
			(xy 52.709827 -315.752924) (xy 52.729118 -315.707648) (xy 52.755421 -315.666052) (xy 52.788056 -315.629215)
			(xy 52.826177 -315.59809) (xy 52.868798 -315.573483) (xy 52.914814 -315.556031) (xy 52.963033 -315.546187)
			(xy 53.012208 -315.544206) (xy 53.061063 -315.550138) (xy 53.108334 -315.56383) (xy 53.152796 -315.584928)
			(xy 53.193299 -315.612884) (xy 53.228792 -315.646976) (xy 53.258357 -315.68632) (xy 53.281228 -315.729897)
			(xy 53.296812 -315.776578) (xy 53.304707 -315.825155) (xy 53.305202 -315.849762) (xy 54.59401 -315.849762)
			(xy 54.59797 -315.800708) (xy 54.609747 -315.752924) (xy 54.629038 -315.707648) (xy 54.655341 -315.666052)
			(xy 54.687976 -315.629215) (xy 54.726097 -315.59809) (xy 54.768718 -315.573483) (xy 54.814734 -315.556031)
			(xy 54.862953 -315.546187) (xy 54.912128 -315.544206) (xy 54.960983 -315.550138) (xy 55.008254 -315.56383)
			(xy 55.052716 -315.584928) (xy 55.093219 -315.612884) (xy 55.128712 -315.646976) (xy 55.158277 -315.68632)
			(xy 55.181148 -315.729897) (xy 55.196732 -315.776578) (xy 55.204627 -315.825155) (xy 55.205122 -315.849762)
			(xy 56.494184 -315.849762) (xy 56.498144 -315.800708) (xy 56.509921 -315.752924) (xy 56.529212 -315.707648)
			(xy 56.555515 -315.666052) (xy 56.58815 -315.629215) (xy 56.626271 -315.59809) (xy 56.668892 -315.573483)
			(xy 56.714908 -315.556031) (xy 56.763127 -315.546187) (xy 56.812302 -315.544206) (xy 56.861157 -315.550138)
			(xy 56.908428 -315.56383) (xy 56.95289 -315.584928) (xy 56.993393 -315.612884) (xy 57.028886 -315.646976)
			(xy 57.058451 -315.68632) (xy 57.081322 -315.729897) (xy 57.096906 -315.776578) (xy 57.104801 -315.825155)
			(xy 57.105296 -315.849762) (xy 58.394104 -315.849762) (xy 58.398064 -315.800708) (xy 58.409841 -315.752924)
			(xy 58.429132 -315.707648) (xy 58.455435 -315.666052) (xy 58.48807 -315.629215) (xy 58.526191 -315.59809)
			(xy 58.568812 -315.573483) (xy 58.614828 -315.556031) (xy 58.663047 -315.546187) (xy 58.712222 -315.544206)
			(xy 58.761077 -315.550138) (xy 58.808348 -315.56383) (xy 58.85281 -315.584928) (xy 58.893313 -315.612884)
			(xy 58.928806 -315.646976) (xy 58.958371 -315.68632) (xy 58.981242 -315.729897) (xy 58.996826 -315.776578)
			(xy 59.004721 -315.825155) (xy 59.005216 -315.849762) (xy 60.294024 -315.849762) (xy 60.297984 -315.800708)
			(xy 60.309761 -315.752924) (xy 60.329052 -315.707648) (xy 60.355355 -315.666052) (xy 60.38799 -315.629215)
			(xy 60.426111 -315.59809) (xy 60.468732 -315.573483) (xy 60.514748 -315.556031) (xy 60.562967 -315.546187)
			(xy 60.612142 -315.544206) (xy 60.660997 -315.550138) (xy 60.708268 -315.56383) (xy 60.75273 -315.584928)
			(xy 60.793233 -315.612884) (xy 60.828726 -315.646976) (xy 60.858291 -315.68632) (xy 60.881162 -315.729897)
			(xy 60.896746 -315.776578) (xy 60.904641 -315.825155) (xy 60.905136 -315.849762) (xy 62.193944 -315.849762)
			(xy 62.197904 -315.800708) (xy 62.209681 -315.752924) (xy 62.228972 -315.707648) (xy 62.255275 -315.666052)
			(xy 62.28791 -315.629215) (xy 62.326031 -315.59809) (xy 62.368652 -315.573483) (xy 62.414668 -315.556031)
			(xy 62.462887 -315.546187) (xy 62.512062 -315.544206) (xy 62.560917 -315.550138) (xy 62.608188 -315.56383)
			(xy 62.65265 -315.584928) (xy 62.693153 -315.612884) (xy 62.728646 -315.646976) (xy 62.758211 -315.68632)
			(xy 62.781082 -315.729897) (xy 62.796666 -315.776578) (xy 62.804561 -315.825155) (xy 62.805056 -315.849762)
			(xy 64.094118 -315.849762) (xy 64.098078 -315.800708) (xy 64.109855 -315.752924) (xy 64.129146 -315.707648)
			(xy 64.155449 -315.666052) (xy 64.188084 -315.629215) (xy 64.226205 -315.59809) (xy 64.268826 -315.573483)
			(xy 64.314842 -315.556031) (xy 64.363061 -315.546187) (xy 64.412236 -315.544206) (xy 64.461091 -315.550138)
			(xy 64.508362 -315.56383) (xy 64.552824 -315.584928) (xy 64.593327 -315.612884) (xy 64.62882 -315.646976)
			(xy 64.658385 -315.68632) (xy 64.681256 -315.729897) (xy 64.69684 -315.776578) (xy 64.704735 -315.825155)
			(xy 64.70523 -315.849762) (xy 65.994038 -315.849762) (xy 65.997998 -315.800708) (xy 66.009775 -315.752924)
			(xy 66.029066 -315.707648) (xy 66.055369 -315.666052) (xy 66.088004 -315.629215) (xy 66.126125 -315.59809)
			(xy 66.168746 -315.573483) (xy 66.214762 -315.556031) (xy 66.262981 -315.546187) (xy 66.312156 -315.544206)
			(xy 66.361011 -315.550138) (xy 66.408282 -315.56383) (xy 66.452744 -315.584928) (xy 66.493247 -315.612884)
			(xy 66.52874 -315.646976) (xy 66.558305 -315.68632) (xy 66.581176 -315.729897) (xy 66.59676 -315.776578)
			(xy 66.604655 -315.825155) (xy 66.60515 -315.849762) (xy 67.893958 -315.849762) (xy 67.897918 -315.800708)
			(xy 67.909695 -315.752924) (xy 67.928986 -315.707648) (xy 67.955289 -315.666052) (xy 67.987924 -315.629215)
			(xy 68.026045 -315.59809) (xy 68.068666 -315.573483) (xy 68.114682 -315.556031) (xy 68.162901 -315.546187)
			(xy 68.212076 -315.544206) (xy 68.260931 -315.550138) (xy 68.308202 -315.56383) (xy 68.352664 -315.584928)
			(xy 68.393167 -315.612884) (xy 68.42866 -315.646976) (xy 68.458225 -315.68632) (xy 68.481096 -315.729897)
			(xy 68.49668 -315.776578) (xy 68.504575 -315.825155) (xy 68.50507 -315.849762) (xy 69.794132 -315.849762)
			(xy 69.798092 -315.800708) (xy 69.809869 -315.752924) (xy 69.82916 -315.707648) (xy 69.855463 -315.666052)
			(xy 69.888098 -315.629215) (xy 69.926219 -315.59809) (xy 69.96884 -315.573483) (xy 70.014856 -315.556031)
			(xy 70.063075 -315.546187) (xy 70.11225 -315.544206) (xy 70.161105 -315.550138) (xy 70.208376 -315.56383)
			(xy 70.252838 -315.584928) (xy 70.293341 -315.612884) (xy 70.328834 -315.646976) (xy 70.358399 -315.68632)
			(xy 70.38127 -315.729897) (xy 70.396854 -315.776578) (xy 70.404749 -315.825155) (xy 70.405244 -315.849762)
			(xy 71.694052 -315.849762) (xy 71.698012 -315.800708) (xy 71.709789 -315.752924) (xy 71.72908 -315.707648)
			(xy 71.755383 -315.666052) (xy 71.788018 -315.629215) (xy 71.826139 -315.59809) (xy 71.86876 -315.573483)
			(xy 71.914776 -315.556031) (xy 71.962995 -315.546187) (xy 72.01217 -315.544206) (xy 72.061025 -315.550138)
			(xy 72.108296 -315.56383) (xy 72.152758 -315.584928) (xy 72.193261 -315.612884) (xy 72.228754 -315.646976)
			(xy 72.258319 -315.68632) (xy 72.28119 -315.729897) (xy 72.296774 -315.776578) (xy 72.304669 -315.825155)
			(xy 72.305164 -315.849762) (xy 73.593972 -315.849762) (xy 73.597932 -315.800708) (xy 73.609709 -315.752924)
			(xy 73.629 -315.707648) (xy 73.655303 -315.666052) (xy 73.687938 -315.629215) (xy 73.726059 -315.59809)
			(xy 73.76868 -315.573483) (xy 73.814696 -315.556031) (xy 73.862915 -315.546187) (xy 73.91209 -315.544206)
			(xy 73.960945 -315.550138) (xy 74.008216 -315.56383) (xy 74.052678 -315.584928) (xy 74.093181 -315.612884)
			(xy 74.128674 -315.646976) (xy 74.158239 -315.68632) (xy 74.18111 -315.729897) (xy 74.196694 -315.776578)
			(xy 74.204589 -315.825155) (xy 74.205084 -315.849762) (xy 75.494146 -315.849762) (xy 75.498106 -315.800708)
			(xy 75.509883 -315.752924) (xy 75.529174 -315.707648) (xy 75.555477 -315.666052) (xy 75.588112 -315.629215)
			(xy 75.626233 -315.59809) (xy 75.668854 -315.573483) (xy 75.71487 -315.556031) (xy 75.763089 -315.546187)
			(xy 75.812264 -315.544206) (xy 75.861119 -315.550138) (xy 75.90839 -315.56383) (xy 75.952852 -315.584928)
			(xy 75.993355 -315.612884) (xy 76.028848 -315.646976) (xy 76.058413 -315.68632) (xy 76.081284 -315.729897)
			(xy 76.096868 -315.776578) (xy 76.104763 -315.825155) (xy 76.105258 -315.849762) (xy 77.394066 -315.849762)
			(xy 77.398026 -315.800708) (xy 77.409803 -315.752924) (xy 77.429094 -315.707648) (xy 77.455397 -315.666052)
			(xy 77.488032 -315.629215) (xy 77.526153 -315.59809) (xy 77.568774 -315.573483) (xy 77.61479 -315.556031)
			(xy 77.663009 -315.546187) (xy 77.712184 -315.544206) (xy 77.761039 -315.550138) (xy 77.80831 -315.56383)
			(xy 77.852772 -315.584928) (xy 77.893275 -315.612884) (xy 77.928768 -315.646976) (xy 77.958333 -315.68632)
			(xy 77.981204 -315.729897) (xy 77.996788 -315.776578) (xy 78.004683 -315.825155) (xy 78.005178 -315.849762)
			(xy 79.293986 -315.849762) (xy 79.297946 -315.800708) (xy 79.309723 -315.752924) (xy 79.329014 -315.707648)
			(xy 79.355317 -315.666052) (xy 79.387952 -315.629215) (xy 79.426073 -315.59809) (xy 79.468694 -315.573483)
			(xy 79.51471 -315.556031) (xy 79.562929 -315.546187) (xy 79.612104 -315.544206) (xy 79.660959 -315.550138)
			(xy 79.70823 -315.56383) (xy 79.752692 -315.584928) (xy 79.793195 -315.612884) (xy 79.828688 -315.646976)
			(xy 79.858253 -315.68632) (xy 79.881124 -315.729897) (xy 79.896708 -315.776578) (xy 79.904603 -315.825155)
			(xy 79.905098 -315.849762) (xy 155.49424 -315.849762) (xy 155.4982 -315.800708) (xy 155.509977 -315.752924)
			(xy 155.529268 -315.707648) (xy 155.555571 -315.666052) (xy 155.588206 -315.629215) (xy 155.626327 -315.59809)
			(xy 155.668948 -315.573483) (xy 155.714964 -315.556031) (xy 155.763183 -315.546187) (xy 155.812358 -315.544206)
			(xy 155.861213 -315.550138) (xy 155.908484 -315.56383) (xy 155.952946 -315.584928) (xy 155.993449 -315.612884)
			(xy 156.028942 -315.646976) (xy 156.058507 -315.68632) (xy 156.081378 -315.729897) (xy 156.096962 -315.776578)
			(xy 156.104857 -315.825155) (xy 156.105352 -315.849762) (xy 157.39416 -315.849762) (xy 157.39812 -315.800708)
			(xy 157.409897 -315.752924) (xy 157.429188 -315.707648) (xy 157.455491 -315.666052) (xy 157.488126 -315.629215)
			(xy 157.526247 -315.59809) (xy 157.568868 -315.573483) (xy 157.614884 -315.556031) (xy 157.663103 -315.546187)
			(xy 157.712278 -315.544206) (xy 157.761133 -315.550138) (xy 157.808404 -315.56383) (xy 157.852866 -315.584928)
			(xy 157.893369 -315.612884) (xy 157.928862 -315.646976) (xy 157.958427 -315.68632) (xy 157.981298 -315.729897)
			(xy 157.996882 -315.776578) (xy 158.004777 -315.825155) (xy 158.005272 -315.849762) (xy 159.29408 -315.849762)
			(xy 159.29804 -315.800708) (xy 159.309817 -315.752924) (xy 159.329108 -315.707648) (xy 159.355411 -315.666052)
			(xy 159.388046 -315.629215) (xy 159.426167 -315.59809) (xy 159.468788 -315.573483) (xy 159.514804 -315.556031)
			(xy 159.563023 -315.546187) (xy 159.612198 -315.544206) (xy 159.661053 -315.550138) (xy 159.708324 -315.56383)
			(xy 159.752786 -315.584928) (xy 159.793289 -315.612884) (xy 159.828782 -315.646976) (xy 159.858347 -315.68632)
			(xy 159.881218 -315.729897) (xy 159.896802 -315.776578) (xy 159.904697 -315.825155) (xy 159.905192 -315.849762)
			(xy 161.194254 -315.849762) (xy 161.198214 -315.800708) (xy 161.209991 -315.752924) (xy 161.229282 -315.707648)
			(xy 161.255585 -315.666052) (xy 161.28822 -315.629215) (xy 161.326341 -315.59809) (xy 161.368962 -315.573483)
			(xy 161.414978 -315.556031) (xy 161.463197 -315.546187) (xy 161.512372 -315.544206) (xy 161.561227 -315.550138)
			(xy 161.608498 -315.56383) (xy 161.65296 -315.584928) (xy 161.693463 -315.612884) (xy 161.728956 -315.646976)
			(xy 161.758521 -315.68632) (xy 161.781392 -315.729897) (xy 161.796976 -315.776578) (xy 161.804871 -315.825155)
			(xy 161.805366 -315.849762) (xy 163.094174 -315.849762) (xy 163.098134 -315.800708) (xy 163.109911 -315.752924)
			(xy 163.129202 -315.707648) (xy 163.155505 -315.666052) (xy 163.18814 -315.629215) (xy 163.226261 -315.59809)
			(xy 163.268882 -315.573483) (xy 163.314898 -315.556031) (xy 163.363117 -315.546187) (xy 163.412292 -315.544206)
			(xy 163.461147 -315.550138) (xy 163.508418 -315.56383) (xy 163.55288 -315.584928) (xy 163.593383 -315.612884)
			(xy 163.628876 -315.646976) (xy 163.658441 -315.68632) (xy 163.681312 -315.729897) (xy 163.696896 -315.776578)
			(xy 163.704791 -315.825155) (xy 163.705286 -315.849762) (xy 164.994094 -315.849762) (xy 164.998054 -315.800708)
			(xy 165.009831 -315.752924) (xy 165.029122 -315.707648) (xy 165.055425 -315.666052) (xy 165.08806 -315.629215)
			(xy 165.126181 -315.59809) (xy 165.168802 -315.573483) (xy 165.214818 -315.556031) (xy 165.263037 -315.546187)
			(xy 165.312212 -315.544206) (xy 165.361067 -315.550138) (xy 165.408338 -315.56383) (xy 165.4528 -315.584928)
			(xy 165.493303 -315.612884) (xy 165.528796 -315.646976) (xy 165.558361 -315.68632) (xy 165.581232 -315.729897)
			(xy 165.596816 -315.776578) (xy 165.604711 -315.825155) (xy 165.605206 -315.849762) (xy 166.894268 -315.849762)
			(xy 166.898228 -315.800708) (xy 166.910005 -315.752924) (xy 166.929296 -315.707648) (xy 166.955599 -315.666052)
			(xy 166.988234 -315.629215) (xy 167.026355 -315.59809) (xy 167.068976 -315.573483) (xy 167.114992 -315.556031)
			(xy 167.163211 -315.546187) (xy 167.212386 -315.544206) (xy 167.261241 -315.550138) (xy 167.308512 -315.56383)
			(xy 167.352974 -315.584928) (xy 167.393477 -315.612884) (xy 167.42897 -315.646976) (xy 167.458535 -315.68632)
			(xy 167.481406 -315.729897) (xy 167.49699 -315.776578) (xy 167.504885 -315.825155) (xy 167.50538 -315.849762)
			(xy 168.794188 -315.849762) (xy 168.798148 -315.800708) (xy 168.809925 -315.752924) (xy 168.829216 -315.707648)
			(xy 168.855519 -315.666052) (xy 168.888154 -315.629215) (xy 168.926275 -315.59809) (xy 168.968896 -315.573483)
			(xy 169.014912 -315.556031) (xy 169.063131 -315.546187) (xy 169.112306 -315.544206) (xy 169.161161 -315.550138)
			(xy 169.208432 -315.56383) (xy 169.252894 -315.584928) (xy 169.293397 -315.612884) (xy 169.32889 -315.646976)
			(xy 169.358455 -315.68632) (xy 169.381326 -315.729897) (xy 169.39691 -315.776578) (xy 169.404805 -315.825155)
			(xy 169.4053 -315.849762) (xy 170.694108 -315.849762) (xy 170.698068 -315.800708) (xy 170.709845 -315.752924)
			(xy 170.729136 -315.707648) (xy 170.755439 -315.666052) (xy 170.788074 -315.629215) (xy 170.826195 -315.59809)
			(xy 170.868816 -315.573483) (xy 170.914832 -315.556031) (xy 170.963051 -315.546187) (xy 171.012226 -315.544206)
			(xy 171.061081 -315.550138) (xy 171.108352 -315.56383) (xy 171.152814 -315.584928) (xy 171.193317 -315.612884)
			(xy 171.22881 -315.646976) (xy 171.258375 -315.68632) (xy 171.281246 -315.729897) (xy 171.29683 -315.776578)
			(xy 171.304725 -315.825155) (xy 171.30522 -315.849762) (xy 172.594282 -315.849762) (xy 172.598242 -315.800708)
			(xy 172.610019 -315.752924) (xy 172.62931 -315.707648) (xy 172.655613 -315.666052) (xy 172.688248 -315.629215)
			(xy 172.726369 -315.59809) (xy 172.76899 -315.573483) (xy 172.815006 -315.556031) (xy 172.863225 -315.546187)
			(xy 172.9124 -315.544206) (xy 172.961255 -315.550138) (xy 173.008526 -315.56383) (xy 173.052988 -315.584928)
			(xy 173.093491 -315.612884) (xy 173.128984 -315.646976) (xy 173.158549 -315.68632) (xy 173.18142 -315.729897)
			(xy 173.197004 -315.776578) (xy 173.204899 -315.825155) (xy 173.205394 -315.849762) (xy 174.494202 -315.849762)
			(xy 174.498162 -315.800708) (xy 174.509939 -315.752924) (xy 174.52923 -315.707648) (xy 174.555533 -315.666052)
			(xy 174.588168 -315.629215) (xy 174.626289 -315.59809) (xy 174.66891 -315.573483) (xy 174.714926 -315.556031)
			(xy 174.763145 -315.546187) (xy 174.81232 -315.544206) (xy 174.861175 -315.550138) (xy 174.908446 -315.56383)
			(xy 174.952908 -315.584928) (xy 174.993411 -315.612884) (xy 175.028904 -315.646976) (xy 175.058469 -315.68632)
			(xy 175.08134 -315.729897) (xy 175.096924 -315.776578) (xy 175.104819 -315.825155) (xy 175.105314 -315.849762)
			(xy 176.394122 -315.849762) (xy 176.398082 -315.800708) (xy 176.409859 -315.752924) (xy 176.42915 -315.707648)
			(xy 176.455453 -315.666052) (xy 176.488088 -315.629215) (xy 176.526209 -315.59809) (xy 176.56883 -315.573483)
			(xy 176.614846 -315.556031) (xy 176.663065 -315.546187) (xy 176.71224 -315.544206) (xy 176.761095 -315.550138)
			(xy 176.808366 -315.56383) (xy 176.852828 -315.584928) (xy 176.893331 -315.612884) (xy 176.928824 -315.646976)
			(xy 176.958389 -315.68632) (xy 176.98126 -315.729897) (xy 176.996844 -315.776578) (xy 177.004739 -315.825155)
			(xy 177.005234 -315.849762) (xy 178.294042 -315.849762) (xy 178.298002 -315.800708) (xy 178.309779 -315.752924)
			(xy 178.32907 -315.707648) (xy 178.355373 -315.666052) (xy 178.388008 -315.629215) (xy 178.426129 -315.59809)
			(xy 178.46875 -315.573483) (xy 178.514766 -315.556031) (xy 178.562985 -315.546187) (xy 178.61216 -315.544206)
			(xy 178.661015 -315.550138) (xy 178.708286 -315.56383) (xy 178.752748 -315.584928) (xy 178.793251 -315.612884)
			(xy 178.828744 -315.646976) (xy 178.858309 -315.68632) (xy 178.88118 -315.729897) (xy 178.896764 -315.776578)
			(xy 178.904659 -315.825155) (xy 178.905154 -315.849762) (xy 180.194216 -315.849762) (xy 180.198176 -315.800708)
			(xy 180.209953 -315.752924) (xy 180.229244 -315.707648) (xy 180.255547 -315.666052) (xy 180.288182 -315.629215)
			(xy 180.326303 -315.59809) (xy 180.368924 -315.573483) (xy 180.41494 -315.556031) (xy 180.463159 -315.546187)
			(xy 180.512334 -315.544206) (xy 180.561189 -315.550138) (xy 180.60846 -315.56383) (xy 180.652922 -315.584928)
			(xy 180.693425 -315.612884) (xy 180.728918 -315.646976) (xy 180.758483 -315.68632) (xy 180.781354 -315.729897)
			(xy 180.796938 -315.776578) (xy 180.804833 -315.825155) (xy 180.805328 -315.849762) (xy 182.094136 -315.849762)
			(xy 182.098096 -315.800708) (xy 182.109873 -315.752924) (xy 182.129164 -315.707648) (xy 182.155467 -315.666052)
			(xy 182.188102 -315.629215) (xy 182.226223 -315.59809) (xy 182.268844 -315.573483) (xy 182.31486 -315.556031)
			(xy 182.363079 -315.546187) (xy 182.412254 -315.544206) (xy 182.461109 -315.550138) (xy 182.50838 -315.56383)
			(xy 182.552842 -315.584928) (xy 182.593345 -315.612884) (xy 182.628838 -315.646976) (xy 182.658403 -315.68632)
			(xy 182.681274 -315.729897) (xy 182.696858 -315.776578) (xy 182.704753 -315.825155) (xy 182.705248 -315.849762)
			(xy 183.994056 -315.849762) (xy 183.998016 -315.800708) (xy 184.009793 -315.752924) (xy 184.029084 -315.707648)
			(xy 184.055387 -315.666052) (xy 184.088022 -315.629215) (xy 184.126143 -315.59809) (xy 184.168764 -315.573483)
			(xy 184.21478 -315.556031) (xy 184.262999 -315.546187) (xy 184.312174 -315.544206) (xy 184.361029 -315.550138)
			(xy 184.4083 -315.56383) (xy 184.452762 -315.584928) (xy 184.493265 -315.612884) (xy 184.528758 -315.646976)
			(xy 184.558323 -315.68632) (xy 184.581194 -315.729897) (xy 184.596778 -315.776578) (xy 184.604673 -315.825155)
			(xy 184.605168 -315.849762) (xy 185.89423 -315.849762) (xy 185.89819 -315.800708) (xy 185.909967 -315.752924)
			(xy 185.929258 -315.707648) (xy 185.955561 -315.666052) (xy 185.988196 -315.629215) (xy 186.026317 -315.59809)
			(xy 186.068938 -315.573483) (xy 186.114954 -315.556031) (xy 186.163173 -315.546187) (xy 186.212348 -315.544206)
			(xy 186.261203 -315.550138) (xy 186.308474 -315.56383) (xy 186.352936 -315.584928) (xy 186.393439 -315.612884)
			(xy 186.428932 -315.646976) (xy 186.458497 -315.68632) (xy 186.481368 -315.729897) (xy 186.496952 -315.776578)
			(xy 186.504847 -315.825155) (xy 186.505342 -315.849762) (xy 187.79415 -315.849762) (xy 187.79811 -315.800708)
			(xy 187.809887 -315.752924) (xy 187.829178 -315.707648) (xy 187.855481 -315.666052) (xy 187.888116 -315.629215)
			(xy 187.926237 -315.59809) (xy 187.968858 -315.573483) (xy 188.014874 -315.556031) (xy 188.063093 -315.546187)
			(xy 188.112268 -315.544206) (xy 188.161123 -315.550138) (xy 188.208394 -315.56383) (xy 188.252856 -315.584928)
			(xy 188.293359 -315.612884) (xy 188.328852 -315.646976) (xy 188.358417 -315.68632) (xy 188.381288 -315.729897)
			(xy 188.396872 -315.776578) (xy 188.404767 -315.825155) (xy 188.405262 -315.849762) (xy 189.69407 -315.849762)
			(xy 189.69803 -315.800708) (xy 189.709807 -315.752924) (xy 189.729098 -315.707648) (xy 189.755401 -315.666052)
			(xy 189.788036 -315.629215) (xy 189.826157 -315.59809) (xy 189.868778 -315.573483) (xy 189.914794 -315.556031)
			(xy 189.963013 -315.546187) (xy 190.012188 -315.544206) (xy 190.061043 -315.550138) (xy 190.108314 -315.56383)
			(xy 190.152776 -315.584928) (xy 190.193279 -315.612884) (xy 190.228772 -315.646976) (xy 190.258337 -315.68632)
			(xy 190.281208 -315.729897) (xy 190.296792 -315.776578) (xy 190.304687 -315.825155) (xy 190.305182 -315.849762)
			(xy 191.594244 -315.849762) (xy 191.598204 -315.800708) (xy 191.609981 -315.752924) (xy 191.629272 -315.707648)
			(xy 191.655575 -315.666052) (xy 191.68821 -315.629215) (xy 191.726331 -315.59809) (xy 191.768952 -315.573483)
			(xy 191.814968 -315.556031) (xy 191.863187 -315.546187) (xy 191.912362 -315.544206) (xy 191.961217 -315.550138)
			(xy 192.008488 -315.56383) (xy 192.05295 -315.584928) (xy 192.093453 -315.612884) (xy 192.128946 -315.646976)
			(xy 192.158511 -315.68632) (xy 192.181382 -315.729897) (xy 192.196966 -315.776578) (xy 192.204861 -315.825155)
			(xy 192.205356 -315.849762) (xy 193.494164 -315.849762) (xy 193.498124 -315.800708) (xy 193.509901 -315.752924)
			(xy 193.529192 -315.707648) (xy 193.555495 -315.666052) (xy 193.58813 -315.629215) (xy 193.626251 -315.59809)
			(xy 193.668872 -315.573483) (xy 193.714888 -315.556031) (xy 193.763107 -315.546187) (xy 193.812282 -315.544206)
			(xy 193.861137 -315.550138) (xy 193.908408 -315.56383) (xy 193.95287 -315.584928) (xy 193.993373 -315.612884)
			(xy 194.028866 -315.646976) (xy 194.058431 -315.68632) (xy 194.081302 -315.729897) (xy 194.096886 -315.776578)
			(xy 194.104781 -315.825155) (xy 194.105276 -315.849762) (xy 195.394084 -315.849762) (xy 195.398044 -315.800708)
			(xy 195.409821 -315.752924) (xy 195.429112 -315.707648) (xy 195.455415 -315.666052) (xy 195.48805 -315.629215)
			(xy 195.526171 -315.59809) (xy 195.568792 -315.573483) (xy 195.614808 -315.556031) (xy 195.663027 -315.546187)
			(xy 195.712202 -315.544206) (xy 195.761057 -315.550138) (xy 195.808328 -315.56383) (xy 195.85279 -315.584928)
			(xy 195.893293 -315.612884) (xy 195.928786 -315.646976) (xy 195.958351 -315.68632) (xy 195.981222 -315.729897)
			(xy 195.996806 -315.776578) (xy 196.004701 -315.825155) (xy 196.005196 -315.849762) (xy 271.594084 -315.849762)
			(xy 271.598044 -315.800708) (xy 271.609821 -315.752924) (xy 271.629112 -315.707648) (xy 271.655415 -315.666052)
			(xy 271.68805 -315.629215) (xy 271.726171 -315.59809) (xy 271.768792 -315.573483) (xy 271.814808 -315.556031)
			(xy 271.863027 -315.546187) (xy 271.912202 -315.544206) (xy 271.961057 -315.550138) (xy 272.008328 -315.56383)
			(xy 272.05279 -315.584928) (xy 272.093293 -315.612884) (xy 272.128786 -315.646976) (xy 272.158351 -315.68632)
			(xy 272.181222 -315.729897) (xy 272.196806 -315.776578) (xy 272.204701 -315.825155) (xy 272.205196 -315.849762)
			(xy 273.494004 -315.849762) (xy 273.497964 -315.800708) (xy 273.509741 -315.752924) (xy 273.529032 -315.707648)
			(xy 273.555335 -315.666052) (xy 273.58797 -315.629215) (xy 273.626091 -315.59809) (xy 273.668712 -315.573483)
			(xy 273.714728 -315.556031) (xy 273.762947 -315.546187) (xy 273.812122 -315.544206) (xy 273.860977 -315.550138)
			(xy 273.908248 -315.56383) (xy 273.95271 -315.584928) (xy 273.993213 -315.612884) (xy 274.028706 -315.646976)
			(xy 274.058271 -315.68632) (xy 274.081142 -315.729897) (xy 274.096726 -315.776578) (xy 274.104621 -315.825155)
			(xy 274.105116 -315.849762) (xy 275.393924 -315.849762) (xy 275.397884 -315.800708) (xy 275.409661 -315.752924)
			(xy 275.428952 -315.707648) (xy 275.455255 -315.666052) (xy 275.48789 -315.629215) (xy 275.526011 -315.59809)
			(xy 275.568632 -315.573483) (xy 275.614648 -315.556031) (xy 275.662867 -315.546187) (xy 275.712042 -315.544206)
			(xy 275.760897 -315.550138) (xy 275.808168 -315.56383) (xy 275.85263 -315.584928) (xy 275.893133 -315.612884)
			(xy 275.928626 -315.646976) (xy 275.958191 -315.68632) (xy 275.981062 -315.729897) (xy 275.996646 -315.776578)
			(xy 276.004541 -315.825155) (xy 276.005036 -315.849762) (xy 277.294098 -315.849762) (xy 277.298058 -315.800708)
			(xy 277.309835 -315.752924) (xy 277.329126 -315.707648) (xy 277.355429 -315.666052) (xy 277.388064 -315.629215)
			(xy 277.426185 -315.59809) (xy 277.468806 -315.573483) (xy 277.514822 -315.556031) (xy 277.563041 -315.546187)
			(xy 277.612216 -315.544206) (xy 277.661071 -315.550138) (xy 277.708342 -315.56383) (xy 277.752804 -315.584928)
			(xy 277.793307 -315.612884) (xy 277.8288 -315.646976) (xy 277.858365 -315.68632) (xy 277.881236 -315.729897)
			(xy 277.89682 -315.776578) (xy 277.904715 -315.825155) (xy 277.90521 -315.849762) (xy 279.194018 -315.849762)
			(xy 279.197978 -315.800708) (xy 279.209755 -315.752924) (xy 279.229046 -315.707648) (xy 279.255349 -315.666052)
			(xy 279.287984 -315.629215) (xy 279.326105 -315.59809) (xy 279.368726 -315.573483) (xy 279.414742 -315.556031)
			(xy 279.462961 -315.546187) (xy 279.512136 -315.544206) (xy 279.560991 -315.550138) (xy 279.608262 -315.56383)
			(xy 279.652724 -315.584928) (xy 279.693227 -315.612884) (xy 279.72872 -315.646976) (xy 279.758285 -315.68632)
			(xy 279.781156 -315.729897) (xy 279.79674 -315.776578) (xy 279.804635 -315.825155) (xy 279.80513 -315.849762)
			(xy 281.093938 -315.849762) (xy 281.097898 -315.800708) (xy 281.109675 -315.752924) (xy 281.128966 -315.707648)
			(xy 281.155269 -315.666052) (xy 281.187904 -315.629215) (xy 281.226025 -315.59809) (xy 281.268646 -315.573483)
			(xy 281.314662 -315.556031) (xy 281.362881 -315.546187) (xy 281.412056 -315.544206) (xy 281.460911 -315.550138)
			(xy 281.508182 -315.56383) (xy 281.552644 -315.584928) (xy 281.593147 -315.612884) (xy 281.62864 -315.646976)
			(xy 281.658205 -315.68632) (xy 281.681076 -315.729897) (xy 281.69666 -315.776578) (xy 281.704555 -315.825155)
			(xy 281.70505 -315.849762) (xy 282.994112 -315.849762) (xy 282.998072 -315.800708) (xy 283.009849 -315.752924)
			(xy 283.02914 -315.707648) (xy 283.055443 -315.666052) (xy 283.088078 -315.629215) (xy 283.126199 -315.59809)
			(xy 283.16882 -315.573483) (xy 283.214836 -315.556031) (xy 283.263055 -315.546187) (xy 283.31223 -315.544206)
			(xy 283.361085 -315.550138) (xy 283.408356 -315.56383) (xy 283.452818 -315.584928) (xy 283.493321 -315.612884)
			(xy 283.528814 -315.646976) (xy 283.558379 -315.68632) (xy 283.58125 -315.729897) (xy 283.596834 -315.776578)
			(xy 283.604729 -315.825155) (xy 283.605224 -315.849762) (xy 284.894032 -315.849762) (xy 284.897992 -315.800708)
			(xy 284.909769 -315.752924) (xy 284.92906 -315.707648) (xy 284.955363 -315.666052) (xy 284.987998 -315.629215)
			(xy 285.026119 -315.59809) (xy 285.06874 -315.573483) (xy 285.114756 -315.556031) (xy 285.162975 -315.546187)
			(xy 285.21215 -315.544206) (xy 285.261005 -315.550138) (xy 285.308276 -315.56383) (xy 285.352738 -315.584928)
			(xy 285.393241 -315.612884) (xy 285.428734 -315.646976) (xy 285.458299 -315.68632) (xy 285.48117 -315.729897)
			(xy 285.496754 -315.776578) (xy 285.504649 -315.825155) (xy 285.505144 -315.849762) (xy 286.793952 -315.849762)
			(xy 286.797912 -315.800708) (xy 286.809689 -315.752924) (xy 286.82898 -315.707648) (xy 286.855283 -315.666052)
			(xy 286.887918 -315.629215) (xy 286.926039 -315.59809) (xy 286.96866 -315.573483) (xy 287.014676 -315.556031)
			(xy 287.062895 -315.546187) (xy 287.11207 -315.544206) (xy 287.160925 -315.550138) (xy 287.208196 -315.56383)
			(xy 287.252658 -315.584928) (xy 287.293161 -315.612884) (xy 287.328654 -315.646976) (xy 287.358219 -315.68632)
			(xy 287.38109 -315.729897) (xy 287.396674 -315.776578) (xy 287.404569 -315.825155) (xy 287.405064 -315.849762)
			(xy 288.694126 -315.849762) (xy 288.698086 -315.800708) (xy 288.709863 -315.752924) (xy 288.729154 -315.707648)
			(xy 288.755457 -315.666052) (xy 288.788092 -315.629215) (xy 288.826213 -315.59809) (xy 288.868834 -315.573483)
			(xy 288.91485 -315.556031) (xy 288.963069 -315.546187) (xy 289.012244 -315.544206) (xy 289.061099 -315.550138)
			(xy 289.10837 -315.56383) (xy 289.152832 -315.584928) (xy 289.193335 -315.612884) (xy 289.228828 -315.646976)
			(xy 289.258393 -315.68632) (xy 289.281264 -315.729897) (xy 289.296848 -315.776578) (xy 289.304743 -315.825155)
			(xy 289.305238 -315.849762) (xy 290.594046 -315.849762) (xy 290.598006 -315.800708) (xy 290.609783 -315.752924)
			(xy 290.629074 -315.707648) (xy 290.655377 -315.666052) (xy 290.688012 -315.629215) (xy 290.726133 -315.59809)
			(xy 290.768754 -315.573483) (xy 290.81477 -315.556031) (xy 290.862989 -315.546187) (xy 290.912164 -315.544206)
			(xy 290.961019 -315.550138) (xy 291.00829 -315.56383) (xy 291.052752 -315.584928) (xy 291.093255 -315.612884)
			(xy 291.128748 -315.646976) (xy 291.158313 -315.68632) (xy 291.181184 -315.729897) (xy 291.196768 -315.776578)
			(xy 291.204663 -315.825155) (xy 291.205158 -315.849762) (xy 292.493966 -315.849762) (xy 292.497926 -315.800708)
			(xy 292.509703 -315.752924) (xy 292.528994 -315.707648) (xy 292.555297 -315.666052) (xy 292.587932 -315.629215)
			(xy 292.626053 -315.59809) (xy 292.668674 -315.573483) (xy 292.71469 -315.556031) (xy 292.762909 -315.546187)
			(xy 292.812084 -315.544206) (xy 292.860939 -315.550138) (xy 292.90821 -315.56383) (xy 292.952672 -315.584928)
			(xy 292.993175 -315.612884) (xy 293.028668 -315.646976) (xy 293.058233 -315.68632) (xy 293.081104 -315.729897)
			(xy 293.096688 -315.776578) (xy 293.104583 -315.825155) (xy 293.105078 -315.849762) (xy 294.393886 -315.849762)
			(xy 294.397846 -315.800708) (xy 294.409623 -315.752924) (xy 294.428914 -315.707648) (xy 294.455217 -315.666052)
			(xy 294.487852 -315.629215) (xy 294.525973 -315.59809) (xy 294.568594 -315.573483) (xy 294.61461 -315.556031)
			(xy 294.662829 -315.546187) (xy 294.712004 -315.544206) (xy 294.760859 -315.550138) (xy 294.80813 -315.56383)
			(xy 294.852592 -315.584928) (xy 294.893095 -315.612884) (xy 294.928588 -315.646976) (xy 294.958153 -315.68632)
			(xy 294.981024 -315.729897) (xy 294.996608 -315.776578) (xy 295.004503 -315.825155) (xy 295.004998 -315.849762)
			(xy 296.29406 -315.849762) (xy 296.29802 -315.800708) (xy 296.309797 -315.752924) (xy 296.329088 -315.707648)
			(xy 296.355391 -315.666052) (xy 296.388026 -315.629215) (xy 296.426147 -315.59809) (xy 296.468768 -315.573483)
			(xy 296.514784 -315.556031) (xy 296.563003 -315.546187) (xy 296.612178 -315.544206) (xy 296.661033 -315.550138)
			(xy 296.708304 -315.56383) (xy 296.752766 -315.584928) (xy 296.793269 -315.612884) (xy 296.828762 -315.646976)
			(xy 296.858327 -315.68632) (xy 296.881198 -315.729897) (xy 296.896782 -315.776578) (xy 296.904677 -315.825155)
			(xy 296.905172 -315.849762) (xy 298.19398 -315.849762) (xy 298.19794 -315.800708) (xy 298.209717 -315.752924)
			(xy 298.229008 -315.707648) (xy 298.255311 -315.666052) (xy 298.287946 -315.629215) (xy 298.326067 -315.59809)
			(xy 298.368688 -315.573483) (xy 298.414704 -315.556031) (xy 298.462923 -315.546187) (xy 298.512098 -315.544206)
			(xy 298.560953 -315.550138) (xy 298.608224 -315.56383) (xy 298.652686 -315.584928) (xy 298.693189 -315.612884)
			(xy 298.728682 -315.646976) (xy 298.758247 -315.68632) (xy 298.781118 -315.729897) (xy 298.796702 -315.776578)
			(xy 298.804597 -315.825155) (xy 298.805092 -315.849762) (xy 300.0939 -315.849762) (xy 300.09786 -315.800708)
			(xy 300.109637 -315.752924) (xy 300.128928 -315.707648) (xy 300.155231 -315.666052) (xy 300.187866 -315.629215)
			(xy 300.225987 -315.59809) (xy 300.268608 -315.573483) (xy 300.314624 -315.556031) (xy 300.362843 -315.546187)
			(xy 300.412018 -315.544206) (xy 300.460873 -315.550138) (xy 300.508144 -315.56383) (xy 300.552606 -315.584928)
			(xy 300.593109 -315.612884) (xy 300.628602 -315.646976) (xy 300.658167 -315.68632) (xy 300.681038 -315.729897)
			(xy 300.696622 -315.776578) (xy 300.704517 -315.825155) (xy 300.705012 -315.849762) (xy 301.994074 -315.849762)
			(xy 301.998034 -315.800708) (xy 302.009811 -315.752924) (xy 302.029102 -315.707648) (xy 302.055405 -315.666052)
			(xy 302.08804 -315.629215) (xy 302.126161 -315.59809) (xy 302.168782 -315.573483) (xy 302.214798 -315.556031)
			(xy 302.263017 -315.546187) (xy 302.312192 -315.544206) (xy 302.361047 -315.550138) (xy 302.408318 -315.56383)
			(xy 302.45278 -315.584928) (xy 302.493283 -315.612884) (xy 302.528776 -315.646976) (xy 302.558341 -315.68632)
			(xy 302.581212 -315.729897) (xy 302.596796 -315.776578) (xy 302.604691 -315.825155) (xy 302.605186 -315.849762)
			(xy 303.893994 -315.849762) (xy 303.897954 -315.800708) (xy 303.909731 -315.752924) (xy 303.929022 -315.707648)
			(xy 303.955325 -315.666052) (xy 303.98796 -315.629215) (xy 304.026081 -315.59809) (xy 304.068702 -315.573483)
			(xy 304.114718 -315.556031) (xy 304.162937 -315.546187) (xy 304.212112 -315.544206) (xy 304.260967 -315.550138)
			(xy 304.308238 -315.56383) (xy 304.3527 -315.584928) (xy 304.393203 -315.612884) (xy 304.428696 -315.646976)
			(xy 304.458261 -315.68632) (xy 304.481132 -315.729897) (xy 304.496716 -315.776578) (xy 304.504611 -315.825155)
			(xy 304.505106 -315.849762) (xy 305.793914 -315.849762) (xy 305.797874 -315.800708) (xy 305.809651 -315.752924)
			(xy 305.828942 -315.707648) (xy 305.855245 -315.666052) (xy 305.88788 -315.629215) (xy 305.926001 -315.59809)
			(xy 305.968622 -315.573483) (xy 306.014638 -315.556031) (xy 306.062857 -315.546187) (xy 306.112032 -315.544206)
			(xy 306.160887 -315.550138) (xy 306.208158 -315.56383) (xy 306.25262 -315.584928) (xy 306.293123 -315.612884)
			(xy 306.328616 -315.646976) (xy 306.358181 -315.68632) (xy 306.381052 -315.729897) (xy 306.396636 -315.776578)
			(xy 306.404531 -315.825155) (xy 306.405026 -315.849762) (xy 307.694088 -315.849762) (xy 307.698048 -315.800708)
			(xy 307.709825 -315.752924) (xy 307.729116 -315.707648) (xy 307.755419 -315.666052) (xy 307.788054 -315.629215)
			(xy 307.826175 -315.59809) (xy 307.868796 -315.573483) (xy 307.914812 -315.556031) (xy 307.963031 -315.546187)
			(xy 308.012206 -315.544206) (xy 308.061061 -315.550138) (xy 308.108332 -315.56383) (xy 308.152794 -315.584928)
			(xy 308.193297 -315.612884) (xy 308.22879 -315.646976) (xy 308.258355 -315.68632) (xy 308.281226 -315.729897)
			(xy 308.29681 -315.776578) (xy 308.304705 -315.825155) (xy 308.3052 -315.849762) (xy 309.594008 -315.849762)
			(xy 309.597968 -315.800708) (xy 309.609745 -315.752924) (xy 309.629036 -315.707648) (xy 309.655339 -315.666052)
			(xy 309.687974 -315.629215) (xy 309.726095 -315.59809) (xy 309.768716 -315.573483) (xy 309.814732 -315.556031)
			(xy 309.862951 -315.546187) (xy 309.912126 -315.544206) (xy 309.960981 -315.550138) (xy 310.008252 -315.56383)
			(xy 310.052714 -315.584928) (xy 310.093217 -315.612884) (xy 310.12871 -315.646976) (xy 310.158275 -315.68632)
			(xy 310.181146 -315.729897) (xy 310.19673 -315.776578) (xy 310.204625 -315.825155) (xy 310.20512 -315.849762)
			(xy 311.493928 -315.849762) (xy 311.497888 -315.800708) (xy 311.509665 -315.752924) (xy 311.528956 -315.707648)
			(xy 311.555259 -315.666052) (xy 311.587894 -315.629215) (xy 311.626015 -315.59809) (xy 311.668636 -315.573483)
			(xy 311.714652 -315.556031) (xy 311.762871 -315.546187) (xy 311.812046 -315.544206) (xy 311.860901 -315.550138)
			(xy 311.908172 -315.56383) (xy 311.952634 -315.584928) (xy 311.993137 -315.612884) (xy 312.02863 -315.646976)
			(xy 312.058195 -315.68632) (xy 312.081066 -315.729897) (xy 312.09665 -315.776578) (xy 312.104545 -315.825155)
			(xy 312.10504 -315.849762) (xy 387.694182 -315.849762) (xy 387.698142 -315.800708) (xy 387.709919 -315.752924)
			(xy 387.72921 -315.707648) (xy 387.755513 -315.666052) (xy 387.788148 -315.629215) (xy 387.826269 -315.59809)
			(xy 387.86889 -315.573483) (xy 387.914906 -315.556031) (xy 387.963125 -315.546187) (xy 388.0123 -315.544206)
			(xy 388.061155 -315.550138) (xy 388.108426 -315.56383) (xy 388.152888 -315.584928) (xy 388.193391 -315.612884)
			(xy 388.228884 -315.646976) (xy 388.258449 -315.68632) (xy 388.28132 -315.729897) (xy 388.296904 -315.776578)
			(xy 388.304799 -315.825155) (xy 388.305294 -315.849762) (xy 389.594102 -315.849762) (xy 389.598062 -315.800708)
			(xy 389.609839 -315.752924) (xy 389.62913 -315.707648) (xy 389.655433 -315.666052) (xy 389.688068 -315.629215)
			(xy 389.726189 -315.59809) (xy 389.76881 -315.573483) (xy 389.814826 -315.556031) (xy 389.863045 -315.546187)
			(xy 389.91222 -315.544206) (xy 389.961075 -315.550138) (xy 390.008346 -315.56383) (xy 390.052808 -315.584928)
			(xy 390.093311 -315.612884) (xy 390.128804 -315.646976) (xy 390.158369 -315.68632) (xy 390.18124 -315.729897)
			(xy 390.196824 -315.776578) (xy 390.204719 -315.825155) (xy 390.205214 -315.849762) (xy 391.494022 -315.849762)
			(xy 391.497982 -315.800708) (xy 391.509759 -315.752924) (xy 391.52905 -315.707648) (xy 391.555353 -315.666052)
			(xy 391.587988 -315.629215) (xy 391.626109 -315.59809) (xy 391.66873 -315.573483) (xy 391.714746 -315.556031)
			(xy 391.762965 -315.546187) (xy 391.81214 -315.544206) (xy 391.860995 -315.550138) (xy 391.908266 -315.56383)
			(xy 391.952728 -315.584928) (xy 391.993231 -315.612884) (xy 392.028724 -315.646976) (xy 392.058289 -315.68632)
			(xy 392.08116 -315.729897) (xy 392.096744 -315.776578) (xy 392.104639 -315.825155) (xy 392.105134 -315.849762)
			(xy 393.394196 -315.849762) (xy 393.398156 -315.800708) (xy 393.409933 -315.752924) (xy 393.429224 -315.707648)
			(xy 393.455527 -315.666052) (xy 393.488162 -315.629215) (xy 393.526283 -315.59809) (xy 393.568904 -315.573483)
			(xy 393.61492 -315.556031) (xy 393.663139 -315.546187) (xy 393.712314 -315.544206) (xy 393.761169 -315.550138)
			(xy 393.80844 -315.56383) (xy 393.852902 -315.584928) (xy 393.893405 -315.612884) (xy 393.928898 -315.646976)
			(xy 393.958463 -315.68632) (xy 393.981334 -315.729897) (xy 393.996918 -315.776578) (xy 394.004813 -315.825155)
			(xy 394.005308 -315.849762) (xy 395.294116 -315.849762) (xy 395.298076 -315.800708) (xy 395.309853 -315.752924)
			(xy 395.329144 -315.707648) (xy 395.355447 -315.666052) (xy 395.388082 -315.629215) (xy 395.426203 -315.59809)
			(xy 395.468824 -315.573483) (xy 395.51484 -315.556031) (xy 395.563059 -315.546187) (xy 395.612234 -315.544206)
			(xy 395.661089 -315.550138) (xy 395.70836 -315.56383) (xy 395.752822 -315.584928) (xy 395.793325 -315.612884)
			(xy 395.828818 -315.646976) (xy 395.858383 -315.68632) (xy 395.881254 -315.729897) (xy 395.896838 -315.776578)
			(xy 395.904733 -315.825155) (xy 395.905228 -315.849762) (xy 397.194036 -315.849762) (xy 397.197996 -315.800708)
			(xy 397.209773 -315.752924) (xy 397.229064 -315.707648) (xy 397.255367 -315.666052) (xy 397.288002 -315.629215)
			(xy 397.326123 -315.59809) (xy 397.368744 -315.573483) (xy 397.41476 -315.556031) (xy 397.462979 -315.546187)
			(xy 397.512154 -315.544206) (xy 397.561009 -315.550138) (xy 397.60828 -315.56383) (xy 397.652742 -315.584928)
			(xy 397.693245 -315.612884) (xy 397.728738 -315.646976) (xy 397.758303 -315.68632) (xy 397.781174 -315.729897)
			(xy 397.796758 -315.776578) (xy 397.804653 -315.825155) (xy 397.805148 -315.849762) (xy 399.09421 -315.849762)
			(xy 399.09817 -315.800708) (xy 399.109947 -315.752924) (xy 399.129238 -315.707648) (xy 399.155541 -315.666052)
			(xy 399.188176 -315.629215) (xy 399.226297 -315.59809) (xy 399.268918 -315.573483) (xy 399.314934 -315.556031)
			(xy 399.363153 -315.546187) (xy 399.412328 -315.544206) (xy 399.461183 -315.550138) (xy 399.508454 -315.56383)
			(xy 399.552916 -315.584928) (xy 399.593419 -315.612884) (xy 399.628912 -315.646976) (xy 399.658477 -315.68632)
			(xy 399.681348 -315.729897) (xy 399.696932 -315.776578) (xy 399.704827 -315.825155) (xy 399.705322 -315.849762)
			(xy 400.99413 -315.849762) (xy 400.99809 -315.800708) (xy 401.009867 -315.752924) (xy 401.029158 -315.707648)
			(xy 401.055461 -315.666052) (xy 401.088096 -315.629215) (xy 401.126217 -315.59809) (xy 401.168838 -315.573483)
			(xy 401.214854 -315.556031) (xy 401.263073 -315.546187) (xy 401.312248 -315.544206) (xy 401.361103 -315.550138)
			(xy 401.408374 -315.56383) (xy 401.452836 -315.584928) (xy 401.493339 -315.612884) (xy 401.528832 -315.646976)
			(xy 401.558397 -315.68632) (xy 401.581268 -315.729897) (xy 401.596852 -315.776578) (xy 401.604747 -315.825155)
			(xy 401.605242 -315.849762) (xy 402.89405 -315.849762) (xy 402.89801 -315.800708) (xy 402.909787 -315.752924)
			(xy 402.929078 -315.707648) (xy 402.955381 -315.666052) (xy 402.988016 -315.629215) (xy 403.026137 -315.59809)
			(xy 403.068758 -315.573483) (xy 403.114774 -315.556031) (xy 403.162993 -315.546187) (xy 403.212168 -315.544206)
			(xy 403.261023 -315.550138) (xy 403.308294 -315.56383) (xy 403.352756 -315.584928) (xy 403.393259 -315.612884)
			(xy 403.428752 -315.646976) (xy 403.458317 -315.68632) (xy 403.481188 -315.729897) (xy 403.496772 -315.776578)
			(xy 403.504667 -315.825155) (xy 403.505162 -315.849762) (xy 404.794224 -315.849762) (xy 404.798184 -315.800708)
			(xy 404.809961 -315.752924) (xy 404.829252 -315.707648) (xy 404.855555 -315.666052) (xy 404.88819 -315.629215)
			(xy 404.926311 -315.59809) (xy 404.968932 -315.573483) (xy 405.014948 -315.556031) (xy 405.063167 -315.546187)
			(xy 405.112342 -315.544206) (xy 405.161197 -315.550138) (xy 405.208468 -315.56383) (xy 405.25293 -315.584928)
			(xy 405.293433 -315.612884) (xy 405.328926 -315.646976) (xy 405.358491 -315.68632) (xy 405.381362 -315.729897)
			(xy 405.396946 -315.776578) (xy 405.404841 -315.825155) (xy 405.405336 -315.849762) (xy 406.694144 -315.849762)
			(xy 406.698104 -315.800708) (xy 406.709881 -315.752924) (xy 406.729172 -315.707648) (xy 406.755475 -315.666052)
			(xy 406.78811 -315.629215) (xy 406.826231 -315.59809) (xy 406.868852 -315.573483) (xy 406.914868 -315.556031)
			(xy 406.963087 -315.546187) (xy 407.012262 -315.544206) (xy 407.061117 -315.550138) (xy 407.108388 -315.56383)
			(xy 407.15285 -315.584928) (xy 407.193353 -315.612884) (xy 407.228846 -315.646976) (xy 407.258411 -315.68632)
			(xy 407.281282 -315.729897) (xy 407.296866 -315.776578) (xy 407.304761 -315.825155) (xy 407.305256 -315.849762)
			(xy 408.594064 -315.849762) (xy 408.598024 -315.800708) (xy 408.609801 -315.752924) (xy 408.629092 -315.707648)
			(xy 408.655395 -315.666052) (xy 408.68803 -315.629215) (xy 408.726151 -315.59809) (xy 408.768772 -315.573483)
			(xy 408.814788 -315.556031) (xy 408.863007 -315.546187) (xy 408.912182 -315.544206) (xy 408.961037 -315.550138)
			(xy 409.008308 -315.56383) (xy 409.05277 -315.584928) (xy 409.093273 -315.612884) (xy 409.128766 -315.646976)
			(xy 409.158331 -315.68632) (xy 409.181202 -315.729897) (xy 409.196786 -315.776578) (xy 409.204681 -315.825155)
			(xy 409.205176 -315.849762) (xy 410.493984 -315.849762) (xy 410.497944 -315.800708) (xy 410.509721 -315.752924)
			(xy 410.529012 -315.707648) (xy 410.555315 -315.666052) (xy 410.58795 -315.629215) (xy 410.626071 -315.59809)
			(xy 410.668692 -315.573483) (xy 410.714708 -315.556031) (xy 410.762927 -315.546187) (xy 410.812102 -315.544206)
			(xy 410.860957 -315.550138) (xy 410.908228 -315.56383) (xy 410.95269 -315.584928) (xy 410.993193 -315.612884)
			(xy 411.028686 -315.646976) (xy 411.058251 -315.68632) (xy 411.081122 -315.729897) (xy 411.096706 -315.776578)
			(xy 411.104601 -315.825155) (xy 411.105096 -315.849762) (xy 412.394158 -315.849762) (xy 412.398118 -315.800708)
			(xy 412.409895 -315.752924) (xy 412.429186 -315.707648) (xy 412.455489 -315.666052) (xy 412.488124 -315.629215)
			(xy 412.526245 -315.59809) (xy 412.568866 -315.573483) (xy 412.614882 -315.556031) (xy 412.663101 -315.546187)
			(xy 412.712276 -315.544206) (xy 412.761131 -315.550138) (xy 412.808402 -315.56383) (xy 412.852864 -315.584928)
			(xy 412.893367 -315.612884) (xy 412.92886 -315.646976) (xy 412.958425 -315.68632) (xy 412.981296 -315.729897)
			(xy 412.99688 -315.776578) (xy 413.004775 -315.825155) (xy 413.00527 -315.849762) (xy 414.294078 -315.849762)
			(xy 414.298038 -315.800708) (xy 414.309815 -315.752924) (xy 414.329106 -315.707648) (xy 414.355409 -315.666052)
			(xy 414.388044 -315.629215) (xy 414.426165 -315.59809) (xy 414.468786 -315.573483) (xy 414.514802 -315.556031)
			(xy 414.563021 -315.546187) (xy 414.612196 -315.544206) (xy 414.661051 -315.550138) (xy 414.708322 -315.56383)
			(xy 414.752784 -315.584928) (xy 414.793287 -315.612884) (xy 414.82878 -315.646976) (xy 414.858345 -315.68632)
			(xy 414.881216 -315.729897) (xy 414.8968 -315.776578) (xy 414.904695 -315.825155) (xy 414.90519 -315.849762)
			(xy 416.193998 -315.849762) (xy 416.197958 -315.800708) (xy 416.209735 -315.752924) (xy 416.229026 -315.707648)
			(xy 416.255329 -315.666052) (xy 416.287964 -315.629215) (xy 416.326085 -315.59809) (xy 416.368706 -315.573483)
			(xy 416.414722 -315.556031) (xy 416.462941 -315.546187) (xy 416.512116 -315.544206) (xy 416.560971 -315.550138)
			(xy 416.608242 -315.56383) (xy 416.652704 -315.584928) (xy 416.693207 -315.612884) (xy 416.7287 -315.646976)
			(xy 416.758265 -315.68632) (xy 416.781136 -315.729897) (xy 416.79672 -315.776578) (xy 416.804615 -315.825155)
			(xy 416.80511 -315.849762) (xy 418.094172 -315.849762) (xy 418.098132 -315.800708) (xy 418.109909 -315.752924)
			(xy 418.1292 -315.707648) (xy 418.155503 -315.666052) (xy 418.188138 -315.629215) (xy 418.226259 -315.59809)
			(xy 418.26888 -315.573483) (xy 418.314896 -315.556031) (xy 418.363115 -315.546187) (xy 418.41229 -315.544206)
			(xy 418.461145 -315.550138) (xy 418.508416 -315.56383) (xy 418.552878 -315.584928) (xy 418.593381 -315.612884)
			(xy 418.628874 -315.646976) (xy 418.658439 -315.68632) (xy 418.68131 -315.729897) (xy 418.696894 -315.776578)
			(xy 418.704789 -315.825155) (xy 418.705284 -315.849762) (xy 419.994092 -315.849762) (xy 419.998052 -315.800708)
			(xy 420.009829 -315.752924) (xy 420.02912 -315.707648) (xy 420.055423 -315.666052) (xy 420.088058 -315.629215)
			(xy 420.126179 -315.59809) (xy 420.1688 -315.573483) (xy 420.214816 -315.556031) (xy 420.263035 -315.546187)
			(xy 420.31221 -315.544206) (xy 420.361065 -315.550138) (xy 420.408336 -315.56383) (xy 420.452798 -315.584928)
			(xy 420.493301 -315.612884) (xy 420.528794 -315.646976) (xy 420.558359 -315.68632) (xy 420.58123 -315.729897)
			(xy 420.596814 -315.776578) (xy 420.604709 -315.825155) (xy 420.605204 -315.849762) (xy 421.894012 -315.849762)
			(xy 421.897972 -315.800708) (xy 421.909749 -315.752924) (xy 421.92904 -315.707648) (xy 421.955343 -315.666052)
			(xy 421.987978 -315.629215) (xy 422.026099 -315.59809) (xy 422.06872 -315.573483) (xy 422.114736 -315.556031)
			(xy 422.162955 -315.546187) (xy 422.21213 -315.544206) (xy 422.260985 -315.550138) (xy 422.308256 -315.56383)
			(xy 422.352718 -315.584928) (xy 422.393221 -315.612884) (xy 422.428714 -315.646976) (xy 422.458279 -315.68632)
			(xy 422.48115 -315.729897) (xy 422.496734 -315.776578) (xy 422.504629 -315.825155) (xy 422.505124 -315.849762)
			(xy 423.794186 -315.849762) (xy 423.798146 -315.800708) (xy 423.809923 -315.752924) (xy 423.829214 -315.707648)
			(xy 423.855517 -315.666052) (xy 423.888152 -315.629215) (xy 423.926273 -315.59809) (xy 423.968894 -315.573483)
			(xy 424.01491 -315.556031) (xy 424.063129 -315.546187) (xy 424.112304 -315.544206) (xy 424.161159 -315.550138)
			(xy 424.20843 -315.56383) (xy 424.252892 -315.584928) (xy 424.293395 -315.612884) (xy 424.328888 -315.646976)
			(xy 424.358453 -315.68632) (xy 424.381324 -315.729897) (xy 424.396908 -315.776578) (xy 424.404803 -315.825155)
			(xy 424.405298 -315.849762) (xy 425.694106 -315.849762) (xy 425.698066 -315.800708) (xy 425.709843 -315.752924)
			(xy 425.729134 -315.707648) (xy 425.755437 -315.666052) (xy 425.788072 -315.629215) (xy 425.826193 -315.59809)
			(xy 425.868814 -315.573483) (xy 425.91483 -315.556031) (xy 425.963049 -315.546187) (xy 426.012224 -315.544206)
			(xy 426.061079 -315.550138) (xy 426.10835 -315.56383) (xy 426.152812 -315.584928) (xy 426.193315 -315.612884)
			(xy 426.228808 -315.646976) (xy 426.258373 -315.68632) (xy 426.281244 -315.729897) (xy 426.296828 -315.776578)
			(xy 426.304723 -315.825155) (xy 426.305218 -315.849762) (xy 427.594026 -315.849762) (xy 427.597986 -315.800708)
			(xy 427.609763 -315.752924) (xy 427.629054 -315.707648) (xy 427.655357 -315.666052) (xy 427.687992 -315.629215)
			(xy 427.726113 -315.59809) (xy 427.768734 -315.573483) (xy 427.81475 -315.556031) (xy 427.862969 -315.546187)
			(xy 427.912144 -315.544206) (xy 427.960999 -315.550138) (xy 428.00827 -315.56383) (xy 428.052732 -315.584928)
			(xy 428.093235 -315.612884) (xy 428.128728 -315.646976) (xy 428.158293 -315.68632) (xy 428.181164 -315.729897)
			(xy 428.196748 -315.776578) (xy 428.204643 -315.825155) (xy 428.205138 -315.849762) (xy 428.204643 -315.874369)
			(xy 428.196748 -315.922946) (xy 428.181164 -315.969627) (xy 428.158293 -316.013204) (xy 428.128728 -316.052548)
			(xy 428.093235 -316.08664) (xy 428.052732 -316.114596) (xy 428.00827 -316.135694) (xy 427.960999 -316.149386)
			(xy 427.912144 -316.155318) (xy 427.862969 -316.153337) (xy 427.81475 -316.143493) (xy 427.768734 -316.126041)
			(xy 427.726113 -316.101434) (xy 427.687992 -316.070309) (xy 427.655357 -316.033472) (xy 427.629054 -315.991876)
			(xy 427.609763 -315.9466) (xy 427.597986 -315.898816) (xy 427.594026 -315.849762) (xy 426.305218 -315.849762)
			(xy 426.304723 -315.874369) (xy 426.296828 -315.922946) (xy 426.281244 -315.969627) (xy 426.258373 -316.013204)
			(xy 426.228808 -316.052548) (xy 426.193315 -316.08664) (xy 426.152812 -316.114596) (xy 426.10835 -316.135694)
			(xy 426.061079 -316.149386) (xy 426.012224 -316.155318) (xy 425.963049 -316.153337) (xy 425.91483 -316.143493)
			(xy 425.868814 -316.126041) (xy 425.826193 -316.101434) (xy 425.788072 -316.070309) (xy 425.755437 -316.033472)
			(xy 425.729134 -315.991876) (xy 425.709843 -315.9466) (xy 425.698066 -315.898816) (xy 425.694106 -315.849762)
			(xy 424.405298 -315.849762) (xy 424.404803 -315.874369) (xy 424.396908 -315.922946) (xy 424.381324 -315.969627)
			(xy 424.358453 -316.013204) (xy 424.328888 -316.052548) (xy 424.293395 -316.08664) (xy 424.252892 -316.114596)
			(xy 424.20843 -316.135694) (xy 424.161159 -316.149386) (xy 424.112304 -316.155318) (xy 424.063129 -316.153337)
			(xy 424.01491 -316.143493) (xy 423.968894 -316.126041) (xy 423.926273 -316.101434) (xy 423.888152 -316.070309)
			(xy 423.855517 -316.033472) (xy 423.829214 -315.991876) (xy 423.809923 -315.9466) (xy 423.798146 -315.898816)
			(xy 423.794186 -315.849762) (xy 422.505124 -315.849762) (xy 422.504629 -315.874369) (xy 422.496734 -315.922946)
			(xy 422.48115 -315.969627) (xy 422.458279 -316.013204) (xy 422.428714 -316.052548) (xy 422.393221 -316.08664)
			(xy 422.352718 -316.114596) (xy 422.308256 -316.135694) (xy 422.260985 -316.149386) (xy 422.21213 -316.155318)
			(xy 422.162955 -316.153337) (xy 422.114736 -316.143493) (xy 422.06872 -316.126041) (xy 422.026099 -316.101434)
			(xy 421.987978 -316.070309) (xy 421.955343 -316.033472) (xy 421.92904 -315.991876) (xy 421.909749 -315.9466)
			(xy 421.897972 -315.898816) (xy 421.894012 -315.849762) (xy 420.605204 -315.849762) (xy 420.604709 -315.874369)
			(xy 420.596814 -315.922946) (xy 420.58123 -315.969627) (xy 420.558359 -316.013204) (xy 420.528794 -316.052548)
			(xy 420.493301 -316.08664) (xy 420.452798 -316.114596) (xy 420.408336 -316.135694) (xy 420.361065 -316.149386)
			(xy 420.31221 -316.155318) (xy 420.263035 -316.153337) (xy 420.214816 -316.143493) (xy 420.1688 -316.126041)
			(xy 420.126179 -316.101434) (xy 420.088058 -316.070309) (xy 420.055423 -316.033472) (xy 420.02912 -315.991876)
			(xy 420.009829 -315.9466) (xy 419.998052 -315.898816) (xy 419.994092 -315.849762) (xy 418.705284 -315.849762)
			(xy 418.704789 -315.874369) (xy 418.696894 -315.922946) (xy 418.68131 -315.969627) (xy 418.658439 -316.013204)
			(xy 418.628874 -316.052548) (xy 418.593381 -316.08664) (xy 418.552878 -316.114596) (xy 418.508416 -316.135694)
			(xy 418.461145 -316.149386) (xy 418.41229 -316.155318) (xy 418.363115 -316.153337) (xy 418.314896 -316.143493)
			(xy 418.26888 -316.126041) (xy 418.226259 -316.101434) (xy 418.188138 -316.070309) (xy 418.155503 -316.033472)
			(xy 418.1292 -315.991876) (xy 418.109909 -315.9466) (xy 418.098132 -315.898816) (xy 418.094172 -315.849762)
			(xy 416.80511 -315.849762) (xy 416.804615 -315.874369) (xy 416.79672 -315.922946) (xy 416.781136 -315.969627)
			(xy 416.758265 -316.013204) (xy 416.7287 -316.052548) (xy 416.693207 -316.08664) (xy 416.652704 -316.114596)
			(xy 416.608242 -316.135694) (xy 416.560971 -316.149386) (xy 416.512116 -316.155318) (xy 416.462941 -316.153337)
			(xy 416.414722 -316.143493) (xy 416.368706 -316.126041) (xy 416.326085 -316.101434) (xy 416.287964 -316.070309)
			(xy 416.255329 -316.033472) (xy 416.229026 -315.991876) (xy 416.209735 -315.9466) (xy 416.197958 -315.898816)
			(xy 416.193998 -315.849762) (xy 414.90519 -315.849762) (xy 414.904695 -315.874369) (xy 414.8968 -315.922946)
			(xy 414.881216 -315.969627) (xy 414.858345 -316.013204) (xy 414.82878 -316.052548) (xy 414.793287 -316.08664)
			(xy 414.752784 -316.114596) (xy 414.708322 -316.135694) (xy 414.661051 -316.149386) (xy 414.612196 -316.155318)
			(xy 414.563021 -316.153337) (xy 414.514802 -316.143493) (xy 414.468786 -316.126041) (xy 414.426165 -316.101434)
			(xy 414.388044 -316.070309) (xy 414.355409 -316.033472) (xy 414.329106 -315.991876) (xy 414.309815 -315.9466)
			(xy 414.298038 -315.898816) (xy 414.294078 -315.849762) (xy 413.00527 -315.849762) (xy 413.004775 -315.874369)
			(xy 412.99688 -315.922946) (xy 412.981296 -315.969627) (xy 412.958425 -316.013204) (xy 412.92886 -316.052548)
			(xy 412.893367 -316.08664) (xy 412.852864 -316.114596) (xy 412.808402 -316.135694) (xy 412.761131 -316.149386)
			(xy 412.712276 -316.155318) (xy 412.663101 -316.153337) (xy 412.614882 -316.143493) (xy 412.568866 -316.126041)
			(xy 412.526245 -316.101434) (xy 412.488124 -316.070309) (xy 412.455489 -316.033472) (xy 412.429186 -315.991876)
			(xy 412.409895 -315.9466) (xy 412.398118 -315.898816) (xy 412.394158 -315.849762) (xy 411.105096 -315.849762)
			(xy 411.104601 -315.874369) (xy 411.096706 -315.922946) (xy 411.081122 -315.969627) (xy 411.058251 -316.013204)
			(xy 411.028686 -316.052548) (xy 410.993193 -316.08664) (xy 410.95269 -316.114596) (xy 410.908228 -316.135694)
			(xy 410.860957 -316.149386) (xy 410.812102 -316.155318) (xy 410.762927 -316.153337) (xy 410.714708 -316.143493)
			(xy 410.668692 -316.126041) (xy 410.626071 -316.101434) (xy 410.58795 -316.070309) (xy 410.555315 -316.033472)
			(xy 410.529012 -315.991876) (xy 410.509721 -315.9466) (xy 410.497944 -315.898816) (xy 410.493984 -315.849762)
			(xy 409.205176 -315.849762) (xy 409.204681 -315.874369) (xy 409.196786 -315.922946) (xy 409.181202 -315.969627)
			(xy 409.158331 -316.013204) (xy 409.128766 -316.052548) (xy 409.093273 -316.08664) (xy 409.05277 -316.114596)
			(xy 409.008308 -316.135694) (xy 408.961037 -316.149386) (xy 408.912182 -316.155318) (xy 408.863007 -316.153337)
			(xy 408.814788 -316.143493) (xy 408.768772 -316.126041) (xy 408.726151 -316.101434) (xy 408.68803 -316.070309)
			(xy 408.655395 -316.033472) (xy 408.629092 -315.991876) (xy 408.609801 -315.9466) (xy 408.598024 -315.898816)
			(xy 408.594064 -315.849762) (xy 407.305256 -315.849762) (xy 407.304761 -315.874369) (xy 407.296866 -315.922946)
			(xy 407.281282 -315.969627) (xy 407.258411 -316.013204) (xy 407.228846 -316.052548) (xy 407.193353 -316.08664)
			(xy 407.15285 -316.114596) (xy 407.108388 -316.135694) (xy 407.061117 -316.149386) (xy 407.012262 -316.155318)
			(xy 406.963087 -316.153337) (xy 406.914868 -316.143493) (xy 406.868852 -316.126041) (xy 406.826231 -316.101434)
			(xy 406.78811 -316.070309) (xy 406.755475 -316.033472) (xy 406.729172 -315.991876) (xy 406.709881 -315.9466)
			(xy 406.698104 -315.898816) (xy 406.694144 -315.849762) (xy 405.405336 -315.849762) (xy 405.404841 -315.874369)
			(xy 405.396946 -315.922946) (xy 405.381362 -315.969627) (xy 405.358491 -316.013204) (xy 405.328926 -316.052548)
			(xy 405.293433 -316.08664) (xy 405.25293 -316.114596) (xy 405.208468 -316.135694) (xy 405.161197 -316.149386)
			(xy 405.112342 -316.155318) (xy 405.063167 -316.153337) (xy 405.014948 -316.143493) (xy 404.968932 -316.126041)
			(xy 404.926311 -316.101434) (xy 404.88819 -316.070309) (xy 404.855555 -316.033472) (xy 404.829252 -315.991876)
			(xy 404.809961 -315.9466) (xy 404.798184 -315.898816) (xy 404.794224 -315.849762) (xy 403.505162 -315.849762)
			(xy 403.504667 -315.874369) (xy 403.496772 -315.922946) (xy 403.481188 -315.969627) (xy 403.458317 -316.013204)
			(xy 403.428752 -316.052548) (xy 403.393259 -316.08664) (xy 403.352756 -316.114596) (xy 403.308294 -316.135694)
			(xy 403.261023 -316.149386) (xy 403.212168 -316.155318) (xy 403.162993 -316.153337) (xy 403.114774 -316.143493)
			(xy 403.068758 -316.126041) (xy 403.026137 -316.101434) (xy 402.988016 -316.070309) (xy 402.955381 -316.033472)
			(xy 402.929078 -315.991876) (xy 402.909787 -315.9466) (xy 402.89801 -315.898816) (xy 402.89405 -315.849762)
			(xy 401.605242 -315.849762) (xy 401.604747 -315.874369) (xy 401.596852 -315.922946) (xy 401.581268 -315.969627)
			(xy 401.558397 -316.013204) (xy 401.528832 -316.052548) (xy 401.493339 -316.08664) (xy 401.452836 -316.114596)
			(xy 401.408374 -316.135694) (xy 401.361103 -316.149386) (xy 401.312248 -316.155318) (xy 401.263073 -316.153337)
			(xy 401.214854 -316.143493) (xy 401.168838 -316.126041) (xy 401.126217 -316.101434) (xy 401.088096 -316.070309)
			(xy 401.055461 -316.033472) (xy 401.029158 -315.991876) (xy 401.009867 -315.9466) (xy 400.99809 -315.898816)
			(xy 400.99413 -315.849762) (xy 399.705322 -315.849762) (xy 399.704827 -315.874369) (xy 399.696932 -315.922946)
			(xy 399.681348 -315.969627) (xy 399.658477 -316.013204) (xy 399.628912 -316.052548) (xy 399.593419 -316.08664)
			(xy 399.552916 -316.114596) (xy 399.508454 -316.135694) (xy 399.461183 -316.149386) (xy 399.412328 -316.155318)
			(xy 399.363153 -316.153337) (xy 399.314934 -316.143493) (xy 399.268918 -316.126041) (xy 399.226297 -316.101434)
			(xy 399.188176 -316.070309) (xy 399.155541 -316.033472) (xy 399.129238 -315.991876) (xy 399.109947 -315.9466)
			(xy 399.09817 -315.898816) (xy 399.09421 -315.849762) (xy 397.805148 -315.849762) (xy 397.804653 -315.874369)
			(xy 397.796758 -315.922946) (xy 397.781174 -315.969627) (xy 397.758303 -316.013204) (xy 397.728738 -316.052548)
			(xy 397.693245 -316.08664) (xy 397.652742 -316.114596) (xy 397.60828 -316.135694) (xy 397.561009 -316.149386)
			(xy 397.512154 -316.155318) (xy 397.462979 -316.153337) (xy 397.41476 -316.143493) (xy 397.368744 -316.126041)
			(xy 397.326123 -316.101434) (xy 397.288002 -316.070309) (xy 397.255367 -316.033472) (xy 397.229064 -315.991876)
			(xy 397.209773 -315.9466) (xy 397.197996 -315.898816) (xy 397.194036 -315.849762) (xy 395.905228 -315.849762)
			(xy 395.904733 -315.874369) (xy 395.896838 -315.922946) (xy 395.881254 -315.969627) (xy 395.858383 -316.013204)
			(xy 395.828818 -316.052548) (xy 395.793325 -316.08664) (xy 395.752822 -316.114596) (xy 395.70836 -316.135694)
			(xy 395.661089 -316.149386) (xy 395.612234 -316.155318) (xy 395.563059 -316.153337) (xy 395.51484 -316.143493)
			(xy 395.468824 -316.126041) (xy 395.426203 -316.101434) (xy 395.388082 -316.070309) (xy 395.355447 -316.033472)
			(xy 395.329144 -315.991876) (xy 395.309853 -315.9466) (xy 395.298076 -315.898816) (xy 395.294116 -315.849762)
			(xy 394.005308 -315.849762) (xy 394.004813 -315.874369) (xy 393.996918 -315.922946) (xy 393.981334 -315.969627)
			(xy 393.958463 -316.013204) (xy 393.928898 -316.052548) (xy 393.893405 -316.08664) (xy 393.852902 -316.114596)
			(xy 393.80844 -316.135694) (xy 393.761169 -316.149386) (xy 393.712314 -316.155318) (xy 393.663139 -316.153337)
			(xy 393.61492 -316.143493) (xy 393.568904 -316.126041) (xy 393.526283 -316.101434) (xy 393.488162 -316.070309)
			(xy 393.455527 -316.033472) (xy 393.429224 -315.991876) (xy 393.409933 -315.9466) (xy 393.398156 -315.898816)
			(xy 393.394196 -315.849762) (xy 392.105134 -315.849762) (xy 392.104639 -315.874369) (xy 392.096744 -315.922946)
			(xy 392.08116 -315.969627) (xy 392.058289 -316.013204) (xy 392.028724 -316.052548) (xy 391.993231 -316.08664)
			(xy 391.952728 -316.114596) (xy 391.908266 -316.135694) (xy 391.860995 -316.149386) (xy 391.81214 -316.155318)
			(xy 391.762965 -316.153337) (xy 391.714746 -316.143493) (xy 391.66873 -316.126041) (xy 391.626109 -316.101434)
			(xy 391.587988 -316.070309) (xy 391.555353 -316.033472) (xy 391.52905 -315.991876) (xy 391.509759 -315.9466)
			(xy 391.497982 -315.898816) (xy 391.494022 -315.849762) (xy 390.205214 -315.849762) (xy 390.204719 -315.874369)
			(xy 390.196824 -315.922946) (xy 390.18124 -315.969627) (xy 390.158369 -316.013204) (xy 390.128804 -316.052548)
			(xy 390.093311 -316.08664) (xy 390.052808 -316.114596) (xy 390.008346 -316.135694) (xy 389.961075 -316.149386)
			(xy 389.91222 -316.155318) (xy 389.863045 -316.153337) (xy 389.814826 -316.143493) (xy 389.76881 -316.126041)
			(xy 389.726189 -316.101434) (xy 389.688068 -316.070309) (xy 389.655433 -316.033472) (xy 389.62913 -315.991876)
			(xy 389.609839 -315.9466) (xy 389.598062 -315.898816) (xy 389.594102 -315.849762) (xy 388.305294 -315.849762)
			(xy 388.304799 -315.874369) (xy 388.296904 -315.922946) (xy 388.28132 -315.969627) (xy 388.258449 -316.013204)
			(xy 388.228884 -316.052548) (xy 388.193391 -316.08664) (xy 388.152888 -316.114596) (xy 388.108426 -316.135694)
			(xy 388.061155 -316.149386) (xy 388.0123 -316.155318) (xy 387.963125 -316.153337) (xy 387.914906 -316.143493)
			(xy 387.86889 -316.126041) (xy 387.826269 -316.101434) (xy 387.788148 -316.070309) (xy 387.755513 -316.033472)
			(xy 387.72921 -315.991876) (xy 387.709919 -315.9466) (xy 387.698142 -315.898816) (xy 387.694182 -315.849762)
			(xy 312.10504 -315.849762) (xy 312.104545 -315.874369) (xy 312.09665 -315.922946) (xy 312.081066 -315.969627)
			(xy 312.058195 -316.013204) (xy 312.02863 -316.052548) (xy 311.993137 -316.08664) (xy 311.952634 -316.114596)
			(xy 311.908172 -316.135694) (xy 311.860901 -316.149386) (xy 311.812046 -316.155318) (xy 311.762871 -316.153337)
			(xy 311.714652 -316.143493) (xy 311.668636 -316.126041) (xy 311.626015 -316.101434) (xy 311.587894 -316.070309)
			(xy 311.555259 -316.033472) (xy 311.528956 -315.991876) (xy 311.509665 -315.9466) (xy 311.497888 -315.898816)
			(xy 311.493928 -315.849762) (xy 310.20512 -315.849762) (xy 310.204625 -315.874369) (xy 310.19673 -315.922946)
			(xy 310.181146 -315.969627) (xy 310.158275 -316.013204) (xy 310.12871 -316.052548) (xy 310.093217 -316.08664)
			(xy 310.052714 -316.114596) (xy 310.008252 -316.135694) (xy 309.960981 -316.149386) (xy 309.912126 -316.155318)
			(xy 309.862951 -316.153337) (xy 309.814732 -316.143493) (xy 309.768716 -316.126041) (xy 309.726095 -316.101434)
			(xy 309.687974 -316.070309) (xy 309.655339 -316.033472) (xy 309.629036 -315.991876) (xy 309.609745 -315.9466)
			(xy 309.597968 -315.898816) (xy 309.594008 -315.849762) (xy 308.3052 -315.849762) (xy 308.304705 -315.874369)
			(xy 308.29681 -315.922946) (xy 308.281226 -315.969627) (xy 308.258355 -316.013204) (xy 308.22879 -316.052548)
			(xy 308.193297 -316.08664) (xy 308.152794 -316.114596) (xy 308.108332 -316.135694) (xy 308.061061 -316.149386)
			(xy 308.012206 -316.155318) (xy 307.963031 -316.153337) (xy 307.914812 -316.143493) (xy 307.868796 -316.126041)
			(xy 307.826175 -316.101434) (xy 307.788054 -316.070309) (xy 307.755419 -316.033472) (xy 307.729116 -315.991876)
			(xy 307.709825 -315.9466) (xy 307.698048 -315.898816) (xy 307.694088 -315.849762) (xy 306.405026 -315.849762)
			(xy 306.404531 -315.874369) (xy 306.396636 -315.922946) (xy 306.381052 -315.969627) (xy 306.358181 -316.013204)
			(xy 306.328616 -316.052548) (xy 306.293123 -316.08664) (xy 306.25262 -316.114596) (xy 306.208158 -316.135694)
			(xy 306.160887 -316.149386) (xy 306.112032 -316.155318) (xy 306.062857 -316.153337) (xy 306.014638 -316.143493)
			(xy 305.968622 -316.126041) (xy 305.926001 -316.101434) (xy 305.88788 -316.070309) (xy 305.855245 -316.033472)
			(xy 305.828942 -315.991876) (xy 305.809651 -315.9466) (xy 305.797874 -315.898816) (xy 305.793914 -315.849762)
			(xy 304.505106 -315.849762) (xy 304.504611 -315.874369) (xy 304.496716 -315.922946) (xy 304.481132 -315.969627)
			(xy 304.458261 -316.013204) (xy 304.428696 -316.052548) (xy 304.393203 -316.08664) (xy 304.3527 -316.114596)
			(xy 304.308238 -316.135694) (xy 304.260967 -316.149386) (xy 304.212112 -316.155318) (xy 304.162937 -316.153337)
			(xy 304.114718 -316.143493) (xy 304.068702 -316.126041) (xy 304.026081 -316.101434) (xy 303.98796 -316.070309)
			(xy 303.955325 -316.033472) (xy 303.929022 -315.991876) (xy 303.909731 -315.9466) (xy 303.897954 -315.898816)
			(xy 303.893994 -315.849762) (xy 302.605186 -315.849762) (xy 302.604691 -315.874369) (xy 302.596796 -315.922946)
			(xy 302.581212 -315.969627) (xy 302.558341 -316.013204) (xy 302.528776 -316.052548) (xy 302.493283 -316.08664)
			(xy 302.45278 -316.114596) (xy 302.408318 -316.135694) (xy 302.361047 -316.149386) (xy 302.312192 -316.155318)
			(xy 302.263017 -316.153337) (xy 302.214798 -316.143493) (xy 302.168782 -316.126041) (xy 302.126161 -316.101434)
			(xy 302.08804 -316.070309) (xy 302.055405 -316.033472) (xy 302.029102 -315.991876) (xy 302.009811 -315.9466)
			(xy 301.998034 -315.898816) (xy 301.994074 -315.849762) (xy 300.705012 -315.849762) (xy 300.704517 -315.874369)
			(xy 300.696622 -315.922946) (xy 300.681038 -315.969627) (xy 300.658167 -316.013204) (xy 300.628602 -316.052548)
			(xy 300.593109 -316.08664) (xy 300.552606 -316.114596) (xy 300.508144 -316.135694) (xy 300.460873 -316.149386)
			(xy 300.412018 -316.155318) (xy 300.362843 -316.153337) (xy 300.314624 -316.143493) (xy 300.268608 -316.126041)
			(xy 300.225987 -316.101434) (xy 300.187866 -316.070309) (xy 300.155231 -316.033472) (xy 300.128928 -315.991876)
			(xy 300.109637 -315.9466) (xy 300.09786 -315.898816) (xy 300.0939 -315.849762) (xy 298.805092 -315.849762)
			(xy 298.804597 -315.874369) (xy 298.796702 -315.922946) (xy 298.781118 -315.969627) (xy 298.758247 -316.013204)
			(xy 298.728682 -316.052548) (xy 298.693189 -316.08664) (xy 298.652686 -316.114596) (xy 298.608224 -316.135694)
			(xy 298.560953 -316.149386) (xy 298.512098 -316.155318) (xy 298.462923 -316.153337) (xy 298.414704 -316.143493)
			(xy 298.368688 -316.126041) (xy 298.326067 -316.101434) (xy 298.287946 -316.070309) (xy 298.255311 -316.033472)
			(xy 298.229008 -315.991876) (xy 298.209717 -315.9466) (xy 298.19794 -315.898816) (xy 298.19398 -315.849762)
			(xy 296.905172 -315.849762) (xy 296.904677 -315.874369) (xy 296.896782 -315.922946) (xy 296.881198 -315.969627)
			(xy 296.858327 -316.013204) (xy 296.828762 -316.052548) (xy 296.793269 -316.08664) (xy 296.752766 -316.114596)
			(xy 296.708304 -316.135694) (xy 296.661033 -316.149386) (xy 296.612178 -316.155318) (xy 296.563003 -316.153337)
			(xy 296.514784 -316.143493) (xy 296.468768 -316.126041) (xy 296.426147 -316.101434) (xy 296.388026 -316.070309)
			(xy 296.355391 -316.033472) (xy 296.329088 -315.991876) (xy 296.309797 -315.9466) (xy 296.29802 -315.898816)
			(xy 296.29406 -315.849762) (xy 295.004998 -315.849762) (xy 295.004503 -315.874369) (xy 294.996608 -315.922946)
			(xy 294.981024 -315.969627) (xy 294.958153 -316.013204) (xy 294.928588 -316.052548) (xy 294.893095 -316.08664)
			(xy 294.852592 -316.114596) (xy 294.80813 -316.135694) (xy 294.760859 -316.149386) (xy 294.712004 -316.155318)
			(xy 294.662829 -316.153337) (xy 294.61461 -316.143493) (xy 294.568594 -316.126041) (xy 294.525973 -316.101434)
			(xy 294.487852 -316.070309) (xy 294.455217 -316.033472) (xy 294.428914 -315.991876) (xy 294.409623 -315.9466)
			(xy 294.397846 -315.898816) (xy 294.393886 -315.849762) (xy 293.105078 -315.849762) (xy 293.104583 -315.874369)
			(xy 293.096688 -315.922946) (xy 293.081104 -315.969627) (xy 293.058233 -316.013204) (xy 293.028668 -316.052548)
			(xy 292.993175 -316.08664) (xy 292.952672 -316.114596) (xy 292.90821 -316.135694) (xy 292.860939 -316.149386)
			(xy 292.812084 -316.155318) (xy 292.762909 -316.153337) (xy 292.71469 -316.143493) (xy 292.668674 -316.126041)
			(xy 292.626053 -316.101434) (xy 292.587932 -316.070309) (xy 292.555297 -316.033472) (xy 292.528994 -315.991876)
			(xy 292.509703 -315.9466) (xy 292.497926 -315.898816) (xy 292.493966 -315.849762) (xy 291.205158 -315.849762)
			(xy 291.204663 -315.874369) (xy 291.196768 -315.922946) (xy 291.181184 -315.969627) (xy 291.158313 -316.013204)
			(xy 291.128748 -316.052548) (xy 291.093255 -316.08664) (xy 291.052752 -316.114596) (xy 291.00829 -316.135694)
			(xy 290.961019 -316.149386) (xy 290.912164 -316.155318) (xy 290.862989 -316.153337) (xy 290.81477 -316.143493)
			(xy 290.768754 -316.126041) (xy 290.726133 -316.101434) (xy 290.688012 -316.070309) (xy 290.655377 -316.033472)
			(xy 290.629074 -315.991876) (xy 290.609783 -315.9466) (xy 290.598006 -315.898816) (xy 290.594046 -315.849762)
			(xy 289.305238 -315.849762) (xy 289.304743 -315.874369) (xy 289.296848 -315.922946) (xy 289.281264 -315.969627)
			(xy 289.258393 -316.013204) (xy 289.228828 -316.052548) (xy 289.193335 -316.08664) (xy 289.152832 -316.114596)
			(xy 289.10837 -316.135694) (xy 289.061099 -316.149386) (xy 289.012244 -316.155318) (xy 288.963069 -316.153337)
			(xy 288.91485 -316.143493) (xy 288.868834 -316.126041) (xy 288.826213 -316.101434) (xy 288.788092 -316.070309)
			(xy 288.755457 -316.033472) (xy 288.729154 -315.991876) (xy 288.709863 -315.9466) (xy 288.698086 -315.898816)
			(xy 288.694126 -315.849762) (xy 287.405064 -315.849762) (xy 287.404569 -315.874369) (xy 287.396674 -315.922946)
			(xy 287.38109 -315.969627) (xy 287.358219 -316.013204) (xy 287.328654 -316.052548) (xy 287.293161 -316.08664)
			(xy 287.252658 -316.114596) (xy 287.208196 -316.135694) (xy 287.160925 -316.149386) (xy 287.11207 -316.155318)
			(xy 287.062895 -316.153337) (xy 287.014676 -316.143493) (xy 286.96866 -316.126041) (xy 286.926039 -316.101434)
			(xy 286.887918 -316.070309) (xy 286.855283 -316.033472) (xy 286.82898 -315.991876) (xy 286.809689 -315.9466)
			(xy 286.797912 -315.898816) (xy 286.793952 -315.849762) (xy 285.505144 -315.849762) (xy 285.504649 -315.874369)
			(xy 285.496754 -315.922946) (xy 285.48117 -315.969627) (xy 285.458299 -316.013204) (xy 285.428734 -316.052548)
			(xy 285.393241 -316.08664) (xy 285.352738 -316.114596) (xy 285.308276 -316.135694) (xy 285.261005 -316.149386)
			(xy 285.21215 -316.155318) (xy 285.162975 -316.153337) (xy 285.114756 -316.143493) (xy 285.06874 -316.126041)
			(xy 285.026119 -316.101434) (xy 284.987998 -316.070309) (xy 284.955363 -316.033472) (xy 284.92906 -315.991876)
			(xy 284.909769 -315.9466) (xy 284.897992 -315.898816) (xy 284.894032 -315.849762) (xy 283.605224 -315.849762)
			(xy 283.604729 -315.874369) (xy 283.596834 -315.922946) (xy 283.58125 -315.969627) (xy 283.558379 -316.013204)
			(xy 283.528814 -316.052548) (xy 283.493321 -316.08664) (xy 283.452818 -316.114596) (xy 283.408356 -316.135694)
			(xy 283.361085 -316.149386) (xy 283.31223 -316.155318) (xy 283.263055 -316.153337) (xy 283.214836 -316.143493)
			(xy 283.16882 -316.126041) (xy 283.126199 -316.101434) (xy 283.088078 -316.070309) (xy 283.055443 -316.033472)
			(xy 283.02914 -315.991876) (xy 283.009849 -315.9466) (xy 282.998072 -315.898816) (xy 282.994112 -315.849762)
			(xy 281.70505 -315.849762) (xy 281.704555 -315.874369) (xy 281.69666 -315.922946) (xy 281.681076 -315.969627)
			(xy 281.658205 -316.013204) (xy 281.62864 -316.052548) (xy 281.593147 -316.08664) (xy 281.552644 -316.114596)
			(xy 281.508182 -316.135694) (xy 281.460911 -316.149386) (xy 281.412056 -316.155318) (xy 281.362881 -316.153337)
			(xy 281.314662 -316.143493) (xy 281.268646 -316.126041) (xy 281.226025 -316.101434) (xy 281.187904 -316.070309)
			(xy 281.155269 -316.033472) (xy 281.128966 -315.991876) (xy 281.109675 -315.9466) (xy 281.097898 -315.898816)
			(xy 281.093938 -315.849762) (xy 279.80513 -315.849762) (xy 279.804635 -315.874369) (xy 279.79674 -315.922946)
			(xy 279.781156 -315.969627) (xy 279.758285 -316.013204) (xy 279.72872 -316.052548) (xy 279.693227 -316.08664)
			(xy 279.652724 -316.114596) (xy 279.608262 -316.135694) (xy 279.560991 -316.149386) (xy 279.512136 -316.155318)
			(xy 279.462961 -316.153337) (xy 279.414742 -316.143493) (xy 279.368726 -316.126041) (xy 279.326105 -316.101434)
			(xy 279.287984 -316.070309) (xy 279.255349 -316.033472) (xy 279.229046 -315.991876) (xy 279.209755 -315.9466)
			(xy 279.197978 -315.898816) (xy 279.194018 -315.849762) (xy 277.90521 -315.849762) (xy 277.904715 -315.874369)
			(xy 277.89682 -315.922946) (xy 277.881236 -315.969627) (xy 277.858365 -316.013204) (xy 277.8288 -316.052548)
			(xy 277.793307 -316.08664) (xy 277.752804 -316.114596) (xy 277.708342 -316.135694) (xy 277.661071 -316.149386)
			(xy 277.612216 -316.155318) (xy 277.563041 -316.153337) (xy 277.514822 -316.143493) (xy 277.468806 -316.126041)
			(xy 277.426185 -316.101434) (xy 277.388064 -316.070309) (xy 277.355429 -316.033472) (xy 277.329126 -315.991876)
			(xy 277.309835 -315.9466) (xy 277.298058 -315.898816) (xy 277.294098 -315.849762) (xy 276.005036 -315.849762)
			(xy 276.004541 -315.874369) (xy 275.996646 -315.922946) (xy 275.981062 -315.969627) (xy 275.958191 -316.013204)
			(xy 275.928626 -316.052548) (xy 275.893133 -316.08664) (xy 275.85263 -316.114596) (xy 275.808168 -316.135694)
			(xy 275.760897 -316.149386) (xy 275.712042 -316.155318) (xy 275.662867 -316.153337) (xy 275.614648 -316.143493)
			(xy 275.568632 -316.126041) (xy 275.526011 -316.101434) (xy 275.48789 -316.070309) (xy 275.455255 -316.033472)
			(xy 275.428952 -315.991876) (xy 275.409661 -315.9466) (xy 275.397884 -315.898816) (xy 275.393924 -315.849762)
			(xy 274.105116 -315.849762) (xy 274.104621 -315.874369) (xy 274.096726 -315.922946) (xy 274.081142 -315.969627)
			(xy 274.058271 -316.013204) (xy 274.028706 -316.052548) (xy 273.993213 -316.08664) (xy 273.95271 -316.114596)
			(xy 273.908248 -316.135694) (xy 273.860977 -316.149386) (xy 273.812122 -316.155318) (xy 273.762947 -316.153337)
			(xy 273.714728 -316.143493) (xy 273.668712 -316.126041) (xy 273.626091 -316.101434) (xy 273.58797 -316.070309)
			(xy 273.555335 -316.033472) (xy 273.529032 -315.991876) (xy 273.509741 -315.9466) (xy 273.497964 -315.898816)
			(xy 273.494004 -315.849762) (xy 272.205196 -315.849762) (xy 272.204701 -315.874369) (xy 272.196806 -315.922946)
			(xy 272.181222 -315.969627) (xy 272.158351 -316.013204) (xy 272.128786 -316.052548) (xy 272.093293 -316.08664)
			(xy 272.05279 -316.114596) (xy 272.008328 -316.135694) (xy 271.961057 -316.149386) (xy 271.912202 -316.155318)
			(xy 271.863027 -316.153337) (xy 271.814808 -316.143493) (xy 271.768792 -316.126041) (xy 271.726171 -316.101434)
			(xy 271.68805 -316.070309) (xy 271.655415 -316.033472) (xy 271.629112 -315.991876) (xy 271.609821 -315.9466)
			(xy 271.598044 -315.898816) (xy 271.594084 -315.849762) (xy 196.005196 -315.849762) (xy 196.004701 -315.874369)
			(xy 195.996806 -315.922946) (xy 195.981222 -315.969627) (xy 195.958351 -316.013204) (xy 195.928786 -316.052548)
			(xy 195.893293 -316.08664) (xy 195.85279 -316.114596) (xy 195.808328 -316.135694) (xy 195.761057 -316.149386)
			(xy 195.712202 -316.155318) (xy 195.663027 -316.153337) (xy 195.614808 -316.143493) (xy 195.568792 -316.126041)
			(xy 195.526171 -316.101434) (xy 195.48805 -316.070309) (xy 195.455415 -316.033472) (xy 195.429112 -315.991876)
			(xy 195.409821 -315.9466) (xy 195.398044 -315.898816) (xy 195.394084 -315.849762) (xy 194.105276 -315.849762)
			(xy 194.104781 -315.874369) (xy 194.096886 -315.922946) (xy 194.081302 -315.969627) (xy 194.058431 -316.013204)
			(xy 194.028866 -316.052548) (xy 193.993373 -316.08664) (xy 193.95287 -316.114596) (xy 193.908408 -316.135694)
			(xy 193.861137 -316.149386) (xy 193.812282 -316.155318) (xy 193.763107 -316.153337) (xy 193.714888 -316.143493)
			(xy 193.668872 -316.126041) (xy 193.626251 -316.101434) (xy 193.58813 -316.070309) (xy 193.555495 -316.033472)
			(xy 193.529192 -315.991876) (xy 193.509901 -315.9466) (xy 193.498124 -315.898816) (xy 193.494164 -315.849762)
			(xy 192.205356 -315.849762) (xy 192.204861 -315.874369) (xy 192.196966 -315.922946) (xy 192.181382 -315.969627)
			(xy 192.158511 -316.013204) (xy 192.128946 -316.052548) (xy 192.093453 -316.08664) (xy 192.05295 -316.114596)
			(xy 192.008488 -316.135694) (xy 191.961217 -316.149386) (xy 191.912362 -316.155318) (xy 191.863187 -316.153337)
			(xy 191.814968 -316.143493) (xy 191.768952 -316.126041) (xy 191.726331 -316.101434) (xy 191.68821 -316.070309)
			(xy 191.655575 -316.033472) (xy 191.629272 -315.991876) (xy 191.609981 -315.9466) (xy 191.598204 -315.898816)
			(xy 191.594244 -315.849762) (xy 190.305182 -315.849762) (xy 190.304687 -315.874369) (xy 190.296792 -315.922946)
			(xy 190.281208 -315.969627) (xy 190.258337 -316.013204) (xy 190.228772 -316.052548) (xy 190.193279 -316.08664)
			(xy 190.152776 -316.114596) (xy 190.108314 -316.135694) (xy 190.061043 -316.149386) (xy 190.012188 -316.155318)
			(xy 189.963013 -316.153337) (xy 189.914794 -316.143493) (xy 189.868778 -316.126041) (xy 189.826157 -316.101434)
			(xy 189.788036 -316.070309) (xy 189.755401 -316.033472) (xy 189.729098 -315.991876) (xy 189.709807 -315.9466)
			(xy 189.69803 -315.898816) (xy 189.69407 -315.849762) (xy 188.405262 -315.849762) (xy 188.404767 -315.874369)
			(xy 188.396872 -315.922946) (xy 188.381288 -315.969627) (xy 188.358417 -316.013204) (xy 188.328852 -316.052548)
			(xy 188.293359 -316.08664) (xy 188.252856 -316.114596) (xy 188.208394 -316.135694) (xy 188.161123 -316.149386)
			(xy 188.112268 -316.155318) (xy 188.063093 -316.153337) (xy 188.014874 -316.143493) (xy 187.968858 -316.126041)
			(xy 187.926237 -316.101434) (xy 187.888116 -316.070309) (xy 187.855481 -316.033472) (xy 187.829178 -315.991876)
			(xy 187.809887 -315.9466) (xy 187.79811 -315.898816) (xy 187.79415 -315.849762) (xy 186.505342 -315.849762)
			(xy 186.504847 -315.874369) (xy 186.496952 -315.922946) (xy 186.481368 -315.969627) (xy 186.458497 -316.013204)
			(xy 186.428932 -316.052548) (xy 186.393439 -316.08664) (xy 186.352936 -316.114596) (xy 186.308474 -316.135694)
			(xy 186.261203 -316.149386) (xy 186.212348 -316.155318) (xy 186.163173 -316.153337) (xy 186.114954 -316.143493)
			(xy 186.068938 -316.126041) (xy 186.026317 -316.101434) (xy 185.988196 -316.070309) (xy 185.955561 -316.033472)
			(xy 185.929258 -315.991876) (xy 185.909967 -315.9466) (xy 185.89819 -315.898816) (xy 185.89423 -315.849762)
			(xy 184.605168 -315.849762) (xy 184.604673 -315.874369) (xy 184.596778 -315.922946) (xy 184.581194 -315.969627)
			(xy 184.558323 -316.013204) (xy 184.528758 -316.052548) (xy 184.493265 -316.08664) (xy 184.452762 -316.114596)
			(xy 184.4083 -316.135694) (xy 184.361029 -316.149386) (xy 184.312174 -316.155318) (xy 184.262999 -316.153337)
			(xy 184.21478 -316.143493) (xy 184.168764 -316.126041) (xy 184.126143 -316.101434) (xy 184.088022 -316.070309)
			(xy 184.055387 -316.033472) (xy 184.029084 -315.991876) (xy 184.009793 -315.9466) (xy 183.998016 -315.898816)
			(xy 183.994056 -315.849762) (xy 182.705248 -315.849762) (xy 182.704753 -315.874369) (xy 182.696858 -315.922946)
			(xy 182.681274 -315.969627) (xy 182.658403 -316.013204) (xy 182.628838 -316.052548) (xy 182.593345 -316.08664)
			(xy 182.552842 -316.114596) (xy 182.50838 -316.135694) (xy 182.461109 -316.149386) (xy 182.412254 -316.155318)
			(xy 182.363079 -316.153337) (xy 182.31486 -316.143493) (xy 182.268844 -316.126041) (xy 182.226223 -316.101434)
			(xy 182.188102 -316.070309) (xy 182.155467 -316.033472) (xy 182.129164 -315.991876) (xy 182.109873 -315.9466)
			(xy 182.098096 -315.898816) (xy 182.094136 -315.849762) (xy 180.805328 -315.849762) (xy 180.804833 -315.874369)
			(xy 180.796938 -315.922946) (xy 180.781354 -315.969627) (xy 180.758483 -316.013204) (xy 180.728918 -316.052548)
			(xy 180.693425 -316.08664) (xy 180.652922 -316.114596) (xy 180.60846 -316.135694) (xy 180.561189 -316.149386)
			(xy 180.512334 -316.155318) (xy 180.463159 -316.153337) (xy 180.41494 -316.143493) (xy 180.368924 -316.126041)
			(xy 180.326303 -316.101434) (xy 180.288182 -316.070309) (xy 180.255547 -316.033472) (xy 180.229244 -315.991876)
			(xy 180.209953 -315.9466) (xy 180.198176 -315.898816) (xy 180.194216 -315.849762) (xy 178.905154 -315.849762)
			(xy 178.904659 -315.874369) (xy 178.896764 -315.922946) (xy 178.88118 -315.969627) (xy 178.858309 -316.013204)
			(xy 178.828744 -316.052548) (xy 178.793251 -316.08664) (xy 178.752748 -316.114596) (xy 178.708286 -316.135694)
			(xy 178.661015 -316.149386) (xy 178.61216 -316.155318) (xy 178.562985 -316.153337) (xy 178.514766 -316.143493)
			(xy 178.46875 -316.126041) (xy 178.426129 -316.101434) (xy 178.388008 -316.070309) (xy 178.355373 -316.033472)
			(xy 178.32907 -315.991876) (xy 178.309779 -315.9466) (xy 178.298002 -315.898816) (xy 178.294042 -315.849762)
			(xy 177.005234 -315.849762) (xy 177.004739 -315.874369) (xy 176.996844 -315.922946) (xy 176.98126 -315.969627)
			(xy 176.958389 -316.013204) (xy 176.928824 -316.052548) (xy 176.893331 -316.08664) (xy 176.852828 -316.114596)
			(xy 176.808366 -316.135694) (xy 176.761095 -316.149386) (xy 176.71224 -316.155318) (xy 176.663065 -316.153337)
			(xy 176.614846 -316.143493) (xy 176.56883 -316.126041) (xy 176.526209 -316.101434) (xy 176.488088 -316.070309)
			(xy 176.455453 -316.033472) (xy 176.42915 -315.991876) (xy 176.409859 -315.9466) (xy 176.398082 -315.898816)
			(xy 176.394122 -315.849762) (xy 175.105314 -315.849762) (xy 175.104819 -315.874369) (xy 175.096924 -315.922946)
			(xy 175.08134 -315.969627) (xy 175.058469 -316.013204) (xy 175.028904 -316.052548) (xy 174.993411 -316.08664)
			(xy 174.952908 -316.114596) (xy 174.908446 -316.135694) (xy 174.861175 -316.149386) (xy 174.81232 -316.155318)
			(xy 174.763145 -316.153337) (xy 174.714926 -316.143493) (xy 174.66891 -316.126041) (xy 174.626289 -316.101434)
			(xy 174.588168 -316.070309) (xy 174.555533 -316.033472) (xy 174.52923 -315.991876) (xy 174.509939 -315.9466)
			(xy 174.498162 -315.898816) (xy 174.494202 -315.849762) (xy 173.205394 -315.849762) (xy 173.204899 -315.874369)
			(xy 173.197004 -315.922946) (xy 173.18142 -315.969627) (xy 173.158549 -316.013204) (xy 173.128984 -316.052548)
			(xy 173.093491 -316.08664) (xy 173.052988 -316.114596) (xy 173.008526 -316.135694) (xy 172.961255 -316.149386)
			(xy 172.9124 -316.155318) (xy 172.863225 -316.153337) (xy 172.815006 -316.143493) (xy 172.76899 -316.126041)
			(xy 172.726369 -316.101434) (xy 172.688248 -316.070309) (xy 172.655613 -316.033472) (xy 172.62931 -315.991876)
			(xy 172.610019 -315.9466) (xy 172.598242 -315.898816) (xy 172.594282 -315.849762) (xy 171.30522 -315.849762)
			(xy 171.304725 -315.874369) (xy 171.29683 -315.922946) (xy 171.281246 -315.969627) (xy 171.258375 -316.013204)
			(xy 171.22881 -316.052548) (xy 171.193317 -316.08664) (xy 171.152814 -316.114596) (xy 171.108352 -316.135694)
			(xy 171.061081 -316.149386) (xy 171.012226 -316.155318) (xy 170.963051 -316.153337) (xy 170.914832 -316.143493)
			(xy 170.868816 -316.126041) (xy 170.826195 -316.101434) (xy 170.788074 -316.070309) (xy 170.755439 -316.033472)
			(xy 170.729136 -315.991876) (xy 170.709845 -315.9466) (xy 170.698068 -315.898816) (xy 170.694108 -315.849762)
			(xy 169.4053 -315.849762) (xy 169.404805 -315.874369) (xy 169.39691 -315.922946) (xy 169.381326 -315.969627)
			(xy 169.358455 -316.013204) (xy 169.32889 -316.052548) (xy 169.293397 -316.08664) (xy 169.252894 -316.114596)
			(xy 169.208432 -316.135694) (xy 169.161161 -316.149386) (xy 169.112306 -316.155318) (xy 169.063131 -316.153337)
			(xy 169.014912 -316.143493) (xy 168.968896 -316.126041) (xy 168.926275 -316.101434) (xy 168.888154 -316.070309)
			(xy 168.855519 -316.033472) (xy 168.829216 -315.991876) (xy 168.809925 -315.9466) (xy 168.798148 -315.898816)
			(xy 168.794188 -315.849762) (xy 167.50538 -315.849762) (xy 167.504885 -315.874369) (xy 167.49699 -315.922946)
			(xy 167.481406 -315.969627) (xy 167.458535 -316.013204) (xy 167.42897 -316.052548) (xy 167.393477 -316.08664)
			(xy 167.352974 -316.114596) (xy 167.308512 -316.135694) (xy 167.261241 -316.149386) (xy 167.212386 -316.155318)
			(xy 167.163211 -316.153337) (xy 167.114992 -316.143493) (xy 167.068976 -316.126041) (xy 167.026355 -316.101434)
			(xy 166.988234 -316.070309) (xy 166.955599 -316.033472) (xy 166.929296 -315.991876) (xy 166.910005 -315.9466)
			(xy 166.898228 -315.898816) (xy 166.894268 -315.849762) (xy 165.605206 -315.849762) (xy 165.604711 -315.874369)
			(xy 165.596816 -315.922946) (xy 165.581232 -315.969627) (xy 165.558361 -316.013204) (xy 165.528796 -316.052548)
			(xy 165.493303 -316.08664) (xy 165.4528 -316.114596) (xy 165.408338 -316.135694) (xy 165.361067 -316.149386)
			(xy 165.312212 -316.155318) (xy 165.263037 -316.153337) (xy 165.214818 -316.143493) (xy 165.168802 -316.126041)
			(xy 165.126181 -316.101434) (xy 165.08806 -316.070309) (xy 165.055425 -316.033472) (xy 165.029122 -315.991876)
			(xy 165.009831 -315.9466) (xy 164.998054 -315.898816) (xy 164.994094 -315.849762) (xy 163.705286 -315.849762)
			(xy 163.704791 -315.874369) (xy 163.696896 -315.922946) (xy 163.681312 -315.969627) (xy 163.658441 -316.013204)
			(xy 163.628876 -316.052548) (xy 163.593383 -316.08664) (xy 163.55288 -316.114596) (xy 163.508418 -316.135694)
			(xy 163.461147 -316.149386) (xy 163.412292 -316.155318) (xy 163.363117 -316.153337) (xy 163.314898 -316.143493)
			(xy 163.268882 -316.126041) (xy 163.226261 -316.101434) (xy 163.18814 -316.070309) (xy 163.155505 -316.033472)
			(xy 163.129202 -315.991876) (xy 163.109911 -315.9466) (xy 163.098134 -315.898816) (xy 163.094174 -315.849762)
			(xy 161.805366 -315.849762) (xy 161.804871 -315.874369) (xy 161.796976 -315.922946) (xy 161.781392 -315.969627)
			(xy 161.758521 -316.013204) (xy 161.728956 -316.052548) (xy 161.693463 -316.08664) (xy 161.65296 -316.114596)
			(xy 161.608498 -316.135694) (xy 161.561227 -316.149386) (xy 161.512372 -316.155318) (xy 161.463197 -316.153337)
			(xy 161.414978 -316.143493) (xy 161.368962 -316.126041) (xy 161.326341 -316.101434) (xy 161.28822 -316.070309)
			(xy 161.255585 -316.033472) (xy 161.229282 -315.991876) (xy 161.209991 -315.9466) (xy 161.198214 -315.898816)
			(xy 161.194254 -315.849762) (xy 159.905192 -315.849762) (xy 159.904697 -315.874369) (xy 159.896802 -315.922946)
			(xy 159.881218 -315.969627) (xy 159.858347 -316.013204) (xy 159.828782 -316.052548) (xy 159.793289 -316.08664)
			(xy 159.752786 -316.114596) (xy 159.708324 -316.135694) (xy 159.661053 -316.149386) (xy 159.612198 -316.155318)
			(xy 159.563023 -316.153337) (xy 159.514804 -316.143493) (xy 159.468788 -316.126041) (xy 159.426167 -316.101434)
			(xy 159.388046 -316.070309) (xy 159.355411 -316.033472) (xy 159.329108 -315.991876) (xy 159.309817 -315.9466)
			(xy 159.29804 -315.898816) (xy 159.29408 -315.849762) (xy 158.005272 -315.849762) (xy 158.004777 -315.874369)
			(xy 157.996882 -315.922946) (xy 157.981298 -315.969627) (xy 157.958427 -316.013204) (xy 157.928862 -316.052548)
			(xy 157.893369 -316.08664) (xy 157.852866 -316.114596) (xy 157.808404 -316.135694) (xy 157.761133 -316.149386)
			(xy 157.712278 -316.155318) (xy 157.663103 -316.153337) (xy 157.614884 -316.143493) (xy 157.568868 -316.126041)
			(xy 157.526247 -316.101434) (xy 157.488126 -316.070309) (xy 157.455491 -316.033472) (xy 157.429188 -315.991876)
			(xy 157.409897 -315.9466) (xy 157.39812 -315.898816) (xy 157.39416 -315.849762) (xy 156.105352 -315.849762)
			(xy 156.104857 -315.874369) (xy 156.096962 -315.922946) (xy 156.081378 -315.969627) (xy 156.058507 -316.013204)
			(xy 156.028942 -316.052548) (xy 155.993449 -316.08664) (xy 155.952946 -316.114596) (xy 155.908484 -316.135694)
			(xy 155.861213 -316.149386) (xy 155.812358 -316.155318) (xy 155.763183 -316.153337) (xy 155.714964 -316.143493)
			(xy 155.668948 -316.126041) (xy 155.626327 -316.101434) (xy 155.588206 -316.070309) (xy 155.555571 -316.033472)
			(xy 155.529268 -315.991876) (xy 155.509977 -315.9466) (xy 155.4982 -315.898816) (xy 155.49424 -315.849762)
			(xy 79.905098 -315.849762) (xy 79.904603 -315.874369) (xy 79.896708 -315.922946) (xy 79.881124 -315.969627)
			(xy 79.858253 -316.013204) (xy 79.828688 -316.052548) (xy 79.793195 -316.08664) (xy 79.752692 -316.114596)
			(xy 79.70823 -316.135694) (xy 79.660959 -316.149386) (xy 79.612104 -316.155318) (xy 79.562929 -316.153337)
			(xy 79.51471 -316.143493) (xy 79.468694 -316.126041) (xy 79.426073 -316.101434) (xy 79.387952 -316.070309)
			(xy 79.355317 -316.033472) (xy 79.329014 -315.991876) (xy 79.309723 -315.9466) (xy 79.297946 -315.898816)
			(xy 79.293986 -315.849762) (xy 78.005178 -315.849762) (xy 78.004683 -315.874369) (xy 77.996788 -315.922946)
			(xy 77.981204 -315.969627) (xy 77.958333 -316.013204) (xy 77.928768 -316.052548) (xy 77.893275 -316.08664)
			(xy 77.852772 -316.114596) (xy 77.80831 -316.135694) (xy 77.761039 -316.149386) (xy 77.712184 -316.155318)
			(xy 77.663009 -316.153337) (xy 77.61479 -316.143493) (xy 77.568774 -316.126041) (xy 77.526153 -316.101434)
			(xy 77.488032 -316.070309) (xy 77.455397 -316.033472) (xy 77.429094 -315.991876) (xy 77.409803 -315.9466)
			(xy 77.398026 -315.898816) (xy 77.394066 -315.849762) (xy 76.105258 -315.849762) (xy 76.104763 -315.874369)
			(xy 76.096868 -315.922946) (xy 76.081284 -315.969627) (xy 76.058413 -316.013204) (xy 76.028848 -316.052548)
			(xy 75.993355 -316.08664) (xy 75.952852 -316.114596) (xy 75.90839 -316.135694) (xy 75.861119 -316.149386)
			(xy 75.812264 -316.155318) (xy 75.763089 -316.153337) (xy 75.71487 -316.143493) (xy 75.668854 -316.126041)
			(xy 75.626233 -316.101434) (xy 75.588112 -316.070309) (xy 75.555477 -316.033472) (xy 75.529174 -315.991876)
			(xy 75.509883 -315.9466) (xy 75.498106 -315.898816) (xy 75.494146 -315.849762) (xy 74.205084 -315.849762)
			(xy 74.204589 -315.874369) (xy 74.196694 -315.922946) (xy 74.18111 -315.969627) (xy 74.158239 -316.013204)
			(xy 74.128674 -316.052548) (xy 74.093181 -316.08664) (xy 74.052678 -316.114596) (xy 74.008216 -316.135694)
			(xy 73.960945 -316.149386) (xy 73.91209 -316.155318) (xy 73.862915 -316.153337) (xy 73.814696 -316.143493)
			(xy 73.76868 -316.126041) (xy 73.726059 -316.101434) (xy 73.687938 -316.070309) (xy 73.655303 -316.033472)
			(xy 73.629 -315.991876) (xy 73.609709 -315.9466) (xy 73.597932 -315.898816) (xy 73.593972 -315.849762)
			(xy 72.305164 -315.849762) (xy 72.304669 -315.874369) (xy 72.296774 -315.922946) (xy 72.28119 -315.969627)
			(xy 72.258319 -316.013204) (xy 72.228754 -316.052548) (xy 72.193261 -316.08664) (xy 72.152758 -316.114596)
			(xy 72.108296 -316.135694) (xy 72.061025 -316.149386) (xy 72.01217 -316.155318) (xy 71.962995 -316.153337)
			(xy 71.914776 -316.143493) (xy 71.86876 -316.126041) (xy 71.826139 -316.101434) (xy 71.788018 -316.070309)
			(xy 71.755383 -316.033472) (xy 71.72908 -315.991876) (xy 71.709789 -315.9466) (xy 71.698012 -315.898816)
			(xy 71.694052 -315.849762) (xy 70.405244 -315.849762) (xy 70.404749 -315.874369) (xy 70.396854 -315.922946)
			(xy 70.38127 -315.969627) (xy 70.358399 -316.013204) (xy 70.328834 -316.052548) (xy 70.293341 -316.08664)
			(xy 70.252838 -316.114596) (xy 70.208376 -316.135694) (xy 70.161105 -316.149386) (xy 70.11225 -316.155318)
			(xy 70.063075 -316.153337) (xy 70.014856 -316.143493) (xy 69.96884 -316.126041) (xy 69.926219 -316.101434)
			(xy 69.888098 -316.070309) (xy 69.855463 -316.033472) (xy 69.82916 -315.991876) (xy 69.809869 -315.9466)
			(xy 69.798092 -315.898816) (xy 69.794132 -315.849762) (xy 68.50507 -315.849762) (xy 68.504575 -315.874369)
			(xy 68.49668 -315.922946) (xy 68.481096 -315.969627) (xy 68.458225 -316.013204) (xy 68.42866 -316.052548)
			(xy 68.393167 -316.08664) (xy 68.352664 -316.114596) (xy 68.308202 -316.135694) (xy 68.260931 -316.149386)
			(xy 68.212076 -316.155318) (xy 68.162901 -316.153337) (xy 68.114682 -316.143493) (xy 68.068666 -316.126041)
			(xy 68.026045 -316.101434) (xy 67.987924 -316.070309) (xy 67.955289 -316.033472) (xy 67.928986 -315.991876)
			(xy 67.909695 -315.9466) (xy 67.897918 -315.898816) (xy 67.893958 -315.849762) (xy 66.60515 -315.849762)
			(xy 66.604655 -315.874369) (xy 66.59676 -315.922946) (xy 66.581176 -315.969627) (xy 66.558305 -316.013204)
			(xy 66.52874 -316.052548) (xy 66.493247 -316.08664) (xy 66.452744 -316.114596) (xy 66.408282 -316.135694)
			(xy 66.361011 -316.149386) (xy 66.312156 -316.155318) (xy 66.262981 -316.153337) (xy 66.214762 -316.143493)
			(xy 66.168746 -316.126041) (xy 66.126125 -316.101434) (xy 66.088004 -316.070309) (xy 66.055369 -316.033472)
			(xy 66.029066 -315.991876) (xy 66.009775 -315.9466) (xy 65.997998 -315.898816) (xy 65.994038 -315.849762)
			(xy 64.70523 -315.849762) (xy 64.704735 -315.874369) (xy 64.69684 -315.922946) (xy 64.681256 -315.969627)
			(xy 64.658385 -316.013204) (xy 64.62882 -316.052548) (xy 64.593327 -316.08664) (xy 64.552824 -316.114596)
			(xy 64.508362 -316.135694) (xy 64.461091 -316.149386) (xy 64.412236 -316.155318) (xy 64.363061 -316.153337)
			(xy 64.314842 -316.143493) (xy 64.268826 -316.126041) (xy 64.226205 -316.101434) (xy 64.188084 -316.070309)
			(xy 64.155449 -316.033472) (xy 64.129146 -315.991876) (xy 64.109855 -315.9466) (xy 64.098078 -315.898816)
			(xy 64.094118 -315.849762) (xy 62.805056 -315.849762) (xy 62.804561 -315.874369) (xy 62.796666 -315.922946)
			(xy 62.781082 -315.969627) (xy 62.758211 -316.013204) (xy 62.728646 -316.052548) (xy 62.693153 -316.08664)
			(xy 62.65265 -316.114596) (xy 62.608188 -316.135694) (xy 62.560917 -316.149386) (xy 62.512062 -316.155318)
			(xy 62.462887 -316.153337) (xy 62.414668 -316.143493) (xy 62.368652 -316.126041) (xy 62.326031 -316.101434)
			(xy 62.28791 -316.070309) (xy 62.255275 -316.033472) (xy 62.228972 -315.991876) (xy 62.209681 -315.9466)
			(xy 62.197904 -315.898816) (xy 62.193944 -315.849762) (xy 60.905136 -315.849762) (xy 60.904641 -315.874369)
			(xy 60.896746 -315.922946) (xy 60.881162 -315.969627) (xy 60.858291 -316.013204) (xy 60.828726 -316.052548)
			(xy 60.793233 -316.08664) (xy 60.75273 -316.114596) (xy 60.708268 -316.135694) (xy 60.660997 -316.149386)
			(xy 60.612142 -316.155318) (xy 60.562967 -316.153337) (xy 60.514748 -316.143493) (xy 60.468732 -316.126041)
			(xy 60.426111 -316.101434) (xy 60.38799 -316.070309) (xy 60.355355 -316.033472) (xy 60.329052 -315.991876)
			(xy 60.309761 -315.9466) (xy 60.297984 -315.898816) (xy 60.294024 -315.849762) (xy 59.005216 -315.849762)
			(xy 59.004721 -315.874369) (xy 58.996826 -315.922946) (xy 58.981242 -315.969627) (xy 58.958371 -316.013204)
			(xy 58.928806 -316.052548) (xy 58.893313 -316.08664) (xy 58.85281 -316.114596) (xy 58.808348 -316.135694)
			(xy 58.761077 -316.149386) (xy 58.712222 -316.155318) (xy 58.663047 -316.153337) (xy 58.614828 -316.143493)
			(xy 58.568812 -316.126041) (xy 58.526191 -316.101434) (xy 58.48807 -316.070309) (xy 58.455435 -316.033472)
			(xy 58.429132 -315.991876) (xy 58.409841 -315.9466) (xy 58.398064 -315.898816) (xy 58.394104 -315.849762)
			(xy 57.105296 -315.849762) (xy 57.104801 -315.874369) (xy 57.096906 -315.922946) (xy 57.081322 -315.969627)
			(xy 57.058451 -316.013204) (xy 57.028886 -316.052548) (xy 56.993393 -316.08664) (xy 56.95289 -316.114596)
			(xy 56.908428 -316.135694) (xy 56.861157 -316.149386) (xy 56.812302 -316.155318) (xy 56.763127 -316.153337)
			(xy 56.714908 -316.143493) (xy 56.668892 -316.126041) (xy 56.626271 -316.101434) (xy 56.58815 -316.070309)
			(xy 56.555515 -316.033472) (xy 56.529212 -315.991876) (xy 56.509921 -315.9466) (xy 56.498144 -315.898816)
			(xy 56.494184 -315.849762) (xy 55.205122 -315.849762) (xy 55.204627 -315.874369) (xy 55.196732 -315.922946)
			(xy 55.181148 -315.969627) (xy 55.158277 -316.013204) (xy 55.128712 -316.052548) (xy 55.093219 -316.08664)
			(xy 55.052716 -316.114596) (xy 55.008254 -316.135694) (xy 54.960983 -316.149386) (xy 54.912128 -316.155318)
			(xy 54.862953 -316.153337) (xy 54.814734 -316.143493) (xy 54.768718 -316.126041) (xy 54.726097 -316.101434)
			(xy 54.687976 -316.070309) (xy 54.655341 -316.033472) (xy 54.629038 -315.991876) (xy 54.609747 -315.9466)
			(xy 54.59797 -315.898816) (xy 54.59401 -315.849762) (xy 53.305202 -315.849762) (xy 53.304707 -315.874369)
			(xy 53.296812 -315.922946) (xy 53.281228 -315.969627) (xy 53.258357 -316.013204) (xy 53.228792 -316.052548)
			(xy 53.193299 -316.08664) (xy 53.152796 -316.114596) (xy 53.108334 -316.135694) (xy 53.061063 -316.149386)
			(xy 53.012208 -316.155318) (xy 52.963033 -316.153337) (xy 52.914814 -316.143493) (xy 52.868798 -316.126041)
			(xy 52.826177 -316.101434) (xy 52.788056 -316.070309) (xy 52.755421 -316.033472) (xy 52.729118 -315.991876)
			(xy 52.709827 -315.9466) (xy 52.69805 -315.898816) (xy 52.69409 -315.849762) (xy 51.405282 -315.849762)
			(xy 51.404787 -315.874369) (xy 51.396892 -315.922946) (xy 51.381308 -315.969627) (xy 51.358437 -316.013204)
			(xy 51.328872 -316.052548) (xy 51.293379 -316.08664) (xy 51.252876 -316.114596) (xy 51.208414 -316.135694)
			(xy 51.161143 -316.149386) (xy 51.112288 -316.155318) (xy 51.063113 -316.153337) (xy 51.014894 -316.143493)
			(xy 50.968878 -316.126041) (xy 50.926257 -316.101434) (xy 50.888136 -316.070309) (xy 50.855501 -316.033472)
			(xy 50.829198 -315.991876) (xy 50.809907 -315.9466) (xy 50.79813 -315.898816) (xy 50.79417 -315.849762)
			(xy 49.505108 -315.849762) (xy 49.504613 -315.874369) (xy 49.496718 -315.922946) (xy 49.481134 -315.969627)
			(xy 49.458263 -316.013204) (xy 49.428698 -316.052548) (xy 49.393205 -316.08664) (xy 49.352702 -316.114596)
			(xy 49.30824 -316.135694) (xy 49.260969 -316.149386) (xy 49.212114 -316.155318) (xy 49.162939 -316.153337)
			(xy 49.11472 -316.143493) (xy 49.068704 -316.126041) (xy 49.026083 -316.101434) (xy 48.987962 -316.070309)
			(xy 48.955327 -316.033472) (xy 48.929024 -315.991876) (xy 48.909733 -315.9466) (xy 48.897956 -315.898816)
			(xy 48.893996 -315.849762) (xy 47.605188 -315.849762) (xy 47.604693 -315.874369) (xy 47.596798 -315.922946)
			(xy 47.581214 -315.969627) (xy 47.558343 -316.013204) (xy 47.528778 -316.052548) (xy 47.493285 -316.08664)
			(xy 47.452782 -316.114596) (xy 47.40832 -316.135694) (xy 47.361049 -316.149386) (xy 47.312194 -316.155318)
			(xy 47.263019 -316.153337) (xy 47.2148 -316.143493) (xy 47.168784 -316.126041) (xy 47.126163 -316.101434)
			(xy 47.088042 -316.070309) (xy 47.055407 -316.033472) (xy 47.029104 -315.991876) (xy 47.009813 -315.9466)
			(xy 46.998036 -315.898816) (xy 46.994076 -315.849762) (xy 45.705268 -315.849762) (xy 45.704773 -315.874369)
			(xy 45.696878 -315.922946) (xy 45.681294 -315.969627) (xy 45.658423 -316.013204) (xy 45.628858 -316.052548)
			(xy 45.593365 -316.08664) (xy 45.552862 -316.114596) (xy 45.5084 -316.135694) (xy 45.461129 -316.149386)
			(xy 45.412274 -316.155318) (xy 45.363099 -316.153337) (xy 45.31488 -316.143493) (xy 45.268864 -316.126041)
			(xy 45.226243 -316.101434) (xy 45.188122 -316.070309) (xy 45.155487 -316.033472) (xy 45.129184 -315.991876)
			(xy 45.109893 -315.9466) (xy 45.098116 -315.898816) (xy 45.094156 -315.849762) (xy 43.805094 -315.849762)
			(xy 43.804599 -315.874369) (xy 43.796704 -315.922946) (xy 43.78112 -315.969627) (xy 43.758249 -316.013204)
			(xy 43.728684 -316.052548) (xy 43.693191 -316.08664) (xy 43.652688 -316.114596) (xy 43.608226 -316.135694)
			(xy 43.560955 -316.149386) (xy 43.5121 -316.155318) (xy 43.462925 -316.153337) (xy 43.414706 -316.143493)
			(xy 43.36869 -316.126041) (xy 43.326069 -316.101434) (xy 43.287948 -316.070309) (xy 43.255313 -316.033472)
			(xy 43.22901 -315.991876) (xy 43.209719 -315.9466) (xy 43.197942 -315.898816) (xy 43.193982 -315.849762)
			(xy 41.905174 -315.849762) (xy 41.904679 -315.874369) (xy 41.896784 -315.922946) (xy 41.8812 -315.969627)
			(xy 41.858329 -316.013204) (xy 41.828764 -316.052548) (xy 41.793271 -316.08664) (xy 41.752768 -316.114596)
			(xy 41.708306 -316.135694) (xy 41.661035 -316.149386) (xy 41.61218 -316.155318) (xy 41.563005 -316.153337)
			(xy 41.514786 -316.143493) (xy 41.46877 -316.126041) (xy 41.426149 -316.101434) (xy 41.388028 -316.070309)
			(xy 41.355393 -316.033472) (xy 41.32909 -315.991876) (xy 41.309799 -315.9466) (xy 41.298022 -315.898816)
			(xy 41.294062 -315.849762) (xy 40.005254 -315.849762) (xy 40.004759 -315.874369) (xy 39.996864 -315.922946)
			(xy 39.98128 -315.969627) (xy 39.958409 -316.013204) (xy 39.928844 -316.052548) (xy 39.893351 -316.08664)
			(xy 39.852848 -316.114596) (xy 39.808386 -316.135694) (xy 39.761115 -316.149386) (xy 39.71226 -316.155318)
			(xy 39.663085 -316.153337) (xy 39.614866 -316.143493) (xy 39.56885 -316.126041) (xy 39.526229 -316.101434)
			(xy 39.488108 -316.070309) (xy 39.455473 -316.033472) (xy 39.42917 -315.991876) (xy 39.409879 -315.9466)
			(xy 39.398102 -315.898816) (xy 39.394142 -315.849762) (xy 0.508 -315.849762) (xy 0.508 -316.799722)
			(xy 36.544008 -316.799722) (xy 36.547968 -316.750668) (xy 36.559745 -316.702884) (xy 36.579036 -316.657608)
			(xy 36.605339 -316.616012) (xy 36.637974 -316.579175) (xy 36.676095 -316.54805) (xy 36.718716 -316.523443)
			(xy 36.764732 -316.505991) (xy 36.812951 -316.496147) (xy 36.862126 -316.494166) (xy 36.910981 -316.500098)
			(xy 36.958252 -316.51379) (xy 37.002714 -316.534888) (xy 37.043217 -316.562844) (xy 37.07871 -316.596936)
			(xy 37.108275 -316.63628) (xy 37.131146 -316.679857) (xy 37.14673 -316.726538) (xy 37.154625 -316.775115)
			(xy 37.15512 -316.799722) (xy 37.493968 -316.799722) (xy 37.497928 -316.750668) (xy 37.509705 -316.702884)
			(xy 37.528996 -316.657608) (xy 37.555299 -316.616012) (xy 37.587934 -316.579175) (xy 37.626055 -316.54805)
			(xy 37.668676 -316.523443) (xy 37.714692 -316.505991) (xy 37.762911 -316.496147) (xy 37.812086 -316.494166)
			(xy 37.860941 -316.500098) (xy 37.908212 -316.51379) (xy 37.952674 -316.534888) (xy 37.993177 -316.562844)
			(xy 38.02867 -316.596936) (xy 38.058235 -316.63628) (xy 38.081106 -316.679857) (xy 38.09669 -316.726538)
			(xy 38.104585 -316.775115) (xy 38.10508 -316.799722) (xy 39.394142 -316.799722) (xy 39.398102 -316.750668)
			(xy 39.409879 -316.702884) (xy 39.42917 -316.657608) (xy 39.455473 -316.616012) (xy 39.488108 -316.579175)
			(xy 39.526229 -316.54805) (xy 39.56885 -316.523443) (xy 39.614866 -316.505991) (xy 39.663085 -316.496147)
			(xy 39.71226 -316.494166) (xy 39.761115 -316.500098) (xy 39.808386 -316.51379) (xy 39.852848 -316.534888)
			(xy 39.893351 -316.562844) (xy 39.928844 -316.596936) (xy 39.958409 -316.63628) (xy 39.98128 -316.679857)
			(xy 39.996864 -316.726538) (xy 40.004759 -316.775115) (xy 40.005254 -316.799722) (xy 41.294062 -316.799722)
			(xy 41.298022 -316.750668) (xy 41.309799 -316.702884) (xy 41.32909 -316.657608) (xy 41.355393 -316.616012)
			(xy 41.388028 -316.579175) (xy 41.426149 -316.54805) (xy 41.46877 -316.523443) (xy 41.514786 -316.505991)
			(xy 41.563005 -316.496147) (xy 41.61218 -316.494166) (xy 41.661035 -316.500098) (xy 41.708306 -316.51379)
			(xy 41.752768 -316.534888) (xy 41.793271 -316.562844) (xy 41.828764 -316.596936) (xy 41.858329 -316.63628)
			(xy 41.8812 -316.679857) (xy 41.896784 -316.726538) (xy 41.904679 -316.775115) (xy 41.905174 -316.799722)
			(xy 43.193982 -316.799722) (xy 43.197942 -316.750668) (xy 43.209719 -316.702884) (xy 43.22901 -316.657608)
			(xy 43.255313 -316.616012) (xy 43.287948 -316.579175) (xy 43.326069 -316.54805) (xy 43.36869 -316.523443)
			(xy 43.414706 -316.505991) (xy 43.462925 -316.496147) (xy 43.5121 -316.494166) (xy 43.560955 -316.500098)
			(xy 43.608226 -316.51379) (xy 43.652688 -316.534888) (xy 43.693191 -316.562844) (xy 43.728684 -316.596936)
			(xy 43.758249 -316.63628) (xy 43.78112 -316.679857) (xy 43.796704 -316.726538) (xy 43.804599 -316.775115)
			(xy 43.805094 -316.799722) (xy 45.094156 -316.799722) (xy 45.098116 -316.750668) (xy 45.109893 -316.702884)
			(xy 45.129184 -316.657608) (xy 45.155487 -316.616012) (xy 45.188122 -316.579175) (xy 45.226243 -316.54805)
			(xy 45.268864 -316.523443) (xy 45.31488 -316.505991) (xy 45.363099 -316.496147) (xy 45.412274 -316.494166)
			(xy 45.461129 -316.500098) (xy 45.5084 -316.51379) (xy 45.552862 -316.534888) (xy 45.593365 -316.562844)
			(xy 45.628858 -316.596936) (xy 45.658423 -316.63628) (xy 45.681294 -316.679857) (xy 45.696878 -316.726538)
			(xy 45.704773 -316.775115) (xy 45.705268 -316.799722) (xy 46.994076 -316.799722) (xy 46.998036 -316.750668)
			(xy 47.009813 -316.702884) (xy 47.029104 -316.657608) (xy 47.055407 -316.616012) (xy 47.088042 -316.579175)
			(xy 47.126163 -316.54805) (xy 47.168784 -316.523443) (xy 47.2148 -316.505991) (xy 47.263019 -316.496147)
			(xy 47.312194 -316.494166) (xy 47.361049 -316.500098) (xy 47.40832 -316.51379) (xy 47.452782 -316.534888)
			(xy 47.493285 -316.562844) (xy 47.528778 -316.596936) (xy 47.558343 -316.63628) (xy 47.581214 -316.679857)
			(xy 47.596798 -316.726538) (xy 47.604693 -316.775115) (xy 47.605188 -316.799722) (xy 48.893996 -316.799722)
			(xy 48.897956 -316.750668) (xy 48.909733 -316.702884) (xy 48.929024 -316.657608) (xy 48.955327 -316.616012)
			(xy 48.987962 -316.579175) (xy 49.026083 -316.54805) (xy 49.068704 -316.523443) (xy 49.11472 -316.505991)
			(xy 49.162939 -316.496147) (xy 49.212114 -316.494166) (xy 49.260969 -316.500098) (xy 49.30824 -316.51379)
			(xy 49.352702 -316.534888) (xy 49.393205 -316.562844) (xy 49.428698 -316.596936) (xy 49.458263 -316.63628)
			(xy 49.481134 -316.679857) (xy 49.496718 -316.726538) (xy 49.504613 -316.775115) (xy 49.505108 -316.799722)
			(xy 50.79417 -316.799722) (xy 50.79813 -316.750668) (xy 50.809907 -316.702884) (xy 50.829198 -316.657608)
			(xy 50.855501 -316.616012) (xy 50.888136 -316.579175) (xy 50.926257 -316.54805) (xy 50.968878 -316.523443)
			(xy 51.014894 -316.505991) (xy 51.063113 -316.496147) (xy 51.112288 -316.494166) (xy 51.161143 -316.500098)
			(xy 51.208414 -316.51379) (xy 51.252876 -316.534888) (xy 51.293379 -316.562844) (xy 51.328872 -316.596936)
			(xy 51.358437 -316.63628) (xy 51.381308 -316.679857) (xy 51.396892 -316.726538) (xy 51.404787 -316.775115)
			(xy 51.405282 -316.799722) (xy 52.69409 -316.799722) (xy 52.69805 -316.750668) (xy 52.709827 -316.702884)
			(xy 52.729118 -316.657608) (xy 52.755421 -316.616012) (xy 52.788056 -316.579175) (xy 52.826177 -316.54805)
			(xy 52.868798 -316.523443) (xy 52.914814 -316.505991) (xy 52.963033 -316.496147) (xy 53.012208 -316.494166)
			(xy 53.061063 -316.500098) (xy 53.108334 -316.51379) (xy 53.152796 -316.534888) (xy 53.193299 -316.562844)
			(xy 53.228792 -316.596936) (xy 53.258357 -316.63628) (xy 53.281228 -316.679857) (xy 53.296812 -316.726538)
			(xy 53.304707 -316.775115) (xy 53.305202 -316.799722) (xy 54.59401 -316.799722) (xy 54.59797 -316.750668)
			(xy 54.609747 -316.702884) (xy 54.629038 -316.657608) (xy 54.655341 -316.616012) (xy 54.687976 -316.579175)
			(xy 54.726097 -316.54805) (xy 54.768718 -316.523443) (xy 54.814734 -316.505991) (xy 54.862953 -316.496147)
			(xy 54.912128 -316.494166) (xy 54.960983 -316.500098) (xy 55.008254 -316.51379) (xy 55.052716 -316.534888)
			(xy 55.093219 -316.562844) (xy 55.128712 -316.596936) (xy 55.158277 -316.63628) (xy 55.181148 -316.679857)
			(xy 55.196732 -316.726538) (xy 55.204627 -316.775115) (xy 55.205122 -316.799722) (xy 56.494184 -316.799722)
			(xy 56.498144 -316.750668) (xy 56.509921 -316.702884) (xy 56.529212 -316.657608) (xy 56.555515 -316.616012)
			(xy 56.58815 -316.579175) (xy 56.626271 -316.54805) (xy 56.668892 -316.523443) (xy 56.714908 -316.505991)
			(xy 56.763127 -316.496147) (xy 56.812302 -316.494166) (xy 56.861157 -316.500098) (xy 56.908428 -316.51379)
			(xy 56.95289 -316.534888) (xy 56.993393 -316.562844) (xy 57.028886 -316.596936) (xy 57.058451 -316.63628)
			(xy 57.081322 -316.679857) (xy 57.096906 -316.726538) (xy 57.104801 -316.775115) (xy 57.105296 -316.799722)
			(xy 58.394104 -316.799722) (xy 58.398064 -316.750668) (xy 58.409841 -316.702884) (xy 58.429132 -316.657608)
			(xy 58.455435 -316.616012) (xy 58.48807 -316.579175) (xy 58.526191 -316.54805) (xy 58.568812 -316.523443)
			(xy 58.614828 -316.505991) (xy 58.663047 -316.496147) (xy 58.712222 -316.494166) (xy 58.761077 -316.500098)
			(xy 58.808348 -316.51379) (xy 58.85281 -316.534888) (xy 58.893313 -316.562844) (xy 58.928806 -316.596936)
			(xy 58.958371 -316.63628) (xy 58.981242 -316.679857) (xy 58.996826 -316.726538) (xy 59.004721 -316.775115)
			(xy 59.005216 -316.799722) (xy 60.294024 -316.799722) (xy 60.297984 -316.750668) (xy 60.309761 -316.702884)
			(xy 60.329052 -316.657608) (xy 60.355355 -316.616012) (xy 60.38799 -316.579175) (xy 60.426111 -316.54805)
			(xy 60.468732 -316.523443) (xy 60.514748 -316.505991) (xy 60.562967 -316.496147) (xy 60.612142 -316.494166)
			(xy 60.660997 -316.500098) (xy 60.708268 -316.51379) (xy 60.75273 -316.534888) (xy 60.793233 -316.562844)
			(xy 60.828726 -316.596936) (xy 60.858291 -316.63628) (xy 60.881162 -316.679857) (xy 60.896746 -316.726538)
			(xy 60.904641 -316.775115) (xy 60.905136 -316.799722) (xy 62.193944 -316.799722) (xy 62.197904 -316.750668)
			(xy 62.209681 -316.702884) (xy 62.228972 -316.657608) (xy 62.255275 -316.616012) (xy 62.28791 -316.579175)
			(xy 62.326031 -316.54805) (xy 62.368652 -316.523443) (xy 62.414668 -316.505991) (xy 62.462887 -316.496147)
			(xy 62.512062 -316.494166) (xy 62.560917 -316.500098) (xy 62.608188 -316.51379) (xy 62.65265 -316.534888)
			(xy 62.693153 -316.562844) (xy 62.728646 -316.596936) (xy 62.758211 -316.63628) (xy 62.781082 -316.679857)
			(xy 62.796666 -316.726538) (xy 62.804561 -316.775115) (xy 62.805056 -316.799722) (xy 64.094118 -316.799722)
			(xy 64.098078 -316.750668) (xy 64.109855 -316.702884) (xy 64.129146 -316.657608) (xy 64.155449 -316.616012)
			(xy 64.188084 -316.579175) (xy 64.226205 -316.54805) (xy 64.268826 -316.523443) (xy 64.314842 -316.505991)
			(xy 64.363061 -316.496147) (xy 64.412236 -316.494166) (xy 64.461091 -316.500098) (xy 64.508362 -316.51379)
			(xy 64.552824 -316.534888) (xy 64.593327 -316.562844) (xy 64.62882 -316.596936) (xy 64.658385 -316.63628)
			(xy 64.681256 -316.679857) (xy 64.69684 -316.726538) (xy 64.704735 -316.775115) (xy 64.70523 -316.799722)
			(xy 65.994038 -316.799722) (xy 65.997998 -316.750668) (xy 66.009775 -316.702884) (xy 66.029066 -316.657608)
			(xy 66.055369 -316.616012) (xy 66.088004 -316.579175) (xy 66.126125 -316.54805) (xy 66.168746 -316.523443)
			(xy 66.214762 -316.505991) (xy 66.262981 -316.496147) (xy 66.312156 -316.494166) (xy 66.361011 -316.500098)
			(xy 66.408282 -316.51379) (xy 66.452744 -316.534888) (xy 66.493247 -316.562844) (xy 66.52874 -316.596936)
			(xy 66.558305 -316.63628) (xy 66.581176 -316.679857) (xy 66.59676 -316.726538) (xy 66.604655 -316.775115)
			(xy 66.60515 -316.799722) (xy 67.893958 -316.799722) (xy 67.897918 -316.750668) (xy 67.909695 -316.702884)
			(xy 67.928986 -316.657608) (xy 67.955289 -316.616012) (xy 67.987924 -316.579175) (xy 68.026045 -316.54805)
			(xy 68.068666 -316.523443) (xy 68.114682 -316.505991) (xy 68.162901 -316.496147) (xy 68.212076 -316.494166)
			(xy 68.260931 -316.500098) (xy 68.308202 -316.51379) (xy 68.352664 -316.534888) (xy 68.393167 -316.562844)
			(xy 68.42866 -316.596936) (xy 68.458225 -316.63628) (xy 68.481096 -316.679857) (xy 68.49668 -316.726538)
			(xy 68.504575 -316.775115) (xy 68.50507 -316.799722) (xy 69.794132 -316.799722) (xy 69.798092 -316.750668)
			(xy 69.809869 -316.702884) (xy 69.82916 -316.657608) (xy 69.855463 -316.616012) (xy 69.888098 -316.579175)
			(xy 69.926219 -316.54805) (xy 69.96884 -316.523443) (xy 70.014856 -316.505991) (xy 70.063075 -316.496147)
			(xy 70.11225 -316.494166) (xy 70.161105 -316.500098) (xy 70.208376 -316.51379) (xy 70.252838 -316.534888)
			(xy 70.293341 -316.562844) (xy 70.328834 -316.596936) (xy 70.358399 -316.63628) (xy 70.38127 -316.679857)
			(xy 70.396854 -316.726538) (xy 70.404749 -316.775115) (xy 70.405244 -316.799722) (xy 71.694052 -316.799722)
			(xy 71.698012 -316.750668) (xy 71.709789 -316.702884) (xy 71.72908 -316.657608) (xy 71.755383 -316.616012)
			(xy 71.788018 -316.579175) (xy 71.826139 -316.54805) (xy 71.86876 -316.523443) (xy 71.914776 -316.505991)
			(xy 71.962995 -316.496147) (xy 72.01217 -316.494166) (xy 72.061025 -316.500098) (xy 72.108296 -316.51379)
			(xy 72.152758 -316.534888) (xy 72.193261 -316.562844) (xy 72.228754 -316.596936) (xy 72.258319 -316.63628)
			(xy 72.28119 -316.679857) (xy 72.296774 -316.726538) (xy 72.304669 -316.775115) (xy 72.305164 -316.799722)
			(xy 73.593972 -316.799722) (xy 73.597932 -316.750668) (xy 73.609709 -316.702884) (xy 73.629 -316.657608)
			(xy 73.655303 -316.616012) (xy 73.687938 -316.579175) (xy 73.726059 -316.54805) (xy 73.76868 -316.523443)
			(xy 73.814696 -316.505991) (xy 73.862915 -316.496147) (xy 73.91209 -316.494166) (xy 73.960945 -316.500098)
			(xy 74.008216 -316.51379) (xy 74.052678 -316.534888) (xy 74.093181 -316.562844) (xy 74.128674 -316.596936)
			(xy 74.158239 -316.63628) (xy 74.18111 -316.679857) (xy 74.196694 -316.726538) (xy 74.204589 -316.775115)
			(xy 74.205084 -316.799722) (xy 75.494146 -316.799722) (xy 75.498106 -316.750668) (xy 75.509883 -316.702884)
			(xy 75.529174 -316.657608) (xy 75.555477 -316.616012) (xy 75.588112 -316.579175) (xy 75.626233 -316.54805)
			(xy 75.668854 -316.523443) (xy 75.71487 -316.505991) (xy 75.763089 -316.496147) (xy 75.812264 -316.494166)
			(xy 75.861119 -316.500098) (xy 75.90839 -316.51379) (xy 75.952852 -316.534888) (xy 75.993355 -316.562844)
			(xy 76.028848 -316.596936) (xy 76.058413 -316.63628) (xy 76.081284 -316.679857) (xy 76.096868 -316.726538)
			(xy 76.104763 -316.775115) (xy 76.105258 -316.799722) (xy 77.394066 -316.799722) (xy 77.398026 -316.750668)
			(xy 77.409803 -316.702884) (xy 77.429094 -316.657608) (xy 77.455397 -316.616012) (xy 77.488032 -316.579175)
			(xy 77.526153 -316.54805) (xy 77.568774 -316.523443) (xy 77.61479 -316.505991) (xy 77.663009 -316.496147)
			(xy 77.712184 -316.494166) (xy 77.761039 -316.500098) (xy 77.80831 -316.51379) (xy 77.852772 -316.534888)
			(xy 77.893275 -316.562844) (xy 77.928768 -316.596936) (xy 77.958333 -316.63628) (xy 77.981204 -316.679857)
			(xy 77.996788 -316.726538) (xy 78.004683 -316.775115) (xy 78.005178 -316.799722) (xy 79.293986 -316.799722)
			(xy 79.297946 -316.750668) (xy 79.309723 -316.702884) (xy 79.329014 -316.657608) (xy 79.355317 -316.616012)
			(xy 79.387952 -316.579175) (xy 79.426073 -316.54805) (xy 79.468694 -316.523443) (xy 79.51471 -316.505991)
			(xy 79.562929 -316.496147) (xy 79.612104 -316.494166) (xy 79.660959 -316.500098) (xy 79.70823 -316.51379)
			(xy 79.752692 -316.534888) (xy 79.793195 -316.562844) (xy 79.828688 -316.596936) (xy 79.858253 -316.63628)
			(xy 79.881124 -316.679857) (xy 79.896708 -316.726538) (xy 79.904603 -316.775115) (xy 79.905098 -316.799722)
			(xy 81.19416 -316.799722) (xy 81.19812 -316.750668) (xy 81.209897 -316.702884) (xy 81.229188 -316.657608)
			(xy 81.255491 -316.616012) (xy 81.288126 -316.579175) (xy 81.326247 -316.54805) (xy 81.368868 -316.523443)
			(xy 81.414884 -316.505991) (xy 81.463103 -316.496147) (xy 81.512278 -316.494166) (xy 81.561133 -316.500098)
			(xy 81.608404 -316.51379) (xy 81.652866 -316.534888) (xy 81.693369 -316.562844) (xy 81.728862 -316.596936)
			(xy 81.758427 -316.63628) (xy 81.781298 -316.679857) (xy 81.796882 -316.726538) (xy 81.804777 -316.775115)
			(xy 81.805272 -316.799722) (xy 82.14412 -316.799722) (xy 82.14808 -316.750668) (xy 82.159857 -316.702884)
			(xy 82.179148 -316.657608) (xy 82.205451 -316.616012) (xy 82.238086 -316.579175) (xy 82.276207 -316.54805)
			(xy 82.318828 -316.523443) (xy 82.364844 -316.505991) (xy 82.413063 -316.496147) (xy 82.462238 -316.494166)
			(xy 82.511093 -316.500098) (xy 82.558364 -316.51379) (xy 82.602826 -316.534888) (xy 82.643329 -316.562844)
			(xy 82.678822 -316.596936) (xy 82.708387 -316.63628) (xy 82.731258 -316.679857) (xy 82.746842 -316.726538)
			(xy 82.754737 -316.775115) (xy 82.755232 -316.799722) (xy 152.644106 -316.799722) (xy 152.648066 -316.750668)
			(xy 152.659843 -316.702884) (xy 152.679134 -316.657608) (xy 152.705437 -316.616012) (xy 152.738072 -316.579175)
			(xy 152.776193 -316.54805) (xy 152.818814 -316.523443) (xy 152.86483 -316.505991) (xy 152.913049 -316.496147)
			(xy 152.962224 -316.494166) (xy 153.011079 -316.500098) (xy 153.05835 -316.51379) (xy 153.102812 -316.534888)
			(xy 153.143315 -316.562844) (xy 153.178808 -316.596936) (xy 153.208373 -316.63628) (xy 153.231244 -316.679857)
			(xy 153.246828 -316.726538) (xy 153.254723 -316.775115) (xy 153.255218 -316.799722) (xy 153.594066 -316.799722)
			(xy 153.598026 -316.750668) (xy 153.609803 -316.702884) (xy 153.629094 -316.657608) (xy 153.655397 -316.616012)
			(xy 153.688032 -316.579175) (xy 153.726153 -316.54805) (xy 153.768774 -316.523443) (xy 153.81479 -316.505991)
			(xy 153.863009 -316.496147) (xy 153.912184 -316.494166) (xy 153.961039 -316.500098) (xy 154.00831 -316.51379)
			(xy 154.052772 -316.534888) (xy 154.093275 -316.562844) (xy 154.128768 -316.596936) (xy 154.158333 -316.63628)
			(xy 154.181204 -316.679857) (xy 154.196788 -316.726538) (xy 154.204683 -316.775115) (xy 154.205178 -316.799722)
			(xy 155.49424 -316.799722) (xy 155.4982 -316.750668) (xy 155.509977 -316.702884) (xy 155.529268 -316.657608)
			(xy 155.555571 -316.616012) (xy 155.588206 -316.579175) (xy 155.626327 -316.54805) (xy 155.668948 -316.523443)
			(xy 155.714964 -316.505991) (xy 155.763183 -316.496147) (xy 155.812358 -316.494166) (xy 155.861213 -316.500098)
			(xy 155.908484 -316.51379) (xy 155.952946 -316.534888) (xy 155.993449 -316.562844) (xy 156.028942 -316.596936)
			(xy 156.058507 -316.63628) (xy 156.081378 -316.679857) (xy 156.096962 -316.726538) (xy 156.104857 -316.775115)
			(xy 156.105352 -316.799722) (xy 157.39416 -316.799722) (xy 157.39812 -316.750668) (xy 157.409897 -316.702884)
			(xy 157.429188 -316.657608) (xy 157.455491 -316.616012) (xy 157.488126 -316.579175) (xy 157.526247 -316.54805)
			(xy 157.568868 -316.523443) (xy 157.614884 -316.505991) (xy 157.663103 -316.496147) (xy 157.712278 -316.494166)
			(xy 157.761133 -316.500098) (xy 157.808404 -316.51379) (xy 157.852866 -316.534888) (xy 157.893369 -316.562844)
			(xy 157.928862 -316.596936) (xy 157.958427 -316.63628) (xy 157.981298 -316.679857) (xy 157.996882 -316.726538)
			(xy 158.004777 -316.775115) (xy 158.005272 -316.799722) (xy 159.29408 -316.799722) (xy 159.29804 -316.750668)
			(xy 159.309817 -316.702884) (xy 159.329108 -316.657608) (xy 159.355411 -316.616012) (xy 159.388046 -316.579175)
			(xy 159.426167 -316.54805) (xy 159.468788 -316.523443) (xy 159.514804 -316.505991) (xy 159.563023 -316.496147)
			(xy 159.612198 -316.494166) (xy 159.661053 -316.500098) (xy 159.708324 -316.51379) (xy 159.752786 -316.534888)
			(xy 159.793289 -316.562844) (xy 159.828782 -316.596936) (xy 159.858347 -316.63628) (xy 159.881218 -316.679857)
			(xy 159.896802 -316.726538) (xy 159.904697 -316.775115) (xy 159.905192 -316.799722) (xy 161.194254 -316.799722)
			(xy 161.198214 -316.750668) (xy 161.209991 -316.702884) (xy 161.229282 -316.657608) (xy 161.255585 -316.616012)
			(xy 161.28822 -316.579175) (xy 161.326341 -316.54805) (xy 161.368962 -316.523443) (xy 161.414978 -316.505991)
			(xy 161.463197 -316.496147) (xy 161.512372 -316.494166) (xy 161.561227 -316.500098) (xy 161.608498 -316.51379)
			(xy 161.65296 -316.534888) (xy 161.693463 -316.562844) (xy 161.728956 -316.596936) (xy 161.758521 -316.63628)
			(xy 161.781392 -316.679857) (xy 161.796976 -316.726538) (xy 161.804871 -316.775115) (xy 161.805366 -316.799722)
			(xy 163.094174 -316.799722) (xy 163.098134 -316.750668) (xy 163.109911 -316.702884) (xy 163.129202 -316.657608)
			(xy 163.155505 -316.616012) (xy 163.18814 -316.579175) (xy 163.226261 -316.54805) (xy 163.268882 -316.523443)
			(xy 163.314898 -316.505991) (xy 163.363117 -316.496147) (xy 163.412292 -316.494166) (xy 163.461147 -316.500098)
			(xy 163.508418 -316.51379) (xy 163.55288 -316.534888) (xy 163.593383 -316.562844) (xy 163.628876 -316.596936)
			(xy 163.658441 -316.63628) (xy 163.681312 -316.679857) (xy 163.696896 -316.726538) (xy 163.704791 -316.775115)
			(xy 163.705286 -316.799722) (xy 164.994094 -316.799722) (xy 164.998054 -316.750668) (xy 165.009831 -316.702884)
			(xy 165.029122 -316.657608) (xy 165.055425 -316.616012) (xy 165.08806 -316.579175) (xy 165.126181 -316.54805)
			(xy 165.168802 -316.523443) (xy 165.214818 -316.505991) (xy 165.263037 -316.496147) (xy 165.312212 -316.494166)
			(xy 165.361067 -316.500098) (xy 165.408338 -316.51379) (xy 165.4528 -316.534888) (xy 165.493303 -316.562844)
			(xy 165.528796 -316.596936) (xy 165.558361 -316.63628) (xy 165.581232 -316.679857) (xy 165.596816 -316.726538)
			(xy 165.604711 -316.775115) (xy 165.605206 -316.799722) (xy 166.894268 -316.799722) (xy 166.898228 -316.750668)
			(xy 166.910005 -316.702884) (xy 166.929296 -316.657608) (xy 166.955599 -316.616012) (xy 166.988234 -316.579175)
			(xy 167.026355 -316.54805) (xy 167.068976 -316.523443) (xy 167.114992 -316.505991) (xy 167.163211 -316.496147)
			(xy 167.212386 -316.494166) (xy 167.261241 -316.500098) (xy 167.308512 -316.51379) (xy 167.352974 -316.534888)
			(xy 167.393477 -316.562844) (xy 167.42897 -316.596936) (xy 167.458535 -316.63628) (xy 167.481406 -316.679857)
			(xy 167.49699 -316.726538) (xy 167.504885 -316.775115) (xy 167.50538 -316.799722) (xy 168.794188 -316.799722)
			(xy 168.798148 -316.750668) (xy 168.809925 -316.702884) (xy 168.829216 -316.657608) (xy 168.855519 -316.616012)
			(xy 168.888154 -316.579175) (xy 168.926275 -316.54805) (xy 168.968896 -316.523443) (xy 169.014912 -316.505991)
			(xy 169.063131 -316.496147) (xy 169.112306 -316.494166) (xy 169.161161 -316.500098) (xy 169.208432 -316.51379)
			(xy 169.252894 -316.534888) (xy 169.293397 -316.562844) (xy 169.32889 -316.596936) (xy 169.358455 -316.63628)
			(xy 169.381326 -316.679857) (xy 169.39691 -316.726538) (xy 169.404805 -316.775115) (xy 169.4053 -316.799722)
			(xy 170.694108 -316.799722) (xy 170.698068 -316.750668) (xy 170.709845 -316.702884) (xy 170.729136 -316.657608)
			(xy 170.755439 -316.616012) (xy 170.788074 -316.579175) (xy 170.826195 -316.54805) (xy 170.868816 -316.523443)
			(xy 170.914832 -316.505991) (xy 170.963051 -316.496147) (xy 171.012226 -316.494166) (xy 171.061081 -316.500098)
			(xy 171.108352 -316.51379) (xy 171.152814 -316.534888) (xy 171.193317 -316.562844) (xy 171.22881 -316.596936)
			(xy 171.258375 -316.63628) (xy 171.281246 -316.679857) (xy 171.29683 -316.726538) (xy 171.304725 -316.775115)
			(xy 171.30522 -316.799722) (xy 172.594282 -316.799722) (xy 172.598242 -316.750668) (xy 172.610019 -316.702884)
			(xy 172.62931 -316.657608) (xy 172.655613 -316.616012) (xy 172.688248 -316.579175) (xy 172.726369 -316.54805)
			(xy 172.76899 -316.523443) (xy 172.815006 -316.505991) (xy 172.863225 -316.496147) (xy 172.9124 -316.494166)
			(xy 172.961255 -316.500098) (xy 173.008526 -316.51379) (xy 173.052988 -316.534888) (xy 173.093491 -316.562844)
			(xy 173.128984 -316.596936) (xy 173.158549 -316.63628) (xy 173.18142 -316.679857) (xy 173.197004 -316.726538)
			(xy 173.204899 -316.775115) (xy 173.205394 -316.799722) (xy 174.494202 -316.799722) (xy 174.498162 -316.750668)
			(xy 174.509939 -316.702884) (xy 174.52923 -316.657608) (xy 174.555533 -316.616012) (xy 174.588168 -316.579175)
			(xy 174.626289 -316.54805) (xy 174.66891 -316.523443) (xy 174.714926 -316.505991) (xy 174.763145 -316.496147)
			(xy 174.81232 -316.494166) (xy 174.861175 -316.500098) (xy 174.908446 -316.51379) (xy 174.952908 -316.534888)
			(xy 174.993411 -316.562844) (xy 175.028904 -316.596936) (xy 175.058469 -316.63628) (xy 175.08134 -316.679857)
			(xy 175.096924 -316.726538) (xy 175.104819 -316.775115) (xy 175.105314 -316.799722) (xy 176.394122 -316.799722)
			(xy 176.398082 -316.750668) (xy 176.409859 -316.702884) (xy 176.42915 -316.657608) (xy 176.455453 -316.616012)
			(xy 176.488088 -316.579175) (xy 176.526209 -316.54805) (xy 176.56883 -316.523443) (xy 176.614846 -316.505991)
			(xy 176.663065 -316.496147) (xy 176.71224 -316.494166) (xy 176.761095 -316.500098) (xy 176.808366 -316.51379)
			(xy 176.852828 -316.534888) (xy 176.893331 -316.562844) (xy 176.928824 -316.596936) (xy 176.958389 -316.63628)
			(xy 176.98126 -316.679857) (xy 176.996844 -316.726538) (xy 177.004739 -316.775115) (xy 177.005234 -316.799722)
			(xy 178.294042 -316.799722) (xy 178.298002 -316.750668) (xy 178.309779 -316.702884) (xy 178.32907 -316.657608)
			(xy 178.355373 -316.616012) (xy 178.388008 -316.579175) (xy 178.426129 -316.54805) (xy 178.46875 -316.523443)
			(xy 178.514766 -316.505991) (xy 178.562985 -316.496147) (xy 178.61216 -316.494166) (xy 178.661015 -316.500098)
			(xy 178.708286 -316.51379) (xy 178.752748 -316.534888) (xy 178.793251 -316.562844) (xy 178.828744 -316.596936)
			(xy 178.858309 -316.63628) (xy 178.88118 -316.679857) (xy 178.896764 -316.726538) (xy 178.904659 -316.775115)
			(xy 178.905154 -316.799722) (xy 180.194216 -316.799722) (xy 180.198176 -316.750668) (xy 180.209953 -316.702884)
			(xy 180.229244 -316.657608) (xy 180.255547 -316.616012) (xy 180.288182 -316.579175) (xy 180.326303 -316.54805)
			(xy 180.368924 -316.523443) (xy 180.41494 -316.505991) (xy 180.463159 -316.496147) (xy 180.512334 -316.494166)
			(xy 180.561189 -316.500098) (xy 180.60846 -316.51379) (xy 180.652922 -316.534888) (xy 180.693425 -316.562844)
			(xy 180.728918 -316.596936) (xy 180.758483 -316.63628) (xy 180.781354 -316.679857) (xy 180.796938 -316.726538)
			(xy 180.804833 -316.775115) (xy 180.805328 -316.799722) (xy 182.094136 -316.799722) (xy 182.098096 -316.750668)
			(xy 182.109873 -316.702884) (xy 182.129164 -316.657608) (xy 182.155467 -316.616012) (xy 182.188102 -316.579175)
			(xy 182.226223 -316.54805) (xy 182.268844 -316.523443) (xy 182.31486 -316.505991) (xy 182.363079 -316.496147)
			(xy 182.412254 -316.494166) (xy 182.461109 -316.500098) (xy 182.50838 -316.51379) (xy 182.552842 -316.534888)
			(xy 182.593345 -316.562844) (xy 182.628838 -316.596936) (xy 182.658403 -316.63628) (xy 182.681274 -316.679857)
			(xy 182.696858 -316.726538) (xy 182.704753 -316.775115) (xy 182.705248 -316.799722) (xy 183.994056 -316.799722)
			(xy 183.998016 -316.750668) (xy 184.009793 -316.702884) (xy 184.029084 -316.657608) (xy 184.055387 -316.616012)
			(xy 184.088022 -316.579175) (xy 184.126143 -316.54805) (xy 184.168764 -316.523443) (xy 184.21478 -316.505991)
			(xy 184.262999 -316.496147) (xy 184.312174 -316.494166) (xy 184.361029 -316.500098) (xy 184.4083 -316.51379)
			(xy 184.452762 -316.534888) (xy 184.493265 -316.562844) (xy 184.528758 -316.596936) (xy 184.558323 -316.63628)
			(xy 184.581194 -316.679857) (xy 184.596778 -316.726538) (xy 184.604673 -316.775115) (xy 184.605168 -316.799722)
			(xy 185.89423 -316.799722) (xy 185.89819 -316.750668) (xy 185.909967 -316.702884) (xy 185.929258 -316.657608)
			(xy 185.955561 -316.616012) (xy 185.988196 -316.579175) (xy 186.026317 -316.54805) (xy 186.068938 -316.523443)
			(xy 186.114954 -316.505991) (xy 186.163173 -316.496147) (xy 186.212348 -316.494166) (xy 186.261203 -316.500098)
			(xy 186.308474 -316.51379) (xy 186.352936 -316.534888) (xy 186.393439 -316.562844) (xy 186.428932 -316.596936)
			(xy 186.458497 -316.63628) (xy 186.481368 -316.679857) (xy 186.496952 -316.726538) (xy 186.504847 -316.775115)
			(xy 186.505342 -316.799722) (xy 187.79415 -316.799722) (xy 187.79811 -316.750668) (xy 187.809887 -316.702884)
			(xy 187.829178 -316.657608) (xy 187.855481 -316.616012) (xy 187.888116 -316.579175) (xy 187.926237 -316.54805)
			(xy 187.968858 -316.523443) (xy 188.014874 -316.505991) (xy 188.063093 -316.496147) (xy 188.112268 -316.494166)
			(xy 188.161123 -316.500098) (xy 188.208394 -316.51379) (xy 188.252856 -316.534888) (xy 188.293359 -316.562844)
			(xy 188.328852 -316.596936) (xy 188.358417 -316.63628) (xy 188.381288 -316.679857) (xy 188.396872 -316.726538)
			(xy 188.404767 -316.775115) (xy 188.405262 -316.799722) (xy 189.69407 -316.799722) (xy 189.69803 -316.750668)
			(xy 189.709807 -316.702884) (xy 189.729098 -316.657608) (xy 189.755401 -316.616012) (xy 189.788036 -316.579175)
			(xy 189.826157 -316.54805) (xy 189.868778 -316.523443) (xy 189.914794 -316.505991) (xy 189.963013 -316.496147)
			(xy 190.012188 -316.494166) (xy 190.061043 -316.500098) (xy 190.108314 -316.51379) (xy 190.152776 -316.534888)
			(xy 190.193279 -316.562844) (xy 190.228772 -316.596936) (xy 190.258337 -316.63628) (xy 190.281208 -316.679857)
			(xy 190.296792 -316.726538) (xy 190.304687 -316.775115) (xy 190.305182 -316.799722) (xy 191.594244 -316.799722)
			(xy 191.598204 -316.750668) (xy 191.609981 -316.702884) (xy 191.629272 -316.657608) (xy 191.655575 -316.616012)
			(xy 191.68821 -316.579175) (xy 191.726331 -316.54805) (xy 191.768952 -316.523443) (xy 191.814968 -316.505991)
			(xy 191.863187 -316.496147) (xy 191.912362 -316.494166) (xy 191.961217 -316.500098) (xy 192.008488 -316.51379)
			(xy 192.05295 -316.534888) (xy 192.093453 -316.562844) (xy 192.128946 -316.596936) (xy 192.158511 -316.63628)
			(xy 192.181382 -316.679857) (xy 192.196966 -316.726538) (xy 192.204861 -316.775115) (xy 192.205356 -316.799722)
			(xy 193.494164 -316.799722) (xy 193.498124 -316.750668) (xy 193.509901 -316.702884) (xy 193.529192 -316.657608)
			(xy 193.555495 -316.616012) (xy 193.58813 -316.579175) (xy 193.626251 -316.54805) (xy 193.668872 -316.523443)
			(xy 193.714888 -316.505991) (xy 193.763107 -316.496147) (xy 193.812282 -316.494166) (xy 193.861137 -316.500098)
			(xy 193.908408 -316.51379) (xy 193.95287 -316.534888) (xy 193.993373 -316.562844) (xy 194.028866 -316.596936)
			(xy 194.058431 -316.63628) (xy 194.081302 -316.679857) (xy 194.096886 -316.726538) (xy 194.104781 -316.775115)
			(xy 194.105276 -316.799722) (xy 195.394084 -316.799722) (xy 195.398044 -316.750668) (xy 195.409821 -316.702884)
			(xy 195.429112 -316.657608) (xy 195.455415 -316.616012) (xy 195.48805 -316.579175) (xy 195.526171 -316.54805)
			(xy 195.568792 -316.523443) (xy 195.614808 -316.505991) (xy 195.663027 -316.496147) (xy 195.712202 -316.494166)
			(xy 195.761057 -316.500098) (xy 195.808328 -316.51379) (xy 195.85279 -316.534888) (xy 195.893293 -316.562844)
			(xy 195.928786 -316.596936) (xy 195.958351 -316.63628) (xy 195.981222 -316.679857) (xy 195.996806 -316.726538)
			(xy 196.004701 -316.775115) (xy 196.005196 -316.799722) (xy 197.294258 -316.799722) (xy 197.298218 -316.750668)
			(xy 197.309995 -316.702884) (xy 197.329286 -316.657608) (xy 197.355589 -316.616012) (xy 197.388224 -316.579175)
			(xy 197.426345 -316.54805) (xy 197.468966 -316.523443) (xy 197.514982 -316.505991) (xy 197.563201 -316.496147)
			(xy 197.612376 -316.494166) (xy 197.661231 -316.500098) (xy 197.708502 -316.51379) (xy 197.752964 -316.534888)
			(xy 197.793467 -316.562844) (xy 197.82896 -316.596936) (xy 197.858525 -316.63628) (xy 197.881396 -316.679857)
			(xy 197.89698 -316.726538) (xy 197.904875 -316.775115) (xy 197.90537 -316.799722) (xy 198.244218 -316.799722)
			(xy 198.248178 -316.750668) (xy 198.259955 -316.702884) (xy 198.279246 -316.657608) (xy 198.305549 -316.616012)
			(xy 198.338184 -316.579175) (xy 198.376305 -316.54805) (xy 198.418926 -316.523443) (xy 198.464942 -316.505991)
			(xy 198.513161 -316.496147) (xy 198.562336 -316.494166) (xy 198.611191 -316.500098) (xy 198.658462 -316.51379)
			(xy 198.702924 -316.534888) (xy 198.743427 -316.562844) (xy 198.77892 -316.596936) (xy 198.808485 -316.63628)
			(xy 198.831356 -316.679857) (xy 198.84694 -316.726538) (xy 198.854835 -316.775115) (xy 198.85533 -316.799722)
			(xy 268.74395 -316.799722) (xy 268.74791 -316.750668) (xy 268.759687 -316.702884) (xy 268.778978 -316.657608)
			(xy 268.805281 -316.616012) (xy 268.837916 -316.579175) (xy 268.876037 -316.54805) (xy 268.918658 -316.523443)
			(xy 268.964674 -316.505991) (xy 269.012893 -316.496147) (xy 269.062068 -316.494166) (xy 269.110923 -316.500098)
			(xy 269.158194 -316.51379) (xy 269.202656 -316.534888) (xy 269.243159 -316.562844) (xy 269.278652 -316.596936)
			(xy 269.308217 -316.63628) (xy 269.331088 -316.679857) (xy 269.346672 -316.726538) (xy 269.354567 -316.775115)
			(xy 269.355062 -316.799722) (xy 269.69391 -316.799722) (xy 269.69787 -316.750668) (xy 269.709647 -316.702884)
			(xy 269.728938 -316.657608) (xy 269.755241 -316.616012) (xy 269.787876 -316.579175) (xy 269.825997 -316.54805)
			(xy 269.868618 -316.523443) (xy 269.914634 -316.505991) (xy 269.962853 -316.496147) (xy 270.012028 -316.494166)
			(xy 270.060883 -316.500098) (xy 270.108154 -316.51379) (xy 270.152616 -316.534888) (xy 270.193119 -316.562844)
			(xy 270.228612 -316.596936) (xy 270.258177 -316.63628) (xy 270.281048 -316.679857) (xy 270.296632 -316.726538)
			(xy 270.304527 -316.775115) (xy 270.305022 -316.799722) (xy 271.594084 -316.799722) (xy 271.598044 -316.750668)
			(xy 271.609821 -316.702884) (xy 271.629112 -316.657608) (xy 271.655415 -316.616012) (xy 271.68805 -316.579175)
			(xy 271.726171 -316.54805) (xy 271.768792 -316.523443) (xy 271.814808 -316.505991) (xy 271.863027 -316.496147)
			(xy 271.912202 -316.494166) (xy 271.961057 -316.500098) (xy 272.008328 -316.51379) (xy 272.05279 -316.534888)
			(xy 272.093293 -316.562844) (xy 272.128786 -316.596936) (xy 272.158351 -316.63628) (xy 272.181222 -316.679857)
			(xy 272.196806 -316.726538) (xy 272.204701 -316.775115) (xy 272.205196 -316.799722) (xy 273.494004 -316.799722)
			(xy 273.497964 -316.750668) (xy 273.509741 -316.702884) (xy 273.529032 -316.657608) (xy 273.555335 -316.616012)
			(xy 273.58797 -316.579175) (xy 273.626091 -316.54805) (xy 273.668712 -316.523443) (xy 273.714728 -316.505991)
			(xy 273.762947 -316.496147) (xy 273.812122 -316.494166) (xy 273.860977 -316.500098) (xy 273.908248 -316.51379)
			(xy 273.95271 -316.534888) (xy 273.993213 -316.562844) (xy 274.028706 -316.596936) (xy 274.058271 -316.63628)
			(xy 274.081142 -316.679857) (xy 274.096726 -316.726538) (xy 274.104621 -316.775115) (xy 274.105116 -316.799722)
			(xy 275.393924 -316.799722) (xy 275.397884 -316.750668) (xy 275.409661 -316.702884) (xy 275.428952 -316.657608)
			(xy 275.455255 -316.616012) (xy 275.48789 -316.579175) (xy 275.526011 -316.54805) (xy 275.568632 -316.523443)
			(xy 275.614648 -316.505991) (xy 275.662867 -316.496147) (xy 275.712042 -316.494166) (xy 275.760897 -316.500098)
			(xy 275.808168 -316.51379) (xy 275.85263 -316.534888) (xy 275.893133 -316.562844) (xy 275.928626 -316.596936)
			(xy 275.958191 -316.63628) (xy 275.981062 -316.679857) (xy 275.996646 -316.726538) (xy 276.004541 -316.775115)
			(xy 276.005036 -316.799722) (xy 277.294098 -316.799722) (xy 277.298058 -316.750668) (xy 277.309835 -316.702884)
			(xy 277.329126 -316.657608) (xy 277.355429 -316.616012) (xy 277.388064 -316.579175) (xy 277.426185 -316.54805)
			(xy 277.468806 -316.523443) (xy 277.514822 -316.505991) (xy 277.563041 -316.496147) (xy 277.612216 -316.494166)
			(xy 277.661071 -316.500098) (xy 277.708342 -316.51379) (xy 277.752804 -316.534888) (xy 277.793307 -316.562844)
			(xy 277.8288 -316.596936) (xy 277.858365 -316.63628) (xy 277.881236 -316.679857) (xy 277.89682 -316.726538)
			(xy 277.904715 -316.775115) (xy 277.90521 -316.799722) (xy 279.194018 -316.799722) (xy 279.197978 -316.750668)
			(xy 279.209755 -316.702884) (xy 279.229046 -316.657608) (xy 279.255349 -316.616012) (xy 279.287984 -316.579175)
			(xy 279.326105 -316.54805) (xy 279.368726 -316.523443) (xy 279.414742 -316.505991) (xy 279.462961 -316.496147)
			(xy 279.512136 -316.494166) (xy 279.560991 -316.500098) (xy 279.608262 -316.51379) (xy 279.652724 -316.534888)
			(xy 279.693227 -316.562844) (xy 279.72872 -316.596936) (xy 279.758285 -316.63628) (xy 279.781156 -316.679857)
			(xy 279.79674 -316.726538) (xy 279.804635 -316.775115) (xy 279.80513 -316.799722) (xy 281.093938 -316.799722)
			(xy 281.097898 -316.750668) (xy 281.109675 -316.702884) (xy 281.128966 -316.657608) (xy 281.155269 -316.616012)
			(xy 281.187904 -316.579175) (xy 281.226025 -316.54805) (xy 281.268646 -316.523443) (xy 281.314662 -316.505991)
			(xy 281.362881 -316.496147) (xy 281.412056 -316.494166) (xy 281.460911 -316.500098) (xy 281.508182 -316.51379)
			(xy 281.552644 -316.534888) (xy 281.593147 -316.562844) (xy 281.62864 -316.596936) (xy 281.658205 -316.63628)
			(xy 281.681076 -316.679857) (xy 281.69666 -316.726538) (xy 281.704555 -316.775115) (xy 281.70505 -316.799722)
			(xy 282.994112 -316.799722) (xy 282.998072 -316.750668) (xy 283.009849 -316.702884) (xy 283.02914 -316.657608)
			(xy 283.055443 -316.616012) (xy 283.088078 -316.579175) (xy 283.126199 -316.54805) (xy 283.16882 -316.523443)
			(xy 283.214836 -316.505991) (xy 283.263055 -316.496147) (xy 283.31223 -316.494166) (xy 283.361085 -316.500098)
			(xy 283.408356 -316.51379) (xy 283.452818 -316.534888) (xy 283.493321 -316.562844) (xy 283.528814 -316.596936)
			(xy 283.558379 -316.63628) (xy 283.58125 -316.679857) (xy 283.596834 -316.726538) (xy 283.604729 -316.775115)
			(xy 283.605224 -316.799722) (xy 284.894032 -316.799722) (xy 284.897992 -316.750668) (xy 284.909769 -316.702884)
			(xy 284.92906 -316.657608) (xy 284.955363 -316.616012) (xy 284.987998 -316.579175) (xy 285.026119 -316.54805)
			(xy 285.06874 -316.523443) (xy 285.114756 -316.505991) (xy 285.162975 -316.496147) (xy 285.21215 -316.494166)
			(xy 285.261005 -316.500098) (xy 285.308276 -316.51379) (xy 285.352738 -316.534888) (xy 285.393241 -316.562844)
			(xy 285.428734 -316.596936) (xy 285.458299 -316.63628) (xy 285.48117 -316.679857) (xy 285.496754 -316.726538)
			(xy 285.504649 -316.775115) (xy 285.505144 -316.799722) (xy 286.793952 -316.799722) (xy 286.797912 -316.750668)
			(xy 286.809689 -316.702884) (xy 286.82898 -316.657608) (xy 286.855283 -316.616012) (xy 286.887918 -316.579175)
			(xy 286.926039 -316.54805) (xy 286.96866 -316.523443) (xy 287.014676 -316.505991) (xy 287.062895 -316.496147)
			(xy 287.11207 -316.494166) (xy 287.160925 -316.500098) (xy 287.208196 -316.51379) (xy 287.252658 -316.534888)
			(xy 287.293161 -316.562844) (xy 287.328654 -316.596936) (xy 287.358219 -316.63628) (xy 287.38109 -316.679857)
			(xy 287.396674 -316.726538) (xy 287.404569 -316.775115) (xy 287.405064 -316.799722) (xy 288.694126 -316.799722)
			(xy 288.698086 -316.750668) (xy 288.709863 -316.702884) (xy 288.729154 -316.657608) (xy 288.755457 -316.616012)
			(xy 288.788092 -316.579175) (xy 288.826213 -316.54805) (xy 288.868834 -316.523443) (xy 288.91485 -316.505991)
			(xy 288.963069 -316.496147) (xy 289.012244 -316.494166) (xy 289.061099 -316.500098) (xy 289.10837 -316.51379)
			(xy 289.152832 -316.534888) (xy 289.193335 -316.562844) (xy 289.228828 -316.596936) (xy 289.258393 -316.63628)
			(xy 289.281264 -316.679857) (xy 289.296848 -316.726538) (xy 289.304743 -316.775115) (xy 289.305238 -316.799722)
			(xy 290.594046 -316.799722) (xy 290.598006 -316.750668) (xy 290.609783 -316.702884) (xy 290.629074 -316.657608)
			(xy 290.655377 -316.616012) (xy 290.688012 -316.579175) (xy 290.726133 -316.54805) (xy 290.768754 -316.523443)
			(xy 290.81477 -316.505991) (xy 290.862989 -316.496147) (xy 290.912164 -316.494166) (xy 290.961019 -316.500098)
			(xy 291.00829 -316.51379) (xy 291.052752 -316.534888) (xy 291.093255 -316.562844) (xy 291.128748 -316.596936)
			(xy 291.158313 -316.63628) (xy 291.181184 -316.679857) (xy 291.196768 -316.726538) (xy 291.204663 -316.775115)
			(xy 291.205158 -316.799722) (xy 292.493966 -316.799722) (xy 292.497926 -316.750668) (xy 292.509703 -316.702884)
			(xy 292.528994 -316.657608) (xy 292.555297 -316.616012) (xy 292.587932 -316.579175) (xy 292.626053 -316.54805)
			(xy 292.668674 -316.523443) (xy 292.71469 -316.505991) (xy 292.762909 -316.496147) (xy 292.812084 -316.494166)
			(xy 292.860939 -316.500098) (xy 292.90821 -316.51379) (xy 292.952672 -316.534888) (xy 292.993175 -316.562844)
			(xy 293.028668 -316.596936) (xy 293.058233 -316.63628) (xy 293.081104 -316.679857) (xy 293.096688 -316.726538)
			(xy 293.104583 -316.775115) (xy 293.105078 -316.799722) (xy 294.393886 -316.799722) (xy 294.397846 -316.750668)
			(xy 294.409623 -316.702884) (xy 294.428914 -316.657608) (xy 294.455217 -316.616012) (xy 294.487852 -316.579175)
			(xy 294.525973 -316.54805) (xy 294.568594 -316.523443) (xy 294.61461 -316.505991) (xy 294.662829 -316.496147)
			(xy 294.712004 -316.494166) (xy 294.760859 -316.500098) (xy 294.80813 -316.51379) (xy 294.852592 -316.534888)
			(xy 294.893095 -316.562844) (xy 294.928588 -316.596936) (xy 294.958153 -316.63628) (xy 294.981024 -316.679857)
			(xy 294.996608 -316.726538) (xy 295.004503 -316.775115) (xy 295.004998 -316.799722) (xy 296.29406 -316.799722)
			(xy 296.29802 -316.750668) (xy 296.309797 -316.702884) (xy 296.329088 -316.657608) (xy 296.355391 -316.616012)
			(xy 296.388026 -316.579175) (xy 296.426147 -316.54805) (xy 296.468768 -316.523443) (xy 296.514784 -316.505991)
			(xy 296.563003 -316.496147) (xy 296.612178 -316.494166) (xy 296.661033 -316.500098) (xy 296.708304 -316.51379)
			(xy 296.752766 -316.534888) (xy 296.793269 -316.562844) (xy 296.828762 -316.596936) (xy 296.858327 -316.63628)
			(xy 296.881198 -316.679857) (xy 296.896782 -316.726538) (xy 296.904677 -316.775115) (xy 296.905172 -316.799722)
			(xy 298.19398 -316.799722) (xy 298.19794 -316.750668) (xy 298.209717 -316.702884) (xy 298.229008 -316.657608)
			(xy 298.255311 -316.616012) (xy 298.287946 -316.579175) (xy 298.326067 -316.54805) (xy 298.368688 -316.523443)
			(xy 298.414704 -316.505991) (xy 298.462923 -316.496147) (xy 298.512098 -316.494166) (xy 298.560953 -316.500098)
			(xy 298.608224 -316.51379) (xy 298.652686 -316.534888) (xy 298.693189 -316.562844) (xy 298.728682 -316.596936)
			(xy 298.758247 -316.63628) (xy 298.781118 -316.679857) (xy 298.796702 -316.726538) (xy 298.804597 -316.775115)
			(xy 298.805092 -316.799722) (xy 300.0939 -316.799722) (xy 300.09786 -316.750668) (xy 300.109637 -316.702884)
			(xy 300.128928 -316.657608) (xy 300.155231 -316.616012) (xy 300.187866 -316.579175) (xy 300.225987 -316.54805)
			(xy 300.268608 -316.523443) (xy 300.314624 -316.505991) (xy 300.362843 -316.496147) (xy 300.412018 -316.494166)
			(xy 300.460873 -316.500098) (xy 300.508144 -316.51379) (xy 300.552606 -316.534888) (xy 300.593109 -316.562844)
			(xy 300.628602 -316.596936) (xy 300.658167 -316.63628) (xy 300.681038 -316.679857) (xy 300.696622 -316.726538)
			(xy 300.704517 -316.775115) (xy 300.705012 -316.799722) (xy 301.994074 -316.799722) (xy 301.998034 -316.750668)
			(xy 302.009811 -316.702884) (xy 302.029102 -316.657608) (xy 302.055405 -316.616012) (xy 302.08804 -316.579175)
			(xy 302.126161 -316.54805) (xy 302.168782 -316.523443) (xy 302.214798 -316.505991) (xy 302.263017 -316.496147)
			(xy 302.312192 -316.494166) (xy 302.361047 -316.500098) (xy 302.408318 -316.51379) (xy 302.45278 -316.534888)
			(xy 302.493283 -316.562844) (xy 302.528776 -316.596936) (xy 302.558341 -316.63628) (xy 302.581212 -316.679857)
			(xy 302.596796 -316.726538) (xy 302.604691 -316.775115) (xy 302.605186 -316.799722) (xy 303.893994 -316.799722)
			(xy 303.897954 -316.750668) (xy 303.909731 -316.702884) (xy 303.929022 -316.657608) (xy 303.955325 -316.616012)
			(xy 303.98796 -316.579175) (xy 304.026081 -316.54805) (xy 304.068702 -316.523443) (xy 304.114718 -316.505991)
			(xy 304.162937 -316.496147) (xy 304.212112 -316.494166) (xy 304.260967 -316.500098) (xy 304.308238 -316.51379)
			(xy 304.3527 -316.534888) (xy 304.393203 -316.562844) (xy 304.428696 -316.596936) (xy 304.458261 -316.63628)
			(xy 304.481132 -316.679857) (xy 304.496716 -316.726538) (xy 304.504611 -316.775115) (xy 304.505106 -316.799722)
			(xy 305.793914 -316.799722) (xy 305.797874 -316.750668) (xy 305.809651 -316.702884) (xy 305.828942 -316.657608)
			(xy 305.855245 -316.616012) (xy 305.88788 -316.579175) (xy 305.926001 -316.54805) (xy 305.968622 -316.523443)
			(xy 306.014638 -316.505991) (xy 306.062857 -316.496147) (xy 306.112032 -316.494166) (xy 306.160887 -316.500098)
			(xy 306.208158 -316.51379) (xy 306.25262 -316.534888) (xy 306.293123 -316.562844) (xy 306.328616 -316.596936)
			(xy 306.358181 -316.63628) (xy 306.381052 -316.679857) (xy 306.396636 -316.726538) (xy 306.404531 -316.775115)
			(xy 306.405026 -316.799722) (xy 307.694088 -316.799722) (xy 307.698048 -316.750668) (xy 307.709825 -316.702884)
			(xy 307.729116 -316.657608) (xy 307.755419 -316.616012) (xy 307.788054 -316.579175) (xy 307.826175 -316.54805)
			(xy 307.868796 -316.523443) (xy 307.914812 -316.505991) (xy 307.963031 -316.496147) (xy 308.012206 -316.494166)
			(xy 308.061061 -316.500098) (xy 308.108332 -316.51379) (xy 308.152794 -316.534888) (xy 308.193297 -316.562844)
			(xy 308.22879 -316.596936) (xy 308.258355 -316.63628) (xy 308.281226 -316.679857) (xy 308.29681 -316.726538)
			(xy 308.304705 -316.775115) (xy 308.3052 -316.799722) (xy 309.594008 -316.799722) (xy 309.597968 -316.750668)
			(xy 309.609745 -316.702884) (xy 309.629036 -316.657608) (xy 309.655339 -316.616012) (xy 309.687974 -316.579175)
			(xy 309.726095 -316.54805) (xy 309.768716 -316.523443) (xy 309.814732 -316.505991) (xy 309.862951 -316.496147)
			(xy 309.912126 -316.494166) (xy 309.960981 -316.500098) (xy 310.008252 -316.51379) (xy 310.052714 -316.534888)
			(xy 310.093217 -316.562844) (xy 310.12871 -316.596936) (xy 310.158275 -316.63628) (xy 310.181146 -316.679857)
			(xy 310.19673 -316.726538) (xy 310.204625 -316.775115) (xy 310.20512 -316.799722) (xy 311.493928 -316.799722)
			(xy 311.497888 -316.750668) (xy 311.509665 -316.702884) (xy 311.528956 -316.657608) (xy 311.555259 -316.616012)
			(xy 311.587894 -316.579175) (xy 311.626015 -316.54805) (xy 311.668636 -316.523443) (xy 311.714652 -316.505991)
			(xy 311.762871 -316.496147) (xy 311.812046 -316.494166) (xy 311.860901 -316.500098) (xy 311.908172 -316.51379)
			(xy 311.952634 -316.534888) (xy 311.993137 -316.562844) (xy 312.02863 -316.596936) (xy 312.058195 -316.63628)
			(xy 312.081066 -316.679857) (xy 312.09665 -316.726538) (xy 312.104545 -316.775115) (xy 312.10504 -316.799722)
			(xy 313.394102 -316.799722) (xy 313.398062 -316.750668) (xy 313.409839 -316.702884) (xy 313.42913 -316.657608)
			(xy 313.455433 -316.616012) (xy 313.488068 -316.579175) (xy 313.526189 -316.54805) (xy 313.56881 -316.523443)
			(xy 313.614826 -316.505991) (xy 313.663045 -316.496147) (xy 313.71222 -316.494166) (xy 313.761075 -316.500098)
			(xy 313.808346 -316.51379) (xy 313.852808 -316.534888) (xy 313.893311 -316.562844) (xy 313.928804 -316.596936)
			(xy 313.958369 -316.63628) (xy 313.98124 -316.679857) (xy 313.996824 -316.726538) (xy 314.004719 -316.775115)
			(xy 314.005214 -316.799722) (xy 314.344062 -316.799722) (xy 314.348022 -316.750668) (xy 314.359799 -316.702884)
			(xy 314.37909 -316.657608) (xy 314.405393 -316.616012) (xy 314.438028 -316.579175) (xy 314.476149 -316.54805)
			(xy 314.51877 -316.523443) (xy 314.564786 -316.505991) (xy 314.613005 -316.496147) (xy 314.66218 -316.494166)
			(xy 314.711035 -316.500098) (xy 314.758306 -316.51379) (xy 314.802768 -316.534888) (xy 314.843271 -316.562844)
			(xy 314.878764 -316.596936) (xy 314.908329 -316.63628) (xy 314.9312 -316.679857) (xy 314.946784 -316.726538)
			(xy 314.954679 -316.775115) (xy 314.955174 -316.799722) (xy 384.844048 -316.799722) (xy 384.848008 -316.750668)
			(xy 384.859785 -316.702884) (xy 384.879076 -316.657608) (xy 384.905379 -316.616012) (xy 384.938014 -316.579175)
			(xy 384.976135 -316.54805) (xy 385.018756 -316.523443) (xy 385.064772 -316.505991) (xy 385.112991 -316.496147)
			(xy 385.162166 -316.494166) (xy 385.211021 -316.500098) (xy 385.258292 -316.51379) (xy 385.302754 -316.534888)
			(xy 385.343257 -316.562844) (xy 385.37875 -316.596936) (xy 385.408315 -316.63628) (xy 385.431186 -316.679857)
			(xy 385.44677 -316.726538) (xy 385.454665 -316.775115) (xy 385.45516 -316.799722) (xy 385.794008 -316.799722)
			(xy 385.797968 -316.750668) (xy 385.809745 -316.702884) (xy 385.829036 -316.657608) (xy 385.855339 -316.616012)
			(xy 385.887974 -316.579175) (xy 385.926095 -316.54805) (xy 385.968716 -316.523443) (xy 386.014732 -316.505991)
			(xy 386.062951 -316.496147) (xy 386.112126 -316.494166) (xy 386.160981 -316.500098) (xy 386.208252 -316.51379)
			(xy 386.252714 -316.534888) (xy 386.293217 -316.562844) (xy 386.32871 -316.596936) (xy 386.358275 -316.63628)
			(xy 386.381146 -316.679857) (xy 386.39673 -316.726538) (xy 386.404625 -316.775115) (xy 386.40512 -316.799722)
			(xy 387.694182 -316.799722) (xy 387.698142 -316.750668) (xy 387.709919 -316.702884) (xy 387.72921 -316.657608)
			(xy 387.755513 -316.616012) (xy 387.788148 -316.579175) (xy 387.826269 -316.54805) (xy 387.86889 -316.523443)
			(xy 387.914906 -316.505991) (xy 387.963125 -316.496147) (xy 388.0123 -316.494166) (xy 388.061155 -316.500098)
			(xy 388.108426 -316.51379) (xy 388.152888 -316.534888) (xy 388.193391 -316.562844) (xy 388.228884 -316.596936)
			(xy 388.258449 -316.63628) (xy 388.28132 -316.679857) (xy 388.296904 -316.726538) (xy 388.304799 -316.775115)
			(xy 388.305294 -316.799722) (xy 389.594102 -316.799722) (xy 389.598062 -316.750668) (xy 389.609839 -316.702884)
			(xy 389.62913 -316.657608) (xy 389.655433 -316.616012) (xy 389.688068 -316.579175) (xy 389.726189 -316.54805)
			(xy 389.76881 -316.523443) (xy 389.814826 -316.505991) (xy 389.863045 -316.496147) (xy 389.91222 -316.494166)
			(xy 389.961075 -316.500098) (xy 390.008346 -316.51379) (xy 390.052808 -316.534888) (xy 390.093311 -316.562844)
			(xy 390.128804 -316.596936) (xy 390.158369 -316.63628) (xy 390.18124 -316.679857) (xy 390.196824 -316.726538)
			(xy 390.204719 -316.775115) (xy 390.205214 -316.799722) (xy 391.494022 -316.799722) (xy 391.497982 -316.750668)
			(xy 391.509759 -316.702884) (xy 391.52905 -316.657608) (xy 391.555353 -316.616012) (xy 391.587988 -316.579175)
			(xy 391.626109 -316.54805) (xy 391.66873 -316.523443) (xy 391.714746 -316.505991) (xy 391.762965 -316.496147)
			(xy 391.81214 -316.494166) (xy 391.860995 -316.500098) (xy 391.908266 -316.51379) (xy 391.952728 -316.534888)
			(xy 391.993231 -316.562844) (xy 392.028724 -316.596936) (xy 392.058289 -316.63628) (xy 392.08116 -316.679857)
			(xy 392.096744 -316.726538) (xy 392.104639 -316.775115) (xy 392.105134 -316.799722) (xy 393.394196 -316.799722)
			(xy 393.398156 -316.750668) (xy 393.409933 -316.702884) (xy 393.429224 -316.657608) (xy 393.455527 -316.616012)
			(xy 393.488162 -316.579175) (xy 393.526283 -316.54805) (xy 393.568904 -316.523443) (xy 393.61492 -316.505991)
			(xy 393.663139 -316.496147) (xy 393.712314 -316.494166) (xy 393.761169 -316.500098) (xy 393.80844 -316.51379)
			(xy 393.852902 -316.534888) (xy 393.893405 -316.562844) (xy 393.928898 -316.596936) (xy 393.958463 -316.63628)
			(xy 393.981334 -316.679857) (xy 393.996918 -316.726538) (xy 394.004813 -316.775115) (xy 394.005308 -316.799722)
			(xy 395.294116 -316.799722) (xy 395.298076 -316.750668) (xy 395.309853 -316.702884) (xy 395.329144 -316.657608)
			(xy 395.355447 -316.616012) (xy 395.388082 -316.579175) (xy 395.426203 -316.54805) (xy 395.468824 -316.523443)
			(xy 395.51484 -316.505991) (xy 395.563059 -316.496147) (xy 395.612234 -316.494166) (xy 395.661089 -316.500098)
			(xy 395.70836 -316.51379) (xy 395.752822 -316.534888) (xy 395.793325 -316.562844) (xy 395.828818 -316.596936)
			(xy 395.858383 -316.63628) (xy 395.881254 -316.679857) (xy 395.896838 -316.726538) (xy 395.904733 -316.775115)
			(xy 395.905228 -316.799722) (xy 397.194036 -316.799722) (xy 397.197996 -316.750668) (xy 397.209773 -316.702884)
			(xy 397.229064 -316.657608) (xy 397.255367 -316.616012) (xy 397.288002 -316.579175) (xy 397.326123 -316.54805)
			(xy 397.368744 -316.523443) (xy 397.41476 -316.505991) (xy 397.462979 -316.496147) (xy 397.512154 -316.494166)
			(xy 397.561009 -316.500098) (xy 397.60828 -316.51379) (xy 397.652742 -316.534888) (xy 397.693245 -316.562844)
			(xy 397.728738 -316.596936) (xy 397.758303 -316.63628) (xy 397.781174 -316.679857) (xy 397.796758 -316.726538)
			(xy 397.804653 -316.775115) (xy 397.805148 -316.799722) (xy 399.09421 -316.799722) (xy 399.09817 -316.750668)
			(xy 399.109947 -316.702884) (xy 399.129238 -316.657608) (xy 399.155541 -316.616012) (xy 399.188176 -316.579175)
			(xy 399.226297 -316.54805) (xy 399.268918 -316.523443) (xy 399.314934 -316.505991) (xy 399.363153 -316.496147)
			(xy 399.412328 -316.494166) (xy 399.461183 -316.500098) (xy 399.508454 -316.51379) (xy 399.552916 -316.534888)
			(xy 399.593419 -316.562844) (xy 399.628912 -316.596936) (xy 399.658477 -316.63628) (xy 399.681348 -316.679857)
			(xy 399.696932 -316.726538) (xy 399.704827 -316.775115) (xy 399.705322 -316.799722) (xy 400.99413 -316.799722)
			(xy 400.99809 -316.750668) (xy 401.009867 -316.702884) (xy 401.029158 -316.657608) (xy 401.055461 -316.616012)
			(xy 401.088096 -316.579175) (xy 401.126217 -316.54805) (xy 401.168838 -316.523443) (xy 401.214854 -316.505991)
			(xy 401.263073 -316.496147) (xy 401.312248 -316.494166) (xy 401.361103 -316.500098) (xy 401.408374 -316.51379)
			(xy 401.452836 -316.534888) (xy 401.493339 -316.562844) (xy 401.528832 -316.596936) (xy 401.558397 -316.63628)
			(xy 401.581268 -316.679857) (xy 401.596852 -316.726538) (xy 401.604747 -316.775115) (xy 401.605242 -316.799722)
			(xy 402.89405 -316.799722) (xy 402.89801 -316.750668) (xy 402.909787 -316.702884) (xy 402.929078 -316.657608)
			(xy 402.955381 -316.616012) (xy 402.988016 -316.579175) (xy 403.026137 -316.54805) (xy 403.068758 -316.523443)
			(xy 403.114774 -316.505991) (xy 403.162993 -316.496147) (xy 403.212168 -316.494166) (xy 403.261023 -316.500098)
			(xy 403.308294 -316.51379) (xy 403.352756 -316.534888) (xy 403.393259 -316.562844) (xy 403.428752 -316.596936)
			(xy 403.458317 -316.63628) (xy 403.481188 -316.679857) (xy 403.496772 -316.726538) (xy 403.504667 -316.775115)
			(xy 403.505162 -316.799722) (xy 404.794224 -316.799722) (xy 404.798184 -316.750668) (xy 404.809961 -316.702884)
			(xy 404.829252 -316.657608) (xy 404.855555 -316.616012) (xy 404.88819 -316.579175) (xy 404.926311 -316.54805)
			(xy 404.968932 -316.523443) (xy 405.014948 -316.505991) (xy 405.063167 -316.496147) (xy 405.112342 -316.494166)
			(xy 405.161197 -316.500098) (xy 405.208468 -316.51379) (xy 405.25293 -316.534888) (xy 405.293433 -316.562844)
			(xy 405.328926 -316.596936) (xy 405.358491 -316.63628) (xy 405.381362 -316.679857) (xy 405.396946 -316.726538)
			(xy 405.404841 -316.775115) (xy 405.405336 -316.799722) (xy 406.694144 -316.799722) (xy 406.698104 -316.750668)
			(xy 406.709881 -316.702884) (xy 406.729172 -316.657608) (xy 406.755475 -316.616012) (xy 406.78811 -316.579175)
			(xy 406.826231 -316.54805) (xy 406.868852 -316.523443) (xy 406.914868 -316.505991) (xy 406.963087 -316.496147)
			(xy 407.012262 -316.494166) (xy 407.061117 -316.500098) (xy 407.108388 -316.51379) (xy 407.15285 -316.534888)
			(xy 407.193353 -316.562844) (xy 407.228846 -316.596936) (xy 407.258411 -316.63628) (xy 407.281282 -316.679857)
			(xy 407.296866 -316.726538) (xy 407.304761 -316.775115) (xy 407.305256 -316.799722) (xy 408.594064 -316.799722)
			(xy 408.598024 -316.750668) (xy 408.609801 -316.702884) (xy 408.629092 -316.657608) (xy 408.655395 -316.616012)
			(xy 408.68803 -316.579175) (xy 408.726151 -316.54805) (xy 408.768772 -316.523443) (xy 408.814788 -316.505991)
			(xy 408.863007 -316.496147) (xy 408.912182 -316.494166) (xy 408.961037 -316.500098) (xy 409.008308 -316.51379)
			(xy 409.05277 -316.534888) (xy 409.093273 -316.562844) (xy 409.128766 -316.596936) (xy 409.158331 -316.63628)
			(xy 409.181202 -316.679857) (xy 409.196786 -316.726538) (xy 409.204681 -316.775115) (xy 409.205176 -316.799722)
			(xy 410.493984 -316.799722) (xy 410.497944 -316.750668) (xy 410.509721 -316.702884) (xy 410.529012 -316.657608)
			(xy 410.555315 -316.616012) (xy 410.58795 -316.579175) (xy 410.626071 -316.54805) (xy 410.668692 -316.523443)
			(xy 410.714708 -316.505991) (xy 410.762927 -316.496147) (xy 410.812102 -316.494166) (xy 410.860957 -316.500098)
			(xy 410.908228 -316.51379) (xy 410.95269 -316.534888) (xy 410.993193 -316.562844) (xy 411.028686 -316.596936)
			(xy 411.058251 -316.63628) (xy 411.081122 -316.679857) (xy 411.096706 -316.726538) (xy 411.104601 -316.775115)
			(xy 411.105096 -316.799722) (xy 412.394158 -316.799722) (xy 412.398118 -316.750668) (xy 412.409895 -316.702884)
			(xy 412.429186 -316.657608) (xy 412.455489 -316.616012) (xy 412.488124 -316.579175) (xy 412.526245 -316.54805)
			(xy 412.568866 -316.523443) (xy 412.614882 -316.505991) (xy 412.663101 -316.496147) (xy 412.712276 -316.494166)
			(xy 412.761131 -316.500098) (xy 412.808402 -316.51379) (xy 412.852864 -316.534888) (xy 412.893367 -316.562844)
			(xy 412.92886 -316.596936) (xy 412.958425 -316.63628) (xy 412.981296 -316.679857) (xy 412.99688 -316.726538)
			(xy 413.004775 -316.775115) (xy 413.00527 -316.799722) (xy 414.294078 -316.799722) (xy 414.298038 -316.750668)
			(xy 414.309815 -316.702884) (xy 414.329106 -316.657608) (xy 414.355409 -316.616012) (xy 414.388044 -316.579175)
			(xy 414.426165 -316.54805) (xy 414.468786 -316.523443) (xy 414.514802 -316.505991) (xy 414.563021 -316.496147)
			(xy 414.612196 -316.494166) (xy 414.661051 -316.500098) (xy 414.708322 -316.51379) (xy 414.752784 -316.534888)
			(xy 414.793287 -316.562844) (xy 414.82878 -316.596936) (xy 414.858345 -316.63628) (xy 414.881216 -316.679857)
			(xy 414.8968 -316.726538) (xy 414.904695 -316.775115) (xy 414.90519 -316.799722) (xy 416.193998 -316.799722)
			(xy 416.197958 -316.750668) (xy 416.209735 -316.702884) (xy 416.229026 -316.657608) (xy 416.255329 -316.616012)
			(xy 416.287964 -316.579175) (xy 416.326085 -316.54805) (xy 416.368706 -316.523443) (xy 416.414722 -316.505991)
			(xy 416.462941 -316.496147) (xy 416.512116 -316.494166) (xy 416.560971 -316.500098) (xy 416.608242 -316.51379)
			(xy 416.652704 -316.534888) (xy 416.693207 -316.562844) (xy 416.7287 -316.596936) (xy 416.758265 -316.63628)
			(xy 416.781136 -316.679857) (xy 416.79672 -316.726538) (xy 416.804615 -316.775115) (xy 416.80511 -316.799722)
			(xy 418.094172 -316.799722) (xy 418.098132 -316.750668) (xy 418.109909 -316.702884) (xy 418.1292 -316.657608)
			(xy 418.155503 -316.616012) (xy 418.188138 -316.579175) (xy 418.226259 -316.54805) (xy 418.26888 -316.523443)
			(xy 418.314896 -316.505991) (xy 418.363115 -316.496147) (xy 418.41229 -316.494166) (xy 418.461145 -316.500098)
			(xy 418.508416 -316.51379) (xy 418.552878 -316.534888) (xy 418.593381 -316.562844) (xy 418.628874 -316.596936)
			(xy 418.658439 -316.63628) (xy 418.68131 -316.679857) (xy 418.696894 -316.726538) (xy 418.704789 -316.775115)
			(xy 418.705284 -316.799722) (xy 419.994092 -316.799722) (xy 419.998052 -316.750668) (xy 420.009829 -316.702884)
			(xy 420.02912 -316.657608) (xy 420.055423 -316.616012) (xy 420.088058 -316.579175) (xy 420.126179 -316.54805)
			(xy 420.1688 -316.523443) (xy 420.214816 -316.505991) (xy 420.263035 -316.496147) (xy 420.31221 -316.494166)
			(xy 420.361065 -316.500098) (xy 420.408336 -316.51379) (xy 420.452798 -316.534888) (xy 420.493301 -316.562844)
			(xy 420.528794 -316.596936) (xy 420.558359 -316.63628) (xy 420.58123 -316.679857) (xy 420.596814 -316.726538)
			(xy 420.604709 -316.775115) (xy 420.605204 -316.799722) (xy 421.894012 -316.799722) (xy 421.897972 -316.750668)
			(xy 421.909749 -316.702884) (xy 421.92904 -316.657608) (xy 421.955343 -316.616012) (xy 421.987978 -316.579175)
			(xy 422.026099 -316.54805) (xy 422.06872 -316.523443) (xy 422.114736 -316.505991) (xy 422.162955 -316.496147)
			(xy 422.21213 -316.494166) (xy 422.260985 -316.500098) (xy 422.308256 -316.51379) (xy 422.352718 -316.534888)
			(xy 422.393221 -316.562844) (xy 422.428714 -316.596936) (xy 422.458279 -316.63628) (xy 422.48115 -316.679857)
			(xy 422.496734 -316.726538) (xy 422.504629 -316.775115) (xy 422.505124 -316.799722) (xy 423.794186 -316.799722)
			(xy 423.798146 -316.750668) (xy 423.809923 -316.702884) (xy 423.829214 -316.657608) (xy 423.855517 -316.616012)
			(xy 423.888152 -316.579175) (xy 423.926273 -316.54805) (xy 423.968894 -316.523443) (xy 424.01491 -316.505991)
			(xy 424.063129 -316.496147) (xy 424.112304 -316.494166) (xy 424.161159 -316.500098) (xy 424.20843 -316.51379)
			(xy 424.252892 -316.534888) (xy 424.293395 -316.562844) (xy 424.328888 -316.596936) (xy 424.358453 -316.63628)
			(xy 424.381324 -316.679857) (xy 424.396908 -316.726538) (xy 424.404803 -316.775115) (xy 424.405298 -316.799722)
			(xy 425.694106 -316.799722) (xy 425.698066 -316.750668) (xy 425.709843 -316.702884) (xy 425.729134 -316.657608)
			(xy 425.755437 -316.616012) (xy 425.788072 -316.579175) (xy 425.826193 -316.54805) (xy 425.868814 -316.523443)
			(xy 425.91483 -316.505991) (xy 425.963049 -316.496147) (xy 426.012224 -316.494166) (xy 426.061079 -316.500098)
			(xy 426.10835 -316.51379) (xy 426.152812 -316.534888) (xy 426.193315 -316.562844) (xy 426.228808 -316.596936)
			(xy 426.258373 -316.63628) (xy 426.281244 -316.679857) (xy 426.296828 -316.726538) (xy 426.304723 -316.775115)
			(xy 426.305218 -316.799722) (xy 427.594026 -316.799722) (xy 427.597986 -316.750668) (xy 427.609763 -316.702884)
			(xy 427.629054 -316.657608) (xy 427.655357 -316.616012) (xy 427.687992 -316.579175) (xy 427.726113 -316.54805)
			(xy 427.768734 -316.523443) (xy 427.81475 -316.505991) (xy 427.862969 -316.496147) (xy 427.912144 -316.494166)
			(xy 427.960999 -316.500098) (xy 428.00827 -316.51379) (xy 428.052732 -316.534888) (xy 428.093235 -316.562844)
			(xy 428.128728 -316.596936) (xy 428.158293 -316.63628) (xy 428.181164 -316.679857) (xy 428.196748 -316.726538)
			(xy 428.204643 -316.775115) (xy 428.205138 -316.799722) (xy 429.4942 -316.799722) (xy 429.49816 -316.750668)
			(xy 429.509937 -316.702884) (xy 429.529228 -316.657608) (xy 429.555531 -316.616012) (xy 429.588166 -316.579175)
			(xy 429.626287 -316.54805) (xy 429.668908 -316.523443) (xy 429.714924 -316.505991) (xy 429.763143 -316.496147)
			(xy 429.812318 -316.494166) (xy 429.861173 -316.500098) (xy 429.908444 -316.51379) (xy 429.952906 -316.534888)
			(xy 429.993409 -316.562844) (xy 430.028902 -316.596936) (xy 430.058467 -316.63628) (xy 430.081338 -316.679857)
			(xy 430.096922 -316.726538) (xy 430.104817 -316.775115) (xy 430.105312 -316.799722) (xy 430.44416 -316.799722)
			(xy 430.44812 -316.750668) (xy 430.459897 -316.702884) (xy 430.479188 -316.657608) (xy 430.505491 -316.616012)
			(xy 430.538126 -316.579175) (xy 430.576247 -316.54805) (xy 430.618868 -316.523443) (xy 430.664884 -316.505991)
			(xy 430.713103 -316.496147) (xy 430.762278 -316.494166) (xy 430.811133 -316.500098) (xy 430.858404 -316.51379)
			(xy 430.902866 -316.534888) (xy 430.943369 -316.562844) (xy 430.978862 -316.596936) (xy 431.008427 -316.63628)
			(xy 431.031298 -316.679857) (xy 431.046882 -316.726538) (xy 431.054777 -316.775115) (xy 431.055272 -316.799722)
			(xy 431.054777 -316.824329) (xy 431.046882 -316.872906) (xy 431.031298 -316.919587) (xy 431.008427 -316.963164)
			(xy 430.978862 -317.002508) (xy 430.943369 -317.0366) (xy 430.902866 -317.064556) (xy 430.858404 -317.085654)
			(xy 430.811133 -317.099346) (xy 430.762278 -317.105278) (xy 430.713103 -317.103297) (xy 430.664884 -317.093453)
			(xy 430.618868 -317.076001) (xy 430.576247 -317.051394) (xy 430.538126 -317.020269) (xy 430.505491 -316.983432)
			(xy 430.479188 -316.941836) (xy 430.459897 -316.89656) (xy 430.44812 -316.848776) (xy 430.44416 -316.799722)
			(xy 430.105312 -316.799722) (xy 430.104817 -316.824329) (xy 430.096922 -316.872906) (xy 430.081338 -316.919587)
			(xy 430.058467 -316.963164) (xy 430.028902 -317.002508) (xy 429.993409 -317.0366) (xy 429.952906 -317.064556)
			(xy 429.908444 -317.085654) (xy 429.861173 -317.099346) (xy 429.812318 -317.105278) (xy 429.763143 -317.103297)
			(xy 429.714924 -317.093453) (xy 429.668908 -317.076001) (xy 429.626287 -317.051394) (xy 429.588166 -317.020269)
			(xy 429.555531 -316.983432) (xy 429.529228 -316.941836) (xy 429.509937 -316.89656) (xy 429.49816 -316.848776)
			(xy 429.4942 -316.799722) (xy 428.205138 -316.799722) (xy 428.204643 -316.824329) (xy 428.196748 -316.872906)
			(xy 428.181164 -316.919587) (xy 428.158293 -316.963164) (xy 428.128728 -317.002508) (xy 428.093235 -317.0366)
			(xy 428.052732 -317.064556) (xy 428.00827 -317.085654) (xy 427.960999 -317.099346) (xy 427.912144 -317.105278)
			(xy 427.862969 -317.103297) (xy 427.81475 -317.093453) (xy 427.768734 -317.076001) (xy 427.726113 -317.051394)
			(xy 427.687992 -317.020269) (xy 427.655357 -316.983432) (xy 427.629054 -316.941836) (xy 427.609763 -316.89656)
			(xy 427.597986 -316.848776) (xy 427.594026 -316.799722) (xy 426.305218 -316.799722) (xy 426.304723 -316.824329)
			(xy 426.296828 -316.872906) (xy 426.281244 -316.919587) (xy 426.258373 -316.963164) (xy 426.228808 -317.002508)
			(xy 426.193315 -317.0366) (xy 426.152812 -317.064556) (xy 426.10835 -317.085654) (xy 426.061079 -317.099346)
			(xy 426.012224 -317.105278) (xy 425.963049 -317.103297) (xy 425.91483 -317.093453) (xy 425.868814 -317.076001)
			(xy 425.826193 -317.051394) (xy 425.788072 -317.020269) (xy 425.755437 -316.983432) (xy 425.729134 -316.941836)
			(xy 425.709843 -316.89656) (xy 425.698066 -316.848776) (xy 425.694106 -316.799722) (xy 424.405298 -316.799722)
			(xy 424.404803 -316.824329) (xy 424.396908 -316.872906) (xy 424.381324 -316.919587) (xy 424.358453 -316.963164)
			(xy 424.328888 -317.002508) (xy 424.293395 -317.0366) (xy 424.252892 -317.064556) (xy 424.20843 -317.085654)
			(xy 424.161159 -317.099346) (xy 424.112304 -317.105278) (xy 424.063129 -317.103297) (xy 424.01491 -317.093453)
			(xy 423.968894 -317.076001) (xy 423.926273 -317.051394) (xy 423.888152 -317.020269) (xy 423.855517 -316.983432)
			(xy 423.829214 -316.941836) (xy 423.809923 -316.89656) (xy 423.798146 -316.848776) (xy 423.794186 -316.799722)
			(xy 422.505124 -316.799722) (xy 422.504629 -316.824329) (xy 422.496734 -316.872906) (xy 422.48115 -316.919587)
			(xy 422.458279 -316.963164) (xy 422.428714 -317.002508) (xy 422.393221 -317.0366) (xy 422.352718 -317.064556)
			(xy 422.308256 -317.085654) (xy 422.260985 -317.099346) (xy 422.21213 -317.105278) (xy 422.162955 -317.103297)
			(xy 422.114736 -317.093453) (xy 422.06872 -317.076001) (xy 422.026099 -317.051394) (xy 421.987978 -317.020269)
			(xy 421.955343 -316.983432) (xy 421.92904 -316.941836) (xy 421.909749 -316.89656) (xy 421.897972 -316.848776)
			(xy 421.894012 -316.799722) (xy 420.605204 -316.799722) (xy 420.604709 -316.824329) (xy 420.596814 -316.872906)
			(xy 420.58123 -316.919587) (xy 420.558359 -316.963164) (xy 420.528794 -317.002508) (xy 420.493301 -317.0366)
			(xy 420.452798 -317.064556) (xy 420.408336 -317.085654) (xy 420.361065 -317.099346) (xy 420.31221 -317.105278)
			(xy 420.263035 -317.103297) (xy 420.214816 -317.093453) (xy 420.1688 -317.076001) (xy 420.126179 -317.051394)
			(xy 420.088058 -317.020269) (xy 420.055423 -316.983432) (xy 420.02912 -316.941836) (xy 420.009829 -316.89656)
			(xy 419.998052 -316.848776) (xy 419.994092 -316.799722) (xy 418.705284 -316.799722) (xy 418.704789 -316.824329)
			(xy 418.696894 -316.872906) (xy 418.68131 -316.919587) (xy 418.658439 -316.963164) (xy 418.628874 -317.002508)
			(xy 418.593381 -317.0366) (xy 418.552878 -317.064556) (xy 418.508416 -317.085654) (xy 418.461145 -317.099346)
			(xy 418.41229 -317.105278) (xy 418.363115 -317.103297) (xy 418.314896 -317.093453) (xy 418.26888 -317.076001)
			(xy 418.226259 -317.051394) (xy 418.188138 -317.020269) (xy 418.155503 -316.983432) (xy 418.1292 -316.941836)
			(xy 418.109909 -316.89656) (xy 418.098132 -316.848776) (xy 418.094172 -316.799722) (xy 416.80511 -316.799722)
			(xy 416.804615 -316.824329) (xy 416.79672 -316.872906) (xy 416.781136 -316.919587) (xy 416.758265 -316.963164)
			(xy 416.7287 -317.002508) (xy 416.693207 -317.0366) (xy 416.652704 -317.064556) (xy 416.608242 -317.085654)
			(xy 416.560971 -317.099346) (xy 416.512116 -317.105278) (xy 416.462941 -317.103297) (xy 416.414722 -317.093453)
			(xy 416.368706 -317.076001) (xy 416.326085 -317.051394) (xy 416.287964 -317.020269) (xy 416.255329 -316.983432)
			(xy 416.229026 -316.941836) (xy 416.209735 -316.89656) (xy 416.197958 -316.848776) (xy 416.193998 -316.799722)
			(xy 414.90519 -316.799722) (xy 414.904695 -316.824329) (xy 414.8968 -316.872906) (xy 414.881216 -316.919587)
			(xy 414.858345 -316.963164) (xy 414.82878 -317.002508) (xy 414.793287 -317.0366) (xy 414.752784 -317.064556)
			(xy 414.708322 -317.085654) (xy 414.661051 -317.099346) (xy 414.612196 -317.105278) (xy 414.563021 -317.103297)
			(xy 414.514802 -317.093453) (xy 414.468786 -317.076001) (xy 414.426165 -317.051394) (xy 414.388044 -317.020269)
			(xy 414.355409 -316.983432) (xy 414.329106 -316.941836) (xy 414.309815 -316.89656) (xy 414.298038 -316.848776)
			(xy 414.294078 -316.799722) (xy 413.00527 -316.799722) (xy 413.004775 -316.824329) (xy 412.99688 -316.872906)
			(xy 412.981296 -316.919587) (xy 412.958425 -316.963164) (xy 412.92886 -317.002508) (xy 412.893367 -317.0366)
			(xy 412.852864 -317.064556) (xy 412.808402 -317.085654) (xy 412.761131 -317.099346) (xy 412.712276 -317.105278)
			(xy 412.663101 -317.103297) (xy 412.614882 -317.093453) (xy 412.568866 -317.076001) (xy 412.526245 -317.051394)
			(xy 412.488124 -317.020269) (xy 412.455489 -316.983432) (xy 412.429186 -316.941836) (xy 412.409895 -316.89656)
			(xy 412.398118 -316.848776) (xy 412.394158 -316.799722) (xy 411.105096 -316.799722) (xy 411.104601 -316.824329)
			(xy 411.096706 -316.872906) (xy 411.081122 -316.919587) (xy 411.058251 -316.963164) (xy 411.028686 -317.002508)
			(xy 410.993193 -317.0366) (xy 410.95269 -317.064556) (xy 410.908228 -317.085654) (xy 410.860957 -317.099346)
			(xy 410.812102 -317.105278) (xy 410.762927 -317.103297) (xy 410.714708 -317.093453) (xy 410.668692 -317.076001)
			(xy 410.626071 -317.051394) (xy 410.58795 -317.020269) (xy 410.555315 -316.983432) (xy 410.529012 -316.941836)
			(xy 410.509721 -316.89656) (xy 410.497944 -316.848776) (xy 410.493984 -316.799722) (xy 409.205176 -316.799722)
			(xy 409.204681 -316.824329) (xy 409.196786 -316.872906) (xy 409.181202 -316.919587) (xy 409.158331 -316.963164)
			(xy 409.128766 -317.002508) (xy 409.093273 -317.0366) (xy 409.05277 -317.064556) (xy 409.008308 -317.085654)
			(xy 408.961037 -317.099346) (xy 408.912182 -317.105278) (xy 408.863007 -317.103297) (xy 408.814788 -317.093453)
			(xy 408.768772 -317.076001) (xy 408.726151 -317.051394) (xy 408.68803 -317.020269) (xy 408.655395 -316.983432)
			(xy 408.629092 -316.941836) (xy 408.609801 -316.89656) (xy 408.598024 -316.848776) (xy 408.594064 -316.799722)
			(xy 407.305256 -316.799722) (xy 407.304761 -316.824329) (xy 407.296866 -316.872906) (xy 407.281282 -316.919587)
			(xy 407.258411 -316.963164) (xy 407.228846 -317.002508) (xy 407.193353 -317.0366) (xy 407.15285 -317.064556)
			(xy 407.108388 -317.085654) (xy 407.061117 -317.099346) (xy 407.012262 -317.105278) (xy 406.963087 -317.103297)
			(xy 406.914868 -317.093453) (xy 406.868852 -317.076001) (xy 406.826231 -317.051394) (xy 406.78811 -317.020269)
			(xy 406.755475 -316.983432) (xy 406.729172 -316.941836) (xy 406.709881 -316.89656) (xy 406.698104 -316.848776)
			(xy 406.694144 -316.799722) (xy 405.405336 -316.799722) (xy 405.404841 -316.824329) (xy 405.396946 -316.872906)
			(xy 405.381362 -316.919587) (xy 405.358491 -316.963164) (xy 405.328926 -317.002508) (xy 405.293433 -317.0366)
			(xy 405.25293 -317.064556) (xy 405.208468 -317.085654) (xy 405.161197 -317.099346) (xy 405.112342 -317.105278)
			(xy 405.063167 -317.103297) (xy 405.014948 -317.093453) (xy 404.968932 -317.076001) (xy 404.926311 -317.051394)
			(xy 404.88819 -317.020269) (xy 404.855555 -316.983432) (xy 404.829252 -316.941836) (xy 404.809961 -316.89656)
			(xy 404.798184 -316.848776) (xy 404.794224 -316.799722) (xy 403.505162 -316.799722) (xy 403.504667 -316.824329)
			(xy 403.496772 -316.872906) (xy 403.481188 -316.919587) (xy 403.458317 -316.963164) (xy 403.428752 -317.002508)
			(xy 403.393259 -317.0366) (xy 403.352756 -317.064556) (xy 403.308294 -317.085654) (xy 403.261023 -317.099346)
			(xy 403.212168 -317.105278) (xy 403.162993 -317.103297) (xy 403.114774 -317.093453) (xy 403.068758 -317.076001)
			(xy 403.026137 -317.051394) (xy 402.988016 -317.020269) (xy 402.955381 -316.983432) (xy 402.929078 -316.941836)
			(xy 402.909787 -316.89656) (xy 402.89801 -316.848776) (xy 402.89405 -316.799722) (xy 401.605242 -316.799722)
			(xy 401.604747 -316.824329) (xy 401.596852 -316.872906) (xy 401.581268 -316.919587) (xy 401.558397 -316.963164)
			(xy 401.528832 -317.002508) (xy 401.493339 -317.0366) (xy 401.452836 -317.064556) (xy 401.408374 -317.085654)
			(xy 401.361103 -317.099346) (xy 401.312248 -317.105278) (xy 401.263073 -317.103297) (xy 401.214854 -317.093453)
			(xy 401.168838 -317.076001) (xy 401.126217 -317.051394) (xy 401.088096 -317.020269) (xy 401.055461 -316.983432)
			(xy 401.029158 -316.941836) (xy 401.009867 -316.89656) (xy 400.99809 -316.848776) (xy 400.99413 -316.799722)
			(xy 399.705322 -316.799722) (xy 399.704827 -316.824329) (xy 399.696932 -316.872906) (xy 399.681348 -316.919587)
			(xy 399.658477 -316.963164) (xy 399.628912 -317.002508) (xy 399.593419 -317.0366) (xy 399.552916 -317.064556)
			(xy 399.508454 -317.085654) (xy 399.461183 -317.099346) (xy 399.412328 -317.105278) (xy 399.363153 -317.103297)
			(xy 399.314934 -317.093453) (xy 399.268918 -317.076001) (xy 399.226297 -317.051394) (xy 399.188176 -317.020269)
			(xy 399.155541 -316.983432) (xy 399.129238 -316.941836) (xy 399.109947 -316.89656) (xy 399.09817 -316.848776)
			(xy 399.09421 -316.799722) (xy 397.805148 -316.799722) (xy 397.804653 -316.824329) (xy 397.796758 -316.872906)
			(xy 397.781174 -316.919587) (xy 397.758303 -316.963164) (xy 397.728738 -317.002508) (xy 397.693245 -317.0366)
			(xy 397.652742 -317.064556) (xy 397.60828 -317.085654) (xy 397.561009 -317.099346) (xy 397.512154 -317.105278)
			(xy 397.462979 -317.103297) (xy 397.41476 -317.093453) (xy 397.368744 -317.076001) (xy 397.326123 -317.051394)
			(xy 397.288002 -317.020269) (xy 397.255367 -316.983432) (xy 397.229064 -316.941836) (xy 397.209773 -316.89656)
			(xy 397.197996 -316.848776) (xy 397.194036 -316.799722) (xy 395.905228 -316.799722) (xy 395.904733 -316.824329)
			(xy 395.896838 -316.872906) (xy 395.881254 -316.919587) (xy 395.858383 -316.963164) (xy 395.828818 -317.002508)
			(xy 395.793325 -317.0366) (xy 395.752822 -317.064556) (xy 395.70836 -317.085654) (xy 395.661089 -317.099346)
			(xy 395.612234 -317.105278) (xy 395.563059 -317.103297) (xy 395.51484 -317.093453) (xy 395.468824 -317.076001)
			(xy 395.426203 -317.051394) (xy 395.388082 -317.020269) (xy 395.355447 -316.983432) (xy 395.329144 -316.941836)
			(xy 395.309853 -316.89656) (xy 395.298076 -316.848776) (xy 395.294116 -316.799722) (xy 394.005308 -316.799722)
			(xy 394.004813 -316.824329) (xy 393.996918 -316.872906) (xy 393.981334 -316.919587) (xy 393.958463 -316.963164)
			(xy 393.928898 -317.002508) (xy 393.893405 -317.0366) (xy 393.852902 -317.064556) (xy 393.80844 -317.085654)
			(xy 393.761169 -317.099346) (xy 393.712314 -317.105278) (xy 393.663139 -317.103297) (xy 393.61492 -317.093453)
			(xy 393.568904 -317.076001) (xy 393.526283 -317.051394) (xy 393.488162 -317.020269) (xy 393.455527 -316.983432)
			(xy 393.429224 -316.941836) (xy 393.409933 -316.89656) (xy 393.398156 -316.848776) (xy 393.394196 -316.799722)
			(xy 392.105134 -316.799722) (xy 392.104639 -316.824329) (xy 392.096744 -316.872906) (xy 392.08116 -316.919587)
			(xy 392.058289 -316.963164) (xy 392.028724 -317.002508) (xy 391.993231 -317.0366) (xy 391.952728 -317.064556)
			(xy 391.908266 -317.085654) (xy 391.860995 -317.099346) (xy 391.81214 -317.105278) (xy 391.762965 -317.103297)
			(xy 391.714746 -317.093453) (xy 391.66873 -317.076001) (xy 391.626109 -317.051394) (xy 391.587988 -317.020269)
			(xy 391.555353 -316.983432) (xy 391.52905 -316.941836) (xy 391.509759 -316.89656) (xy 391.497982 -316.848776)
			(xy 391.494022 -316.799722) (xy 390.205214 -316.799722) (xy 390.204719 -316.824329) (xy 390.196824 -316.872906)
			(xy 390.18124 -316.919587) (xy 390.158369 -316.963164) (xy 390.128804 -317.002508) (xy 390.093311 -317.0366)
			(xy 390.052808 -317.064556) (xy 390.008346 -317.085654) (xy 389.961075 -317.099346) (xy 389.91222 -317.105278)
			(xy 389.863045 -317.103297) (xy 389.814826 -317.093453) (xy 389.76881 -317.076001) (xy 389.726189 -317.051394)
			(xy 389.688068 -317.020269) (xy 389.655433 -316.983432) (xy 389.62913 -316.941836) (xy 389.609839 -316.89656)
			(xy 389.598062 -316.848776) (xy 389.594102 -316.799722) (xy 388.305294 -316.799722) (xy 388.304799 -316.824329)
			(xy 388.296904 -316.872906) (xy 388.28132 -316.919587) (xy 388.258449 -316.963164) (xy 388.228884 -317.002508)
			(xy 388.193391 -317.0366) (xy 388.152888 -317.064556) (xy 388.108426 -317.085654) (xy 388.061155 -317.099346)
			(xy 388.0123 -317.105278) (xy 387.963125 -317.103297) (xy 387.914906 -317.093453) (xy 387.86889 -317.076001)
			(xy 387.826269 -317.051394) (xy 387.788148 -317.020269) (xy 387.755513 -316.983432) (xy 387.72921 -316.941836)
			(xy 387.709919 -316.89656) (xy 387.698142 -316.848776) (xy 387.694182 -316.799722) (xy 386.40512 -316.799722)
			(xy 386.404625 -316.824329) (xy 386.39673 -316.872906) (xy 386.381146 -316.919587) (xy 386.358275 -316.963164)
			(xy 386.32871 -317.002508) (xy 386.293217 -317.0366) (xy 386.252714 -317.064556) (xy 386.208252 -317.085654)
			(xy 386.160981 -317.099346) (xy 386.112126 -317.105278) (xy 386.062951 -317.103297) (xy 386.014732 -317.093453)
			(xy 385.968716 -317.076001) (xy 385.926095 -317.051394) (xy 385.887974 -317.020269) (xy 385.855339 -316.983432)
			(xy 385.829036 -316.941836) (xy 385.809745 -316.89656) (xy 385.797968 -316.848776) (xy 385.794008 -316.799722)
			(xy 385.45516 -316.799722) (xy 385.454665 -316.824329) (xy 385.44677 -316.872906) (xy 385.431186 -316.919587)
			(xy 385.408315 -316.963164) (xy 385.37875 -317.002508) (xy 385.343257 -317.0366) (xy 385.302754 -317.064556)
			(xy 385.258292 -317.085654) (xy 385.211021 -317.099346) (xy 385.162166 -317.105278) (xy 385.112991 -317.103297)
			(xy 385.064772 -317.093453) (xy 385.018756 -317.076001) (xy 384.976135 -317.051394) (xy 384.938014 -317.020269)
			(xy 384.905379 -316.983432) (xy 384.879076 -316.941836) (xy 384.859785 -316.89656) (xy 384.848008 -316.848776)
			(xy 384.844048 -316.799722) (xy 314.955174 -316.799722) (xy 314.954679 -316.824329) (xy 314.946784 -316.872906)
			(xy 314.9312 -316.919587) (xy 314.908329 -316.963164) (xy 314.878764 -317.002508) (xy 314.843271 -317.0366)
			(xy 314.802768 -317.064556) (xy 314.758306 -317.085654) (xy 314.711035 -317.099346) (xy 314.66218 -317.105278)
			(xy 314.613005 -317.103297) (xy 314.564786 -317.093453) (xy 314.51877 -317.076001) (xy 314.476149 -317.051394)
			(xy 314.438028 -317.020269) (xy 314.405393 -316.983432) (xy 314.37909 -316.941836) (xy 314.359799 -316.89656)
			(xy 314.348022 -316.848776) (xy 314.344062 -316.799722) (xy 314.005214 -316.799722) (xy 314.004719 -316.824329)
			(xy 313.996824 -316.872906) (xy 313.98124 -316.919587) (xy 313.958369 -316.963164) (xy 313.928804 -317.002508)
			(xy 313.893311 -317.0366) (xy 313.852808 -317.064556) (xy 313.808346 -317.085654) (xy 313.761075 -317.099346)
			(xy 313.71222 -317.105278) (xy 313.663045 -317.103297) (xy 313.614826 -317.093453) (xy 313.56881 -317.076001)
			(xy 313.526189 -317.051394) (xy 313.488068 -317.020269) (xy 313.455433 -316.983432) (xy 313.42913 -316.941836)
			(xy 313.409839 -316.89656) (xy 313.398062 -316.848776) (xy 313.394102 -316.799722) (xy 312.10504 -316.799722)
			(xy 312.104545 -316.824329) (xy 312.09665 -316.872906) (xy 312.081066 -316.919587) (xy 312.058195 -316.963164)
			(xy 312.02863 -317.002508) (xy 311.993137 -317.0366) (xy 311.952634 -317.064556) (xy 311.908172 -317.085654)
			(xy 311.860901 -317.099346) (xy 311.812046 -317.105278) (xy 311.762871 -317.103297) (xy 311.714652 -317.093453)
			(xy 311.668636 -317.076001) (xy 311.626015 -317.051394) (xy 311.587894 -317.020269) (xy 311.555259 -316.983432)
			(xy 311.528956 -316.941836) (xy 311.509665 -316.89656) (xy 311.497888 -316.848776) (xy 311.493928 -316.799722)
			(xy 310.20512 -316.799722) (xy 310.204625 -316.824329) (xy 310.19673 -316.872906) (xy 310.181146 -316.919587)
			(xy 310.158275 -316.963164) (xy 310.12871 -317.002508) (xy 310.093217 -317.0366) (xy 310.052714 -317.064556)
			(xy 310.008252 -317.085654) (xy 309.960981 -317.099346) (xy 309.912126 -317.105278) (xy 309.862951 -317.103297)
			(xy 309.814732 -317.093453) (xy 309.768716 -317.076001) (xy 309.726095 -317.051394) (xy 309.687974 -317.020269)
			(xy 309.655339 -316.983432) (xy 309.629036 -316.941836) (xy 309.609745 -316.89656) (xy 309.597968 -316.848776)
			(xy 309.594008 -316.799722) (xy 308.3052 -316.799722) (xy 308.304705 -316.824329) (xy 308.29681 -316.872906)
			(xy 308.281226 -316.919587) (xy 308.258355 -316.963164) (xy 308.22879 -317.002508) (xy 308.193297 -317.0366)
			(xy 308.152794 -317.064556) (xy 308.108332 -317.085654) (xy 308.061061 -317.099346) (xy 308.012206 -317.105278)
			(xy 307.963031 -317.103297) (xy 307.914812 -317.093453) (xy 307.868796 -317.076001) (xy 307.826175 -317.051394)
			(xy 307.788054 -317.020269) (xy 307.755419 -316.983432) (xy 307.729116 -316.941836) (xy 307.709825 -316.89656)
			(xy 307.698048 -316.848776) (xy 307.694088 -316.799722) (xy 306.405026 -316.799722) (xy 306.404531 -316.824329)
			(xy 306.396636 -316.872906) (xy 306.381052 -316.919587) (xy 306.358181 -316.963164) (xy 306.328616 -317.002508)
			(xy 306.293123 -317.0366) (xy 306.25262 -317.064556) (xy 306.208158 -317.085654) (xy 306.160887 -317.099346)
			(xy 306.112032 -317.105278) (xy 306.062857 -317.103297) (xy 306.014638 -317.093453) (xy 305.968622 -317.076001)
			(xy 305.926001 -317.051394) (xy 305.88788 -317.020269) (xy 305.855245 -316.983432) (xy 305.828942 -316.941836)
			(xy 305.809651 -316.89656) (xy 305.797874 -316.848776) (xy 305.793914 -316.799722) (xy 304.505106 -316.799722)
			(xy 304.504611 -316.824329) (xy 304.496716 -316.872906) (xy 304.481132 -316.919587) (xy 304.458261 -316.963164)
			(xy 304.428696 -317.002508) (xy 304.393203 -317.0366) (xy 304.3527 -317.064556) (xy 304.308238 -317.085654)
			(xy 304.260967 -317.099346) (xy 304.212112 -317.105278) (xy 304.162937 -317.103297) (xy 304.114718 -317.093453)
			(xy 304.068702 -317.076001) (xy 304.026081 -317.051394) (xy 303.98796 -317.020269) (xy 303.955325 -316.983432)
			(xy 303.929022 -316.941836) (xy 303.909731 -316.89656) (xy 303.897954 -316.848776) (xy 303.893994 -316.799722)
			(xy 302.605186 -316.799722) (xy 302.604691 -316.824329) (xy 302.596796 -316.872906) (xy 302.581212 -316.919587)
			(xy 302.558341 -316.963164) (xy 302.528776 -317.002508) (xy 302.493283 -317.0366) (xy 302.45278 -317.064556)
			(xy 302.408318 -317.085654) (xy 302.361047 -317.099346) (xy 302.312192 -317.105278) (xy 302.263017 -317.103297)
			(xy 302.214798 -317.093453) (xy 302.168782 -317.076001) (xy 302.126161 -317.051394) (xy 302.08804 -317.020269)
			(xy 302.055405 -316.983432) (xy 302.029102 -316.941836) (xy 302.009811 -316.89656) (xy 301.998034 -316.848776)
			(xy 301.994074 -316.799722) (xy 300.705012 -316.799722) (xy 300.704517 -316.824329) (xy 300.696622 -316.872906)
			(xy 300.681038 -316.919587) (xy 300.658167 -316.963164) (xy 300.628602 -317.002508) (xy 300.593109 -317.0366)
			(xy 300.552606 -317.064556) (xy 300.508144 -317.085654) (xy 300.460873 -317.099346) (xy 300.412018 -317.105278)
			(xy 300.362843 -317.103297) (xy 300.314624 -317.093453) (xy 300.268608 -317.076001) (xy 300.225987 -317.051394)
			(xy 300.187866 -317.020269) (xy 300.155231 -316.983432) (xy 300.128928 -316.941836) (xy 300.109637 -316.89656)
			(xy 300.09786 -316.848776) (xy 300.0939 -316.799722) (xy 298.805092 -316.799722) (xy 298.804597 -316.824329)
			(xy 298.796702 -316.872906) (xy 298.781118 -316.919587) (xy 298.758247 -316.963164) (xy 298.728682 -317.002508)
			(xy 298.693189 -317.0366) (xy 298.652686 -317.064556) (xy 298.608224 -317.085654) (xy 298.560953 -317.099346)
			(xy 298.512098 -317.105278) (xy 298.462923 -317.103297) (xy 298.414704 -317.093453) (xy 298.368688 -317.076001)
			(xy 298.326067 -317.051394) (xy 298.287946 -317.020269) (xy 298.255311 -316.983432) (xy 298.229008 -316.941836)
			(xy 298.209717 -316.89656) (xy 298.19794 -316.848776) (xy 298.19398 -316.799722) (xy 296.905172 -316.799722)
			(xy 296.904677 -316.824329) (xy 296.896782 -316.872906) (xy 296.881198 -316.919587) (xy 296.858327 -316.963164)
			(xy 296.828762 -317.002508) (xy 296.793269 -317.0366) (xy 296.752766 -317.064556) (xy 296.708304 -317.085654)
			(xy 296.661033 -317.099346) (xy 296.612178 -317.105278) (xy 296.563003 -317.103297) (xy 296.514784 -317.093453)
			(xy 296.468768 -317.076001) (xy 296.426147 -317.051394) (xy 296.388026 -317.020269) (xy 296.355391 -316.983432)
			(xy 296.329088 -316.941836) (xy 296.309797 -316.89656) (xy 296.29802 -316.848776) (xy 296.29406 -316.799722)
			(xy 295.004998 -316.799722) (xy 295.004503 -316.824329) (xy 294.996608 -316.872906) (xy 294.981024 -316.919587)
			(xy 294.958153 -316.963164) (xy 294.928588 -317.002508) (xy 294.893095 -317.0366) (xy 294.852592 -317.064556)
			(xy 294.80813 -317.085654) (xy 294.760859 -317.099346) (xy 294.712004 -317.105278) (xy 294.662829 -317.103297)
			(xy 294.61461 -317.093453) (xy 294.568594 -317.076001) (xy 294.525973 -317.051394) (xy 294.487852 -317.020269)
			(xy 294.455217 -316.983432) (xy 294.428914 -316.941836) (xy 294.409623 -316.89656) (xy 294.397846 -316.848776)
			(xy 294.393886 -316.799722) (xy 293.105078 -316.799722) (xy 293.104583 -316.824329) (xy 293.096688 -316.872906)
			(xy 293.081104 -316.919587) (xy 293.058233 -316.963164) (xy 293.028668 -317.002508) (xy 292.993175 -317.0366)
			(xy 292.952672 -317.064556) (xy 292.90821 -317.085654) (xy 292.860939 -317.099346) (xy 292.812084 -317.105278)
			(xy 292.762909 -317.103297) (xy 292.71469 -317.093453) (xy 292.668674 -317.076001) (xy 292.626053 -317.051394)
			(xy 292.587932 -317.020269) (xy 292.555297 -316.983432) (xy 292.528994 -316.941836) (xy 292.509703 -316.89656)
			(xy 292.497926 -316.848776) (xy 292.493966 -316.799722) (xy 291.205158 -316.799722) (xy 291.204663 -316.824329)
			(xy 291.196768 -316.872906) (xy 291.181184 -316.919587) (xy 291.158313 -316.963164) (xy 291.128748 -317.002508)
			(xy 291.093255 -317.0366) (xy 291.052752 -317.064556) (xy 291.00829 -317.085654) (xy 290.961019 -317.099346)
			(xy 290.912164 -317.105278) (xy 290.862989 -317.103297) (xy 290.81477 -317.093453) (xy 290.768754 -317.076001)
			(xy 290.726133 -317.051394) (xy 290.688012 -317.020269) (xy 290.655377 -316.983432) (xy 290.629074 -316.941836)
			(xy 290.609783 -316.89656) (xy 290.598006 -316.848776) (xy 290.594046 -316.799722) (xy 289.305238 -316.799722)
			(xy 289.304743 -316.824329) (xy 289.296848 -316.872906) (xy 289.281264 -316.919587) (xy 289.258393 -316.963164)
			(xy 289.228828 -317.002508) (xy 289.193335 -317.0366) (xy 289.152832 -317.064556) (xy 289.10837 -317.085654)
			(xy 289.061099 -317.099346) (xy 289.012244 -317.105278) (xy 288.963069 -317.103297) (xy 288.91485 -317.093453)
			(xy 288.868834 -317.076001) (xy 288.826213 -317.051394) (xy 288.788092 -317.020269) (xy 288.755457 -316.983432)
			(xy 288.729154 -316.941836) (xy 288.709863 -316.89656) (xy 288.698086 -316.848776) (xy 288.694126 -316.799722)
			(xy 287.405064 -316.799722) (xy 287.404569 -316.824329) (xy 287.396674 -316.872906) (xy 287.38109 -316.919587)
			(xy 287.358219 -316.963164) (xy 287.328654 -317.002508) (xy 287.293161 -317.0366) (xy 287.252658 -317.064556)
			(xy 287.208196 -317.085654) (xy 287.160925 -317.099346) (xy 287.11207 -317.105278) (xy 287.062895 -317.103297)
			(xy 287.014676 -317.093453) (xy 286.96866 -317.076001) (xy 286.926039 -317.051394) (xy 286.887918 -317.020269)
			(xy 286.855283 -316.983432) (xy 286.82898 -316.941836) (xy 286.809689 -316.89656) (xy 286.797912 -316.848776)
			(xy 286.793952 -316.799722) (xy 285.505144 -316.799722) (xy 285.504649 -316.824329) (xy 285.496754 -316.872906)
			(xy 285.48117 -316.919587) (xy 285.458299 -316.963164) (xy 285.428734 -317.002508) (xy 285.393241 -317.0366)
			(xy 285.352738 -317.064556) (xy 285.308276 -317.085654) (xy 285.261005 -317.099346) (xy 285.21215 -317.105278)
			(xy 285.162975 -317.103297) (xy 285.114756 -317.093453) (xy 285.06874 -317.076001) (xy 285.026119 -317.051394)
			(xy 284.987998 -317.020269) (xy 284.955363 -316.983432) (xy 284.92906 -316.941836) (xy 284.909769 -316.89656)
			(xy 284.897992 -316.848776) (xy 284.894032 -316.799722) (xy 283.605224 -316.799722) (xy 283.604729 -316.824329)
			(xy 283.596834 -316.872906) (xy 283.58125 -316.919587) (xy 283.558379 -316.963164) (xy 283.528814 -317.002508)
			(xy 283.493321 -317.0366) (xy 283.452818 -317.064556) (xy 283.408356 -317.085654) (xy 283.361085 -317.099346)
			(xy 283.31223 -317.105278) (xy 283.263055 -317.103297) (xy 283.214836 -317.093453) (xy 283.16882 -317.076001)
			(xy 283.126199 -317.051394) (xy 283.088078 -317.020269) (xy 283.055443 -316.983432) (xy 283.02914 -316.941836)
			(xy 283.009849 -316.89656) (xy 282.998072 -316.848776) (xy 282.994112 -316.799722) (xy 281.70505 -316.799722)
			(xy 281.704555 -316.824329) (xy 281.69666 -316.872906) (xy 281.681076 -316.919587) (xy 281.658205 -316.963164)
			(xy 281.62864 -317.002508) (xy 281.593147 -317.0366) (xy 281.552644 -317.064556) (xy 281.508182 -317.085654)
			(xy 281.460911 -317.099346) (xy 281.412056 -317.105278) (xy 281.362881 -317.103297) (xy 281.314662 -317.093453)
			(xy 281.268646 -317.076001) (xy 281.226025 -317.051394) (xy 281.187904 -317.020269) (xy 281.155269 -316.983432)
			(xy 281.128966 -316.941836) (xy 281.109675 -316.89656) (xy 281.097898 -316.848776) (xy 281.093938 -316.799722)
			(xy 279.80513 -316.799722) (xy 279.804635 -316.824329) (xy 279.79674 -316.872906) (xy 279.781156 -316.919587)
			(xy 279.758285 -316.963164) (xy 279.72872 -317.002508) (xy 279.693227 -317.0366) (xy 279.652724 -317.064556)
			(xy 279.608262 -317.085654) (xy 279.560991 -317.099346) (xy 279.512136 -317.105278) (xy 279.462961 -317.103297)
			(xy 279.414742 -317.093453) (xy 279.368726 -317.076001) (xy 279.326105 -317.051394) (xy 279.287984 -317.020269)
			(xy 279.255349 -316.983432) (xy 279.229046 -316.941836) (xy 279.209755 -316.89656) (xy 279.197978 -316.848776)
			(xy 279.194018 -316.799722) (xy 277.90521 -316.799722) (xy 277.904715 -316.824329) (xy 277.89682 -316.872906)
			(xy 277.881236 -316.919587) (xy 277.858365 -316.963164) (xy 277.8288 -317.002508) (xy 277.793307 -317.0366)
			(xy 277.752804 -317.064556) (xy 277.708342 -317.085654) (xy 277.661071 -317.099346) (xy 277.612216 -317.105278)
			(xy 277.563041 -317.103297) (xy 277.514822 -317.093453) (xy 277.468806 -317.076001) (xy 277.426185 -317.051394)
			(xy 277.388064 -317.020269) (xy 277.355429 -316.983432) (xy 277.329126 -316.941836) (xy 277.309835 -316.89656)
			(xy 277.298058 -316.848776) (xy 277.294098 -316.799722) (xy 276.005036 -316.799722) (xy 276.004541 -316.824329)
			(xy 275.996646 -316.872906) (xy 275.981062 -316.919587) (xy 275.958191 -316.963164) (xy 275.928626 -317.002508)
			(xy 275.893133 -317.0366) (xy 275.85263 -317.064556) (xy 275.808168 -317.085654) (xy 275.760897 -317.099346)
			(xy 275.712042 -317.105278) (xy 275.662867 -317.103297) (xy 275.614648 -317.093453) (xy 275.568632 -317.076001)
			(xy 275.526011 -317.051394) (xy 275.48789 -317.020269) (xy 275.455255 -316.983432) (xy 275.428952 -316.941836)
			(xy 275.409661 -316.89656) (xy 275.397884 -316.848776) (xy 275.393924 -316.799722) (xy 274.105116 -316.799722)
			(xy 274.104621 -316.824329) (xy 274.096726 -316.872906) (xy 274.081142 -316.919587) (xy 274.058271 -316.963164)
			(xy 274.028706 -317.002508) (xy 273.993213 -317.0366) (xy 273.95271 -317.064556) (xy 273.908248 -317.085654)
			(xy 273.860977 -317.099346) (xy 273.812122 -317.105278) (xy 273.762947 -317.103297) (xy 273.714728 -317.093453)
			(xy 273.668712 -317.076001) (xy 273.626091 -317.051394) (xy 273.58797 -317.020269) (xy 273.555335 -316.983432)
			(xy 273.529032 -316.941836) (xy 273.509741 -316.89656) (xy 273.497964 -316.848776) (xy 273.494004 -316.799722)
			(xy 272.205196 -316.799722) (xy 272.204701 -316.824329) (xy 272.196806 -316.872906) (xy 272.181222 -316.919587)
			(xy 272.158351 -316.963164) (xy 272.128786 -317.002508) (xy 272.093293 -317.0366) (xy 272.05279 -317.064556)
			(xy 272.008328 -317.085654) (xy 271.961057 -317.099346) (xy 271.912202 -317.105278) (xy 271.863027 -317.103297)
			(xy 271.814808 -317.093453) (xy 271.768792 -317.076001) (xy 271.726171 -317.051394) (xy 271.68805 -317.020269)
			(xy 271.655415 -316.983432) (xy 271.629112 -316.941836) (xy 271.609821 -316.89656) (xy 271.598044 -316.848776)
			(xy 271.594084 -316.799722) (xy 270.305022 -316.799722) (xy 270.304527 -316.824329) (xy 270.296632 -316.872906)
			(xy 270.281048 -316.919587) (xy 270.258177 -316.963164) (xy 270.228612 -317.002508) (xy 270.193119 -317.0366)
			(xy 270.152616 -317.064556) (xy 270.108154 -317.085654) (xy 270.060883 -317.099346) (xy 270.012028 -317.105278)
			(xy 269.962853 -317.103297) (xy 269.914634 -317.093453) (xy 269.868618 -317.076001) (xy 269.825997 -317.051394)
			(xy 269.787876 -317.020269) (xy 269.755241 -316.983432) (xy 269.728938 -316.941836) (xy 269.709647 -316.89656)
			(xy 269.69787 -316.848776) (xy 269.69391 -316.799722) (xy 269.355062 -316.799722) (xy 269.354567 -316.824329)
			(xy 269.346672 -316.872906) (xy 269.331088 -316.919587) (xy 269.308217 -316.963164) (xy 269.278652 -317.002508)
			(xy 269.243159 -317.0366) (xy 269.202656 -317.064556) (xy 269.158194 -317.085654) (xy 269.110923 -317.099346)
			(xy 269.062068 -317.105278) (xy 269.012893 -317.103297) (xy 268.964674 -317.093453) (xy 268.918658 -317.076001)
			(xy 268.876037 -317.051394) (xy 268.837916 -317.020269) (xy 268.805281 -316.983432) (xy 268.778978 -316.941836)
			(xy 268.759687 -316.89656) (xy 268.74791 -316.848776) (xy 268.74395 -316.799722) (xy 198.85533 -316.799722)
			(xy 198.854835 -316.824329) (xy 198.84694 -316.872906) (xy 198.831356 -316.919587) (xy 198.808485 -316.963164)
			(xy 198.77892 -317.002508) (xy 198.743427 -317.0366) (xy 198.702924 -317.064556) (xy 198.658462 -317.085654)
			(xy 198.611191 -317.099346) (xy 198.562336 -317.105278) (xy 198.513161 -317.103297) (xy 198.464942 -317.093453)
			(xy 198.418926 -317.076001) (xy 198.376305 -317.051394) (xy 198.338184 -317.020269) (xy 198.305549 -316.983432)
			(xy 198.279246 -316.941836) (xy 198.259955 -316.89656) (xy 198.248178 -316.848776) (xy 198.244218 -316.799722)
			(xy 197.90537 -316.799722) (xy 197.904875 -316.824329) (xy 197.89698 -316.872906) (xy 197.881396 -316.919587)
			(xy 197.858525 -316.963164) (xy 197.82896 -317.002508) (xy 197.793467 -317.0366) (xy 197.752964 -317.064556)
			(xy 197.708502 -317.085654) (xy 197.661231 -317.099346) (xy 197.612376 -317.105278) (xy 197.563201 -317.103297)
			(xy 197.514982 -317.093453) (xy 197.468966 -317.076001) (xy 197.426345 -317.051394) (xy 197.388224 -317.020269)
			(xy 197.355589 -316.983432) (xy 197.329286 -316.941836) (xy 197.309995 -316.89656) (xy 197.298218 -316.848776)
			(xy 197.294258 -316.799722) (xy 196.005196 -316.799722) (xy 196.004701 -316.824329) (xy 195.996806 -316.872906)
			(xy 195.981222 -316.919587) (xy 195.958351 -316.963164) (xy 195.928786 -317.002508) (xy 195.893293 -317.0366)
			(xy 195.85279 -317.064556) (xy 195.808328 -317.085654) (xy 195.761057 -317.099346) (xy 195.712202 -317.105278)
			(xy 195.663027 -317.103297) (xy 195.614808 -317.093453) (xy 195.568792 -317.076001) (xy 195.526171 -317.051394)
			(xy 195.48805 -317.020269) (xy 195.455415 -316.983432) (xy 195.429112 -316.941836) (xy 195.409821 -316.89656)
			(xy 195.398044 -316.848776) (xy 195.394084 -316.799722) (xy 194.105276 -316.799722) (xy 194.104781 -316.824329)
			(xy 194.096886 -316.872906) (xy 194.081302 -316.919587) (xy 194.058431 -316.963164) (xy 194.028866 -317.002508)
			(xy 193.993373 -317.0366) (xy 193.95287 -317.064556) (xy 193.908408 -317.085654) (xy 193.861137 -317.099346)
			(xy 193.812282 -317.105278) (xy 193.763107 -317.103297) (xy 193.714888 -317.093453) (xy 193.668872 -317.076001)
			(xy 193.626251 -317.051394) (xy 193.58813 -317.020269) (xy 193.555495 -316.983432) (xy 193.529192 -316.941836)
			(xy 193.509901 -316.89656) (xy 193.498124 -316.848776) (xy 193.494164 -316.799722) (xy 192.205356 -316.799722)
			(xy 192.204861 -316.824329) (xy 192.196966 -316.872906) (xy 192.181382 -316.919587) (xy 192.158511 -316.963164)
			(xy 192.128946 -317.002508) (xy 192.093453 -317.0366) (xy 192.05295 -317.064556) (xy 192.008488 -317.085654)
			(xy 191.961217 -317.099346) (xy 191.912362 -317.105278) (xy 191.863187 -317.103297) (xy 191.814968 -317.093453)
			(xy 191.768952 -317.076001) (xy 191.726331 -317.051394) (xy 191.68821 -317.020269) (xy 191.655575 -316.983432)
			(xy 191.629272 -316.941836) (xy 191.609981 -316.89656) (xy 191.598204 -316.848776) (xy 191.594244 -316.799722)
			(xy 190.305182 -316.799722) (xy 190.304687 -316.824329) (xy 190.296792 -316.872906) (xy 190.281208 -316.919587)
			(xy 190.258337 -316.963164) (xy 190.228772 -317.002508) (xy 190.193279 -317.0366) (xy 190.152776 -317.064556)
			(xy 190.108314 -317.085654) (xy 190.061043 -317.099346) (xy 190.012188 -317.105278) (xy 189.963013 -317.103297)
			(xy 189.914794 -317.093453) (xy 189.868778 -317.076001) (xy 189.826157 -317.051394) (xy 189.788036 -317.020269)
			(xy 189.755401 -316.983432) (xy 189.729098 -316.941836) (xy 189.709807 -316.89656) (xy 189.69803 -316.848776)
			(xy 189.69407 -316.799722) (xy 188.405262 -316.799722) (xy 188.404767 -316.824329) (xy 188.396872 -316.872906)
			(xy 188.381288 -316.919587) (xy 188.358417 -316.963164) (xy 188.328852 -317.002508) (xy 188.293359 -317.0366)
			(xy 188.252856 -317.064556) (xy 188.208394 -317.085654) (xy 188.161123 -317.099346) (xy 188.112268 -317.105278)
			(xy 188.063093 -317.103297) (xy 188.014874 -317.093453) (xy 187.968858 -317.076001) (xy 187.926237 -317.051394)
			(xy 187.888116 -317.020269) (xy 187.855481 -316.983432) (xy 187.829178 -316.941836) (xy 187.809887 -316.89656)
			(xy 187.79811 -316.848776) (xy 187.79415 -316.799722) (xy 186.505342 -316.799722) (xy 186.504847 -316.824329)
			(xy 186.496952 -316.872906) (xy 186.481368 -316.919587) (xy 186.458497 -316.963164) (xy 186.428932 -317.002508)
			(xy 186.393439 -317.0366) (xy 186.352936 -317.064556) (xy 186.308474 -317.085654) (xy 186.261203 -317.099346)
			(xy 186.212348 -317.105278) (xy 186.163173 -317.103297) (xy 186.114954 -317.093453) (xy 186.068938 -317.076001)
			(xy 186.026317 -317.051394) (xy 185.988196 -317.020269) (xy 185.955561 -316.983432) (xy 185.929258 -316.941836)
			(xy 185.909967 -316.89656) (xy 185.89819 -316.848776) (xy 185.89423 -316.799722) (xy 184.605168 -316.799722)
			(xy 184.604673 -316.824329) (xy 184.596778 -316.872906) (xy 184.581194 -316.919587) (xy 184.558323 -316.963164)
			(xy 184.528758 -317.002508) (xy 184.493265 -317.0366) (xy 184.452762 -317.064556) (xy 184.4083 -317.085654)
			(xy 184.361029 -317.099346) (xy 184.312174 -317.105278) (xy 184.262999 -317.103297) (xy 184.21478 -317.093453)
			(xy 184.168764 -317.076001) (xy 184.126143 -317.051394) (xy 184.088022 -317.020269) (xy 184.055387 -316.983432)
			(xy 184.029084 -316.941836) (xy 184.009793 -316.89656) (xy 183.998016 -316.848776) (xy 183.994056 -316.799722)
			(xy 182.705248 -316.799722) (xy 182.704753 -316.824329) (xy 182.696858 -316.872906) (xy 182.681274 -316.919587)
			(xy 182.658403 -316.963164) (xy 182.628838 -317.002508) (xy 182.593345 -317.0366) (xy 182.552842 -317.064556)
			(xy 182.50838 -317.085654) (xy 182.461109 -317.099346) (xy 182.412254 -317.105278) (xy 182.363079 -317.103297)
			(xy 182.31486 -317.093453) (xy 182.268844 -317.076001) (xy 182.226223 -317.051394) (xy 182.188102 -317.020269)
			(xy 182.155467 -316.983432) (xy 182.129164 -316.941836) (xy 182.109873 -316.89656) (xy 182.098096 -316.848776)
			(xy 182.094136 -316.799722) (xy 180.805328 -316.799722) (xy 180.804833 -316.824329) (xy 180.796938 -316.872906)
			(xy 180.781354 -316.919587) (xy 180.758483 -316.963164) (xy 180.728918 -317.002508) (xy 180.693425 -317.0366)
			(xy 180.652922 -317.064556) (xy 180.60846 -317.085654) (xy 180.561189 -317.099346) (xy 180.512334 -317.105278)
			(xy 180.463159 -317.103297) (xy 180.41494 -317.093453) (xy 180.368924 -317.076001) (xy 180.326303 -317.051394)
			(xy 180.288182 -317.020269) (xy 180.255547 -316.983432) (xy 180.229244 -316.941836) (xy 180.209953 -316.89656)
			(xy 180.198176 -316.848776) (xy 180.194216 -316.799722) (xy 178.905154 -316.799722) (xy 178.904659 -316.824329)
			(xy 178.896764 -316.872906) (xy 178.88118 -316.919587) (xy 178.858309 -316.963164) (xy 178.828744 -317.002508)
			(xy 178.793251 -317.0366) (xy 178.752748 -317.064556) (xy 178.708286 -317.085654) (xy 178.661015 -317.099346)
			(xy 178.61216 -317.105278) (xy 178.562985 -317.103297) (xy 178.514766 -317.093453) (xy 178.46875 -317.076001)
			(xy 178.426129 -317.051394) (xy 178.388008 -317.020269) (xy 178.355373 -316.983432) (xy 178.32907 -316.941836)
			(xy 178.309779 -316.89656) (xy 178.298002 -316.848776) (xy 178.294042 -316.799722) (xy 177.005234 -316.799722)
			(xy 177.004739 -316.824329) (xy 176.996844 -316.872906) (xy 176.98126 -316.919587) (xy 176.958389 -316.963164)
			(xy 176.928824 -317.002508) (xy 176.893331 -317.0366) (xy 176.852828 -317.064556) (xy 176.808366 -317.085654)
			(xy 176.761095 -317.099346) (xy 176.71224 -317.105278) (xy 176.663065 -317.103297) (xy 176.614846 -317.093453)
			(xy 176.56883 -317.076001) (xy 176.526209 -317.051394) (xy 176.488088 -317.020269) (xy 176.455453 -316.983432)
			(xy 176.42915 -316.941836) (xy 176.409859 -316.89656) (xy 176.398082 -316.848776) (xy 176.394122 -316.799722)
			(xy 175.105314 -316.799722) (xy 175.104819 -316.824329) (xy 175.096924 -316.872906) (xy 175.08134 -316.919587)
			(xy 175.058469 -316.963164) (xy 175.028904 -317.002508) (xy 174.993411 -317.0366) (xy 174.952908 -317.064556)
			(xy 174.908446 -317.085654) (xy 174.861175 -317.099346) (xy 174.81232 -317.105278) (xy 174.763145 -317.103297)
			(xy 174.714926 -317.093453) (xy 174.66891 -317.076001) (xy 174.626289 -317.051394) (xy 174.588168 -317.020269)
			(xy 174.555533 -316.983432) (xy 174.52923 -316.941836) (xy 174.509939 -316.89656) (xy 174.498162 -316.848776)
			(xy 174.494202 -316.799722) (xy 173.205394 -316.799722) (xy 173.204899 -316.824329) (xy 173.197004 -316.872906)
			(xy 173.18142 -316.919587) (xy 173.158549 -316.963164) (xy 173.128984 -317.002508) (xy 173.093491 -317.0366)
			(xy 173.052988 -317.064556) (xy 173.008526 -317.085654) (xy 172.961255 -317.099346) (xy 172.9124 -317.105278)
			(xy 172.863225 -317.103297) (xy 172.815006 -317.093453) (xy 172.76899 -317.076001) (xy 172.726369 -317.051394)
			(xy 172.688248 -317.020269) (xy 172.655613 -316.983432) (xy 172.62931 -316.941836) (xy 172.610019 -316.89656)
			(xy 172.598242 -316.848776) (xy 172.594282 -316.799722) (xy 171.30522 -316.799722) (xy 171.304725 -316.824329)
			(xy 171.29683 -316.872906) (xy 171.281246 -316.919587) (xy 171.258375 -316.963164) (xy 171.22881 -317.002508)
			(xy 171.193317 -317.0366) (xy 171.152814 -317.064556) (xy 171.108352 -317.085654) (xy 171.061081 -317.099346)
			(xy 171.012226 -317.105278) (xy 170.963051 -317.103297) (xy 170.914832 -317.093453) (xy 170.868816 -317.076001)
			(xy 170.826195 -317.051394) (xy 170.788074 -317.020269) (xy 170.755439 -316.983432) (xy 170.729136 -316.941836)
			(xy 170.709845 -316.89656) (xy 170.698068 -316.848776) (xy 170.694108 -316.799722) (xy 169.4053 -316.799722)
			(xy 169.404805 -316.824329) (xy 169.39691 -316.872906) (xy 169.381326 -316.919587) (xy 169.358455 -316.963164)
			(xy 169.32889 -317.002508) (xy 169.293397 -317.0366) (xy 169.252894 -317.064556) (xy 169.208432 -317.085654)
			(xy 169.161161 -317.099346) (xy 169.112306 -317.105278) (xy 169.063131 -317.103297) (xy 169.014912 -317.093453)
			(xy 168.968896 -317.076001) (xy 168.926275 -317.051394) (xy 168.888154 -317.020269) (xy 168.855519 -316.983432)
			(xy 168.829216 -316.941836) (xy 168.809925 -316.89656) (xy 168.798148 -316.848776) (xy 168.794188 -316.799722)
			(xy 167.50538 -316.799722) (xy 167.504885 -316.824329) (xy 167.49699 -316.872906) (xy 167.481406 -316.919587)
			(xy 167.458535 -316.963164) (xy 167.42897 -317.002508) (xy 167.393477 -317.0366) (xy 167.352974 -317.064556)
			(xy 167.308512 -317.085654) (xy 167.261241 -317.099346) (xy 167.212386 -317.105278) (xy 167.163211 -317.103297)
			(xy 167.114992 -317.093453) (xy 167.068976 -317.076001) (xy 167.026355 -317.051394) (xy 166.988234 -317.020269)
			(xy 166.955599 -316.983432) (xy 166.929296 -316.941836) (xy 166.910005 -316.89656) (xy 166.898228 -316.848776)
			(xy 166.894268 -316.799722) (xy 165.605206 -316.799722) (xy 165.604711 -316.824329) (xy 165.596816 -316.872906)
			(xy 165.581232 -316.919587) (xy 165.558361 -316.963164) (xy 165.528796 -317.002508) (xy 165.493303 -317.0366)
			(xy 165.4528 -317.064556) (xy 165.408338 -317.085654) (xy 165.361067 -317.099346) (xy 165.312212 -317.105278)
			(xy 165.263037 -317.103297) (xy 165.214818 -317.093453) (xy 165.168802 -317.076001) (xy 165.126181 -317.051394)
			(xy 165.08806 -317.020269) (xy 165.055425 -316.983432) (xy 165.029122 -316.941836) (xy 165.009831 -316.89656)
			(xy 164.998054 -316.848776) (xy 164.994094 -316.799722) (xy 163.705286 -316.799722) (xy 163.704791 -316.824329)
			(xy 163.696896 -316.872906) (xy 163.681312 -316.919587) (xy 163.658441 -316.963164) (xy 163.628876 -317.002508)
			(xy 163.593383 -317.0366) (xy 163.55288 -317.064556) (xy 163.508418 -317.085654) (xy 163.461147 -317.099346)
			(xy 163.412292 -317.105278) (xy 163.363117 -317.103297) (xy 163.314898 -317.093453) (xy 163.268882 -317.076001)
			(xy 163.226261 -317.051394) (xy 163.18814 -317.020269) (xy 163.155505 -316.983432) (xy 163.129202 -316.941836)
			(xy 163.109911 -316.89656) (xy 163.098134 -316.848776) (xy 163.094174 -316.799722) (xy 161.805366 -316.799722)
			(xy 161.804871 -316.824329) (xy 161.796976 -316.872906) (xy 161.781392 -316.919587) (xy 161.758521 -316.963164)
			(xy 161.728956 -317.002508) (xy 161.693463 -317.0366) (xy 161.65296 -317.064556) (xy 161.608498 -317.085654)
			(xy 161.561227 -317.099346) (xy 161.512372 -317.105278) (xy 161.463197 -317.103297) (xy 161.414978 -317.093453)
			(xy 161.368962 -317.076001) (xy 161.326341 -317.051394) (xy 161.28822 -317.020269) (xy 161.255585 -316.983432)
			(xy 161.229282 -316.941836) (xy 161.209991 -316.89656) (xy 161.198214 -316.848776) (xy 161.194254 -316.799722)
			(xy 159.905192 -316.799722) (xy 159.904697 -316.824329) (xy 159.896802 -316.872906) (xy 159.881218 -316.919587)
			(xy 159.858347 -316.963164) (xy 159.828782 -317.002508) (xy 159.793289 -317.0366) (xy 159.752786 -317.064556)
			(xy 159.708324 -317.085654) (xy 159.661053 -317.099346) (xy 159.612198 -317.105278) (xy 159.563023 -317.103297)
			(xy 159.514804 -317.093453) (xy 159.468788 -317.076001) (xy 159.426167 -317.051394) (xy 159.388046 -317.020269)
			(xy 159.355411 -316.983432) (xy 159.329108 -316.941836) (xy 159.309817 -316.89656) (xy 159.29804 -316.848776)
			(xy 159.29408 -316.799722) (xy 158.005272 -316.799722) (xy 158.004777 -316.824329) (xy 157.996882 -316.872906)
			(xy 157.981298 -316.919587) (xy 157.958427 -316.963164) (xy 157.928862 -317.002508) (xy 157.893369 -317.0366)
			(xy 157.852866 -317.064556) (xy 157.808404 -317.085654) (xy 157.761133 -317.099346) (xy 157.712278 -317.105278)
			(xy 157.663103 -317.103297) (xy 157.614884 -317.093453) (xy 157.568868 -317.076001) (xy 157.526247 -317.051394)
			(xy 157.488126 -317.020269) (xy 157.455491 -316.983432) (xy 157.429188 -316.941836) (xy 157.409897 -316.89656)
			(xy 157.39812 -316.848776) (xy 157.39416 -316.799722) (xy 156.105352 -316.799722) (xy 156.104857 -316.824329)
			(xy 156.096962 -316.872906) (xy 156.081378 -316.919587) (xy 156.058507 -316.963164) (xy 156.028942 -317.002508)
			(xy 155.993449 -317.0366) (xy 155.952946 -317.064556) (xy 155.908484 -317.085654) (xy 155.861213 -317.099346)
			(xy 155.812358 -317.105278) (xy 155.763183 -317.103297) (xy 155.714964 -317.093453) (xy 155.668948 -317.076001)
			(xy 155.626327 -317.051394) (xy 155.588206 -317.020269) (xy 155.555571 -316.983432) (xy 155.529268 -316.941836)
			(xy 155.509977 -316.89656) (xy 155.4982 -316.848776) (xy 155.49424 -316.799722) (xy 154.205178 -316.799722)
			(xy 154.204683 -316.824329) (xy 154.196788 -316.872906) (xy 154.181204 -316.919587) (xy 154.158333 -316.963164)
			(xy 154.128768 -317.002508) (xy 154.093275 -317.0366) (xy 154.052772 -317.064556) (xy 154.00831 -317.085654)
			(xy 153.961039 -317.099346) (xy 153.912184 -317.105278) (xy 153.863009 -317.103297) (xy 153.81479 -317.093453)
			(xy 153.768774 -317.076001) (xy 153.726153 -317.051394) (xy 153.688032 -317.020269) (xy 153.655397 -316.983432)
			(xy 153.629094 -316.941836) (xy 153.609803 -316.89656) (xy 153.598026 -316.848776) (xy 153.594066 -316.799722)
			(xy 153.255218 -316.799722) (xy 153.254723 -316.824329) (xy 153.246828 -316.872906) (xy 153.231244 -316.919587)
			(xy 153.208373 -316.963164) (xy 153.178808 -317.002508) (xy 153.143315 -317.0366) (xy 153.102812 -317.064556)
			(xy 153.05835 -317.085654) (xy 153.011079 -317.099346) (xy 152.962224 -317.105278) (xy 152.913049 -317.103297)
			(xy 152.86483 -317.093453) (xy 152.818814 -317.076001) (xy 152.776193 -317.051394) (xy 152.738072 -317.020269)
			(xy 152.705437 -316.983432) (xy 152.679134 -316.941836) (xy 152.659843 -316.89656) (xy 152.648066 -316.848776)
			(xy 152.644106 -316.799722) (xy 82.755232 -316.799722) (xy 82.754737 -316.824329) (xy 82.746842 -316.872906)
			(xy 82.731258 -316.919587) (xy 82.708387 -316.963164) (xy 82.678822 -317.002508) (xy 82.643329 -317.0366)
			(xy 82.602826 -317.064556) (xy 82.558364 -317.085654) (xy 82.511093 -317.099346) (xy 82.462238 -317.105278)
			(xy 82.413063 -317.103297) (xy 82.364844 -317.093453) (xy 82.318828 -317.076001) (xy 82.276207 -317.051394)
			(xy 82.238086 -317.020269) (xy 82.205451 -316.983432) (xy 82.179148 -316.941836) (xy 82.159857 -316.89656)
			(xy 82.14808 -316.848776) (xy 82.14412 -316.799722) (xy 81.805272 -316.799722) (xy 81.804777 -316.824329)
			(xy 81.796882 -316.872906) (xy 81.781298 -316.919587) (xy 81.758427 -316.963164) (xy 81.728862 -317.002508)
			(xy 81.693369 -317.0366) (xy 81.652866 -317.064556) (xy 81.608404 -317.085654) (xy 81.561133 -317.099346)
			(xy 81.512278 -317.105278) (xy 81.463103 -317.103297) (xy 81.414884 -317.093453) (xy 81.368868 -317.076001)
			(xy 81.326247 -317.051394) (xy 81.288126 -317.020269) (xy 81.255491 -316.983432) (xy 81.229188 -316.941836)
			(xy 81.209897 -316.89656) (xy 81.19812 -316.848776) (xy 81.19416 -316.799722) (xy 79.905098 -316.799722)
			(xy 79.904603 -316.824329) (xy 79.896708 -316.872906) (xy 79.881124 -316.919587) (xy 79.858253 -316.963164)
			(xy 79.828688 -317.002508) (xy 79.793195 -317.0366) (xy 79.752692 -317.064556) (xy 79.70823 -317.085654)
			(xy 79.660959 -317.099346) (xy 79.612104 -317.105278) (xy 79.562929 -317.103297) (xy 79.51471 -317.093453)
			(xy 79.468694 -317.076001) (xy 79.426073 -317.051394) (xy 79.387952 -317.020269) (xy 79.355317 -316.983432)
			(xy 79.329014 -316.941836) (xy 79.309723 -316.89656) (xy 79.297946 -316.848776) (xy 79.293986 -316.799722)
			(xy 78.005178 -316.799722) (xy 78.004683 -316.824329) (xy 77.996788 -316.872906) (xy 77.981204 -316.919587)
			(xy 77.958333 -316.963164) (xy 77.928768 -317.002508) (xy 77.893275 -317.0366) (xy 77.852772 -317.064556)
			(xy 77.80831 -317.085654) (xy 77.761039 -317.099346) (xy 77.712184 -317.105278) (xy 77.663009 -317.103297)
			(xy 77.61479 -317.093453) (xy 77.568774 -317.076001) (xy 77.526153 -317.051394) (xy 77.488032 -317.020269)
			(xy 77.455397 -316.983432) (xy 77.429094 -316.941836) (xy 77.409803 -316.89656) (xy 77.398026 -316.848776)
			(xy 77.394066 -316.799722) (xy 76.105258 -316.799722) (xy 76.104763 -316.824329) (xy 76.096868 -316.872906)
			(xy 76.081284 -316.919587) (xy 76.058413 -316.963164) (xy 76.028848 -317.002508) (xy 75.993355 -317.0366)
			(xy 75.952852 -317.064556) (xy 75.90839 -317.085654) (xy 75.861119 -317.099346) (xy 75.812264 -317.105278)
			(xy 75.763089 -317.103297) (xy 75.71487 -317.093453) (xy 75.668854 -317.076001) (xy 75.626233 -317.051394)
			(xy 75.588112 -317.020269) (xy 75.555477 -316.983432) (xy 75.529174 -316.941836) (xy 75.509883 -316.89656)
			(xy 75.498106 -316.848776) (xy 75.494146 -316.799722) (xy 74.205084 -316.799722) (xy 74.204589 -316.824329)
			(xy 74.196694 -316.872906) (xy 74.18111 -316.919587) (xy 74.158239 -316.963164) (xy 74.128674 -317.002508)
			(xy 74.093181 -317.0366) (xy 74.052678 -317.064556) (xy 74.008216 -317.085654) (xy 73.960945 -317.099346)
			(xy 73.91209 -317.105278) (xy 73.862915 -317.103297) (xy 73.814696 -317.093453) (xy 73.76868 -317.076001)
			(xy 73.726059 -317.051394) (xy 73.687938 -317.020269) (xy 73.655303 -316.983432) (xy 73.629 -316.941836)
			(xy 73.609709 -316.89656) (xy 73.597932 -316.848776) (xy 73.593972 -316.799722) (xy 72.305164 -316.799722)
			(xy 72.304669 -316.824329) (xy 72.296774 -316.872906) (xy 72.28119 -316.919587) (xy 72.258319 -316.963164)
			(xy 72.228754 -317.002508) (xy 72.193261 -317.0366) (xy 72.152758 -317.064556) (xy 72.108296 -317.085654)
			(xy 72.061025 -317.099346) (xy 72.01217 -317.105278) (xy 71.962995 -317.103297) (xy 71.914776 -317.093453)
			(xy 71.86876 -317.076001) (xy 71.826139 -317.051394) (xy 71.788018 -317.020269) (xy 71.755383 -316.983432)
			(xy 71.72908 -316.941836) (xy 71.709789 -316.89656) (xy 71.698012 -316.848776) (xy 71.694052 -316.799722)
			(xy 70.405244 -316.799722) (xy 70.404749 -316.824329) (xy 70.396854 -316.872906) (xy 70.38127 -316.919587)
			(xy 70.358399 -316.963164) (xy 70.328834 -317.002508) (xy 70.293341 -317.0366) (xy 70.252838 -317.064556)
			(xy 70.208376 -317.085654) (xy 70.161105 -317.099346) (xy 70.11225 -317.105278) (xy 70.063075 -317.103297)
			(xy 70.014856 -317.093453) (xy 69.96884 -317.076001) (xy 69.926219 -317.051394) (xy 69.888098 -317.020269)
			(xy 69.855463 -316.983432) (xy 69.82916 -316.941836) (xy 69.809869 -316.89656) (xy 69.798092 -316.848776)
			(xy 69.794132 -316.799722) (xy 68.50507 -316.799722) (xy 68.504575 -316.824329) (xy 68.49668 -316.872906)
			(xy 68.481096 -316.919587) (xy 68.458225 -316.963164) (xy 68.42866 -317.002508) (xy 68.393167 -317.0366)
			(xy 68.352664 -317.064556) (xy 68.308202 -317.085654) (xy 68.260931 -317.099346) (xy 68.212076 -317.105278)
			(xy 68.162901 -317.103297) (xy 68.114682 -317.093453) (xy 68.068666 -317.076001) (xy 68.026045 -317.051394)
			(xy 67.987924 -317.020269) (xy 67.955289 -316.983432) (xy 67.928986 -316.941836) (xy 67.909695 -316.89656)
			(xy 67.897918 -316.848776) (xy 67.893958 -316.799722) (xy 66.60515 -316.799722) (xy 66.604655 -316.824329)
			(xy 66.59676 -316.872906) (xy 66.581176 -316.919587) (xy 66.558305 -316.963164) (xy 66.52874 -317.002508)
			(xy 66.493247 -317.0366) (xy 66.452744 -317.064556) (xy 66.408282 -317.085654) (xy 66.361011 -317.099346)
			(xy 66.312156 -317.105278) (xy 66.262981 -317.103297) (xy 66.214762 -317.093453) (xy 66.168746 -317.076001)
			(xy 66.126125 -317.051394) (xy 66.088004 -317.020269) (xy 66.055369 -316.983432) (xy 66.029066 -316.941836)
			(xy 66.009775 -316.89656) (xy 65.997998 -316.848776) (xy 65.994038 -316.799722) (xy 64.70523 -316.799722)
			(xy 64.704735 -316.824329) (xy 64.69684 -316.872906) (xy 64.681256 -316.919587) (xy 64.658385 -316.963164)
			(xy 64.62882 -317.002508) (xy 64.593327 -317.0366) (xy 64.552824 -317.064556) (xy 64.508362 -317.085654)
			(xy 64.461091 -317.099346) (xy 64.412236 -317.105278) (xy 64.363061 -317.103297) (xy 64.314842 -317.093453)
			(xy 64.268826 -317.076001) (xy 64.226205 -317.051394) (xy 64.188084 -317.020269) (xy 64.155449 -316.983432)
			(xy 64.129146 -316.941836) (xy 64.109855 -316.89656) (xy 64.098078 -316.848776) (xy 64.094118 -316.799722)
			(xy 62.805056 -316.799722) (xy 62.804561 -316.824329) (xy 62.796666 -316.872906) (xy 62.781082 -316.919587)
			(xy 62.758211 -316.963164) (xy 62.728646 -317.002508) (xy 62.693153 -317.0366) (xy 62.65265 -317.064556)
			(xy 62.608188 -317.085654) (xy 62.560917 -317.099346) (xy 62.512062 -317.105278) (xy 62.462887 -317.103297)
			(xy 62.414668 -317.093453) (xy 62.368652 -317.076001) (xy 62.326031 -317.051394) (xy 62.28791 -317.020269)
			(xy 62.255275 -316.983432) (xy 62.228972 -316.941836) (xy 62.209681 -316.89656) (xy 62.197904 -316.848776)
			(xy 62.193944 -316.799722) (xy 60.905136 -316.799722) (xy 60.904641 -316.824329) (xy 60.896746 -316.872906)
			(xy 60.881162 -316.919587) (xy 60.858291 -316.963164) (xy 60.828726 -317.002508) (xy 60.793233 -317.0366)
			(xy 60.75273 -317.064556) (xy 60.708268 -317.085654) (xy 60.660997 -317.099346) (xy 60.612142 -317.105278)
			(xy 60.562967 -317.103297) (xy 60.514748 -317.093453) (xy 60.468732 -317.076001) (xy 60.426111 -317.051394)
			(xy 60.38799 -317.020269) (xy 60.355355 -316.983432) (xy 60.329052 -316.941836) (xy 60.309761 -316.89656)
			(xy 60.297984 -316.848776) (xy 60.294024 -316.799722) (xy 59.005216 -316.799722) (xy 59.004721 -316.824329)
			(xy 58.996826 -316.872906) (xy 58.981242 -316.919587) (xy 58.958371 -316.963164) (xy 58.928806 -317.002508)
			(xy 58.893313 -317.0366) (xy 58.85281 -317.064556) (xy 58.808348 -317.085654) (xy 58.761077 -317.099346)
			(xy 58.712222 -317.105278) (xy 58.663047 -317.103297) (xy 58.614828 -317.093453) (xy 58.568812 -317.076001)
			(xy 58.526191 -317.051394) (xy 58.48807 -317.020269) (xy 58.455435 -316.983432) (xy 58.429132 -316.941836)
			(xy 58.409841 -316.89656) (xy 58.398064 -316.848776) (xy 58.394104 -316.799722) (xy 57.105296 -316.799722)
			(xy 57.104801 -316.824329) (xy 57.096906 -316.872906) (xy 57.081322 -316.919587) (xy 57.058451 -316.963164)
			(xy 57.028886 -317.002508) (xy 56.993393 -317.0366) (xy 56.95289 -317.064556) (xy 56.908428 -317.085654)
			(xy 56.861157 -317.099346) (xy 56.812302 -317.105278) (xy 56.763127 -317.103297) (xy 56.714908 -317.093453)
			(xy 56.668892 -317.076001) (xy 56.626271 -317.051394) (xy 56.58815 -317.020269) (xy 56.555515 -316.983432)
			(xy 56.529212 -316.941836) (xy 56.509921 -316.89656) (xy 56.498144 -316.848776) (xy 56.494184 -316.799722)
			(xy 55.205122 -316.799722) (xy 55.204627 -316.824329) (xy 55.196732 -316.872906) (xy 55.181148 -316.919587)
			(xy 55.158277 -316.963164) (xy 55.128712 -317.002508) (xy 55.093219 -317.0366) (xy 55.052716 -317.064556)
			(xy 55.008254 -317.085654) (xy 54.960983 -317.099346) (xy 54.912128 -317.105278) (xy 54.862953 -317.103297)
			(xy 54.814734 -317.093453) (xy 54.768718 -317.076001) (xy 54.726097 -317.051394) (xy 54.687976 -317.020269)
			(xy 54.655341 -316.983432) (xy 54.629038 -316.941836) (xy 54.609747 -316.89656) (xy 54.59797 -316.848776)
			(xy 54.59401 -316.799722) (xy 53.305202 -316.799722) (xy 53.304707 -316.824329) (xy 53.296812 -316.872906)
			(xy 53.281228 -316.919587) (xy 53.258357 -316.963164) (xy 53.228792 -317.002508) (xy 53.193299 -317.0366)
			(xy 53.152796 -317.064556) (xy 53.108334 -317.085654) (xy 53.061063 -317.099346) (xy 53.012208 -317.105278)
			(xy 52.963033 -317.103297) (xy 52.914814 -317.093453) (xy 52.868798 -317.076001) (xy 52.826177 -317.051394)
			(xy 52.788056 -317.020269) (xy 52.755421 -316.983432) (xy 52.729118 -316.941836) (xy 52.709827 -316.89656)
			(xy 52.69805 -316.848776) (xy 52.69409 -316.799722) (xy 51.405282 -316.799722) (xy 51.404787 -316.824329)
			(xy 51.396892 -316.872906) (xy 51.381308 -316.919587) (xy 51.358437 -316.963164) (xy 51.328872 -317.002508)
			(xy 51.293379 -317.0366) (xy 51.252876 -317.064556) (xy 51.208414 -317.085654) (xy 51.161143 -317.099346)
			(xy 51.112288 -317.105278) (xy 51.063113 -317.103297) (xy 51.014894 -317.093453) (xy 50.968878 -317.076001)
			(xy 50.926257 -317.051394) (xy 50.888136 -317.020269) (xy 50.855501 -316.983432) (xy 50.829198 -316.941836)
			(xy 50.809907 -316.89656) (xy 50.79813 -316.848776) (xy 50.79417 -316.799722) (xy 49.505108 -316.799722)
			(xy 49.504613 -316.824329) (xy 49.496718 -316.872906) (xy 49.481134 -316.919587) (xy 49.458263 -316.963164)
			(xy 49.428698 -317.002508) (xy 49.393205 -317.0366) (xy 49.352702 -317.064556) (xy 49.30824 -317.085654)
			(xy 49.260969 -317.099346) (xy 49.212114 -317.105278) (xy 49.162939 -317.103297) (xy 49.11472 -317.093453)
			(xy 49.068704 -317.076001) (xy 49.026083 -317.051394) (xy 48.987962 -317.020269) (xy 48.955327 -316.983432)
			(xy 48.929024 -316.941836) (xy 48.909733 -316.89656) (xy 48.897956 -316.848776) (xy 48.893996 -316.799722)
			(xy 47.605188 -316.799722) (xy 47.604693 -316.824329) (xy 47.596798 -316.872906) (xy 47.581214 -316.919587)
			(xy 47.558343 -316.963164) (xy 47.528778 -317.002508) (xy 47.493285 -317.0366) (xy 47.452782 -317.064556)
			(xy 47.40832 -317.085654) (xy 47.361049 -317.099346) (xy 47.312194 -317.105278) (xy 47.263019 -317.103297)
			(xy 47.2148 -317.093453) (xy 47.168784 -317.076001) (xy 47.126163 -317.051394) (xy 47.088042 -317.020269)
			(xy 47.055407 -316.983432) (xy 47.029104 -316.941836) (xy 47.009813 -316.89656) (xy 46.998036 -316.848776)
			(xy 46.994076 -316.799722) (xy 45.705268 -316.799722) (xy 45.704773 -316.824329) (xy 45.696878 -316.872906)
			(xy 45.681294 -316.919587) (xy 45.658423 -316.963164) (xy 45.628858 -317.002508) (xy 45.593365 -317.0366)
			(xy 45.552862 -317.064556) (xy 45.5084 -317.085654) (xy 45.461129 -317.099346) (xy 45.412274 -317.105278)
			(xy 45.363099 -317.103297) (xy 45.31488 -317.093453) (xy 45.268864 -317.076001) (xy 45.226243 -317.051394)
			(xy 45.188122 -317.020269) (xy 45.155487 -316.983432) (xy 45.129184 -316.941836) (xy 45.109893 -316.89656)
			(xy 45.098116 -316.848776) (xy 45.094156 -316.799722) (xy 43.805094 -316.799722) (xy 43.804599 -316.824329)
			(xy 43.796704 -316.872906) (xy 43.78112 -316.919587) (xy 43.758249 -316.963164) (xy 43.728684 -317.002508)
			(xy 43.693191 -317.0366) (xy 43.652688 -317.064556) (xy 43.608226 -317.085654) (xy 43.560955 -317.099346)
			(xy 43.5121 -317.105278) (xy 43.462925 -317.103297) (xy 43.414706 -317.093453) (xy 43.36869 -317.076001)
			(xy 43.326069 -317.051394) (xy 43.287948 -317.020269) (xy 43.255313 -316.983432) (xy 43.22901 -316.941836)
			(xy 43.209719 -316.89656) (xy 43.197942 -316.848776) (xy 43.193982 -316.799722) (xy 41.905174 -316.799722)
			(xy 41.904679 -316.824329) (xy 41.896784 -316.872906) (xy 41.8812 -316.919587) (xy 41.858329 -316.963164)
			(xy 41.828764 -317.002508) (xy 41.793271 -317.0366) (xy 41.752768 -317.064556) (xy 41.708306 -317.085654)
			(xy 41.661035 -317.099346) (xy 41.61218 -317.105278) (xy 41.563005 -317.103297) (xy 41.514786 -317.093453)
			(xy 41.46877 -317.076001) (xy 41.426149 -317.051394) (xy 41.388028 -317.020269) (xy 41.355393 -316.983432)
			(xy 41.32909 -316.941836) (xy 41.309799 -316.89656) (xy 41.298022 -316.848776) (xy 41.294062 -316.799722)
			(xy 40.005254 -316.799722) (xy 40.004759 -316.824329) (xy 39.996864 -316.872906) (xy 39.98128 -316.919587)
			(xy 39.958409 -316.963164) (xy 39.928844 -317.002508) (xy 39.893351 -317.0366) (xy 39.852848 -317.064556)
			(xy 39.808386 -317.085654) (xy 39.761115 -317.099346) (xy 39.71226 -317.105278) (xy 39.663085 -317.103297)
			(xy 39.614866 -317.093453) (xy 39.56885 -317.076001) (xy 39.526229 -317.051394) (xy 39.488108 -317.020269)
			(xy 39.455473 -316.983432) (xy 39.42917 -316.941836) (xy 39.409879 -316.89656) (xy 39.398102 -316.848776)
			(xy 39.394142 -316.799722) (xy 38.10508 -316.799722) (xy 38.104585 -316.824329) (xy 38.09669 -316.872906)
			(xy 38.081106 -316.919587) (xy 38.058235 -316.963164) (xy 38.02867 -317.002508) (xy 37.993177 -317.0366)
			(xy 37.952674 -317.064556) (xy 37.908212 -317.085654) (xy 37.860941 -317.099346) (xy 37.812086 -317.105278)
			(xy 37.762911 -317.103297) (xy 37.714692 -317.093453) (xy 37.668676 -317.076001) (xy 37.626055 -317.051394)
			(xy 37.587934 -317.020269) (xy 37.555299 -316.983432) (xy 37.528996 -316.941836) (xy 37.509705 -316.89656)
			(xy 37.497928 -316.848776) (xy 37.493968 -316.799722) (xy 37.15512 -316.799722) (xy 37.154625 -316.824329)
			(xy 37.14673 -316.872906) (xy 37.131146 -316.919587) (xy 37.108275 -316.963164) (xy 37.07871 -317.002508)
			(xy 37.043217 -317.0366) (xy 37.002714 -317.064556) (xy 36.958252 -317.085654) (xy 36.910981 -317.099346)
			(xy 36.862126 -317.105278) (xy 36.812951 -317.103297) (xy 36.764732 -317.093453) (xy 36.718716 -317.076001)
			(xy 36.676095 -317.051394) (xy 36.637974 -317.020269) (xy 36.605339 -316.983432) (xy 36.579036 -316.941836)
			(xy 36.559745 -316.89656) (xy 36.547968 -316.848776) (xy 36.544008 -316.799722) (xy 0.508 -316.799722)
			(xy 0.508 -317.749936) (xy 38.444182 -317.749936) (xy 38.448142 -317.700882) (xy 38.459919 -317.653098)
			(xy 38.47921 -317.607822) (xy 38.505513 -317.566226) (xy 38.538148 -317.529389) (xy 38.576269 -317.498264)
			(xy 38.61889 -317.473657) (xy 38.664906 -317.456205) (xy 38.713125 -317.446361) (xy 38.7623 -317.44438)
			(xy 38.811155 -317.450312) (xy 38.858426 -317.464004) (xy 38.902888 -317.485102) (xy 38.943391 -317.513058)
			(xy 38.978884 -317.54715) (xy 39.008449 -317.586494) (xy 39.03132 -317.630071) (xy 39.046904 -317.676752)
			(xy 39.054799 -317.725329) (xy 39.055294 -317.749936) (xy 40.344102 -317.749936) (xy 40.348062 -317.700882)
			(xy 40.359839 -317.653098) (xy 40.37913 -317.607822) (xy 40.405433 -317.566226) (xy 40.438068 -317.529389)
			(xy 40.476189 -317.498264) (xy 40.51881 -317.473657) (xy 40.564826 -317.456205) (xy 40.613045 -317.446361)
			(xy 40.66222 -317.44438) (xy 40.711075 -317.450312) (xy 40.758346 -317.464004) (xy 40.802808 -317.485102)
			(xy 40.843311 -317.513058) (xy 40.878804 -317.54715) (xy 40.908369 -317.586494) (xy 40.93124 -317.630071)
			(xy 40.946824 -317.676752) (xy 40.954719 -317.725329) (xy 40.955214 -317.749936) (xy 42.244022 -317.749936)
			(xy 42.247982 -317.700882) (xy 42.259759 -317.653098) (xy 42.27905 -317.607822) (xy 42.305353 -317.566226)
			(xy 42.337988 -317.529389) (xy 42.376109 -317.498264) (xy 42.41873 -317.473657) (xy 42.464746 -317.456205)
			(xy 42.512965 -317.446361) (xy 42.56214 -317.44438) (xy 42.610995 -317.450312) (xy 42.658266 -317.464004)
			(xy 42.702728 -317.485102) (xy 42.743231 -317.513058) (xy 42.778724 -317.54715) (xy 42.808289 -317.586494)
			(xy 42.83116 -317.630071) (xy 42.846744 -317.676752) (xy 42.854639 -317.725329) (xy 42.855134 -317.749936)
			(xy 44.143942 -317.749936) (xy 44.147902 -317.700882) (xy 44.159679 -317.653098) (xy 44.17897 -317.607822)
			(xy 44.205273 -317.566226) (xy 44.237908 -317.529389) (xy 44.276029 -317.498264) (xy 44.31865 -317.473657)
			(xy 44.364666 -317.456205) (xy 44.412885 -317.446361) (xy 44.46206 -317.44438) (xy 44.510915 -317.450312)
			(xy 44.558186 -317.464004) (xy 44.602648 -317.485102) (xy 44.643151 -317.513058) (xy 44.678644 -317.54715)
			(xy 44.708209 -317.586494) (xy 44.73108 -317.630071) (xy 44.746664 -317.676752) (xy 44.754559 -317.725329)
			(xy 44.755054 -317.749936) (xy 46.044116 -317.749936) (xy 46.048076 -317.700882) (xy 46.059853 -317.653098)
			(xy 46.079144 -317.607822) (xy 46.105447 -317.566226) (xy 46.138082 -317.529389) (xy 46.176203 -317.498264)
			(xy 46.218824 -317.473657) (xy 46.26484 -317.456205) (xy 46.313059 -317.446361) (xy 46.362234 -317.44438)
			(xy 46.411089 -317.450312) (xy 46.45836 -317.464004) (xy 46.502822 -317.485102) (xy 46.543325 -317.513058)
			(xy 46.578818 -317.54715) (xy 46.608383 -317.586494) (xy 46.631254 -317.630071) (xy 46.646838 -317.676752)
			(xy 46.654733 -317.725329) (xy 46.655228 -317.749936) (xy 47.944036 -317.749936) (xy 47.947996 -317.700882)
			(xy 47.959773 -317.653098) (xy 47.979064 -317.607822) (xy 48.005367 -317.566226) (xy 48.038002 -317.529389)
			(xy 48.076123 -317.498264) (xy 48.118744 -317.473657) (xy 48.16476 -317.456205) (xy 48.212979 -317.446361)
			(xy 48.262154 -317.44438) (xy 48.311009 -317.450312) (xy 48.35828 -317.464004) (xy 48.402742 -317.485102)
			(xy 48.443245 -317.513058) (xy 48.478738 -317.54715) (xy 48.508303 -317.586494) (xy 48.531174 -317.630071)
			(xy 48.546758 -317.676752) (xy 48.554653 -317.725329) (xy 48.555148 -317.749936) (xy 49.843956 -317.749936)
			(xy 49.847916 -317.700882) (xy 49.859693 -317.653098) (xy 49.878984 -317.607822) (xy 49.905287 -317.566226)
			(xy 49.937922 -317.529389) (xy 49.976043 -317.498264) (xy 50.018664 -317.473657) (xy 50.06468 -317.456205)
			(xy 50.112899 -317.446361) (xy 50.162074 -317.44438) (xy 50.210929 -317.450312) (xy 50.2582 -317.464004)
			(xy 50.302662 -317.485102) (xy 50.343165 -317.513058) (xy 50.378658 -317.54715) (xy 50.408223 -317.586494)
			(xy 50.431094 -317.630071) (xy 50.446678 -317.676752) (xy 50.454573 -317.725329) (xy 50.455068 -317.749936)
			(xy 51.74413 -317.749936) (xy 51.74809 -317.700882) (xy 51.759867 -317.653098) (xy 51.779158 -317.607822)
			(xy 51.805461 -317.566226) (xy 51.838096 -317.529389) (xy 51.876217 -317.498264) (xy 51.918838 -317.473657)
			(xy 51.964854 -317.456205) (xy 52.013073 -317.446361) (xy 52.062248 -317.44438) (xy 52.111103 -317.450312)
			(xy 52.158374 -317.464004) (xy 52.202836 -317.485102) (xy 52.243339 -317.513058) (xy 52.278832 -317.54715)
			(xy 52.308397 -317.586494) (xy 52.331268 -317.630071) (xy 52.346852 -317.676752) (xy 52.354747 -317.725329)
			(xy 52.355242 -317.749936) (xy 53.64405 -317.749936) (xy 53.64801 -317.700882) (xy 53.659787 -317.653098)
			(xy 53.679078 -317.607822) (xy 53.705381 -317.566226) (xy 53.738016 -317.529389) (xy 53.776137 -317.498264)
			(xy 53.818758 -317.473657) (xy 53.864774 -317.456205) (xy 53.912993 -317.446361) (xy 53.962168 -317.44438)
			(xy 54.011023 -317.450312) (xy 54.058294 -317.464004) (xy 54.102756 -317.485102) (xy 54.143259 -317.513058)
			(xy 54.178752 -317.54715) (xy 54.208317 -317.586494) (xy 54.231188 -317.630071) (xy 54.246772 -317.676752)
			(xy 54.254667 -317.725329) (xy 54.255162 -317.749936) (xy 55.54397 -317.749936) (xy 55.54793 -317.700882)
			(xy 55.559707 -317.653098) (xy 55.578998 -317.607822) (xy 55.605301 -317.566226) (xy 55.637936 -317.529389)
			(xy 55.676057 -317.498264) (xy 55.718678 -317.473657) (xy 55.764694 -317.456205) (xy 55.812913 -317.446361)
			(xy 55.862088 -317.44438) (xy 55.910943 -317.450312) (xy 55.958214 -317.464004) (xy 56.002676 -317.485102)
			(xy 56.043179 -317.513058) (xy 56.078672 -317.54715) (xy 56.108237 -317.586494) (xy 56.131108 -317.630071)
			(xy 56.146692 -317.676752) (xy 56.154587 -317.725329) (xy 56.155082 -317.749936) (xy 57.444144 -317.749936)
			(xy 57.448104 -317.700882) (xy 57.459881 -317.653098) (xy 57.479172 -317.607822) (xy 57.505475 -317.566226)
			(xy 57.53811 -317.529389) (xy 57.576231 -317.498264) (xy 57.618852 -317.473657) (xy 57.664868 -317.456205)
			(xy 57.713087 -317.446361) (xy 57.762262 -317.44438) (xy 57.811117 -317.450312) (xy 57.858388 -317.464004)
			(xy 57.90285 -317.485102) (xy 57.943353 -317.513058) (xy 57.978846 -317.54715) (xy 58.008411 -317.586494)
			(xy 58.031282 -317.630071) (xy 58.046866 -317.676752) (xy 58.054761 -317.725329) (xy 58.055256 -317.749936)
			(xy 59.344064 -317.749936) (xy 59.348024 -317.700882) (xy 59.359801 -317.653098) (xy 59.379092 -317.607822)
			(xy 59.405395 -317.566226) (xy 59.43803 -317.529389) (xy 59.476151 -317.498264) (xy 59.518772 -317.473657)
			(xy 59.564788 -317.456205) (xy 59.613007 -317.446361) (xy 59.662182 -317.44438) (xy 59.711037 -317.450312)
			(xy 59.758308 -317.464004) (xy 59.80277 -317.485102) (xy 59.843273 -317.513058) (xy 59.878766 -317.54715)
			(xy 59.908331 -317.586494) (xy 59.931202 -317.630071) (xy 59.946786 -317.676752) (xy 59.954681 -317.725329)
			(xy 59.955176 -317.749936) (xy 61.243984 -317.749936) (xy 61.247944 -317.700882) (xy 61.259721 -317.653098)
			(xy 61.279012 -317.607822) (xy 61.305315 -317.566226) (xy 61.33795 -317.529389) (xy 61.376071 -317.498264)
			(xy 61.418692 -317.473657) (xy 61.464708 -317.456205) (xy 61.512927 -317.446361) (xy 61.562102 -317.44438)
			(xy 61.610957 -317.450312) (xy 61.658228 -317.464004) (xy 61.70269 -317.485102) (xy 61.743193 -317.513058)
			(xy 61.778686 -317.54715) (xy 61.808251 -317.586494) (xy 61.831122 -317.630071) (xy 61.846706 -317.676752)
			(xy 61.854601 -317.725329) (xy 61.855096 -317.749936) (xy 63.144158 -317.749936) (xy 63.148118 -317.700882)
			(xy 63.159895 -317.653098) (xy 63.179186 -317.607822) (xy 63.205489 -317.566226) (xy 63.238124 -317.529389)
			(xy 63.276245 -317.498264) (xy 63.318866 -317.473657) (xy 63.364882 -317.456205) (xy 63.413101 -317.446361)
			(xy 63.462276 -317.44438) (xy 63.511131 -317.450312) (xy 63.558402 -317.464004) (xy 63.602864 -317.485102)
			(xy 63.643367 -317.513058) (xy 63.67886 -317.54715) (xy 63.708425 -317.586494) (xy 63.731296 -317.630071)
			(xy 63.74688 -317.676752) (xy 63.754775 -317.725329) (xy 63.75527 -317.749936) (xy 65.044078 -317.749936)
			(xy 65.048038 -317.700882) (xy 65.059815 -317.653098) (xy 65.079106 -317.607822) (xy 65.105409 -317.566226)
			(xy 65.138044 -317.529389) (xy 65.176165 -317.498264) (xy 65.218786 -317.473657) (xy 65.264802 -317.456205)
			(xy 65.313021 -317.446361) (xy 65.362196 -317.44438) (xy 65.411051 -317.450312) (xy 65.458322 -317.464004)
			(xy 65.502784 -317.485102) (xy 65.543287 -317.513058) (xy 65.57878 -317.54715) (xy 65.608345 -317.586494)
			(xy 65.631216 -317.630071) (xy 65.6468 -317.676752) (xy 65.654695 -317.725329) (xy 65.65519 -317.749936)
			(xy 66.943998 -317.749936) (xy 66.947958 -317.700882) (xy 66.959735 -317.653098) (xy 66.979026 -317.607822)
			(xy 67.005329 -317.566226) (xy 67.037964 -317.529389) (xy 67.076085 -317.498264) (xy 67.118706 -317.473657)
			(xy 67.164722 -317.456205) (xy 67.212941 -317.446361) (xy 67.262116 -317.44438) (xy 67.310971 -317.450312)
			(xy 67.358242 -317.464004) (xy 67.402704 -317.485102) (xy 67.443207 -317.513058) (xy 67.4787 -317.54715)
			(xy 67.508265 -317.586494) (xy 67.531136 -317.630071) (xy 67.54672 -317.676752) (xy 67.554615 -317.725329)
			(xy 67.55511 -317.749936) (xy 68.844172 -317.749936) (xy 68.848132 -317.700882) (xy 68.859909 -317.653098)
			(xy 68.8792 -317.607822) (xy 68.905503 -317.566226) (xy 68.938138 -317.529389) (xy 68.976259 -317.498264)
			(xy 69.01888 -317.473657) (xy 69.064896 -317.456205) (xy 69.113115 -317.446361) (xy 69.16229 -317.44438)
			(xy 69.211145 -317.450312) (xy 69.258416 -317.464004) (xy 69.302878 -317.485102) (xy 69.343381 -317.513058)
			(xy 69.378874 -317.54715) (xy 69.408439 -317.586494) (xy 69.43131 -317.630071) (xy 69.446894 -317.676752)
			(xy 69.454789 -317.725329) (xy 69.455284 -317.749936) (xy 70.744092 -317.749936) (xy 70.748052 -317.700882)
			(xy 70.759829 -317.653098) (xy 70.77912 -317.607822) (xy 70.805423 -317.566226) (xy 70.838058 -317.529389)
			(xy 70.876179 -317.498264) (xy 70.9188 -317.473657) (xy 70.964816 -317.456205) (xy 71.013035 -317.446361)
			(xy 71.06221 -317.44438) (xy 71.111065 -317.450312) (xy 71.158336 -317.464004) (xy 71.202798 -317.485102)
			(xy 71.243301 -317.513058) (xy 71.278794 -317.54715) (xy 71.308359 -317.586494) (xy 71.33123 -317.630071)
			(xy 71.346814 -317.676752) (xy 71.354709 -317.725329) (xy 71.355204 -317.749936) (xy 72.644012 -317.749936)
			(xy 72.647972 -317.700882) (xy 72.659749 -317.653098) (xy 72.67904 -317.607822) (xy 72.705343 -317.566226)
			(xy 72.737978 -317.529389) (xy 72.776099 -317.498264) (xy 72.81872 -317.473657) (xy 72.864736 -317.456205)
			(xy 72.912955 -317.446361) (xy 72.96213 -317.44438) (xy 73.010985 -317.450312) (xy 73.058256 -317.464004)
			(xy 73.102718 -317.485102) (xy 73.143221 -317.513058) (xy 73.178714 -317.54715) (xy 73.208279 -317.586494)
			(xy 73.23115 -317.630071) (xy 73.246734 -317.676752) (xy 73.254629 -317.725329) (xy 73.255124 -317.749936)
			(xy 74.544186 -317.749936) (xy 74.548146 -317.700882) (xy 74.559923 -317.653098) (xy 74.579214 -317.607822)
			(xy 74.605517 -317.566226) (xy 74.638152 -317.529389) (xy 74.676273 -317.498264) (xy 74.718894 -317.473657)
			(xy 74.76491 -317.456205) (xy 74.813129 -317.446361) (xy 74.862304 -317.44438) (xy 74.911159 -317.450312)
			(xy 74.95843 -317.464004) (xy 75.002892 -317.485102) (xy 75.043395 -317.513058) (xy 75.078888 -317.54715)
			(xy 75.108453 -317.586494) (xy 75.131324 -317.630071) (xy 75.146908 -317.676752) (xy 75.154803 -317.725329)
			(xy 75.155298 -317.749936) (xy 76.444106 -317.749936) (xy 76.448066 -317.700882) (xy 76.459843 -317.653098)
			(xy 76.479134 -317.607822) (xy 76.505437 -317.566226) (xy 76.538072 -317.529389) (xy 76.576193 -317.498264)
			(xy 76.618814 -317.473657) (xy 76.66483 -317.456205) (xy 76.713049 -317.446361) (xy 76.762224 -317.44438)
			(xy 76.811079 -317.450312) (xy 76.85835 -317.464004) (xy 76.902812 -317.485102) (xy 76.943315 -317.513058)
			(xy 76.978808 -317.54715) (xy 77.008373 -317.586494) (xy 77.031244 -317.630071) (xy 77.046828 -317.676752)
			(xy 77.054723 -317.725329) (xy 77.055218 -317.749936) (xy 78.344026 -317.749936) (xy 78.347986 -317.700882)
			(xy 78.359763 -317.653098) (xy 78.379054 -317.607822) (xy 78.405357 -317.566226) (xy 78.437992 -317.529389)
			(xy 78.476113 -317.498264) (xy 78.518734 -317.473657) (xy 78.56475 -317.456205) (xy 78.612969 -317.446361)
			(xy 78.662144 -317.44438) (xy 78.710999 -317.450312) (xy 78.75827 -317.464004) (xy 78.802732 -317.485102)
			(xy 78.843235 -317.513058) (xy 78.878728 -317.54715) (xy 78.908293 -317.586494) (xy 78.931164 -317.630071)
			(xy 78.946748 -317.676752) (xy 78.954643 -317.725329) (xy 78.955138 -317.749936) (xy 80.243946 -317.749936)
			(xy 80.247906 -317.700882) (xy 80.259683 -317.653098) (xy 80.278974 -317.607822) (xy 80.305277 -317.566226)
			(xy 80.337912 -317.529389) (xy 80.376033 -317.498264) (xy 80.418654 -317.473657) (xy 80.46467 -317.456205)
			(xy 80.512889 -317.446361) (xy 80.562064 -317.44438) (xy 80.610919 -317.450312) (xy 80.65819 -317.464004)
			(xy 80.702652 -317.485102) (xy 80.743155 -317.513058) (xy 80.778648 -317.54715) (xy 80.808213 -317.586494)
			(xy 80.831084 -317.630071) (xy 80.846668 -317.676752) (xy 80.854563 -317.725329) (xy 80.855058 -317.749936)
			(xy 154.54428 -317.749936) (xy 154.54824 -317.700882) (xy 154.560017 -317.653098) (xy 154.579308 -317.607822)
			(xy 154.605611 -317.566226) (xy 154.638246 -317.529389) (xy 154.676367 -317.498264) (xy 154.718988 -317.473657)
			(xy 154.765004 -317.456205) (xy 154.813223 -317.446361) (xy 154.862398 -317.44438) (xy 154.911253 -317.450312)
			(xy 154.958524 -317.464004) (xy 155.002986 -317.485102) (xy 155.043489 -317.513058) (xy 155.078982 -317.54715)
			(xy 155.108547 -317.586494) (xy 155.131418 -317.630071) (xy 155.147002 -317.676752) (xy 155.154897 -317.725329)
			(xy 155.155392 -317.749936) (xy 156.4442 -317.749936) (xy 156.44816 -317.700882) (xy 156.459937 -317.653098)
			(xy 156.479228 -317.607822) (xy 156.505531 -317.566226) (xy 156.538166 -317.529389) (xy 156.576287 -317.498264)
			(xy 156.618908 -317.473657) (xy 156.664924 -317.456205) (xy 156.713143 -317.446361) (xy 156.762318 -317.44438)
			(xy 156.811173 -317.450312) (xy 156.858444 -317.464004) (xy 156.902906 -317.485102) (xy 156.943409 -317.513058)
			(xy 156.978902 -317.54715) (xy 157.008467 -317.586494) (xy 157.031338 -317.630071) (xy 157.046922 -317.676752)
			(xy 157.054817 -317.725329) (xy 157.055312 -317.749936) (xy 158.34412 -317.749936) (xy 158.34808 -317.700882)
			(xy 158.359857 -317.653098) (xy 158.379148 -317.607822) (xy 158.405451 -317.566226) (xy 158.438086 -317.529389)
			(xy 158.476207 -317.498264) (xy 158.518828 -317.473657) (xy 158.564844 -317.456205) (xy 158.613063 -317.446361)
			(xy 158.662238 -317.44438) (xy 158.711093 -317.450312) (xy 158.758364 -317.464004) (xy 158.802826 -317.485102)
			(xy 158.843329 -317.513058) (xy 158.878822 -317.54715) (xy 158.908387 -317.586494) (xy 158.931258 -317.630071)
			(xy 158.946842 -317.676752) (xy 158.954737 -317.725329) (xy 158.955232 -317.749936) (xy 160.24404 -317.749936)
			(xy 160.248 -317.700882) (xy 160.259777 -317.653098) (xy 160.279068 -317.607822) (xy 160.305371 -317.566226)
			(xy 160.338006 -317.529389) (xy 160.376127 -317.498264) (xy 160.418748 -317.473657) (xy 160.464764 -317.456205)
			(xy 160.512983 -317.446361) (xy 160.562158 -317.44438) (xy 160.611013 -317.450312) (xy 160.658284 -317.464004)
			(xy 160.702746 -317.485102) (xy 160.743249 -317.513058) (xy 160.778742 -317.54715) (xy 160.808307 -317.586494)
			(xy 160.831178 -317.630071) (xy 160.846762 -317.676752) (xy 160.854657 -317.725329) (xy 160.855152 -317.749936)
			(xy 162.144214 -317.749936) (xy 162.148174 -317.700882) (xy 162.159951 -317.653098) (xy 162.179242 -317.607822)
			(xy 162.205545 -317.566226) (xy 162.23818 -317.529389) (xy 162.276301 -317.498264) (xy 162.318922 -317.473657)
			(xy 162.364938 -317.456205) (xy 162.413157 -317.446361) (xy 162.462332 -317.44438) (xy 162.511187 -317.450312)
			(xy 162.558458 -317.464004) (xy 162.60292 -317.485102) (xy 162.643423 -317.513058) (xy 162.678916 -317.54715)
			(xy 162.708481 -317.586494) (xy 162.731352 -317.630071) (xy 162.746936 -317.676752) (xy 162.754831 -317.725329)
			(xy 162.755326 -317.749936) (xy 164.044134 -317.749936) (xy 164.048094 -317.700882) (xy 164.059871 -317.653098)
			(xy 164.079162 -317.607822) (xy 164.105465 -317.566226) (xy 164.1381 -317.529389) (xy 164.176221 -317.498264)
			(xy 164.218842 -317.473657) (xy 164.264858 -317.456205) (xy 164.313077 -317.446361) (xy 164.362252 -317.44438)
			(xy 164.411107 -317.450312) (xy 164.458378 -317.464004) (xy 164.50284 -317.485102) (xy 164.543343 -317.513058)
			(xy 164.578836 -317.54715) (xy 164.608401 -317.586494) (xy 164.631272 -317.630071) (xy 164.646856 -317.676752)
			(xy 164.654751 -317.725329) (xy 164.655246 -317.749936) (xy 165.944054 -317.749936) (xy 165.948014 -317.700882)
			(xy 165.959791 -317.653098) (xy 165.979082 -317.607822) (xy 166.005385 -317.566226) (xy 166.03802 -317.529389)
			(xy 166.076141 -317.498264) (xy 166.118762 -317.473657) (xy 166.164778 -317.456205) (xy 166.212997 -317.446361)
			(xy 166.262172 -317.44438) (xy 166.311027 -317.450312) (xy 166.358298 -317.464004) (xy 166.40276 -317.485102)
			(xy 166.443263 -317.513058) (xy 166.478756 -317.54715) (xy 166.508321 -317.586494) (xy 166.531192 -317.630071)
			(xy 166.546776 -317.676752) (xy 166.554671 -317.725329) (xy 166.555166 -317.749936) (xy 167.844228 -317.749936)
			(xy 167.848188 -317.700882) (xy 167.859965 -317.653098) (xy 167.879256 -317.607822) (xy 167.905559 -317.566226)
			(xy 167.938194 -317.529389) (xy 167.976315 -317.498264) (xy 168.018936 -317.473657) (xy 168.064952 -317.456205)
			(xy 168.113171 -317.446361) (xy 168.162346 -317.44438) (xy 168.211201 -317.450312) (xy 168.258472 -317.464004)
			(xy 168.302934 -317.485102) (xy 168.343437 -317.513058) (xy 168.37893 -317.54715) (xy 168.408495 -317.586494)
			(xy 168.431366 -317.630071) (xy 168.44695 -317.676752) (xy 168.454845 -317.725329) (xy 168.45534 -317.749936)
			(xy 169.744148 -317.749936) (xy 169.748108 -317.700882) (xy 169.759885 -317.653098) (xy 169.779176 -317.607822)
			(xy 169.805479 -317.566226) (xy 169.838114 -317.529389) (xy 169.876235 -317.498264) (xy 169.918856 -317.473657)
			(xy 169.964872 -317.456205) (xy 170.013091 -317.446361) (xy 170.062266 -317.44438) (xy 170.111121 -317.450312)
			(xy 170.158392 -317.464004) (xy 170.202854 -317.485102) (xy 170.243357 -317.513058) (xy 170.27885 -317.54715)
			(xy 170.308415 -317.586494) (xy 170.331286 -317.630071) (xy 170.34687 -317.676752) (xy 170.354765 -317.725329)
			(xy 170.35526 -317.749936) (xy 171.644068 -317.749936) (xy 171.648028 -317.700882) (xy 171.659805 -317.653098)
			(xy 171.679096 -317.607822) (xy 171.705399 -317.566226) (xy 171.738034 -317.529389) (xy 171.776155 -317.498264)
			(xy 171.818776 -317.473657) (xy 171.864792 -317.456205) (xy 171.913011 -317.446361) (xy 171.962186 -317.44438)
			(xy 172.011041 -317.450312) (xy 172.058312 -317.464004) (xy 172.102774 -317.485102) (xy 172.143277 -317.513058)
			(xy 172.17877 -317.54715) (xy 172.208335 -317.586494) (xy 172.231206 -317.630071) (xy 172.24679 -317.676752)
			(xy 172.254685 -317.725329) (xy 172.25518 -317.749936) (xy 173.544242 -317.749936) (xy 173.548202 -317.700882)
			(xy 173.559979 -317.653098) (xy 173.57927 -317.607822) (xy 173.605573 -317.566226) (xy 173.638208 -317.529389)
			(xy 173.676329 -317.498264) (xy 173.71895 -317.473657) (xy 173.764966 -317.456205) (xy 173.813185 -317.446361)
			(xy 173.86236 -317.44438) (xy 173.911215 -317.450312) (xy 173.958486 -317.464004) (xy 174.002948 -317.485102)
			(xy 174.043451 -317.513058) (xy 174.078944 -317.54715) (xy 174.108509 -317.586494) (xy 174.13138 -317.630071)
			(xy 174.146964 -317.676752) (xy 174.154859 -317.725329) (xy 174.155354 -317.749936) (xy 175.444162 -317.749936)
			(xy 175.448122 -317.700882) (xy 175.459899 -317.653098) (xy 175.47919 -317.607822) (xy 175.505493 -317.566226)
			(xy 175.538128 -317.529389) (xy 175.576249 -317.498264) (xy 175.61887 -317.473657) (xy 175.664886 -317.456205)
			(xy 175.713105 -317.446361) (xy 175.76228 -317.44438) (xy 175.811135 -317.450312) (xy 175.858406 -317.464004)
			(xy 175.902868 -317.485102) (xy 175.943371 -317.513058) (xy 175.978864 -317.54715) (xy 176.008429 -317.586494)
			(xy 176.0313 -317.630071) (xy 176.046884 -317.676752) (xy 176.054779 -317.725329) (xy 176.055274 -317.749936)
			(xy 177.344082 -317.749936) (xy 177.348042 -317.700882) (xy 177.359819 -317.653098) (xy 177.37911 -317.607822)
			(xy 177.405413 -317.566226) (xy 177.438048 -317.529389) (xy 177.476169 -317.498264) (xy 177.51879 -317.473657)
			(xy 177.564806 -317.456205) (xy 177.613025 -317.446361) (xy 177.6622 -317.44438) (xy 177.711055 -317.450312)
			(xy 177.758326 -317.464004) (xy 177.802788 -317.485102) (xy 177.843291 -317.513058) (xy 177.878784 -317.54715)
			(xy 177.908349 -317.586494) (xy 177.93122 -317.630071) (xy 177.946804 -317.676752) (xy 177.954699 -317.725329)
			(xy 177.955194 -317.749936) (xy 179.244256 -317.749936) (xy 179.248216 -317.700882) (xy 179.259993 -317.653098)
			(xy 179.279284 -317.607822) (xy 179.305587 -317.566226) (xy 179.338222 -317.529389) (xy 179.376343 -317.498264)
			(xy 179.418964 -317.473657) (xy 179.46498 -317.456205) (xy 179.513199 -317.446361) (xy 179.562374 -317.44438)
			(xy 179.611229 -317.450312) (xy 179.6585 -317.464004) (xy 179.702962 -317.485102) (xy 179.743465 -317.513058)
			(xy 179.778958 -317.54715) (xy 179.808523 -317.586494) (xy 179.831394 -317.630071) (xy 179.846978 -317.676752)
			(xy 179.854873 -317.725329) (xy 179.855368 -317.749936) (xy 181.144176 -317.749936) (xy 181.148136 -317.700882)
			(xy 181.159913 -317.653098) (xy 181.179204 -317.607822) (xy 181.205507 -317.566226) (xy 181.238142 -317.529389)
			(xy 181.276263 -317.498264) (xy 181.318884 -317.473657) (xy 181.3649 -317.456205) (xy 181.413119 -317.446361)
			(xy 181.462294 -317.44438) (xy 181.511149 -317.450312) (xy 181.55842 -317.464004) (xy 181.602882 -317.485102)
			(xy 181.643385 -317.513058) (xy 181.678878 -317.54715) (xy 181.708443 -317.586494) (xy 181.731314 -317.630071)
			(xy 181.746898 -317.676752) (xy 181.754793 -317.725329) (xy 181.755288 -317.749936) (xy 183.044096 -317.749936)
			(xy 183.048056 -317.700882) (xy 183.059833 -317.653098) (xy 183.079124 -317.607822) (xy 183.105427 -317.566226)
			(xy 183.138062 -317.529389) (xy 183.176183 -317.498264) (xy 183.218804 -317.473657) (xy 183.26482 -317.456205)
			(xy 183.313039 -317.446361) (xy 183.362214 -317.44438) (xy 183.411069 -317.450312) (xy 183.45834 -317.464004)
			(xy 183.502802 -317.485102) (xy 183.543305 -317.513058) (xy 183.578798 -317.54715) (xy 183.608363 -317.586494)
			(xy 183.631234 -317.630071) (xy 183.646818 -317.676752) (xy 183.654713 -317.725329) (xy 183.655208 -317.749936)
			(xy 184.94427 -317.749936) (xy 184.94823 -317.700882) (xy 184.960007 -317.653098) (xy 184.979298 -317.607822)
			(xy 185.005601 -317.566226) (xy 185.038236 -317.529389) (xy 185.076357 -317.498264) (xy 185.118978 -317.473657)
			(xy 185.164994 -317.456205) (xy 185.213213 -317.446361) (xy 185.262388 -317.44438) (xy 185.311243 -317.450312)
			(xy 185.358514 -317.464004) (xy 185.402976 -317.485102) (xy 185.443479 -317.513058) (xy 185.478972 -317.54715)
			(xy 185.508537 -317.586494) (xy 185.531408 -317.630071) (xy 185.546992 -317.676752) (xy 185.554887 -317.725329)
			(xy 185.555382 -317.749936) (xy 186.84419 -317.749936) (xy 186.84815 -317.700882) (xy 186.859927 -317.653098)
			(xy 186.879218 -317.607822) (xy 186.905521 -317.566226) (xy 186.938156 -317.529389) (xy 186.976277 -317.498264)
			(xy 187.018898 -317.473657) (xy 187.064914 -317.456205) (xy 187.113133 -317.446361) (xy 187.162308 -317.44438)
			(xy 187.211163 -317.450312) (xy 187.258434 -317.464004) (xy 187.302896 -317.485102) (xy 187.343399 -317.513058)
			(xy 187.378892 -317.54715) (xy 187.408457 -317.586494) (xy 187.431328 -317.630071) (xy 187.446912 -317.676752)
			(xy 187.454807 -317.725329) (xy 187.455302 -317.749936) (xy 188.74411 -317.749936) (xy 188.74807 -317.700882)
			(xy 188.759847 -317.653098) (xy 188.779138 -317.607822) (xy 188.805441 -317.566226) (xy 188.838076 -317.529389)
			(xy 188.876197 -317.498264) (xy 188.918818 -317.473657) (xy 188.964834 -317.456205) (xy 189.013053 -317.446361)
			(xy 189.062228 -317.44438) (xy 189.111083 -317.450312) (xy 189.158354 -317.464004) (xy 189.202816 -317.485102)
			(xy 189.243319 -317.513058) (xy 189.278812 -317.54715) (xy 189.308377 -317.586494) (xy 189.331248 -317.630071)
			(xy 189.346832 -317.676752) (xy 189.354727 -317.725329) (xy 189.355222 -317.749936) (xy 190.644284 -317.749936)
			(xy 190.648244 -317.700882) (xy 190.660021 -317.653098) (xy 190.679312 -317.607822) (xy 190.705615 -317.566226)
			(xy 190.73825 -317.529389) (xy 190.776371 -317.498264) (xy 190.818992 -317.473657) (xy 190.865008 -317.456205)
			(xy 190.913227 -317.446361) (xy 190.962402 -317.44438) (xy 191.011257 -317.450312) (xy 191.058528 -317.464004)
			(xy 191.10299 -317.485102) (xy 191.143493 -317.513058) (xy 191.178986 -317.54715) (xy 191.208551 -317.586494)
			(xy 191.231422 -317.630071) (xy 191.247006 -317.676752) (xy 191.254901 -317.725329) (xy 191.255396 -317.749936)
			(xy 192.544204 -317.749936) (xy 192.548164 -317.700882) (xy 192.559941 -317.653098) (xy 192.579232 -317.607822)
			(xy 192.605535 -317.566226) (xy 192.63817 -317.529389) (xy 192.676291 -317.498264) (xy 192.718912 -317.473657)
			(xy 192.764928 -317.456205) (xy 192.813147 -317.446361) (xy 192.862322 -317.44438) (xy 192.911177 -317.450312)
			(xy 192.958448 -317.464004) (xy 193.00291 -317.485102) (xy 193.043413 -317.513058) (xy 193.078906 -317.54715)
			(xy 193.108471 -317.586494) (xy 193.131342 -317.630071) (xy 193.146926 -317.676752) (xy 193.154821 -317.725329)
			(xy 193.155316 -317.749936) (xy 194.444124 -317.749936) (xy 194.448084 -317.700882) (xy 194.459861 -317.653098)
			(xy 194.479152 -317.607822) (xy 194.505455 -317.566226) (xy 194.53809 -317.529389) (xy 194.576211 -317.498264)
			(xy 194.618832 -317.473657) (xy 194.664848 -317.456205) (xy 194.713067 -317.446361) (xy 194.762242 -317.44438)
			(xy 194.811097 -317.450312) (xy 194.858368 -317.464004) (xy 194.90283 -317.485102) (xy 194.943333 -317.513058)
			(xy 194.978826 -317.54715) (xy 195.008391 -317.586494) (xy 195.031262 -317.630071) (xy 195.046846 -317.676752)
			(xy 195.054741 -317.725329) (xy 195.055236 -317.749936) (xy 196.344044 -317.749936) (xy 196.348004 -317.700882)
			(xy 196.359781 -317.653098) (xy 196.379072 -317.607822) (xy 196.405375 -317.566226) (xy 196.43801 -317.529389)
			(xy 196.476131 -317.498264) (xy 196.518752 -317.473657) (xy 196.564768 -317.456205) (xy 196.612987 -317.446361)
			(xy 196.662162 -317.44438) (xy 196.711017 -317.450312) (xy 196.758288 -317.464004) (xy 196.80275 -317.485102)
			(xy 196.843253 -317.513058) (xy 196.878746 -317.54715) (xy 196.908311 -317.586494) (xy 196.931182 -317.630071)
			(xy 196.946766 -317.676752) (xy 196.954661 -317.725329) (xy 196.955156 -317.749936) (xy 270.644124 -317.749936)
			(xy 270.648084 -317.700882) (xy 270.659861 -317.653098) (xy 270.679152 -317.607822) (xy 270.705455 -317.566226)
			(xy 270.73809 -317.529389) (xy 270.776211 -317.498264) (xy 270.818832 -317.473657) (xy 270.864848 -317.456205)
			(xy 270.913067 -317.446361) (xy 270.962242 -317.44438) (xy 271.011097 -317.450312) (xy 271.058368 -317.464004)
			(xy 271.10283 -317.485102) (xy 271.143333 -317.513058) (xy 271.178826 -317.54715) (xy 271.208391 -317.586494)
			(xy 271.231262 -317.630071) (xy 271.246846 -317.676752) (xy 271.254741 -317.725329) (xy 271.255236 -317.749936)
			(xy 272.544044 -317.749936) (xy 272.548004 -317.700882) (xy 272.559781 -317.653098) (xy 272.579072 -317.607822)
			(xy 272.605375 -317.566226) (xy 272.63801 -317.529389) (xy 272.676131 -317.498264) (xy 272.718752 -317.473657)
			(xy 272.764768 -317.456205) (xy 272.812987 -317.446361) (xy 272.862162 -317.44438) (xy 272.911017 -317.450312)
			(xy 272.958288 -317.464004) (xy 273.00275 -317.485102) (xy 273.043253 -317.513058) (xy 273.078746 -317.54715)
			(xy 273.108311 -317.586494) (xy 273.131182 -317.630071) (xy 273.146766 -317.676752) (xy 273.154661 -317.725329)
			(xy 273.155156 -317.749936) (xy 274.443964 -317.749936) (xy 274.447924 -317.700882) (xy 274.459701 -317.653098)
			(xy 274.478992 -317.607822) (xy 274.505295 -317.566226) (xy 274.53793 -317.529389) (xy 274.576051 -317.498264)
			(xy 274.618672 -317.473657) (xy 274.664688 -317.456205) (xy 274.712907 -317.446361) (xy 274.762082 -317.44438)
			(xy 274.810937 -317.450312) (xy 274.858208 -317.464004) (xy 274.90267 -317.485102) (xy 274.943173 -317.513058)
			(xy 274.978666 -317.54715) (xy 275.008231 -317.586494) (xy 275.031102 -317.630071) (xy 275.046686 -317.676752)
			(xy 275.054581 -317.725329) (xy 275.055076 -317.749936) (xy 276.343884 -317.749936) (xy 276.347844 -317.700882)
			(xy 276.359621 -317.653098) (xy 276.378912 -317.607822) (xy 276.405215 -317.566226) (xy 276.43785 -317.529389)
			(xy 276.475971 -317.498264) (xy 276.518592 -317.473657) (xy 276.564608 -317.456205) (xy 276.612827 -317.446361)
			(xy 276.662002 -317.44438) (xy 276.710857 -317.450312) (xy 276.758128 -317.464004) (xy 276.80259 -317.485102)
			(xy 276.843093 -317.513058) (xy 276.878586 -317.54715) (xy 276.908151 -317.586494) (xy 276.931022 -317.630071)
			(xy 276.946606 -317.676752) (xy 276.954501 -317.725329) (xy 276.954996 -317.749936) (xy 278.244058 -317.749936)
			(xy 278.248018 -317.700882) (xy 278.259795 -317.653098) (xy 278.279086 -317.607822) (xy 278.305389 -317.566226)
			(xy 278.338024 -317.529389) (xy 278.376145 -317.498264) (xy 278.418766 -317.473657) (xy 278.464782 -317.456205)
			(xy 278.513001 -317.446361) (xy 278.562176 -317.44438) (xy 278.611031 -317.450312) (xy 278.658302 -317.464004)
			(xy 278.702764 -317.485102) (xy 278.743267 -317.513058) (xy 278.77876 -317.54715) (xy 278.808325 -317.586494)
			(xy 278.831196 -317.630071) (xy 278.84678 -317.676752) (xy 278.854675 -317.725329) (xy 278.85517 -317.749936)
			(xy 280.143978 -317.749936) (xy 280.147938 -317.700882) (xy 280.159715 -317.653098) (xy 280.179006 -317.607822)
			(xy 280.205309 -317.566226) (xy 280.237944 -317.529389) (xy 280.276065 -317.498264) (xy 280.318686 -317.473657)
			(xy 280.364702 -317.456205) (xy 280.412921 -317.446361) (xy 280.462096 -317.44438) (xy 280.510951 -317.450312)
			(xy 280.558222 -317.464004) (xy 280.602684 -317.485102) (xy 280.643187 -317.513058) (xy 280.67868 -317.54715)
			(xy 280.708245 -317.586494) (xy 280.731116 -317.630071) (xy 280.7467 -317.676752) (xy 280.754595 -317.725329)
			(xy 280.75509 -317.749936) (xy 282.043898 -317.749936) (xy 282.047858 -317.700882) (xy 282.059635 -317.653098)
			(xy 282.078926 -317.607822) (xy 282.105229 -317.566226) (xy 282.137864 -317.529389) (xy 282.175985 -317.498264)
			(xy 282.218606 -317.473657) (xy 282.264622 -317.456205) (xy 282.312841 -317.446361) (xy 282.362016 -317.44438)
			(xy 282.410871 -317.450312) (xy 282.458142 -317.464004) (xy 282.502604 -317.485102) (xy 282.543107 -317.513058)
			(xy 282.5786 -317.54715) (xy 282.608165 -317.586494) (xy 282.631036 -317.630071) (xy 282.64662 -317.676752)
			(xy 282.654515 -317.725329) (xy 282.65501 -317.749936) (xy 283.944072 -317.749936) (xy 283.948032 -317.700882)
			(xy 283.959809 -317.653098) (xy 283.9791 -317.607822) (xy 284.005403 -317.566226) (xy 284.038038 -317.529389)
			(xy 284.076159 -317.498264) (xy 284.11878 -317.473657) (xy 284.164796 -317.456205) (xy 284.213015 -317.446361)
			(xy 284.26219 -317.44438) (xy 284.311045 -317.450312) (xy 284.358316 -317.464004) (xy 284.402778 -317.485102)
			(xy 284.443281 -317.513058) (xy 284.478774 -317.54715) (xy 284.508339 -317.586494) (xy 284.53121 -317.630071)
			(xy 284.546794 -317.676752) (xy 284.554689 -317.725329) (xy 284.555184 -317.749936) (xy 285.843992 -317.749936)
			(xy 285.847952 -317.700882) (xy 285.859729 -317.653098) (xy 285.87902 -317.607822) (xy 285.905323 -317.566226)
			(xy 285.937958 -317.529389) (xy 285.976079 -317.498264) (xy 286.0187 -317.473657) (xy 286.064716 -317.456205)
			(xy 286.112935 -317.446361) (xy 286.16211 -317.44438) (xy 286.210965 -317.450312) (xy 286.258236 -317.464004)
			(xy 286.302698 -317.485102) (xy 286.343201 -317.513058) (xy 286.378694 -317.54715) (xy 286.408259 -317.586494)
			(xy 286.43113 -317.630071) (xy 286.446714 -317.676752) (xy 286.454609 -317.725329) (xy 286.455104 -317.749936)
			(xy 287.743912 -317.749936) (xy 287.747872 -317.700882) (xy 287.759649 -317.653098) (xy 287.77894 -317.607822)
			(xy 287.805243 -317.566226) (xy 287.837878 -317.529389) (xy 287.875999 -317.498264) (xy 287.91862 -317.473657)
			(xy 287.964636 -317.456205) (xy 288.012855 -317.446361) (xy 288.06203 -317.44438) (xy 288.110885 -317.450312)
			(xy 288.158156 -317.464004) (xy 288.202618 -317.485102) (xy 288.243121 -317.513058) (xy 288.278614 -317.54715)
			(xy 288.308179 -317.586494) (xy 288.33105 -317.630071) (xy 288.346634 -317.676752) (xy 288.354529 -317.725329)
			(xy 288.355024 -317.749936) (xy 289.644086 -317.749936) (xy 289.648046 -317.700882) (xy 289.659823 -317.653098)
			(xy 289.679114 -317.607822) (xy 289.705417 -317.566226) (xy 289.738052 -317.529389) (xy 289.776173 -317.498264)
			(xy 289.818794 -317.473657) (xy 289.86481 -317.456205) (xy 289.913029 -317.446361) (xy 289.962204 -317.44438)
			(xy 290.011059 -317.450312) (xy 290.05833 -317.464004) (xy 290.102792 -317.485102) (xy 290.143295 -317.513058)
			(xy 290.178788 -317.54715) (xy 290.208353 -317.586494) (xy 290.231224 -317.630071) (xy 290.246808 -317.676752)
			(xy 290.254703 -317.725329) (xy 290.255198 -317.749936) (xy 291.544006 -317.749936) (xy 291.547966 -317.700882)
			(xy 291.559743 -317.653098) (xy 291.579034 -317.607822) (xy 291.605337 -317.566226) (xy 291.637972 -317.529389)
			(xy 291.676093 -317.498264) (xy 291.718714 -317.473657) (xy 291.76473 -317.456205) (xy 291.812949 -317.446361)
			(xy 291.862124 -317.44438) (xy 291.910979 -317.450312) (xy 291.95825 -317.464004) (xy 292.002712 -317.485102)
			(xy 292.043215 -317.513058) (xy 292.078708 -317.54715) (xy 292.108273 -317.586494) (xy 292.131144 -317.630071)
			(xy 292.146728 -317.676752) (xy 292.154623 -317.725329) (xy 292.155118 -317.749936) (xy 293.443926 -317.749936)
			(xy 293.447886 -317.700882) (xy 293.459663 -317.653098) (xy 293.478954 -317.607822) (xy 293.505257 -317.566226)
			(xy 293.537892 -317.529389) (xy 293.576013 -317.498264) (xy 293.618634 -317.473657) (xy 293.66465 -317.456205)
			(xy 293.712869 -317.446361) (xy 293.762044 -317.44438) (xy 293.810899 -317.450312) (xy 293.85817 -317.464004)
			(xy 293.902632 -317.485102) (xy 293.943135 -317.513058) (xy 293.978628 -317.54715) (xy 294.008193 -317.586494)
			(xy 294.031064 -317.630071) (xy 294.046648 -317.676752) (xy 294.054543 -317.725329) (xy 294.055038 -317.749936)
			(xy 295.3441 -317.749936) (xy 295.34806 -317.700882) (xy 295.359837 -317.653098) (xy 295.379128 -317.607822)
			(xy 295.405431 -317.566226) (xy 295.438066 -317.529389) (xy 295.476187 -317.498264) (xy 295.518808 -317.473657)
			(xy 295.564824 -317.456205) (xy 295.613043 -317.446361) (xy 295.662218 -317.44438) (xy 295.711073 -317.450312)
			(xy 295.758344 -317.464004) (xy 295.802806 -317.485102) (xy 295.843309 -317.513058) (xy 295.878802 -317.54715)
			(xy 295.908367 -317.586494) (xy 295.931238 -317.630071) (xy 295.946822 -317.676752) (xy 295.954717 -317.725329)
			(xy 295.955212 -317.749936) (xy 297.24402 -317.749936) (xy 297.24798 -317.700882) (xy 297.259757 -317.653098)
			(xy 297.279048 -317.607822) (xy 297.305351 -317.566226) (xy 297.337986 -317.529389) (xy 297.376107 -317.498264)
			(xy 297.418728 -317.473657) (xy 297.464744 -317.456205) (xy 297.512963 -317.446361) (xy 297.562138 -317.44438)
			(xy 297.610993 -317.450312) (xy 297.658264 -317.464004) (xy 297.702726 -317.485102) (xy 297.743229 -317.513058)
			(xy 297.778722 -317.54715) (xy 297.808287 -317.586494) (xy 297.831158 -317.630071) (xy 297.846742 -317.676752)
			(xy 297.854637 -317.725329) (xy 297.855132 -317.749936) (xy 299.14394 -317.749936) (xy 299.1479 -317.700882)
			(xy 299.159677 -317.653098) (xy 299.178968 -317.607822) (xy 299.205271 -317.566226) (xy 299.237906 -317.529389)
			(xy 299.276027 -317.498264) (xy 299.318648 -317.473657) (xy 299.364664 -317.456205) (xy 299.412883 -317.446361)
			(xy 299.462058 -317.44438) (xy 299.510913 -317.450312) (xy 299.558184 -317.464004) (xy 299.602646 -317.485102)
			(xy 299.643149 -317.513058) (xy 299.678642 -317.54715) (xy 299.708207 -317.586494) (xy 299.731078 -317.630071)
			(xy 299.746662 -317.676752) (xy 299.754557 -317.725329) (xy 299.755052 -317.749936) (xy 301.044114 -317.749936)
			(xy 301.048074 -317.700882) (xy 301.059851 -317.653098) (xy 301.079142 -317.607822) (xy 301.105445 -317.566226)
			(xy 301.13808 -317.529389) (xy 301.176201 -317.498264) (xy 301.218822 -317.473657) (xy 301.264838 -317.456205)
			(xy 301.313057 -317.446361) (xy 301.362232 -317.44438) (xy 301.411087 -317.450312) (xy 301.458358 -317.464004)
			(xy 301.50282 -317.485102) (xy 301.543323 -317.513058) (xy 301.578816 -317.54715) (xy 301.608381 -317.586494)
			(xy 301.631252 -317.630071) (xy 301.646836 -317.676752) (xy 301.654731 -317.725329) (xy 301.655226 -317.749936)
			(xy 302.944034 -317.749936) (xy 302.947994 -317.700882) (xy 302.959771 -317.653098) (xy 302.979062 -317.607822)
			(xy 303.005365 -317.566226) (xy 303.038 -317.529389) (xy 303.076121 -317.498264) (xy 303.118742 -317.473657)
			(xy 303.164758 -317.456205) (xy 303.212977 -317.446361) (xy 303.262152 -317.44438) (xy 303.311007 -317.450312)
			(xy 303.358278 -317.464004) (xy 303.40274 -317.485102) (xy 303.443243 -317.513058) (xy 303.478736 -317.54715)
			(xy 303.508301 -317.586494) (xy 303.531172 -317.630071) (xy 303.546756 -317.676752) (xy 303.554651 -317.725329)
			(xy 303.555146 -317.749936) (xy 304.843954 -317.749936) (xy 304.847914 -317.700882) (xy 304.859691 -317.653098)
			(xy 304.878982 -317.607822) (xy 304.905285 -317.566226) (xy 304.93792 -317.529389) (xy 304.976041 -317.498264)
			(xy 305.018662 -317.473657) (xy 305.064678 -317.456205) (xy 305.112897 -317.446361) (xy 305.162072 -317.44438)
			(xy 305.210927 -317.450312) (xy 305.258198 -317.464004) (xy 305.30266 -317.485102) (xy 305.343163 -317.513058)
			(xy 305.378656 -317.54715) (xy 305.408221 -317.586494) (xy 305.431092 -317.630071) (xy 305.446676 -317.676752)
			(xy 305.454571 -317.725329) (xy 305.455066 -317.749936) (xy 306.744128 -317.749936) (xy 306.748088 -317.700882)
			(xy 306.759865 -317.653098) (xy 306.779156 -317.607822) (xy 306.805459 -317.566226) (xy 306.838094 -317.529389)
			(xy 306.876215 -317.498264) (xy 306.918836 -317.473657) (xy 306.964852 -317.456205) (xy 307.013071 -317.446361)
			(xy 307.062246 -317.44438) (xy 307.111101 -317.450312) (xy 307.158372 -317.464004) (xy 307.202834 -317.485102)
			(xy 307.243337 -317.513058) (xy 307.27883 -317.54715) (xy 307.308395 -317.586494) (xy 307.331266 -317.630071)
			(xy 307.34685 -317.676752) (xy 307.354745 -317.725329) (xy 307.35524 -317.749936) (xy 308.644048 -317.749936)
			(xy 308.648008 -317.700882) (xy 308.659785 -317.653098) (xy 308.679076 -317.607822) (xy 308.705379 -317.566226)
			(xy 308.738014 -317.529389) (xy 308.776135 -317.498264) (xy 308.818756 -317.473657) (xy 308.864772 -317.456205)
			(xy 308.912991 -317.446361) (xy 308.962166 -317.44438) (xy 309.011021 -317.450312) (xy 309.058292 -317.464004)
			(xy 309.102754 -317.485102) (xy 309.143257 -317.513058) (xy 309.17875 -317.54715) (xy 309.208315 -317.586494)
			(xy 309.231186 -317.630071) (xy 309.24677 -317.676752) (xy 309.254665 -317.725329) (xy 309.25516 -317.749936)
			(xy 310.543968 -317.749936) (xy 310.547928 -317.700882) (xy 310.559705 -317.653098) (xy 310.578996 -317.607822)
			(xy 310.605299 -317.566226) (xy 310.637934 -317.529389) (xy 310.676055 -317.498264) (xy 310.718676 -317.473657)
			(xy 310.764692 -317.456205) (xy 310.812911 -317.446361) (xy 310.862086 -317.44438) (xy 310.910941 -317.450312)
			(xy 310.958212 -317.464004) (xy 311.002674 -317.485102) (xy 311.043177 -317.513058) (xy 311.07867 -317.54715)
			(xy 311.108235 -317.586494) (xy 311.131106 -317.630071) (xy 311.14669 -317.676752) (xy 311.154585 -317.725329)
			(xy 311.15508 -317.749936) (xy 312.443888 -317.749936) (xy 312.447848 -317.700882) (xy 312.459625 -317.653098)
			(xy 312.478916 -317.607822) (xy 312.505219 -317.566226) (xy 312.537854 -317.529389) (xy 312.575975 -317.498264)
			(xy 312.618596 -317.473657) (xy 312.664612 -317.456205) (xy 312.712831 -317.446361) (xy 312.762006 -317.44438)
			(xy 312.810861 -317.450312) (xy 312.858132 -317.464004) (xy 312.902594 -317.485102) (xy 312.943097 -317.513058)
			(xy 312.97859 -317.54715) (xy 313.008155 -317.586494) (xy 313.031026 -317.630071) (xy 313.04661 -317.676752)
			(xy 313.054505 -317.725329) (xy 313.055 -317.749936) (xy 386.744222 -317.749936) (xy 386.748182 -317.700882)
			(xy 386.759959 -317.653098) (xy 386.77925 -317.607822) (xy 386.805553 -317.566226) (xy 386.838188 -317.529389)
			(xy 386.876309 -317.498264) (xy 386.91893 -317.473657) (xy 386.964946 -317.456205) (xy 387.013165 -317.446361)
			(xy 387.06234 -317.44438) (xy 387.111195 -317.450312) (xy 387.158466 -317.464004) (xy 387.202928 -317.485102)
			(xy 387.243431 -317.513058) (xy 387.278924 -317.54715) (xy 387.308489 -317.586494) (xy 387.33136 -317.630071)
			(xy 387.346944 -317.676752) (xy 387.354839 -317.725329) (xy 387.355334 -317.749936) (xy 388.644142 -317.749936)
			(xy 388.648102 -317.700882) (xy 388.659879 -317.653098) (xy 388.67917 -317.607822) (xy 388.705473 -317.566226)
			(xy 388.738108 -317.529389) (xy 388.776229 -317.498264) (xy 388.81885 -317.473657) (xy 388.864866 -317.456205)
			(xy 388.913085 -317.446361) (xy 388.96226 -317.44438) (xy 389.011115 -317.450312) (xy 389.058386 -317.464004)
			(xy 389.102848 -317.485102) (xy 389.143351 -317.513058) (xy 389.178844 -317.54715) (xy 389.208409 -317.586494)
			(xy 389.23128 -317.630071) (xy 389.246864 -317.676752) (xy 389.254759 -317.725329) (xy 389.255254 -317.749936)
			(xy 390.544062 -317.749936) (xy 390.548022 -317.700882) (xy 390.559799 -317.653098) (xy 390.57909 -317.607822)
			(xy 390.605393 -317.566226) (xy 390.638028 -317.529389) (xy 390.676149 -317.498264) (xy 390.71877 -317.473657)
			(xy 390.764786 -317.456205) (xy 390.813005 -317.446361) (xy 390.86218 -317.44438) (xy 390.911035 -317.450312)
			(xy 390.958306 -317.464004) (xy 391.002768 -317.485102) (xy 391.043271 -317.513058) (xy 391.078764 -317.54715)
			(xy 391.108329 -317.586494) (xy 391.1312 -317.630071) (xy 391.146784 -317.676752) (xy 391.154679 -317.725329)
			(xy 391.155174 -317.749936) (xy 392.443982 -317.749936) (xy 392.447942 -317.700882) (xy 392.459719 -317.653098)
			(xy 392.47901 -317.607822) (xy 392.505313 -317.566226) (xy 392.537948 -317.529389) (xy 392.576069 -317.498264)
			(xy 392.61869 -317.473657) (xy 392.664706 -317.456205) (xy 392.712925 -317.446361) (xy 392.7621 -317.44438)
			(xy 392.810955 -317.450312) (xy 392.858226 -317.464004) (xy 392.902688 -317.485102) (xy 392.943191 -317.513058)
			(xy 392.978684 -317.54715) (xy 393.008249 -317.586494) (xy 393.03112 -317.630071) (xy 393.046704 -317.676752)
			(xy 393.054599 -317.725329) (xy 393.055094 -317.749936) (xy 394.344156 -317.749936) (xy 394.348116 -317.700882)
			(xy 394.359893 -317.653098) (xy 394.379184 -317.607822) (xy 394.405487 -317.566226) (xy 394.438122 -317.529389)
			(xy 394.476243 -317.498264) (xy 394.518864 -317.473657) (xy 394.56488 -317.456205) (xy 394.613099 -317.446361)
			(xy 394.662274 -317.44438) (xy 394.711129 -317.450312) (xy 394.7584 -317.464004) (xy 394.802862 -317.485102)
			(xy 394.843365 -317.513058) (xy 394.878858 -317.54715) (xy 394.908423 -317.586494) (xy 394.931294 -317.630071)
			(xy 394.946878 -317.676752) (xy 394.954773 -317.725329) (xy 394.955268 -317.749936) (xy 396.244076 -317.749936)
			(xy 396.248036 -317.700882) (xy 396.259813 -317.653098) (xy 396.279104 -317.607822) (xy 396.305407 -317.566226)
			(xy 396.338042 -317.529389) (xy 396.376163 -317.498264) (xy 396.418784 -317.473657) (xy 396.4648 -317.456205)
			(xy 396.513019 -317.446361) (xy 396.562194 -317.44438) (xy 396.611049 -317.450312) (xy 396.65832 -317.464004)
			(xy 396.702782 -317.485102) (xy 396.743285 -317.513058) (xy 396.778778 -317.54715) (xy 396.808343 -317.586494)
			(xy 396.831214 -317.630071) (xy 396.846798 -317.676752) (xy 396.854693 -317.725329) (xy 396.855188 -317.749936)
			(xy 398.143996 -317.749936) (xy 398.147956 -317.700882) (xy 398.159733 -317.653098) (xy 398.179024 -317.607822)
			(xy 398.205327 -317.566226) (xy 398.237962 -317.529389) (xy 398.276083 -317.498264) (xy 398.318704 -317.473657)
			(xy 398.36472 -317.456205) (xy 398.412939 -317.446361) (xy 398.462114 -317.44438) (xy 398.510969 -317.450312)
			(xy 398.55824 -317.464004) (xy 398.602702 -317.485102) (xy 398.643205 -317.513058) (xy 398.678698 -317.54715)
			(xy 398.708263 -317.586494) (xy 398.731134 -317.630071) (xy 398.746718 -317.676752) (xy 398.754613 -317.725329)
			(xy 398.755108 -317.749936) (xy 400.04417 -317.749936) (xy 400.04813 -317.700882) (xy 400.059907 -317.653098)
			(xy 400.079198 -317.607822) (xy 400.105501 -317.566226) (xy 400.138136 -317.529389) (xy 400.176257 -317.498264)
			(xy 400.218878 -317.473657) (xy 400.264894 -317.456205) (xy 400.313113 -317.446361) (xy 400.362288 -317.44438)
			(xy 400.411143 -317.450312) (xy 400.458414 -317.464004) (xy 400.502876 -317.485102) (xy 400.543379 -317.513058)
			(xy 400.578872 -317.54715) (xy 400.608437 -317.586494) (xy 400.631308 -317.630071) (xy 400.646892 -317.676752)
			(xy 400.654787 -317.725329) (xy 400.655282 -317.749936) (xy 401.94409 -317.749936) (xy 401.94805 -317.700882)
			(xy 401.959827 -317.653098) (xy 401.979118 -317.607822) (xy 402.005421 -317.566226) (xy 402.038056 -317.529389)
			(xy 402.076177 -317.498264) (xy 402.118798 -317.473657) (xy 402.164814 -317.456205) (xy 402.213033 -317.446361)
			(xy 402.262208 -317.44438) (xy 402.311063 -317.450312) (xy 402.358334 -317.464004) (xy 402.402796 -317.485102)
			(xy 402.443299 -317.513058) (xy 402.478792 -317.54715) (xy 402.508357 -317.586494) (xy 402.531228 -317.630071)
			(xy 402.546812 -317.676752) (xy 402.554707 -317.725329) (xy 402.555202 -317.749936) (xy 403.84401 -317.749936)
			(xy 403.84797 -317.700882) (xy 403.859747 -317.653098) (xy 403.879038 -317.607822) (xy 403.905341 -317.566226)
			(xy 403.937976 -317.529389) (xy 403.976097 -317.498264) (xy 404.018718 -317.473657) (xy 404.064734 -317.456205)
			(xy 404.112953 -317.446361) (xy 404.162128 -317.44438) (xy 404.210983 -317.450312) (xy 404.258254 -317.464004)
			(xy 404.302716 -317.485102) (xy 404.343219 -317.513058) (xy 404.378712 -317.54715) (xy 404.408277 -317.586494)
			(xy 404.431148 -317.630071) (xy 404.446732 -317.676752) (xy 404.454627 -317.725329) (xy 404.455122 -317.749936)
			(xy 405.744184 -317.749936) (xy 405.748144 -317.700882) (xy 405.759921 -317.653098) (xy 405.779212 -317.607822)
			(xy 405.805515 -317.566226) (xy 405.83815 -317.529389) (xy 405.876271 -317.498264) (xy 405.918892 -317.473657)
			(xy 405.964908 -317.456205) (xy 406.013127 -317.446361) (xy 406.062302 -317.44438) (xy 406.111157 -317.450312)
			(xy 406.158428 -317.464004) (xy 406.20289 -317.485102) (xy 406.243393 -317.513058) (xy 406.278886 -317.54715)
			(xy 406.308451 -317.586494) (xy 406.331322 -317.630071) (xy 406.346906 -317.676752) (xy 406.354801 -317.725329)
			(xy 406.355296 -317.749936) (xy 407.644104 -317.749936) (xy 407.648064 -317.700882) (xy 407.659841 -317.653098)
			(xy 407.679132 -317.607822) (xy 407.705435 -317.566226) (xy 407.73807 -317.529389) (xy 407.776191 -317.498264)
			(xy 407.818812 -317.473657) (xy 407.864828 -317.456205) (xy 407.913047 -317.446361) (xy 407.962222 -317.44438)
			(xy 408.011077 -317.450312) (xy 408.058348 -317.464004) (xy 408.10281 -317.485102) (xy 408.143313 -317.513058)
			(xy 408.178806 -317.54715) (xy 408.208371 -317.586494) (xy 408.231242 -317.630071) (xy 408.246826 -317.676752)
			(xy 408.254721 -317.725329) (xy 408.255216 -317.749936) (xy 409.544024 -317.749936) (xy 409.547984 -317.700882)
			(xy 409.559761 -317.653098) (xy 409.579052 -317.607822) (xy 409.605355 -317.566226) (xy 409.63799 -317.529389)
			(xy 409.676111 -317.498264) (xy 409.718732 -317.473657) (xy 409.764748 -317.456205) (xy 409.812967 -317.446361)
			(xy 409.862142 -317.44438) (xy 409.910997 -317.450312) (xy 409.958268 -317.464004) (xy 410.00273 -317.485102)
			(xy 410.043233 -317.513058) (xy 410.078726 -317.54715) (xy 410.108291 -317.586494) (xy 410.131162 -317.630071)
			(xy 410.146746 -317.676752) (xy 410.154641 -317.725329) (xy 410.155136 -317.749936) (xy 411.444198 -317.749936)
			(xy 411.448158 -317.700882) (xy 411.459935 -317.653098) (xy 411.479226 -317.607822) (xy 411.505529 -317.566226)
			(xy 411.538164 -317.529389) (xy 411.576285 -317.498264) (xy 411.618906 -317.473657) (xy 411.664922 -317.456205)
			(xy 411.713141 -317.446361) (xy 411.762316 -317.44438) (xy 411.811171 -317.450312) (xy 411.858442 -317.464004)
			(xy 411.902904 -317.485102) (xy 411.943407 -317.513058) (xy 411.9789 -317.54715) (xy 412.008465 -317.586494)
			(xy 412.031336 -317.630071) (xy 412.04692 -317.676752) (xy 412.054815 -317.725329) (xy 412.05531 -317.749936)
			(xy 413.344118 -317.749936) (xy 413.348078 -317.700882) (xy 413.359855 -317.653098) (xy 413.379146 -317.607822)
			(xy 413.405449 -317.566226) (xy 413.438084 -317.529389) (xy 413.476205 -317.498264) (xy 413.518826 -317.473657)
			(xy 413.564842 -317.456205) (xy 413.613061 -317.446361) (xy 413.662236 -317.44438) (xy 413.711091 -317.450312)
			(xy 413.758362 -317.464004) (xy 413.802824 -317.485102) (xy 413.843327 -317.513058) (xy 413.87882 -317.54715)
			(xy 413.908385 -317.586494) (xy 413.931256 -317.630071) (xy 413.94684 -317.676752) (xy 413.954735 -317.725329)
			(xy 413.95523 -317.749936) (xy 415.244038 -317.749936) (xy 415.247998 -317.700882) (xy 415.259775 -317.653098)
			(xy 415.279066 -317.607822) (xy 415.305369 -317.566226) (xy 415.338004 -317.529389) (xy 415.376125 -317.498264)
			(xy 415.418746 -317.473657) (xy 415.464762 -317.456205) (xy 415.512981 -317.446361) (xy 415.562156 -317.44438)
			(xy 415.611011 -317.450312) (xy 415.658282 -317.464004) (xy 415.702744 -317.485102) (xy 415.743247 -317.513058)
			(xy 415.77874 -317.54715) (xy 415.808305 -317.586494) (xy 415.831176 -317.630071) (xy 415.84676 -317.676752)
			(xy 415.854655 -317.725329) (xy 415.85515 -317.749936) (xy 417.144212 -317.749936) (xy 417.148172 -317.700882)
			(xy 417.159949 -317.653098) (xy 417.17924 -317.607822) (xy 417.205543 -317.566226) (xy 417.238178 -317.529389)
			(xy 417.276299 -317.498264) (xy 417.31892 -317.473657) (xy 417.364936 -317.456205) (xy 417.413155 -317.446361)
			(xy 417.46233 -317.44438) (xy 417.511185 -317.450312) (xy 417.558456 -317.464004) (xy 417.602918 -317.485102)
			(xy 417.643421 -317.513058) (xy 417.678914 -317.54715) (xy 417.708479 -317.586494) (xy 417.73135 -317.630071)
			(xy 417.746934 -317.676752) (xy 417.754829 -317.725329) (xy 417.755324 -317.749936) (xy 419.044132 -317.749936)
			(xy 419.048092 -317.700882) (xy 419.059869 -317.653098) (xy 419.07916 -317.607822) (xy 419.105463 -317.566226)
			(xy 419.138098 -317.529389) (xy 419.176219 -317.498264) (xy 419.21884 -317.473657) (xy 419.264856 -317.456205)
			(xy 419.313075 -317.446361) (xy 419.36225 -317.44438) (xy 419.411105 -317.450312) (xy 419.458376 -317.464004)
			(xy 419.502838 -317.485102) (xy 419.543341 -317.513058) (xy 419.578834 -317.54715) (xy 419.608399 -317.586494)
			(xy 419.63127 -317.630071) (xy 419.646854 -317.676752) (xy 419.654749 -317.725329) (xy 419.655244 -317.749936)
			(xy 420.944052 -317.749936) (xy 420.948012 -317.700882) (xy 420.959789 -317.653098) (xy 420.97908 -317.607822)
			(xy 421.005383 -317.566226) (xy 421.038018 -317.529389) (xy 421.076139 -317.498264) (xy 421.11876 -317.473657)
			(xy 421.164776 -317.456205) (xy 421.212995 -317.446361) (xy 421.26217 -317.44438) (xy 421.311025 -317.450312)
			(xy 421.358296 -317.464004) (xy 421.402758 -317.485102) (xy 421.443261 -317.513058) (xy 421.478754 -317.54715)
			(xy 421.508319 -317.586494) (xy 421.53119 -317.630071) (xy 421.546774 -317.676752) (xy 421.554669 -317.725329)
			(xy 421.555164 -317.749936) (xy 422.844226 -317.749936) (xy 422.848186 -317.700882) (xy 422.859963 -317.653098)
			(xy 422.879254 -317.607822) (xy 422.905557 -317.566226) (xy 422.938192 -317.529389) (xy 422.976313 -317.498264)
			(xy 423.018934 -317.473657) (xy 423.06495 -317.456205) (xy 423.113169 -317.446361) (xy 423.162344 -317.44438)
			(xy 423.211199 -317.450312) (xy 423.25847 -317.464004) (xy 423.302932 -317.485102) (xy 423.343435 -317.513058)
			(xy 423.378928 -317.54715) (xy 423.408493 -317.586494) (xy 423.431364 -317.630071) (xy 423.446948 -317.676752)
			(xy 423.454843 -317.725329) (xy 423.455338 -317.749936) (xy 424.744146 -317.749936) (xy 424.748106 -317.700882)
			(xy 424.759883 -317.653098) (xy 424.779174 -317.607822) (xy 424.805477 -317.566226) (xy 424.838112 -317.529389)
			(xy 424.876233 -317.498264) (xy 424.918854 -317.473657) (xy 424.96487 -317.456205) (xy 425.013089 -317.446361)
			(xy 425.062264 -317.44438) (xy 425.111119 -317.450312) (xy 425.15839 -317.464004) (xy 425.202852 -317.485102)
			(xy 425.243355 -317.513058) (xy 425.278848 -317.54715) (xy 425.308413 -317.586494) (xy 425.331284 -317.630071)
			(xy 425.346868 -317.676752) (xy 425.354763 -317.725329) (xy 425.355258 -317.749936) (xy 426.644066 -317.749936)
			(xy 426.648026 -317.700882) (xy 426.659803 -317.653098) (xy 426.679094 -317.607822) (xy 426.705397 -317.566226)
			(xy 426.738032 -317.529389) (xy 426.776153 -317.498264) (xy 426.818774 -317.473657) (xy 426.86479 -317.456205)
			(xy 426.913009 -317.446361) (xy 426.962184 -317.44438) (xy 427.011039 -317.450312) (xy 427.05831 -317.464004)
			(xy 427.102772 -317.485102) (xy 427.143275 -317.513058) (xy 427.178768 -317.54715) (xy 427.208333 -317.586494)
			(xy 427.231204 -317.630071) (xy 427.246788 -317.676752) (xy 427.254683 -317.725329) (xy 427.255178 -317.749936)
			(xy 428.543986 -317.749936) (xy 428.547946 -317.700882) (xy 428.559723 -317.653098) (xy 428.579014 -317.607822)
			(xy 428.605317 -317.566226) (xy 428.637952 -317.529389) (xy 428.676073 -317.498264) (xy 428.718694 -317.473657)
			(xy 428.76471 -317.456205) (xy 428.812929 -317.446361) (xy 428.862104 -317.44438) (xy 428.910959 -317.450312)
			(xy 428.95823 -317.464004) (xy 429.002692 -317.485102) (xy 429.043195 -317.513058) (xy 429.078688 -317.54715)
			(xy 429.108253 -317.586494) (xy 429.131124 -317.630071) (xy 429.146708 -317.676752) (xy 429.154603 -317.725329)
			(xy 429.155098 -317.749936) (xy 429.154603 -317.774543) (xy 429.146708 -317.82312) (xy 429.131124 -317.869801)
			(xy 429.108253 -317.913378) (xy 429.078688 -317.952722) (xy 429.043195 -317.986814) (xy 429.002692 -318.01477)
			(xy 428.95823 -318.035868) (xy 428.910959 -318.04956) (xy 428.862104 -318.055492) (xy 428.812929 -318.053511)
			(xy 428.76471 -318.043667) (xy 428.718694 -318.026215) (xy 428.676073 -318.001608) (xy 428.637952 -317.970483)
			(xy 428.605317 -317.933646) (xy 428.579014 -317.89205) (xy 428.559723 -317.846774) (xy 428.547946 -317.79899)
			(xy 428.543986 -317.749936) (xy 427.255178 -317.749936) (xy 427.254683 -317.774543) (xy 427.246788 -317.82312)
			(xy 427.231204 -317.869801) (xy 427.208333 -317.913378) (xy 427.178768 -317.952722) (xy 427.143275 -317.986814)
			(xy 427.102772 -318.01477) (xy 427.05831 -318.035868) (xy 427.011039 -318.04956) (xy 426.962184 -318.055492)
			(xy 426.913009 -318.053511) (xy 426.86479 -318.043667) (xy 426.818774 -318.026215) (xy 426.776153 -318.001608)
			(xy 426.738032 -317.970483) (xy 426.705397 -317.933646) (xy 426.679094 -317.89205) (xy 426.659803 -317.846774)
			(xy 426.648026 -317.79899) (xy 426.644066 -317.749936) (xy 425.355258 -317.749936) (xy 425.354763 -317.774543)
			(xy 425.346868 -317.82312) (xy 425.331284 -317.869801) (xy 425.308413 -317.913378) (xy 425.278848 -317.952722)
			(xy 425.243355 -317.986814) (xy 425.202852 -318.01477) (xy 425.15839 -318.035868) (xy 425.111119 -318.04956)
			(xy 425.062264 -318.055492) (xy 425.013089 -318.053511) (xy 424.96487 -318.043667) (xy 424.918854 -318.026215)
			(xy 424.876233 -318.001608) (xy 424.838112 -317.970483) (xy 424.805477 -317.933646) (xy 424.779174 -317.89205)
			(xy 424.759883 -317.846774) (xy 424.748106 -317.79899) (xy 424.744146 -317.749936) (xy 423.455338 -317.749936)
			(xy 423.454843 -317.774543) (xy 423.446948 -317.82312) (xy 423.431364 -317.869801) (xy 423.408493 -317.913378)
			(xy 423.378928 -317.952722) (xy 423.343435 -317.986814) (xy 423.302932 -318.01477) (xy 423.25847 -318.035868)
			(xy 423.211199 -318.04956) (xy 423.162344 -318.055492) (xy 423.113169 -318.053511) (xy 423.06495 -318.043667)
			(xy 423.018934 -318.026215) (xy 422.976313 -318.001608) (xy 422.938192 -317.970483) (xy 422.905557 -317.933646)
			(xy 422.879254 -317.89205) (xy 422.859963 -317.846774) (xy 422.848186 -317.79899) (xy 422.844226 -317.749936)
			(xy 421.555164 -317.749936) (xy 421.554669 -317.774543) (xy 421.546774 -317.82312) (xy 421.53119 -317.869801)
			(xy 421.508319 -317.913378) (xy 421.478754 -317.952722) (xy 421.443261 -317.986814) (xy 421.402758 -318.01477)
			(xy 421.358296 -318.035868) (xy 421.311025 -318.04956) (xy 421.26217 -318.055492) (xy 421.212995 -318.053511)
			(xy 421.164776 -318.043667) (xy 421.11876 -318.026215) (xy 421.076139 -318.001608) (xy 421.038018 -317.970483)
			(xy 421.005383 -317.933646) (xy 420.97908 -317.89205) (xy 420.959789 -317.846774) (xy 420.948012 -317.79899)
			(xy 420.944052 -317.749936) (xy 419.655244 -317.749936) (xy 419.654749 -317.774543) (xy 419.646854 -317.82312)
			(xy 419.63127 -317.869801) (xy 419.608399 -317.913378) (xy 419.578834 -317.952722) (xy 419.543341 -317.986814)
			(xy 419.502838 -318.01477) (xy 419.458376 -318.035868) (xy 419.411105 -318.04956) (xy 419.36225 -318.055492)
			(xy 419.313075 -318.053511) (xy 419.264856 -318.043667) (xy 419.21884 -318.026215) (xy 419.176219 -318.001608)
			(xy 419.138098 -317.970483) (xy 419.105463 -317.933646) (xy 419.07916 -317.89205) (xy 419.059869 -317.846774)
			(xy 419.048092 -317.79899) (xy 419.044132 -317.749936) (xy 417.755324 -317.749936) (xy 417.754829 -317.774543)
			(xy 417.746934 -317.82312) (xy 417.73135 -317.869801) (xy 417.708479 -317.913378) (xy 417.678914 -317.952722)
			(xy 417.643421 -317.986814) (xy 417.602918 -318.01477) (xy 417.558456 -318.035868) (xy 417.511185 -318.04956)
			(xy 417.46233 -318.055492) (xy 417.413155 -318.053511) (xy 417.364936 -318.043667) (xy 417.31892 -318.026215)
			(xy 417.276299 -318.001608) (xy 417.238178 -317.970483) (xy 417.205543 -317.933646) (xy 417.17924 -317.89205)
			(xy 417.159949 -317.846774) (xy 417.148172 -317.79899) (xy 417.144212 -317.749936) (xy 415.85515 -317.749936)
			(xy 415.854655 -317.774543) (xy 415.84676 -317.82312) (xy 415.831176 -317.869801) (xy 415.808305 -317.913378)
			(xy 415.77874 -317.952722) (xy 415.743247 -317.986814) (xy 415.702744 -318.01477) (xy 415.658282 -318.035868)
			(xy 415.611011 -318.04956) (xy 415.562156 -318.055492) (xy 415.512981 -318.053511) (xy 415.464762 -318.043667)
			(xy 415.418746 -318.026215) (xy 415.376125 -318.001608) (xy 415.338004 -317.970483) (xy 415.305369 -317.933646)
			(xy 415.279066 -317.89205) (xy 415.259775 -317.846774) (xy 415.247998 -317.79899) (xy 415.244038 -317.749936)
			(xy 413.95523 -317.749936) (xy 413.954735 -317.774543) (xy 413.94684 -317.82312) (xy 413.931256 -317.869801)
			(xy 413.908385 -317.913378) (xy 413.87882 -317.952722) (xy 413.843327 -317.986814) (xy 413.802824 -318.01477)
			(xy 413.758362 -318.035868) (xy 413.711091 -318.04956) (xy 413.662236 -318.055492) (xy 413.613061 -318.053511)
			(xy 413.564842 -318.043667) (xy 413.518826 -318.026215) (xy 413.476205 -318.001608) (xy 413.438084 -317.970483)
			(xy 413.405449 -317.933646) (xy 413.379146 -317.89205) (xy 413.359855 -317.846774) (xy 413.348078 -317.79899)
			(xy 413.344118 -317.749936) (xy 412.05531 -317.749936) (xy 412.054815 -317.774543) (xy 412.04692 -317.82312)
			(xy 412.031336 -317.869801) (xy 412.008465 -317.913378) (xy 411.9789 -317.952722) (xy 411.943407 -317.986814)
			(xy 411.902904 -318.01477) (xy 411.858442 -318.035868) (xy 411.811171 -318.04956) (xy 411.762316 -318.055492)
			(xy 411.713141 -318.053511) (xy 411.664922 -318.043667) (xy 411.618906 -318.026215) (xy 411.576285 -318.001608)
			(xy 411.538164 -317.970483) (xy 411.505529 -317.933646) (xy 411.479226 -317.89205) (xy 411.459935 -317.846774)
			(xy 411.448158 -317.79899) (xy 411.444198 -317.749936) (xy 410.155136 -317.749936) (xy 410.154641 -317.774543)
			(xy 410.146746 -317.82312) (xy 410.131162 -317.869801) (xy 410.108291 -317.913378) (xy 410.078726 -317.952722)
			(xy 410.043233 -317.986814) (xy 410.00273 -318.01477) (xy 409.958268 -318.035868) (xy 409.910997 -318.04956)
			(xy 409.862142 -318.055492) (xy 409.812967 -318.053511) (xy 409.764748 -318.043667) (xy 409.718732 -318.026215)
			(xy 409.676111 -318.001608) (xy 409.63799 -317.970483) (xy 409.605355 -317.933646) (xy 409.579052 -317.89205)
			(xy 409.559761 -317.846774) (xy 409.547984 -317.79899) (xy 409.544024 -317.749936) (xy 408.255216 -317.749936)
			(xy 408.254721 -317.774543) (xy 408.246826 -317.82312) (xy 408.231242 -317.869801) (xy 408.208371 -317.913378)
			(xy 408.178806 -317.952722) (xy 408.143313 -317.986814) (xy 408.10281 -318.01477) (xy 408.058348 -318.035868)
			(xy 408.011077 -318.04956) (xy 407.962222 -318.055492) (xy 407.913047 -318.053511) (xy 407.864828 -318.043667)
			(xy 407.818812 -318.026215) (xy 407.776191 -318.001608) (xy 407.73807 -317.970483) (xy 407.705435 -317.933646)
			(xy 407.679132 -317.89205) (xy 407.659841 -317.846774) (xy 407.648064 -317.79899) (xy 407.644104 -317.749936)
			(xy 406.355296 -317.749936) (xy 406.354801 -317.774543) (xy 406.346906 -317.82312) (xy 406.331322 -317.869801)
			(xy 406.308451 -317.913378) (xy 406.278886 -317.952722) (xy 406.243393 -317.986814) (xy 406.20289 -318.01477)
			(xy 406.158428 -318.035868) (xy 406.111157 -318.04956) (xy 406.062302 -318.055492) (xy 406.013127 -318.053511)
			(xy 405.964908 -318.043667) (xy 405.918892 -318.026215) (xy 405.876271 -318.001608) (xy 405.83815 -317.970483)
			(xy 405.805515 -317.933646) (xy 405.779212 -317.89205) (xy 405.759921 -317.846774) (xy 405.748144 -317.79899)
			(xy 405.744184 -317.749936) (xy 404.455122 -317.749936) (xy 404.454627 -317.774543) (xy 404.446732 -317.82312)
			(xy 404.431148 -317.869801) (xy 404.408277 -317.913378) (xy 404.378712 -317.952722) (xy 404.343219 -317.986814)
			(xy 404.302716 -318.01477) (xy 404.258254 -318.035868) (xy 404.210983 -318.04956) (xy 404.162128 -318.055492)
			(xy 404.112953 -318.053511) (xy 404.064734 -318.043667) (xy 404.018718 -318.026215) (xy 403.976097 -318.001608)
			(xy 403.937976 -317.970483) (xy 403.905341 -317.933646) (xy 403.879038 -317.89205) (xy 403.859747 -317.846774)
			(xy 403.84797 -317.79899) (xy 403.84401 -317.749936) (xy 402.555202 -317.749936) (xy 402.554707 -317.774543)
			(xy 402.546812 -317.82312) (xy 402.531228 -317.869801) (xy 402.508357 -317.913378) (xy 402.478792 -317.952722)
			(xy 402.443299 -317.986814) (xy 402.402796 -318.01477) (xy 402.358334 -318.035868) (xy 402.311063 -318.04956)
			(xy 402.262208 -318.055492) (xy 402.213033 -318.053511) (xy 402.164814 -318.043667) (xy 402.118798 -318.026215)
			(xy 402.076177 -318.001608) (xy 402.038056 -317.970483) (xy 402.005421 -317.933646) (xy 401.979118 -317.89205)
			(xy 401.959827 -317.846774) (xy 401.94805 -317.79899) (xy 401.94409 -317.749936) (xy 400.655282 -317.749936)
			(xy 400.654787 -317.774543) (xy 400.646892 -317.82312) (xy 400.631308 -317.869801) (xy 400.608437 -317.913378)
			(xy 400.578872 -317.952722) (xy 400.543379 -317.986814) (xy 400.502876 -318.01477) (xy 400.458414 -318.035868)
			(xy 400.411143 -318.04956) (xy 400.362288 -318.055492) (xy 400.313113 -318.053511) (xy 400.264894 -318.043667)
			(xy 400.218878 -318.026215) (xy 400.176257 -318.001608) (xy 400.138136 -317.970483) (xy 400.105501 -317.933646)
			(xy 400.079198 -317.89205) (xy 400.059907 -317.846774) (xy 400.04813 -317.79899) (xy 400.04417 -317.749936)
			(xy 398.755108 -317.749936) (xy 398.754613 -317.774543) (xy 398.746718 -317.82312) (xy 398.731134 -317.869801)
			(xy 398.708263 -317.913378) (xy 398.678698 -317.952722) (xy 398.643205 -317.986814) (xy 398.602702 -318.01477)
			(xy 398.55824 -318.035868) (xy 398.510969 -318.04956) (xy 398.462114 -318.055492) (xy 398.412939 -318.053511)
			(xy 398.36472 -318.043667) (xy 398.318704 -318.026215) (xy 398.276083 -318.001608) (xy 398.237962 -317.970483)
			(xy 398.205327 -317.933646) (xy 398.179024 -317.89205) (xy 398.159733 -317.846774) (xy 398.147956 -317.79899)
			(xy 398.143996 -317.749936) (xy 396.855188 -317.749936) (xy 396.854693 -317.774543) (xy 396.846798 -317.82312)
			(xy 396.831214 -317.869801) (xy 396.808343 -317.913378) (xy 396.778778 -317.952722) (xy 396.743285 -317.986814)
			(xy 396.702782 -318.01477) (xy 396.65832 -318.035868) (xy 396.611049 -318.04956) (xy 396.562194 -318.055492)
			(xy 396.513019 -318.053511) (xy 396.4648 -318.043667) (xy 396.418784 -318.026215) (xy 396.376163 -318.001608)
			(xy 396.338042 -317.970483) (xy 396.305407 -317.933646) (xy 396.279104 -317.89205) (xy 396.259813 -317.846774)
			(xy 396.248036 -317.79899) (xy 396.244076 -317.749936) (xy 394.955268 -317.749936) (xy 394.954773 -317.774543)
			(xy 394.946878 -317.82312) (xy 394.931294 -317.869801) (xy 394.908423 -317.913378) (xy 394.878858 -317.952722)
			(xy 394.843365 -317.986814) (xy 394.802862 -318.01477) (xy 394.7584 -318.035868) (xy 394.711129 -318.04956)
			(xy 394.662274 -318.055492) (xy 394.613099 -318.053511) (xy 394.56488 -318.043667) (xy 394.518864 -318.026215)
			(xy 394.476243 -318.001608) (xy 394.438122 -317.970483) (xy 394.405487 -317.933646) (xy 394.379184 -317.89205)
			(xy 394.359893 -317.846774) (xy 394.348116 -317.79899) (xy 394.344156 -317.749936) (xy 393.055094 -317.749936)
			(xy 393.054599 -317.774543) (xy 393.046704 -317.82312) (xy 393.03112 -317.869801) (xy 393.008249 -317.913378)
			(xy 392.978684 -317.952722) (xy 392.943191 -317.986814) (xy 392.902688 -318.01477) (xy 392.858226 -318.035868)
			(xy 392.810955 -318.04956) (xy 392.7621 -318.055492) (xy 392.712925 -318.053511) (xy 392.664706 -318.043667)
			(xy 392.61869 -318.026215) (xy 392.576069 -318.001608) (xy 392.537948 -317.970483) (xy 392.505313 -317.933646)
			(xy 392.47901 -317.89205) (xy 392.459719 -317.846774) (xy 392.447942 -317.79899) (xy 392.443982 -317.749936)
			(xy 391.155174 -317.749936) (xy 391.154679 -317.774543) (xy 391.146784 -317.82312) (xy 391.1312 -317.869801)
			(xy 391.108329 -317.913378) (xy 391.078764 -317.952722) (xy 391.043271 -317.986814) (xy 391.002768 -318.01477)
			(xy 390.958306 -318.035868) (xy 390.911035 -318.04956) (xy 390.86218 -318.055492) (xy 390.813005 -318.053511)
			(xy 390.764786 -318.043667) (xy 390.71877 -318.026215) (xy 390.676149 -318.001608) (xy 390.638028 -317.970483)
			(xy 390.605393 -317.933646) (xy 390.57909 -317.89205) (xy 390.559799 -317.846774) (xy 390.548022 -317.79899)
			(xy 390.544062 -317.749936) (xy 389.255254 -317.749936) (xy 389.254759 -317.774543) (xy 389.246864 -317.82312)
			(xy 389.23128 -317.869801) (xy 389.208409 -317.913378) (xy 389.178844 -317.952722) (xy 389.143351 -317.986814)
			(xy 389.102848 -318.01477) (xy 389.058386 -318.035868) (xy 389.011115 -318.04956) (xy 388.96226 -318.055492)
			(xy 388.913085 -318.053511) (xy 388.864866 -318.043667) (xy 388.81885 -318.026215) (xy 388.776229 -318.001608)
			(xy 388.738108 -317.970483) (xy 388.705473 -317.933646) (xy 388.67917 -317.89205) (xy 388.659879 -317.846774)
			(xy 388.648102 -317.79899) (xy 388.644142 -317.749936) (xy 387.355334 -317.749936) (xy 387.354839 -317.774543)
			(xy 387.346944 -317.82312) (xy 387.33136 -317.869801) (xy 387.308489 -317.913378) (xy 387.278924 -317.952722)
			(xy 387.243431 -317.986814) (xy 387.202928 -318.01477) (xy 387.158466 -318.035868) (xy 387.111195 -318.04956)
			(xy 387.06234 -318.055492) (xy 387.013165 -318.053511) (xy 386.964946 -318.043667) (xy 386.91893 -318.026215)
			(xy 386.876309 -318.001608) (xy 386.838188 -317.970483) (xy 386.805553 -317.933646) (xy 386.77925 -317.89205)
			(xy 386.759959 -317.846774) (xy 386.748182 -317.79899) (xy 386.744222 -317.749936) (xy 313.055 -317.749936)
			(xy 313.054505 -317.774543) (xy 313.04661 -317.82312) (xy 313.031026 -317.869801) (xy 313.008155 -317.913378)
			(xy 312.97859 -317.952722) (xy 312.943097 -317.986814) (xy 312.902594 -318.01477) (xy 312.858132 -318.035868)
			(xy 312.810861 -318.04956) (xy 312.762006 -318.055492) (xy 312.712831 -318.053511) (xy 312.664612 -318.043667)
			(xy 312.618596 -318.026215) (xy 312.575975 -318.001608) (xy 312.537854 -317.970483) (xy 312.505219 -317.933646)
			(xy 312.478916 -317.89205) (xy 312.459625 -317.846774) (xy 312.447848 -317.79899) (xy 312.443888 -317.749936)
			(xy 311.15508 -317.749936) (xy 311.154585 -317.774543) (xy 311.14669 -317.82312) (xy 311.131106 -317.869801)
			(xy 311.108235 -317.913378) (xy 311.07867 -317.952722) (xy 311.043177 -317.986814) (xy 311.002674 -318.01477)
			(xy 310.958212 -318.035868) (xy 310.910941 -318.04956) (xy 310.862086 -318.055492) (xy 310.812911 -318.053511)
			(xy 310.764692 -318.043667) (xy 310.718676 -318.026215) (xy 310.676055 -318.001608) (xy 310.637934 -317.970483)
			(xy 310.605299 -317.933646) (xy 310.578996 -317.89205) (xy 310.559705 -317.846774) (xy 310.547928 -317.79899)
			(xy 310.543968 -317.749936) (xy 309.25516 -317.749936) (xy 309.254665 -317.774543) (xy 309.24677 -317.82312)
			(xy 309.231186 -317.869801) (xy 309.208315 -317.913378) (xy 309.17875 -317.952722) (xy 309.143257 -317.986814)
			(xy 309.102754 -318.01477) (xy 309.058292 -318.035868) (xy 309.011021 -318.04956) (xy 308.962166 -318.055492)
			(xy 308.912991 -318.053511) (xy 308.864772 -318.043667) (xy 308.818756 -318.026215) (xy 308.776135 -318.001608)
			(xy 308.738014 -317.970483) (xy 308.705379 -317.933646) (xy 308.679076 -317.89205) (xy 308.659785 -317.846774)
			(xy 308.648008 -317.79899) (xy 308.644048 -317.749936) (xy 307.35524 -317.749936) (xy 307.354745 -317.774543)
			(xy 307.34685 -317.82312) (xy 307.331266 -317.869801) (xy 307.308395 -317.913378) (xy 307.27883 -317.952722)
			(xy 307.243337 -317.986814) (xy 307.202834 -318.01477) (xy 307.158372 -318.035868) (xy 307.111101 -318.04956)
			(xy 307.062246 -318.055492) (xy 307.013071 -318.053511) (xy 306.964852 -318.043667) (xy 306.918836 -318.026215)
			(xy 306.876215 -318.001608) (xy 306.838094 -317.970483) (xy 306.805459 -317.933646) (xy 306.779156 -317.89205)
			(xy 306.759865 -317.846774) (xy 306.748088 -317.79899) (xy 306.744128 -317.749936) (xy 305.455066 -317.749936)
			(xy 305.454571 -317.774543) (xy 305.446676 -317.82312) (xy 305.431092 -317.869801) (xy 305.408221 -317.913378)
			(xy 305.378656 -317.952722) (xy 305.343163 -317.986814) (xy 305.30266 -318.01477) (xy 305.258198 -318.035868)
			(xy 305.210927 -318.04956) (xy 305.162072 -318.055492) (xy 305.112897 -318.053511) (xy 305.064678 -318.043667)
			(xy 305.018662 -318.026215) (xy 304.976041 -318.001608) (xy 304.93792 -317.970483) (xy 304.905285 -317.933646)
			(xy 304.878982 -317.89205) (xy 304.859691 -317.846774) (xy 304.847914 -317.79899) (xy 304.843954 -317.749936)
			(xy 303.555146 -317.749936) (xy 303.554651 -317.774543) (xy 303.546756 -317.82312) (xy 303.531172 -317.869801)
			(xy 303.508301 -317.913378) (xy 303.478736 -317.952722) (xy 303.443243 -317.986814) (xy 303.40274 -318.01477)
			(xy 303.358278 -318.035868) (xy 303.311007 -318.04956) (xy 303.262152 -318.055492) (xy 303.212977 -318.053511)
			(xy 303.164758 -318.043667) (xy 303.118742 -318.026215) (xy 303.076121 -318.001608) (xy 303.038 -317.970483)
			(xy 303.005365 -317.933646) (xy 302.979062 -317.89205) (xy 302.959771 -317.846774) (xy 302.947994 -317.79899)
			(xy 302.944034 -317.749936) (xy 301.655226 -317.749936) (xy 301.654731 -317.774543) (xy 301.646836 -317.82312)
			(xy 301.631252 -317.869801) (xy 301.608381 -317.913378) (xy 301.578816 -317.952722) (xy 301.543323 -317.986814)
			(xy 301.50282 -318.01477) (xy 301.458358 -318.035868) (xy 301.411087 -318.04956) (xy 301.362232 -318.055492)
			(xy 301.313057 -318.053511) (xy 301.264838 -318.043667) (xy 301.218822 -318.026215) (xy 301.176201 -318.001608)
			(xy 301.13808 -317.970483) (xy 301.105445 -317.933646) (xy 301.079142 -317.89205) (xy 301.059851 -317.846774)
			(xy 301.048074 -317.79899) (xy 301.044114 -317.749936) (xy 299.755052 -317.749936) (xy 299.754557 -317.774543)
			(xy 299.746662 -317.82312) (xy 299.731078 -317.869801) (xy 299.708207 -317.913378) (xy 299.678642 -317.952722)
			(xy 299.643149 -317.986814) (xy 299.602646 -318.01477) (xy 299.558184 -318.035868) (xy 299.510913 -318.04956)
			(xy 299.462058 -318.055492) (xy 299.412883 -318.053511) (xy 299.364664 -318.043667) (xy 299.318648 -318.026215)
			(xy 299.276027 -318.001608) (xy 299.237906 -317.970483) (xy 299.205271 -317.933646) (xy 299.178968 -317.89205)
			(xy 299.159677 -317.846774) (xy 299.1479 -317.79899) (xy 299.14394 -317.749936) (xy 297.855132 -317.749936)
			(xy 297.854637 -317.774543) (xy 297.846742 -317.82312) (xy 297.831158 -317.869801) (xy 297.808287 -317.913378)
			(xy 297.778722 -317.952722) (xy 297.743229 -317.986814) (xy 297.702726 -318.01477) (xy 297.658264 -318.035868)
			(xy 297.610993 -318.04956) (xy 297.562138 -318.055492) (xy 297.512963 -318.053511) (xy 297.464744 -318.043667)
			(xy 297.418728 -318.026215) (xy 297.376107 -318.001608) (xy 297.337986 -317.970483) (xy 297.305351 -317.933646)
			(xy 297.279048 -317.89205) (xy 297.259757 -317.846774) (xy 297.24798 -317.79899) (xy 297.24402 -317.749936)
			(xy 295.955212 -317.749936) (xy 295.954717 -317.774543) (xy 295.946822 -317.82312) (xy 295.931238 -317.869801)
			(xy 295.908367 -317.913378) (xy 295.878802 -317.952722) (xy 295.843309 -317.986814) (xy 295.802806 -318.01477)
			(xy 295.758344 -318.035868) (xy 295.711073 -318.04956) (xy 295.662218 -318.055492) (xy 295.613043 -318.053511)
			(xy 295.564824 -318.043667) (xy 295.518808 -318.026215) (xy 295.476187 -318.001608) (xy 295.438066 -317.970483)
			(xy 295.405431 -317.933646) (xy 295.379128 -317.89205) (xy 295.359837 -317.846774) (xy 295.34806 -317.79899)
			(xy 295.3441 -317.749936) (xy 294.055038 -317.749936) (xy 294.054543 -317.774543) (xy 294.046648 -317.82312)
			(xy 294.031064 -317.869801) (xy 294.008193 -317.913378) (xy 293.978628 -317.952722) (xy 293.943135 -317.986814)
			(xy 293.902632 -318.01477) (xy 293.85817 -318.035868) (xy 293.810899 -318.04956) (xy 293.762044 -318.055492)
			(xy 293.712869 -318.053511) (xy 293.66465 -318.043667) (xy 293.618634 -318.026215) (xy 293.576013 -318.001608)
			(xy 293.537892 -317.970483) (xy 293.505257 -317.933646) (xy 293.478954 -317.89205) (xy 293.459663 -317.846774)
			(xy 293.447886 -317.79899) (xy 293.443926 -317.749936) (xy 292.155118 -317.749936) (xy 292.154623 -317.774543)
			(xy 292.146728 -317.82312) (xy 292.131144 -317.869801) (xy 292.108273 -317.913378) (xy 292.078708 -317.952722)
			(xy 292.043215 -317.986814) (xy 292.002712 -318.01477) (xy 291.95825 -318.035868) (xy 291.910979 -318.04956)
			(xy 291.862124 -318.055492) (xy 291.812949 -318.053511) (xy 291.76473 -318.043667) (xy 291.718714 -318.026215)
			(xy 291.676093 -318.001608) (xy 291.637972 -317.970483) (xy 291.605337 -317.933646) (xy 291.579034 -317.89205)
			(xy 291.559743 -317.846774) (xy 291.547966 -317.79899) (xy 291.544006 -317.749936) (xy 290.255198 -317.749936)
			(xy 290.254703 -317.774543) (xy 290.246808 -317.82312) (xy 290.231224 -317.869801) (xy 290.208353 -317.913378)
			(xy 290.178788 -317.952722) (xy 290.143295 -317.986814) (xy 290.102792 -318.01477) (xy 290.05833 -318.035868)
			(xy 290.011059 -318.04956) (xy 289.962204 -318.055492) (xy 289.913029 -318.053511) (xy 289.86481 -318.043667)
			(xy 289.818794 -318.026215) (xy 289.776173 -318.001608) (xy 289.738052 -317.970483) (xy 289.705417 -317.933646)
			(xy 289.679114 -317.89205) (xy 289.659823 -317.846774) (xy 289.648046 -317.79899) (xy 289.644086 -317.749936)
			(xy 288.355024 -317.749936) (xy 288.354529 -317.774543) (xy 288.346634 -317.82312) (xy 288.33105 -317.869801)
			(xy 288.308179 -317.913378) (xy 288.278614 -317.952722) (xy 288.243121 -317.986814) (xy 288.202618 -318.01477)
			(xy 288.158156 -318.035868) (xy 288.110885 -318.04956) (xy 288.06203 -318.055492) (xy 288.012855 -318.053511)
			(xy 287.964636 -318.043667) (xy 287.91862 -318.026215) (xy 287.875999 -318.001608) (xy 287.837878 -317.970483)
			(xy 287.805243 -317.933646) (xy 287.77894 -317.89205) (xy 287.759649 -317.846774) (xy 287.747872 -317.79899)
			(xy 287.743912 -317.749936) (xy 286.455104 -317.749936) (xy 286.454609 -317.774543) (xy 286.446714 -317.82312)
			(xy 286.43113 -317.869801) (xy 286.408259 -317.913378) (xy 286.378694 -317.952722) (xy 286.343201 -317.986814)
			(xy 286.302698 -318.01477) (xy 286.258236 -318.035868) (xy 286.210965 -318.04956) (xy 286.16211 -318.055492)
			(xy 286.112935 -318.053511) (xy 286.064716 -318.043667) (xy 286.0187 -318.026215) (xy 285.976079 -318.001608)
			(xy 285.937958 -317.970483) (xy 285.905323 -317.933646) (xy 285.87902 -317.89205) (xy 285.859729 -317.846774)
			(xy 285.847952 -317.79899) (xy 285.843992 -317.749936) (xy 284.555184 -317.749936) (xy 284.554689 -317.774543)
			(xy 284.546794 -317.82312) (xy 284.53121 -317.869801) (xy 284.508339 -317.913378) (xy 284.478774 -317.952722)
			(xy 284.443281 -317.986814) (xy 284.402778 -318.01477) (xy 284.358316 -318.035868) (xy 284.311045 -318.04956)
			(xy 284.26219 -318.055492) (xy 284.213015 -318.053511) (xy 284.164796 -318.043667) (xy 284.11878 -318.026215)
			(xy 284.076159 -318.001608) (xy 284.038038 -317.970483) (xy 284.005403 -317.933646) (xy 283.9791 -317.89205)
			(xy 283.959809 -317.846774) (xy 283.948032 -317.79899) (xy 283.944072 -317.749936) (xy 282.65501 -317.749936)
			(xy 282.654515 -317.774543) (xy 282.64662 -317.82312) (xy 282.631036 -317.869801) (xy 282.608165 -317.913378)
			(xy 282.5786 -317.952722) (xy 282.543107 -317.986814) (xy 282.502604 -318.01477) (xy 282.458142 -318.035868)
			(xy 282.410871 -318.04956) (xy 282.362016 -318.055492) (xy 282.312841 -318.053511) (xy 282.264622 -318.043667)
			(xy 282.218606 -318.026215) (xy 282.175985 -318.001608) (xy 282.137864 -317.970483) (xy 282.105229 -317.933646)
			(xy 282.078926 -317.89205) (xy 282.059635 -317.846774) (xy 282.047858 -317.79899) (xy 282.043898 -317.749936)
			(xy 280.75509 -317.749936) (xy 280.754595 -317.774543) (xy 280.7467 -317.82312) (xy 280.731116 -317.869801)
			(xy 280.708245 -317.913378) (xy 280.67868 -317.952722) (xy 280.643187 -317.986814) (xy 280.602684 -318.01477)
			(xy 280.558222 -318.035868) (xy 280.510951 -318.04956) (xy 280.462096 -318.055492) (xy 280.412921 -318.053511)
			(xy 280.364702 -318.043667) (xy 280.318686 -318.026215) (xy 280.276065 -318.001608) (xy 280.237944 -317.970483)
			(xy 280.205309 -317.933646) (xy 280.179006 -317.89205) (xy 280.159715 -317.846774) (xy 280.147938 -317.79899)
			(xy 280.143978 -317.749936) (xy 278.85517 -317.749936) (xy 278.854675 -317.774543) (xy 278.84678 -317.82312)
			(xy 278.831196 -317.869801) (xy 278.808325 -317.913378) (xy 278.77876 -317.952722) (xy 278.743267 -317.986814)
			(xy 278.702764 -318.01477) (xy 278.658302 -318.035868) (xy 278.611031 -318.04956) (xy 278.562176 -318.055492)
			(xy 278.513001 -318.053511) (xy 278.464782 -318.043667) (xy 278.418766 -318.026215) (xy 278.376145 -318.001608)
			(xy 278.338024 -317.970483) (xy 278.305389 -317.933646) (xy 278.279086 -317.89205) (xy 278.259795 -317.846774)
			(xy 278.248018 -317.79899) (xy 278.244058 -317.749936) (xy 276.954996 -317.749936) (xy 276.954501 -317.774543)
			(xy 276.946606 -317.82312) (xy 276.931022 -317.869801) (xy 276.908151 -317.913378) (xy 276.878586 -317.952722)
			(xy 276.843093 -317.986814) (xy 276.80259 -318.01477) (xy 276.758128 -318.035868) (xy 276.710857 -318.04956)
			(xy 276.662002 -318.055492) (xy 276.612827 -318.053511) (xy 276.564608 -318.043667) (xy 276.518592 -318.026215)
			(xy 276.475971 -318.001608) (xy 276.43785 -317.970483) (xy 276.405215 -317.933646) (xy 276.378912 -317.89205)
			(xy 276.359621 -317.846774) (xy 276.347844 -317.79899) (xy 276.343884 -317.749936) (xy 275.055076 -317.749936)
			(xy 275.054581 -317.774543) (xy 275.046686 -317.82312) (xy 275.031102 -317.869801) (xy 275.008231 -317.913378)
			(xy 274.978666 -317.952722) (xy 274.943173 -317.986814) (xy 274.90267 -318.01477) (xy 274.858208 -318.035868)
			(xy 274.810937 -318.04956) (xy 274.762082 -318.055492) (xy 274.712907 -318.053511) (xy 274.664688 -318.043667)
			(xy 274.618672 -318.026215) (xy 274.576051 -318.001608) (xy 274.53793 -317.970483) (xy 274.505295 -317.933646)
			(xy 274.478992 -317.89205) (xy 274.459701 -317.846774) (xy 274.447924 -317.79899) (xy 274.443964 -317.749936)
			(xy 273.155156 -317.749936) (xy 273.154661 -317.774543) (xy 273.146766 -317.82312) (xy 273.131182 -317.869801)
			(xy 273.108311 -317.913378) (xy 273.078746 -317.952722) (xy 273.043253 -317.986814) (xy 273.00275 -318.01477)
			(xy 272.958288 -318.035868) (xy 272.911017 -318.04956) (xy 272.862162 -318.055492) (xy 272.812987 -318.053511)
			(xy 272.764768 -318.043667) (xy 272.718752 -318.026215) (xy 272.676131 -318.001608) (xy 272.63801 -317.970483)
			(xy 272.605375 -317.933646) (xy 272.579072 -317.89205) (xy 272.559781 -317.846774) (xy 272.548004 -317.79899)
			(xy 272.544044 -317.749936) (xy 271.255236 -317.749936) (xy 271.254741 -317.774543) (xy 271.246846 -317.82312)
			(xy 271.231262 -317.869801) (xy 271.208391 -317.913378) (xy 271.178826 -317.952722) (xy 271.143333 -317.986814)
			(xy 271.10283 -318.01477) (xy 271.058368 -318.035868) (xy 271.011097 -318.04956) (xy 270.962242 -318.055492)
			(xy 270.913067 -318.053511) (xy 270.864848 -318.043667) (xy 270.818832 -318.026215) (xy 270.776211 -318.001608)
			(xy 270.73809 -317.970483) (xy 270.705455 -317.933646) (xy 270.679152 -317.89205) (xy 270.659861 -317.846774)
			(xy 270.648084 -317.79899) (xy 270.644124 -317.749936) (xy 196.955156 -317.749936) (xy 196.954661 -317.774543)
			(xy 196.946766 -317.82312) (xy 196.931182 -317.869801) (xy 196.908311 -317.913378) (xy 196.878746 -317.952722)
			(xy 196.843253 -317.986814) (xy 196.80275 -318.01477) (xy 196.758288 -318.035868) (xy 196.711017 -318.04956)
			(xy 196.662162 -318.055492) (xy 196.612987 -318.053511) (xy 196.564768 -318.043667) (xy 196.518752 -318.026215)
			(xy 196.476131 -318.001608) (xy 196.43801 -317.970483) (xy 196.405375 -317.933646) (xy 196.379072 -317.89205)
			(xy 196.359781 -317.846774) (xy 196.348004 -317.79899) (xy 196.344044 -317.749936) (xy 195.055236 -317.749936)
			(xy 195.054741 -317.774543) (xy 195.046846 -317.82312) (xy 195.031262 -317.869801) (xy 195.008391 -317.913378)
			(xy 194.978826 -317.952722) (xy 194.943333 -317.986814) (xy 194.90283 -318.01477) (xy 194.858368 -318.035868)
			(xy 194.811097 -318.04956) (xy 194.762242 -318.055492) (xy 194.713067 -318.053511) (xy 194.664848 -318.043667)
			(xy 194.618832 -318.026215) (xy 194.576211 -318.001608) (xy 194.53809 -317.970483) (xy 194.505455 -317.933646)
			(xy 194.479152 -317.89205) (xy 194.459861 -317.846774) (xy 194.448084 -317.79899) (xy 194.444124 -317.749936)
			(xy 193.155316 -317.749936) (xy 193.154821 -317.774543) (xy 193.146926 -317.82312) (xy 193.131342 -317.869801)
			(xy 193.108471 -317.913378) (xy 193.078906 -317.952722) (xy 193.043413 -317.986814) (xy 193.00291 -318.01477)
			(xy 192.958448 -318.035868) (xy 192.911177 -318.04956) (xy 192.862322 -318.055492) (xy 192.813147 -318.053511)
			(xy 192.764928 -318.043667) (xy 192.718912 -318.026215) (xy 192.676291 -318.001608) (xy 192.63817 -317.970483)
			(xy 192.605535 -317.933646) (xy 192.579232 -317.89205) (xy 192.559941 -317.846774) (xy 192.548164 -317.79899)
			(xy 192.544204 -317.749936) (xy 191.255396 -317.749936) (xy 191.254901 -317.774543) (xy 191.247006 -317.82312)
			(xy 191.231422 -317.869801) (xy 191.208551 -317.913378) (xy 191.178986 -317.952722) (xy 191.143493 -317.986814)
			(xy 191.10299 -318.01477) (xy 191.058528 -318.035868) (xy 191.011257 -318.04956) (xy 190.962402 -318.055492)
			(xy 190.913227 -318.053511) (xy 190.865008 -318.043667) (xy 190.818992 -318.026215) (xy 190.776371 -318.001608)
			(xy 190.73825 -317.970483) (xy 190.705615 -317.933646) (xy 190.679312 -317.89205) (xy 190.660021 -317.846774)
			(xy 190.648244 -317.79899) (xy 190.644284 -317.749936) (xy 189.355222 -317.749936) (xy 189.354727 -317.774543)
			(xy 189.346832 -317.82312) (xy 189.331248 -317.869801) (xy 189.308377 -317.913378) (xy 189.278812 -317.952722)
			(xy 189.243319 -317.986814) (xy 189.202816 -318.01477) (xy 189.158354 -318.035868) (xy 189.111083 -318.04956)
			(xy 189.062228 -318.055492) (xy 189.013053 -318.053511) (xy 188.964834 -318.043667) (xy 188.918818 -318.026215)
			(xy 188.876197 -318.001608) (xy 188.838076 -317.970483) (xy 188.805441 -317.933646) (xy 188.779138 -317.89205)
			(xy 188.759847 -317.846774) (xy 188.74807 -317.79899) (xy 188.74411 -317.749936) (xy 187.455302 -317.749936)
			(xy 187.454807 -317.774543) (xy 187.446912 -317.82312) (xy 187.431328 -317.869801) (xy 187.408457 -317.913378)
			(xy 187.378892 -317.952722) (xy 187.343399 -317.986814) (xy 187.302896 -318.01477) (xy 187.258434 -318.035868)
			(xy 187.211163 -318.04956) (xy 187.162308 -318.055492) (xy 187.113133 -318.053511) (xy 187.064914 -318.043667)
			(xy 187.018898 -318.026215) (xy 186.976277 -318.001608) (xy 186.938156 -317.970483) (xy 186.905521 -317.933646)
			(xy 186.879218 -317.89205) (xy 186.859927 -317.846774) (xy 186.84815 -317.79899) (xy 186.84419 -317.749936)
			(xy 185.555382 -317.749936) (xy 185.554887 -317.774543) (xy 185.546992 -317.82312) (xy 185.531408 -317.869801)
			(xy 185.508537 -317.913378) (xy 185.478972 -317.952722) (xy 185.443479 -317.986814) (xy 185.402976 -318.01477)
			(xy 185.358514 -318.035868) (xy 185.311243 -318.04956) (xy 185.262388 -318.055492) (xy 185.213213 -318.053511)
			(xy 185.164994 -318.043667) (xy 185.118978 -318.026215) (xy 185.076357 -318.001608) (xy 185.038236 -317.970483)
			(xy 185.005601 -317.933646) (xy 184.979298 -317.89205) (xy 184.960007 -317.846774) (xy 184.94823 -317.79899)
			(xy 184.94427 -317.749936) (xy 183.655208 -317.749936) (xy 183.654713 -317.774543) (xy 183.646818 -317.82312)
			(xy 183.631234 -317.869801) (xy 183.608363 -317.913378) (xy 183.578798 -317.952722) (xy 183.543305 -317.986814)
			(xy 183.502802 -318.01477) (xy 183.45834 -318.035868) (xy 183.411069 -318.04956) (xy 183.362214 -318.055492)
			(xy 183.313039 -318.053511) (xy 183.26482 -318.043667) (xy 183.218804 -318.026215) (xy 183.176183 -318.001608)
			(xy 183.138062 -317.970483) (xy 183.105427 -317.933646) (xy 183.079124 -317.89205) (xy 183.059833 -317.846774)
			(xy 183.048056 -317.79899) (xy 183.044096 -317.749936) (xy 181.755288 -317.749936) (xy 181.754793 -317.774543)
			(xy 181.746898 -317.82312) (xy 181.731314 -317.869801) (xy 181.708443 -317.913378) (xy 181.678878 -317.952722)
			(xy 181.643385 -317.986814) (xy 181.602882 -318.01477) (xy 181.55842 -318.035868) (xy 181.511149 -318.04956)
			(xy 181.462294 -318.055492) (xy 181.413119 -318.053511) (xy 181.3649 -318.043667) (xy 181.318884 -318.026215)
			(xy 181.276263 -318.001608) (xy 181.238142 -317.970483) (xy 181.205507 -317.933646) (xy 181.179204 -317.89205)
			(xy 181.159913 -317.846774) (xy 181.148136 -317.79899) (xy 181.144176 -317.749936) (xy 179.855368 -317.749936)
			(xy 179.854873 -317.774543) (xy 179.846978 -317.82312) (xy 179.831394 -317.869801) (xy 179.808523 -317.913378)
			(xy 179.778958 -317.952722) (xy 179.743465 -317.986814) (xy 179.702962 -318.01477) (xy 179.6585 -318.035868)
			(xy 179.611229 -318.04956) (xy 179.562374 -318.055492) (xy 179.513199 -318.053511) (xy 179.46498 -318.043667)
			(xy 179.418964 -318.026215) (xy 179.376343 -318.001608) (xy 179.338222 -317.970483) (xy 179.305587 -317.933646)
			(xy 179.279284 -317.89205) (xy 179.259993 -317.846774) (xy 179.248216 -317.79899) (xy 179.244256 -317.749936)
			(xy 177.955194 -317.749936) (xy 177.954699 -317.774543) (xy 177.946804 -317.82312) (xy 177.93122 -317.869801)
			(xy 177.908349 -317.913378) (xy 177.878784 -317.952722) (xy 177.843291 -317.986814) (xy 177.802788 -318.01477)
			(xy 177.758326 -318.035868) (xy 177.711055 -318.04956) (xy 177.6622 -318.055492) (xy 177.613025 -318.053511)
			(xy 177.564806 -318.043667) (xy 177.51879 -318.026215) (xy 177.476169 -318.001608) (xy 177.438048 -317.970483)
			(xy 177.405413 -317.933646) (xy 177.37911 -317.89205) (xy 177.359819 -317.846774) (xy 177.348042 -317.79899)
			(xy 177.344082 -317.749936) (xy 176.055274 -317.749936) (xy 176.054779 -317.774543) (xy 176.046884 -317.82312)
			(xy 176.0313 -317.869801) (xy 176.008429 -317.913378) (xy 175.978864 -317.952722) (xy 175.943371 -317.986814)
			(xy 175.902868 -318.01477) (xy 175.858406 -318.035868) (xy 175.811135 -318.04956) (xy 175.76228 -318.055492)
			(xy 175.713105 -318.053511) (xy 175.664886 -318.043667) (xy 175.61887 -318.026215) (xy 175.576249 -318.001608)
			(xy 175.538128 -317.970483) (xy 175.505493 -317.933646) (xy 175.47919 -317.89205) (xy 175.459899 -317.846774)
			(xy 175.448122 -317.79899) (xy 175.444162 -317.749936) (xy 174.155354 -317.749936) (xy 174.154859 -317.774543)
			(xy 174.146964 -317.82312) (xy 174.13138 -317.869801) (xy 174.108509 -317.913378) (xy 174.078944 -317.952722)
			(xy 174.043451 -317.986814) (xy 174.002948 -318.01477) (xy 173.958486 -318.035868) (xy 173.911215 -318.04956)
			(xy 173.86236 -318.055492) (xy 173.813185 -318.053511) (xy 173.764966 -318.043667) (xy 173.71895 -318.026215)
			(xy 173.676329 -318.001608) (xy 173.638208 -317.970483) (xy 173.605573 -317.933646) (xy 173.57927 -317.89205)
			(xy 173.559979 -317.846774) (xy 173.548202 -317.79899) (xy 173.544242 -317.749936) (xy 172.25518 -317.749936)
			(xy 172.254685 -317.774543) (xy 172.24679 -317.82312) (xy 172.231206 -317.869801) (xy 172.208335 -317.913378)
			(xy 172.17877 -317.952722) (xy 172.143277 -317.986814) (xy 172.102774 -318.01477) (xy 172.058312 -318.035868)
			(xy 172.011041 -318.04956) (xy 171.962186 -318.055492) (xy 171.913011 -318.053511) (xy 171.864792 -318.043667)
			(xy 171.818776 -318.026215) (xy 171.776155 -318.001608) (xy 171.738034 -317.970483) (xy 171.705399 -317.933646)
			(xy 171.679096 -317.89205) (xy 171.659805 -317.846774) (xy 171.648028 -317.79899) (xy 171.644068 -317.749936)
			(xy 170.35526 -317.749936) (xy 170.354765 -317.774543) (xy 170.34687 -317.82312) (xy 170.331286 -317.869801)
			(xy 170.308415 -317.913378) (xy 170.27885 -317.952722) (xy 170.243357 -317.986814) (xy 170.202854 -318.01477)
			(xy 170.158392 -318.035868) (xy 170.111121 -318.04956) (xy 170.062266 -318.055492) (xy 170.013091 -318.053511)
			(xy 169.964872 -318.043667) (xy 169.918856 -318.026215) (xy 169.876235 -318.001608) (xy 169.838114 -317.970483)
			(xy 169.805479 -317.933646) (xy 169.779176 -317.89205) (xy 169.759885 -317.846774) (xy 169.748108 -317.79899)
			(xy 169.744148 -317.749936) (xy 168.45534 -317.749936) (xy 168.454845 -317.774543) (xy 168.44695 -317.82312)
			(xy 168.431366 -317.869801) (xy 168.408495 -317.913378) (xy 168.37893 -317.952722) (xy 168.343437 -317.986814)
			(xy 168.302934 -318.01477) (xy 168.258472 -318.035868) (xy 168.211201 -318.04956) (xy 168.162346 -318.055492)
			(xy 168.113171 -318.053511) (xy 168.064952 -318.043667) (xy 168.018936 -318.026215) (xy 167.976315 -318.001608)
			(xy 167.938194 -317.970483) (xy 167.905559 -317.933646) (xy 167.879256 -317.89205) (xy 167.859965 -317.846774)
			(xy 167.848188 -317.79899) (xy 167.844228 -317.749936) (xy 166.555166 -317.749936) (xy 166.554671 -317.774543)
			(xy 166.546776 -317.82312) (xy 166.531192 -317.869801) (xy 166.508321 -317.913378) (xy 166.478756 -317.952722)
			(xy 166.443263 -317.986814) (xy 166.40276 -318.01477) (xy 166.358298 -318.035868) (xy 166.311027 -318.04956)
			(xy 166.262172 -318.055492) (xy 166.212997 -318.053511) (xy 166.164778 -318.043667) (xy 166.118762 -318.026215)
			(xy 166.076141 -318.001608) (xy 166.03802 -317.970483) (xy 166.005385 -317.933646) (xy 165.979082 -317.89205)
			(xy 165.959791 -317.846774) (xy 165.948014 -317.79899) (xy 165.944054 -317.749936) (xy 164.655246 -317.749936)
			(xy 164.654751 -317.774543) (xy 164.646856 -317.82312) (xy 164.631272 -317.869801) (xy 164.608401 -317.913378)
			(xy 164.578836 -317.952722) (xy 164.543343 -317.986814) (xy 164.50284 -318.01477) (xy 164.458378 -318.035868)
			(xy 164.411107 -318.04956) (xy 164.362252 -318.055492) (xy 164.313077 -318.053511) (xy 164.264858 -318.043667)
			(xy 164.218842 -318.026215) (xy 164.176221 -318.001608) (xy 164.1381 -317.970483) (xy 164.105465 -317.933646)
			(xy 164.079162 -317.89205) (xy 164.059871 -317.846774) (xy 164.048094 -317.79899) (xy 164.044134 -317.749936)
			(xy 162.755326 -317.749936) (xy 162.754831 -317.774543) (xy 162.746936 -317.82312) (xy 162.731352 -317.869801)
			(xy 162.708481 -317.913378) (xy 162.678916 -317.952722) (xy 162.643423 -317.986814) (xy 162.60292 -318.01477)
			(xy 162.558458 -318.035868) (xy 162.511187 -318.04956) (xy 162.462332 -318.055492) (xy 162.413157 -318.053511)
			(xy 162.364938 -318.043667) (xy 162.318922 -318.026215) (xy 162.276301 -318.001608) (xy 162.23818 -317.970483)
			(xy 162.205545 -317.933646) (xy 162.179242 -317.89205) (xy 162.159951 -317.846774) (xy 162.148174 -317.79899)
			(xy 162.144214 -317.749936) (xy 160.855152 -317.749936) (xy 160.854657 -317.774543) (xy 160.846762 -317.82312)
			(xy 160.831178 -317.869801) (xy 160.808307 -317.913378) (xy 160.778742 -317.952722) (xy 160.743249 -317.986814)
			(xy 160.702746 -318.01477) (xy 160.658284 -318.035868) (xy 160.611013 -318.04956) (xy 160.562158 -318.055492)
			(xy 160.512983 -318.053511) (xy 160.464764 -318.043667) (xy 160.418748 -318.026215) (xy 160.376127 -318.001608)
			(xy 160.338006 -317.970483) (xy 160.305371 -317.933646) (xy 160.279068 -317.89205) (xy 160.259777 -317.846774)
			(xy 160.248 -317.79899) (xy 160.24404 -317.749936) (xy 158.955232 -317.749936) (xy 158.954737 -317.774543)
			(xy 158.946842 -317.82312) (xy 158.931258 -317.869801) (xy 158.908387 -317.913378) (xy 158.878822 -317.952722)
			(xy 158.843329 -317.986814) (xy 158.802826 -318.01477) (xy 158.758364 -318.035868) (xy 158.711093 -318.04956)
			(xy 158.662238 -318.055492) (xy 158.613063 -318.053511) (xy 158.564844 -318.043667) (xy 158.518828 -318.026215)
			(xy 158.476207 -318.001608) (xy 158.438086 -317.970483) (xy 158.405451 -317.933646) (xy 158.379148 -317.89205)
			(xy 158.359857 -317.846774) (xy 158.34808 -317.79899) (xy 158.34412 -317.749936) (xy 157.055312 -317.749936)
			(xy 157.054817 -317.774543) (xy 157.046922 -317.82312) (xy 157.031338 -317.869801) (xy 157.008467 -317.913378)
			(xy 156.978902 -317.952722) (xy 156.943409 -317.986814) (xy 156.902906 -318.01477) (xy 156.858444 -318.035868)
			(xy 156.811173 -318.04956) (xy 156.762318 -318.055492) (xy 156.713143 -318.053511) (xy 156.664924 -318.043667)
			(xy 156.618908 -318.026215) (xy 156.576287 -318.001608) (xy 156.538166 -317.970483) (xy 156.505531 -317.933646)
			(xy 156.479228 -317.89205) (xy 156.459937 -317.846774) (xy 156.44816 -317.79899) (xy 156.4442 -317.749936)
			(xy 155.155392 -317.749936) (xy 155.154897 -317.774543) (xy 155.147002 -317.82312) (xy 155.131418 -317.869801)
			(xy 155.108547 -317.913378) (xy 155.078982 -317.952722) (xy 155.043489 -317.986814) (xy 155.002986 -318.01477)
			(xy 154.958524 -318.035868) (xy 154.911253 -318.04956) (xy 154.862398 -318.055492) (xy 154.813223 -318.053511)
			(xy 154.765004 -318.043667) (xy 154.718988 -318.026215) (xy 154.676367 -318.001608) (xy 154.638246 -317.970483)
			(xy 154.605611 -317.933646) (xy 154.579308 -317.89205) (xy 154.560017 -317.846774) (xy 154.54824 -317.79899)
			(xy 154.54428 -317.749936) (xy 80.855058 -317.749936) (xy 80.854563 -317.774543) (xy 80.846668 -317.82312)
			(xy 80.831084 -317.869801) (xy 80.808213 -317.913378) (xy 80.778648 -317.952722) (xy 80.743155 -317.986814)
			(xy 80.702652 -318.01477) (xy 80.65819 -318.035868) (xy 80.610919 -318.04956) (xy 80.562064 -318.055492)
			(xy 80.512889 -318.053511) (xy 80.46467 -318.043667) (xy 80.418654 -318.026215) (xy 80.376033 -318.001608)
			(xy 80.337912 -317.970483) (xy 80.305277 -317.933646) (xy 80.278974 -317.89205) (xy 80.259683 -317.846774)
			(xy 80.247906 -317.79899) (xy 80.243946 -317.749936) (xy 78.955138 -317.749936) (xy 78.954643 -317.774543)
			(xy 78.946748 -317.82312) (xy 78.931164 -317.869801) (xy 78.908293 -317.913378) (xy 78.878728 -317.952722)
			(xy 78.843235 -317.986814) (xy 78.802732 -318.01477) (xy 78.75827 -318.035868) (xy 78.710999 -318.04956)
			(xy 78.662144 -318.055492) (xy 78.612969 -318.053511) (xy 78.56475 -318.043667) (xy 78.518734 -318.026215)
			(xy 78.476113 -318.001608) (xy 78.437992 -317.970483) (xy 78.405357 -317.933646) (xy 78.379054 -317.89205)
			(xy 78.359763 -317.846774) (xy 78.347986 -317.79899) (xy 78.344026 -317.749936) (xy 77.055218 -317.749936)
			(xy 77.054723 -317.774543) (xy 77.046828 -317.82312) (xy 77.031244 -317.869801) (xy 77.008373 -317.913378)
			(xy 76.978808 -317.952722) (xy 76.943315 -317.986814) (xy 76.902812 -318.01477) (xy 76.85835 -318.035868)
			(xy 76.811079 -318.04956) (xy 76.762224 -318.055492) (xy 76.713049 -318.053511) (xy 76.66483 -318.043667)
			(xy 76.618814 -318.026215) (xy 76.576193 -318.001608) (xy 76.538072 -317.970483) (xy 76.505437 -317.933646)
			(xy 76.479134 -317.89205) (xy 76.459843 -317.846774) (xy 76.448066 -317.79899) (xy 76.444106 -317.749936)
			(xy 75.155298 -317.749936) (xy 75.154803 -317.774543) (xy 75.146908 -317.82312) (xy 75.131324 -317.869801)
			(xy 75.108453 -317.913378) (xy 75.078888 -317.952722) (xy 75.043395 -317.986814) (xy 75.002892 -318.01477)
			(xy 74.95843 -318.035868) (xy 74.911159 -318.04956) (xy 74.862304 -318.055492) (xy 74.813129 -318.053511)
			(xy 74.76491 -318.043667) (xy 74.718894 -318.026215) (xy 74.676273 -318.001608) (xy 74.638152 -317.970483)
			(xy 74.605517 -317.933646) (xy 74.579214 -317.89205) (xy 74.559923 -317.846774) (xy 74.548146 -317.79899)
			(xy 74.544186 -317.749936) (xy 73.255124 -317.749936) (xy 73.254629 -317.774543) (xy 73.246734 -317.82312)
			(xy 73.23115 -317.869801) (xy 73.208279 -317.913378) (xy 73.178714 -317.952722) (xy 73.143221 -317.986814)
			(xy 73.102718 -318.01477) (xy 73.058256 -318.035868) (xy 73.010985 -318.04956) (xy 72.96213 -318.055492)
			(xy 72.912955 -318.053511) (xy 72.864736 -318.043667) (xy 72.81872 -318.026215) (xy 72.776099 -318.001608)
			(xy 72.737978 -317.970483) (xy 72.705343 -317.933646) (xy 72.67904 -317.89205) (xy 72.659749 -317.846774)
			(xy 72.647972 -317.79899) (xy 72.644012 -317.749936) (xy 71.355204 -317.749936) (xy 71.354709 -317.774543)
			(xy 71.346814 -317.82312) (xy 71.33123 -317.869801) (xy 71.308359 -317.913378) (xy 71.278794 -317.952722)
			(xy 71.243301 -317.986814) (xy 71.202798 -318.01477) (xy 71.158336 -318.035868) (xy 71.111065 -318.04956)
			(xy 71.06221 -318.055492) (xy 71.013035 -318.053511) (xy 70.964816 -318.043667) (xy 70.9188 -318.026215)
			(xy 70.876179 -318.001608) (xy 70.838058 -317.970483) (xy 70.805423 -317.933646) (xy 70.77912 -317.89205)
			(xy 70.759829 -317.846774) (xy 70.748052 -317.79899) (xy 70.744092 -317.749936) (xy 69.455284 -317.749936)
			(xy 69.454789 -317.774543) (xy 69.446894 -317.82312) (xy 69.43131 -317.869801) (xy 69.408439 -317.913378)
			(xy 69.378874 -317.952722) (xy 69.343381 -317.986814) (xy 69.302878 -318.01477) (xy 69.258416 -318.035868)
			(xy 69.211145 -318.04956) (xy 69.16229 -318.055492) (xy 69.113115 -318.053511) (xy 69.064896 -318.043667)
			(xy 69.01888 -318.026215) (xy 68.976259 -318.001608) (xy 68.938138 -317.970483) (xy 68.905503 -317.933646)
			(xy 68.8792 -317.89205) (xy 68.859909 -317.846774) (xy 68.848132 -317.79899) (xy 68.844172 -317.749936)
			(xy 67.55511 -317.749936) (xy 67.554615 -317.774543) (xy 67.54672 -317.82312) (xy 67.531136 -317.869801)
			(xy 67.508265 -317.913378) (xy 67.4787 -317.952722) (xy 67.443207 -317.986814) (xy 67.402704 -318.01477)
			(xy 67.358242 -318.035868) (xy 67.310971 -318.04956) (xy 67.262116 -318.055492) (xy 67.212941 -318.053511)
			(xy 67.164722 -318.043667) (xy 67.118706 -318.026215) (xy 67.076085 -318.001608) (xy 67.037964 -317.970483)
			(xy 67.005329 -317.933646) (xy 66.979026 -317.89205) (xy 66.959735 -317.846774) (xy 66.947958 -317.79899)
			(xy 66.943998 -317.749936) (xy 65.65519 -317.749936) (xy 65.654695 -317.774543) (xy 65.6468 -317.82312)
			(xy 65.631216 -317.869801) (xy 65.608345 -317.913378) (xy 65.57878 -317.952722) (xy 65.543287 -317.986814)
			(xy 65.502784 -318.01477) (xy 65.458322 -318.035868) (xy 65.411051 -318.04956) (xy 65.362196 -318.055492)
			(xy 65.313021 -318.053511) (xy 65.264802 -318.043667) (xy 65.218786 -318.026215) (xy 65.176165 -318.001608)
			(xy 65.138044 -317.970483) (xy 65.105409 -317.933646) (xy 65.079106 -317.89205) (xy 65.059815 -317.846774)
			(xy 65.048038 -317.79899) (xy 65.044078 -317.749936) (xy 63.75527 -317.749936) (xy 63.754775 -317.774543)
			(xy 63.74688 -317.82312) (xy 63.731296 -317.869801) (xy 63.708425 -317.913378) (xy 63.67886 -317.952722)
			(xy 63.643367 -317.986814) (xy 63.602864 -318.01477) (xy 63.558402 -318.035868) (xy 63.511131 -318.04956)
			(xy 63.462276 -318.055492) (xy 63.413101 -318.053511) (xy 63.364882 -318.043667) (xy 63.318866 -318.026215)
			(xy 63.276245 -318.001608) (xy 63.238124 -317.970483) (xy 63.205489 -317.933646) (xy 63.179186 -317.89205)
			(xy 63.159895 -317.846774) (xy 63.148118 -317.79899) (xy 63.144158 -317.749936) (xy 61.855096 -317.749936)
			(xy 61.854601 -317.774543) (xy 61.846706 -317.82312) (xy 61.831122 -317.869801) (xy 61.808251 -317.913378)
			(xy 61.778686 -317.952722) (xy 61.743193 -317.986814) (xy 61.70269 -318.01477) (xy 61.658228 -318.035868)
			(xy 61.610957 -318.04956) (xy 61.562102 -318.055492) (xy 61.512927 -318.053511) (xy 61.464708 -318.043667)
			(xy 61.418692 -318.026215) (xy 61.376071 -318.001608) (xy 61.33795 -317.970483) (xy 61.305315 -317.933646)
			(xy 61.279012 -317.89205) (xy 61.259721 -317.846774) (xy 61.247944 -317.79899) (xy 61.243984 -317.749936)
			(xy 59.955176 -317.749936) (xy 59.954681 -317.774543) (xy 59.946786 -317.82312) (xy 59.931202 -317.869801)
			(xy 59.908331 -317.913378) (xy 59.878766 -317.952722) (xy 59.843273 -317.986814) (xy 59.80277 -318.01477)
			(xy 59.758308 -318.035868) (xy 59.711037 -318.04956) (xy 59.662182 -318.055492) (xy 59.613007 -318.053511)
			(xy 59.564788 -318.043667) (xy 59.518772 -318.026215) (xy 59.476151 -318.001608) (xy 59.43803 -317.970483)
			(xy 59.405395 -317.933646) (xy 59.379092 -317.89205) (xy 59.359801 -317.846774) (xy 59.348024 -317.79899)
			(xy 59.344064 -317.749936) (xy 58.055256 -317.749936) (xy 58.054761 -317.774543) (xy 58.046866 -317.82312)
			(xy 58.031282 -317.869801) (xy 58.008411 -317.913378) (xy 57.978846 -317.952722) (xy 57.943353 -317.986814)
			(xy 57.90285 -318.01477) (xy 57.858388 -318.035868) (xy 57.811117 -318.04956) (xy 57.762262 -318.055492)
			(xy 57.713087 -318.053511) (xy 57.664868 -318.043667) (xy 57.618852 -318.026215) (xy 57.576231 -318.001608)
			(xy 57.53811 -317.970483) (xy 57.505475 -317.933646) (xy 57.479172 -317.89205) (xy 57.459881 -317.846774)
			(xy 57.448104 -317.79899) (xy 57.444144 -317.749936) (xy 56.155082 -317.749936) (xy 56.154587 -317.774543)
			(xy 56.146692 -317.82312) (xy 56.131108 -317.869801) (xy 56.108237 -317.913378) (xy 56.078672 -317.952722)
			(xy 56.043179 -317.986814) (xy 56.002676 -318.01477) (xy 55.958214 -318.035868) (xy 55.910943 -318.04956)
			(xy 55.862088 -318.055492) (xy 55.812913 -318.053511) (xy 55.764694 -318.043667) (xy 55.718678 -318.026215)
			(xy 55.676057 -318.001608) (xy 55.637936 -317.970483) (xy 55.605301 -317.933646) (xy 55.578998 -317.89205)
			(xy 55.559707 -317.846774) (xy 55.54793 -317.79899) (xy 55.54397 -317.749936) (xy 54.255162 -317.749936)
			(xy 54.254667 -317.774543) (xy 54.246772 -317.82312) (xy 54.231188 -317.869801) (xy 54.208317 -317.913378)
			(xy 54.178752 -317.952722) (xy 54.143259 -317.986814) (xy 54.102756 -318.01477) (xy 54.058294 -318.035868)
			(xy 54.011023 -318.04956) (xy 53.962168 -318.055492) (xy 53.912993 -318.053511) (xy 53.864774 -318.043667)
			(xy 53.818758 -318.026215) (xy 53.776137 -318.001608) (xy 53.738016 -317.970483) (xy 53.705381 -317.933646)
			(xy 53.679078 -317.89205) (xy 53.659787 -317.846774) (xy 53.64801 -317.79899) (xy 53.64405 -317.749936)
			(xy 52.355242 -317.749936) (xy 52.354747 -317.774543) (xy 52.346852 -317.82312) (xy 52.331268 -317.869801)
			(xy 52.308397 -317.913378) (xy 52.278832 -317.952722) (xy 52.243339 -317.986814) (xy 52.202836 -318.01477)
			(xy 52.158374 -318.035868) (xy 52.111103 -318.04956) (xy 52.062248 -318.055492) (xy 52.013073 -318.053511)
			(xy 51.964854 -318.043667) (xy 51.918838 -318.026215) (xy 51.876217 -318.001608) (xy 51.838096 -317.970483)
			(xy 51.805461 -317.933646) (xy 51.779158 -317.89205) (xy 51.759867 -317.846774) (xy 51.74809 -317.79899)
			(xy 51.74413 -317.749936) (xy 50.455068 -317.749936) (xy 50.454573 -317.774543) (xy 50.446678 -317.82312)
			(xy 50.431094 -317.869801) (xy 50.408223 -317.913378) (xy 50.378658 -317.952722) (xy 50.343165 -317.986814)
			(xy 50.302662 -318.01477) (xy 50.2582 -318.035868) (xy 50.210929 -318.04956) (xy 50.162074 -318.055492)
			(xy 50.112899 -318.053511) (xy 50.06468 -318.043667) (xy 50.018664 -318.026215) (xy 49.976043 -318.001608)
			(xy 49.937922 -317.970483) (xy 49.905287 -317.933646) (xy 49.878984 -317.89205) (xy 49.859693 -317.846774)
			(xy 49.847916 -317.79899) (xy 49.843956 -317.749936) (xy 48.555148 -317.749936) (xy 48.554653 -317.774543)
			(xy 48.546758 -317.82312) (xy 48.531174 -317.869801) (xy 48.508303 -317.913378) (xy 48.478738 -317.952722)
			(xy 48.443245 -317.986814) (xy 48.402742 -318.01477) (xy 48.35828 -318.035868) (xy 48.311009 -318.04956)
			(xy 48.262154 -318.055492) (xy 48.212979 -318.053511) (xy 48.16476 -318.043667) (xy 48.118744 -318.026215)
			(xy 48.076123 -318.001608) (xy 48.038002 -317.970483) (xy 48.005367 -317.933646) (xy 47.979064 -317.89205)
			(xy 47.959773 -317.846774) (xy 47.947996 -317.79899) (xy 47.944036 -317.749936) (xy 46.655228 -317.749936)
			(xy 46.654733 -317.774543) (xy 46.646838 -317.82312) (xy 46.631254 -317.869801) (xy 46.608383 -317.913378)
			(xy 46.578818 -317.952722) (xy 46.543325 -317.986814) (xy 46.502822 -318.01477) (xy 46.45836 -318.035868)
			(xy 46.411089 -318.04956) (xy 46.362234 -318.055492) (xy 46.313059 -318.053511) (xy 46.26484 -318.043667)
			(xy 46.218824 -318.026215) (xy 46.176203 -318.001608) (xy 46.138082 -317.970483) (xy 46.105447 -317.933646)
			(xy 46.079144 -317.89205) (xy 46.059853 -317.846774) (xy 46.048076 -317.79899) (xy 46.044116 -317.749936)
			(xy 44.755054 -317.749936) (xy 44.754559 -317.774543) (xy 44.746664 -317.82312) (xy 44.73108 -317.869801)
			(xy 44.708209 -317.913378) (xy 44.678644 -317.952722) (xy 44.643151 -317.986814) (xy 44.602648 -318.01477)
			(xy 44.558186 -318.035868) (xy 44.510915 -318.04956) (xy 44.46206 -318.055492) (xy 44.412885 -318.053511)
			(xy 44.364666 -318.043667) (xy 44.31865 -318.026215) (xy 44.276029 -318.001608) (xy 44.237908 -317.970483)
			(xy 44.205273 -317.933646) (xy 44.17897 -317.89205) (xy 44.159679 -317.846774) (xy 44.147902 -317.79899)
			(xy 44.143942 -317.749936) (xy 42.855134 -317.749936) (xy 42.854639 -317.774543) (xy 42.846744 -317.82312)
			(xy 42.83116 -317.869801) (xy 42.808289 -317.913378) (xy 42.778724 -317.952722) (xy 42.743231 -317.986814)
			(xy 42.702728 -318.01477) (xy 42.658266 -318.035868) (xy 42.610995 -318.04956) (xy 42.56214 -318.055492)
			(xy 42.512965 -318.053511) (xy 42.464746 -318.043667) (xy 42.41873 -318.026215) (xy 42.376109 -318.001608)
			(xy 42.337988 -317.970483) (xy 42.305353 -317.933646) (xy 42.27905 -317.89205) (xy 42.259759 -317.846774)
			(xy 42.247982 -317.79899) (xy 42.244022 -317.749936) (xy 40.955214 -317.749936) (xy 40.954719 -317.774543)
			(xy 40.946824 -317.82312) (xy 40.93124 -317.869801) (xy 40.908369 -317.913378) (xy 40.878804 -317.952722)
			(xy 40.843311 -317.986814) (xy 40.802808 -318.01477) (xy 40.758346 -318.035868) (xy 40.711075 -318.04956)
			(xy 40.66222 -318.055492) (xy 40.613045 -318.053511) (xy 40.564826 -318.043667) (xy 40.51881 -318.026215)
			(xy 40.476189 -318.001608) (xy 40.438068 -317.970483) (xy 40.405433 -317.933646) (xy 40.37913 -317.89205)
			(xy 40.359839 -317.846774) (xy 40.348062 -317.79899) (xy 40.344102 -317.749936) (xy 39.055294 -317.749936)
			(xy 39.054799 -317.774543) (xy 39.046904 -317.82312) (xy 39.03132 -317.869801) (xy 39.008449 -317.913378)
			(xy 38.978884 -317.952722) (xy 38.943391 -317.986814) (xy 38.902888 -318.01477) (xy 38.858426 -318.035868)
			(xy 38.811155 -318.04956) (xy 38.7623 -318.055492) (xy 38.713125 -318.053511) (xy 38.664906 -318.043667)
			(xy 38.61889 -318.026215) (xy 38.576269 -318.001608) (xy 38.538148 -317.970483) (xy 38.505513 -317.933646)
			(xy 38.47921 -317.89205) (xy 38.459919 -317.846774) (xy 38.448142 -317.79899) (xy 38.444182 -317.749936)
			(xy 0.508 -317.749936) (xy 0.508 -320.900044) (xy 26.882353 -320.900044) (xy 26.886342 -320.751504)
			(xy 26.898299 -320.603391) (xy 26.918189 -320.456134) (xy 26.945954 -320.310158) (xy 26.981515 -320.165881)
			(xy 27.024769 -320.023722) (xy 27.075591 -319.884089) (xy 27.133835 -319.747386) (xy 27.199333 -319.614006)
			(xy 27.271896 -319.484334) (xy 27.351314 -319.358744) (xy 27.437359 -319.237597) (xy 27.529783 -319.121244)
			(xy 27.628319 -319.01002) (xy 27.732683 -318.904245) (xy 27.842575 -318.804225) (xy 27.957676 -318.710247)
			(xy 28.077656 -318.622583) (xy 28.202169 -318.541486) (xy 28.330855 -318.467189) (xy 28.463344 -318.399907)
			(xy 28.599253 -318.339833) (xy 28.738191 -318.287141) (xy 28.879757 -318.241982) (xy 29.023543 -318.204487)
			(xy 29.169134 -318.174765) (xy 29.31611 -318.1529) (xy 29.464049 -318.138956) (xy 29.612522 -318.132972)
			(xy 29.761103 -318.134967) (xy 29.909362 -318.144935) (xy 30.056873 -318.162846) (xy 30.203209 -318.188649)
			(xy 30.34795 -318.222269) (xy 30.490677 -318.263611) (xy 30.63098 -318.312554) (xy 30.768453 -318.368957)
			(xy 30.9027 -318.432658) (xy 31.033335 -318.503474) (xy 31.15998 -318.581199) (xy 31.28227 -318.66561)
			(xy 31.326643 -318.699896) (xy 38.444182 -318.699896) (xy 38.448142 -318.650842) (xy 38.459919 -318.603058)
			(xy 38.47921 -318.557782) (xy 38.505513 -318.516186) (xy 38.538148 -318.479349) (xy 38.576269 -318.448224)
			(xy 38.61889 -318.423617) (xy 38.664906 -318.406165) (xy 38.713125 -318.396321) (xy 38.7623 -318.39434)
			(xy 38.811155 -318.400272) (xy 38.858426 -318.413964) (xy 38.902888 -318.435062) (xy 38.943391 -318.463018)
			(xy 38.978884 -318.49711) (xy 39.008449 -318.536454) (xy 39.03132 -318.580031) (xy 39.046904 -318.626712)
			(xy 39.054799 -318.675289) (xy 39.055294 -318.699896) (xy 40.344102 -318.699896) (xy 40.348062 -318.650842)
			(xy 40.359839 -318.603058) (xy 40.37913 -318.557782) (xy 40.405433 -318.516186) (xy 40.438068 -318.479349)
			(xy 40.476189 -318.448224) (xy 40.51881 -318.423617) (xy 40.564826 -318.406165) (xy 40.613045 -318.396321)
			(xy 40.66222 -318.39434) (xy 40.711075 -318.400272) (xy 40.758346 -318.413964) (xy 40.802808 -318.435062)
			(xy 40.843311 -318.463018) (xy 40.878804 -318.49711) (xy 40.908369 -318.536454) (xy 40.93124 -318.580031)
			(xy 40.946824 -318.626712) (xy 40.954719 -318.675289) (xy 40.955214 -318.699896) (xy 42.244022 -318.699896)
			(xy 42.247982 -318.650842) (xy 42.259759 -318.603058) (xy 42.27905 -318.557782) (xy 42.305353 -318.516186)
			(xy 42.337988 -318.479349) (xy 42.376109 -318.448224) (xy 42.41873 -318.423617) (xy 42.464746 -318.406165)
			(xy 42.512965 -318.396321) (xy 42.56214 -318.39434) (xy 42.610995 -318.400272) (xy 42.658266 -318.413964)
			(xy 42.702728 -318.435062) (xy 42.743231 -318.463018) (xy 42.778724 -318.49711) (xy 42.808289 -318.536454)
			(xy 42.83116 -318.580031) (xy 42.846744 -318.626712) (xy 42.854639 -318.675289) (xy 42.855134 -318.699896)
			(xy 44.143942 -318.699896) (xy 44.147902 -318.650842) (xy 44.159679 -318.603058) (xy 44.17897 -318.557782)
			(xy 44.205273 -318.516186) (xy 44.237908 -318.479349) (xy 44.276029 -318.448224) (xy 44.31865 -318.423617)
			(xy 44.364666 -318.406165) (xy 44.412885 -318.396321) (xy 44.46206 -318.39434) (xy 44.510915 -318.400272)
			(xy 44.558186 -318.413964) (xy 44.602648 -318.435062) (xy 44.643151 -318.463018) (xy 44.678644 -318.49711)
			(xy 44.708209 -318.536454) (xy 44.73108 -318.580031) (xy 44.746664 -318.626712) (xy 44.754559 -318.675289)
			(xy 44.755054 -318.699896) (xy 46.044116 -318.699896) (xy 46.048076 -318.650842) (xy 46.059853 -318.603058)
			(xy 46.079144 -318.557782) (xy 46.105447 -318.516186) (xy 46.138082 -318.479349) (xy 46.176203 -318.448224)
			(xy 46.218824 -318.423617) (xy 46.26484 -318.406165) (xy 46.313059 -318.396321) (xy 46.362234 -318.39434)
			(xy 46.411089 -318.400272) (xy 46.45836 -318.413964) (xy 46.502822 -318.435062) (xy 46.543325 -318.463018)
			(xy 46.578818 -318.49711) (xy 46.608383 -318.536454) (xy 46.631254 -318.580031) (xy 46.646838 -318.626712)
			(xy 46.654733 -318.675289) (xy 46.655228 -318.699896) (xy 47.944036 -318.699896) (xy 47.947996 -318.650842)
			(xy 47.959773 -318.603058) (xy 47.979064 -318.557782) (xy 48.005367 -318.516186) (xy 48.038002 -318.479349)
			(xy 48.076123 -318.448224) (xy 48.118744 -318.423617) (xy 48.16476 -318.406165) (xy 48.212979 -318.396321)
			(xy 48.262154 -318.39434) (xy 48.311009 -318.400272) (xy 48.35828 -318.413964) (xy 48.402742 -318.435062)
			(xy 48.443245 -318.463018) (xy 48.478738 -318.49711) (xy 48.508303 -318.536454) (xy 48.531174 -318.580031)
			(xy 48.546758 -318.626712) (xy 48.554653 -318.675289) (xy 48.555148 -318.699896) (xy 49.843956 -318.699896)
			(xy 49.847916 -318.650842) (xy 49.859693 -318.603058) (xy 49.878984 -318.557782) (xy 49.905287 -318.516186)
			(xy 49.937922 -318.479349) (xy 49.976043 -318.448224) (xy 50.018664 -318.423617) (xy 50.06468 -318.406165)
			(xy 50.112899 -318.396321) (xy 50.162074 -318.39434) (xy 50.210929 -318.400272) (xy 50.2582 -318.413964)
			(xy 50.302662 -318.435062) (xy 50.343165 -318.463018) (xy 50.378658 -318.49711) (xy 50.408223 -318.536454)
			(xy 50.431094 -318.580031) (xy 50.446678 -318.626712) (xy 50.454573 -318.675289) (xy 50.455068 -318.699896)
			(xy 51.74413 -318.699896) (xy 51.74809 -318.650842) (xy 51.759867 -318.603058) (xy 51.779158 -318.557782)
			(xy 51.805461 -318.516186) (xy 51.838096 -318.479349) (xy 51.876217 -318.448224) (xy 51.918838 -318.423617)
			(xy 51.964854 -318.406165) (xy 52.013073 -318.396321) (xy 52.062248 -318.39434) (xy 52.111103 -318.400272)
			(xy 52.158374 -318.413964) (xy 52.202836 -318.435062) (xy 52.243339 -318.463018) (xy 52.278832 -318.49711)
			(xy 52.308397 -318.536454) (xy 52.331268 -318.580031) (xy 52.346852 -318.626712) (xy 52.354747 -318.675289)
			(xy 52.355242 -318.699896) (xy 53.64405 -318.699896) (xy 53.64801 -318.650842) (xy 53.659787 -318.603058)
			(xy 53.679078 -318.557782) (xy 53.705381 -318.516186) (xy 53.738016 -318.479349) (xy 53.776137 -318.448224)
			(xy 53.818758 -318.423617) (xy 53.864774 -318.406165) (xy 53.912993 -318.396321) (xy 53.962168 -318.39434)
			(xy 54.011023 -318.400272) (xy 54.058294 -318.413964) (xy 54.102756 -318.435062) (xy 54.143259 -318.463018)
			(xy 54.178752 -318.49711) (xy 54.208317 -318.536454) (xy 54.231188 -318.580031) (xy 54.246772 -318.626712)
			(xy 54.254667 -318.675289) (xy 54.255162 -318.699896) (xy 55.54397 -318.699896) (xy 55.54793 -318.650842)
			(xy 55.559707 -318.603058) (xy 55.578998 -318.557782) (xy 55.605301 -318.516186) (xy 55.637936 -318.479349)
			(xy 55.676057 -318.448224) (xy 55.718678 -318.423617) (xy 55.764694 -318.406165) (xy 55.812913 -318.396321)
			(xy 55.862088 -318.39434) (xy 55.910943 -318.400272) (xy 55.958214 -318.413964) (xy 56.002676 -318.435062)
			(xy 56.043179 -318.463018) (xy 56.078672 -318.49711) (xy 56.108237 -318.536454) (xy 56.131108 -318.580031)
			(xy 56.146692 -318.626712) (xy 56.154587 -318.675289) (xy 56.155082 -318.699896) (xy 57.444144 -318.699896)
			(xy 57.448104 -318.650842) (xy 57.459881 -318.603058) (xy 57.479172 -318.557782) (xy 57.505475 -318.516186)
			(xy 57.53811 -318.479349) (xy 57.576231 -318.448224) (xy 57.618852 -318.423617) (xy 57.664868 -318.406165)
			(xy 57.713087 -318.396321) (xy 57.762262 -318.39434) (xy 57.811117 -318.400272) (xy 57.858388 -318.413964)
			(xy 57.90285 -318.435062) (xy 57.943353 -318.463018) (xy 57.978846 -318.49711) (xy 58.008411 -318.536454)
			(xy 58.031282 -318.580031) (xy 58.046866 -318.626712) (xy 58.054761 -318.675289) (xy 58.055256 -318.699896)
			(xy 59.344064 -318.699896) (xy 59.348024 -318.650842) (xy 59.359801 -318.603058) (xy 59.379092 -318.557782)
			(xy 59.405395 -318.516186) (xy 59.43803 -318.479349) (xy 59.476151 -318.448224) (xy 59.518772 -318.423617)
			(xy 59.564788 -318.406165) (xy 59.613007 -318.396321) (xy 59.662182 -318.39434) (xy 59.711037 -318.400272)
			(xy 59.758308 -318.413964) (xy 59.80277 -318.435062) (xy 59.843273 -318.463018) (xy 59.878766 -318.49711)
			(xy 59.908331 -318.536454) (xy 59.931202 -318.580031) (xy 59.946786 -318.626712) (xy 59.954681 -318.675289)
			(xy 59.955176 -318.699896) (xy 61.243984 -318.699896) (xy 61.247944 -318.650842) (xy 61.259721 -318.603058)
			(xy 61.279012 -318.557782) (xy 61.305315 -318.516186) (xy 61.33795 -318.479349) (xy 61.376071 -318.448224)
			(xy 61.418692 -318.423617) (xy 61.464708 -318.406165) (xy 61.512927 -318.396321) (xy 61.562102 -318.39434)
			(xy 61.610957 -318.400272) (xy 61.658228 -318.413964) (xy 61.70269 -318.435062) (xy 61.743193 -318.463018)
			(xy 61.778686 -318.49711) (xy 61.808251 -318.536454) (xy 61.831122 -318.580031) (xy 61.846706 -318.626712)
			(xy 61.854601 -318.675289) (xy 61.855096 -318.699896) (xy 63.144158 -318.699896) (xy 63.148118 -318.650842)
			(xy 63.159895 -318.603058) (xy 63.179186 -318.557782) (xy 63.205489 -318.516186) (xy 63.238124 -318.479349)
			(xy 63.276245 -318.448224) (xy 63.318866 -318.423617) (xy 63.364882 -318.406165) (xy 63.413101 -318.396321)
			(xy 63.462276 -318.39434) (xy 63.511131 -318.400272) (xy 63.558402 -318.413964) (xy 63.602864 -318.435062)
			(xy 63.643367 -318.463018) (xy 63.67886 -318.49711) (xy 63.708425 -318.536454) (xy 63.731296 -318.580031)
			(xy 63.74688 -318.626712) (xy 63.754775 -318.675289) (xy 63.75527 -318.699896) (xy 65.044078 -318.699896)
			(xy 65.048038 -318.650842) (xy 65.059815 -318.603058) (xy 65.079106 -318.557782) (xy 65.105409 -318.516186)
			(xy 65.138044 -318.479349) (xy 65.176165 -318.448224) (xy 65.218786 -318.423617) (xy 65.264802 -318.406165)
			(xy 65.313021 -318.396321) (xy 65.362196 -318.39434) (xy 65.411051 -318.400272) (xy 65.458322 -318.413964)
			(xy 65.502784 -318.435062) (xy 65.543287 -318.463018) (xy 65.57878 -318.49711) (xy 65.608345 -318.536454)
			(xy 65.631216 -318.580031) (xy 65.6468 -318.626712) (xy 65.654695 -318.675289) (xy 65.65519 -318.699896)
			(xy 66.943998 -318.699896) (xy 66.947958 -318.650842) (xy 66.959735 -318.603058) (xy 66.979026 -318.557782)
			(xy 67.005329 -318.516186) (xy 67.037964 -318.479349) (xy 67.076085 -318.448224) (xy 67.118706 -318.423617)
			(xy 67.164722 -318.406165) (xy 67.212941 -318.396321) (xy 67.262116 -318.39434) (xy 67.310971 -318.400272)
			(xy 67.358242 -318.413964) (xy 67.402704 -318.435062) (xy 67.443207 -318.463018) (xy 67.4787 -318.49711)
			(xy 67.508265 -318.536454) (xy 67.531136 -318.580031) (xy 67.54672 -318.626712) (xy 67.554615 -318.675289)
			(xy 67.55511 -318.699896) (xy 68.844172 -318.699896) (xy 68.848132 -318.650842) (xy 68.859909 -318.603058)
			(xy 68.8792 -318.557782) (xy 68.905503 -318.516186) (xy 68.938138 -318.479349) (xy 68.976259 -318.448224)
			(xy 69.01888 -318.423617) (xy 69.064896 -318.406165) (xy 69.113115 -318.396321) (xy 69.16229 -318.39434)
			(xy 69.211145 -318.400272) (xy 69.258416 -318.413964) (xy 69.302878 -318.435062) (xy 69.343381 -318.463018)
			(xy 69.378874 -318.49711) (xy 69.408439 -318.536454) (xy 69.43131 -318.580031) (xy 69.446894 -318.626712)
			(xy 69.454789 -318.675289) (xy 69.455284 -318.699896) (xy 70.744092 -318.699896) (xy 70.748052 -318.650842)
			(xy 70.759829 -318.603058) (xy 70.77912 -318.557782) (xy 70.805423 -318.516186) (xy 70.838058 -318.479349)
			(xy 70.876179 -318.448224) (xy 70.9188 -318.423617) (xy 70.964816 -318.406165) (xy 71.013035 -318.396321)
			(xy 71.06221 -318.39434) (xy 71.111065 -318.400272) (xy 71.158336 -318.413964) (xy 71.202798 -318.435062)
			(xy 71.243301 -318.463018) (xy 71.278794 -318.49711) (xy 71.308359 -318.536454) (xy 71.33123 -318.580031)
			(xy 71.346814 -318.626712) (xy 71.354709 -318.675289) (xy 71.355204 -318.699896) (xy 72.644012 -318.699896)
			(xy 72.647972 -318.650842) (xy 72.659749 -318.603058) (xy 72.67904 -318.557782) (xy 72.705343 -318.516186)
			(xy 72.737978 -318.479349) (xy 72.776099 -318.448224) (xy 72.81872 -318.423617) (xy 72.864736 -318.406165)
			(xy 72.912955 -318.396321) (xy 72.96213 -318.39434) (xy 73.010985 -318.400272) (xy 73.058256 -318.413964)
			(xy 73.102718 -318.435062) (xy 73.143221 -318.463018) (xy 73.178714 -318.49711) (xy 73.208279 -318.536454)
			(xy 73.23115 -318.580031) (xy 73.246734 -318.626712) (xy 73.254629 -318.675289) (xy 73.255124 -318.699896)
			(xy 74.544186 -318.699896) (xy 74.548146 -318.650842) (xy 74.559923 -318.603058) (xy 74.579214 -318.557782)
			(xy 74.605517 -318.516186) (xy 74.638152 -318.479349) (xy 74.676273 -318.448224) (xy 74.718894 -318.423617)
			(xy 74.76491 -318.406165) (xy 74.813129 -318.396321) (xy 74.862304 -318.39434) (xy 74.911159 -318.400272)
			(xy 74.95843 -318.413964) (xy 75.002892 -318.435062) (xy 75.043395 -318.463018) (xy 75.078888 -318.49711)
			(xy 75.108453 -318.536454) (xy 75.131324 -318.580031) (xy 75.146908 -318.626712) (xy 75.154803 -318.675289)
			(xy 75.155298 -318.699896) (xy 76.444106 -318.699896) (xy 76.448066 -318.650842) (xy 76.459843 -318.603058)
			(xy 76.479134 -318.557782) (xy 76.505437 -318.516186) (xy 76.538072 -318.479349) (xy 76.576193 -318.448224)
			(xy 76.618814 -318.423617) (xy 76.66483 -318.406165) (xy 76.713049 -318.396321) (xy 76.762224 -318.39434)
			(xy 76.811079 -318.400272) (xy 76.85835 -318.413964) (xy 76.902812 -318.435062) (xy 76.943315 -318.463018)
			(xy 76.978808 -318.49711) (xy 77.008373 -318.536454) (xy 77.031244 -318.580031) (xy 77.046828 -318.626712)
			(xy 77.054723 -318.675289) (xy 77.055218 -318.699896) (xy 78.344026 -318.699896) (xy 78.347986 -318.650842)
			(xy 78.359763 -318.603058) (xy 78.379054 -318.557782) (xy 78.405357 -318.516186) (xy 78.437992 -318.479349)
			(xy 78.476113 -318.448224) (xy 78.518734 -318.423617) (xy 78.56475 -318.406165) (xy 78.612969 -318.396321)
			(xy 78.662144 -318.39434) (xy 78.710999 -318.400272) (xy 78.75827 -318.413964) (xy 78.802732 -318.435062)
			(xy 78.843235 -318.463018) (xy 78.878728 -318.49711) (xy 78.908293 -318.536454) (xy 78.931164 -318.580031)
			(xy 78.946748 -318.626712) (xy 78.954643 -318.675289) (xy 78.955138 -318.699896) (xy 80.243946 -318.699896)
			(xy 80.247906 -318.650842) (xy 80.259683 -318.603058) (xy 80.278974 -318.557782) (xy 80.305277 -318.516186)
			(xy 80.337912 -318.479349) (xy 80.376033 -318.448224) (xy 80.418654 -318.423617) (xy 80.46467 -318.406165)
			(xy 80.512889 -318.396321) (xy 80.562064 -318.39434) (xy 80.610919 -318.400272) (xy 80.65819 -318.413964)
			(xy 80.702652 -318.435062) (xy 80.743155 -318.463018) (xy 80.778648 -318.49711) (xy 80.808213 -318.536454)
			(xy 80.831084 -318.580031) (xy 80.846668 -318.626712) (xy 80.854563 -318.675289) (xy 80.855058 -318.699896)
			(xy 80.854563 -318.724503) (xy 80.846668 -318.77308) (xy 80.831084 -318.819761) (xy 80.808213 -318.863338)
			(xy 80.778648 -318.902682) (xy 80.743155 -318.936774) (xy 80.702652 -318.96473) (xy 80.65819 -318.985828)
			(xy 80.610919 -318.99952) (xy 80.562064 -319.005452) (xy 80.512889 -319.003471) (xy 80.46467 -318.993627)
			(xy 80.418654 -318.976175) (xy 80.376033 -318.951568) (xy 80.337912 -318.920443) (xy 80.305277 -318.883606)
			(xy 80.278974 -318.84201) (xy 80.259683 -318.796734) (xy 80.247906 -318.74895) (xy 80.243946 -318.699896)
			(xy 78.955138 -318.699896) (xy 78.954643 -318.724503) (xy 78.946748 -318.77308) (xy 78.931164 -318.819761)
			(xy 78.908293 -318.863338) (xy 78.878728 -318.902682) (xy 78.843235 -318.936774) (xy 78.802732 -318.96473)
			(xy 78.75827 -318.985828) (xy 78.710999 -318.99952) (xy 78.662144 -319.005452) (xy 78.612969 -319.003471)
			(xy 78.56475 -318.993627) (xy 78.518734 -318.976175) (xy 78.476113 -318.951568) (xy 78.437992 -318.920443)
			(xy 78.405357 -318.883606) (xy 78.379054 -318.84201) (xy 78.359763 -318.796734) (xy 78.347986 -318.74895)
			(xy 78.344026 -318.699896) (xy 77.055218 -318.699896) (xy 77.054723 -318.724503) (xy 77.046828 -318.77308)
			(xy 77.031244 -318.819761) (xy 77.008373 -318.863338) (xy 76.978808 -318.902682) (xy 76.943315 -318.936774)
			(xy 76.902812 -318.96473) (xy 76.85835 -318.985828) (xy 76.811079 -318.99952) (xy 76.762224 -319.005452)
			(xy 76.713049 -319.003471) (xy 76.66483 -318.993627) (xy 76.618814 -318.976175) (xy 76.576193 -318.951568)
			(xy 76.538072 -318.920443) (xy 76.505437 -318.883606) (xy 76.479134 -318.84201) (xy 76.459843 -318.796734)
			(xy 76.448066 -318.74895) (xy 76.444106 -318.699896) (xy 75.155298 -318.699896) (xy 75.154803 -318.724503)
			(xy 75.146908 -318.77308) (xy 75.131324 -318.819761) (xy 75.108453 -318.863338) (xy 75.078888 -318.902682)
			(xy 75.043395 -318.936774) (xy 75.002892 -318.96473) (xy 74.95843 -318.985828) (xy 74.911159 -318.99952)
			(xy 74.862304 -319.005452) (xy 74.813129 -319.003471) (xy 74.76491 -318.993627) (xy 74.718894 -318.976175)
			(xy 74.676273 -318.951568) (xy 74.638152 -318.920443) (xy 74.605517 -318.883606) (xy 74.579214 -318.84201)
			(xy 74.559923 -318.796734) (xy 74.548146 -318.74895) (xy 74.544186 -318.699896) (xy 73.255124 -318.699896)
			(xy 73.254629 -318.724503) (xy 73.246734 -318.77308) (xy 73.23115 -318.819761) (xy 73.208279 -318.863338)
			(xy 73.178714 -318.902682) (xy 73.143221 -318.936774) (xy 73.102718 -318.96473) (xy 73.058256 -318.985828)
			(xy 73.010985 -318.99952) (xy 72.96213 -319.005452) (xy 72.912955 -319.003471) (xy 72.864736 -318.993627)
			(xy 72.81872 -318.976175) (xy 72.776099 -318.951568) (xy 72.737978 -318.920443) (xy 72.705343 -318.883606)
			(xy 72.67904 -318.84201) (xy 72.659749 -318.796734) (xy 72.647972 -318.74895) (xy 72.644012 -318.699896)
			(xy 71.355204 -318.699896) (xy 71.354709 -318.724503) (xy 71.346814 -318.77308) (xy 71.33123 -318.819761)
			(xy 71.308359 -318.863338) (xy 71.278794 -318.902682) (xy 71.243301 -318.936774) (xy 71.202798 -318.96473)
			(xy 71.158336 -318.985828) (xy 71.111065 -318.99952) (xy 71.06221 -319.005452) (xy 71.013035 -319.003471)
			(xy 70.964816 -318.993627) (xy 70.9188 -318.976175) (xy 70.876179 -318.951568) (xy 70.838058 -318.920443)
			(xy 70.805423 -318.883606) (xy 70.77912 -318.84201) (xy 70.759829 -318.796734) (xy 70.748052 -318.74895)
			(xy 70.744092 -318.699896) (xy 69.455284 -318.699896) (xy 69.454789 -318.724503) (xy 69.446894 -318.77308)
			(xy 69.43131 -318.819761) (xy 69.408439 -318.863338) (xy 69.378874 -318.902682) (xy 69.343381 -318.936774)
			(xy 69.302878 -318.96473) (xy 69.258416 -318.985828) (xy 69.211145 -318.99952) (xy 69.16229 -319.005452)
			(xy 69.113115 -319.003471) (xy 69.064896 -318.993627) (xy 69.01888 -318.976175) (xy 68.976259 -318.951568)
			(xy 68.938138 -318.920443) (xy 68.905503 -318.883606) (xy 68.8792 -318.84201) (xy 68.859909 -318.796734)
			(xy 68.848132 -318.74895) (xy 68.844172 -318.699896) (xy 67.55511 -318.699896) (xy 67.554615 -318.724503)
			(xy 67.54672 -318.77308) (xy 67.531136 -318.819761) (xy 67.508265 -318.863338) (xy 67.4787 -318.902682)
			(xy 67.443207 -318.936774) (xy 67.402704 -318.96473) (xy 67.358242 -318.985828) (xy 67.310971 -318.99952)
			(xy 67.262116 -319.005452) (xy 67.212941 -319.003471) (xy 67.164722 -318.993627) (xy 67.118706 -318.976175)
			(xy 67.076085 -318.951568) (xy 67.037964 -318.920443) (xy 67.005329 -318.883606) (xy 66.979026 -318.84201)
			(xy 66.959735 -318.796734) (xy 66.947958 -318.74895) (xy 66.943998 -318.699896) (xy 65.65519 -318.699896)
			(xy 65.654695 -318.724503) (xy 65.6468 -318.77308) (xy 65.631216 -318.819761) (xy 65.608345 -318.863338)
			(xy 65.57878 -318.902682) (xy 65.543287 -318.936774) (xy 65.502784 -318.96473) (xy 65.458322 -318.985828)
			(xy 65.411051 -318.99952) (xy 65.362196 -319.005452) (xy 65.313021 -319.003471) (xy 65.264802 -318.993627)
			(xy 65.218786 -318.976175) (xy 65.176165 -318.951568) (xy 65.138044 -318.920443) (xy 65.105409 -318.883606)
			(xy 65.079106 -318.84201) (xy 65.059815 -318.796734) (xy 65.048038 -318.74895) (xy 65.044078 -318.699896)
			(xy 63.75527 -318.699896) (xy 63.754775 -318.724503) (xy 63.74688 -318.77308) (xy 63.731296 -318.819761)
			(xy 63.708425 -318.863338) (xy 63.67886 -318.902682) (xy 63.643367 -318.936774) (xy 63.602864 -318.96473)
			(xy 63.558402 -318.985828) (xy 63.511131 -318.99952) (xy 63.462276 -319.005452) (xy 63.413101 -319.003471)
			(xy 63.364882 -318.993627) (xy 63.318866 -318.976175) (xy 63.276245 -318.951568) (xy 63.238124 -318.920443)
			(xy 63.205489 -318.883606) (xy 63.179186 -318.84201) (xy 63.159895 -318.796734) (xy 63.148118 -318.74895)
			(xy 63.144158 -318.699896) (xy 61.855096 -318.699896) (xy 61.854601 -318.724503) (xy 61.846706 -318.77308)
			(xy 61.831122 -318.819761) (xy 61.808251 -318.863338) (xy 61.778686 -318.902682) (xy 61.743193 -318.936774)
			(xy 61.70269 -318.96473) (xy 61.658228 -318.985828) (xy 61.610957 -318.99952) (xy 61.562102 -319.005452)
			(xy 61.512927 -319.003471) (xy 61.464708 -318.993627) (xy 61.418692 -318.976175) (xy 61.376071 -318.951568)
			(xy 61.33795 -318.920443) (xy 61.305315 -318.883606) (xy 61.279012 -318.84201) (xy 61.259721 -318.796734)
			(xy 61.247944 -318.74895) (xy 61.243984 -318.699896) (xy 59.955176 -318.699896) (xy 59.954681 -318.724503)
			(xy 59.946786 -318.77308) (xy 59.931202 -318.819761) (xy 59.908331 -318.863338) (xy 59.878766 -318.902682)
			(xy 59.843273 -318.936774) (xy 59.80277 -318.96473) (xy 59.758308 -318.985828) (xy 59.711037 -318.99952)
			(xy 59.662182 -319.005452) (xy 59.613007 -319.003471) (xy 59.564788 -318.993627) (xy 59.518772 -318.976175)
			(xy 59.476151 -318.951568) (xy 59.43803 -318.920443) (xy 59.405395 -318.883606) (xy 59.379092 -318.84201)
			(xy 59.359801 -318.796734) (xy 59.348024 -318.74895) (xy 59.344064 -318.699896) (xy 58.055256 -318.699896)
			(xy 58.054761 -318.724503) (xy 58.046866 -318.77308) (xy 58.031282 -318.819761) (xy 58.008411 -318.863338)
			(xy 57.978846 -318.902682) (xy 57.943353 -318.936774) (xy 57.90285 -318.96473) (xy 57.858388 -318.985828)
			(xy 57.811117 -318.99952) (xy 57.762262 -319.005452) (xy 57.713087 -319.003471) (xy 57.664868 -318.993627)
			(xy 57.618852 -318.976175) (xy 57.576231 -318.951568) (xy 57.53811 -318.920443) (xy 57.505475 -318.883606)
			(xy 57.479172 -318.84201) (xy 57.459881 -318.796734) (xy 57.448104 -318.74895) (xy 57.444144 -318.699896)
			(xy 56.155082 -318.699896) (xy 56.154587 -318.724503) (xy 56.146692 -318.77308) (xy 56.131108 -318.819761)
			(xy 56.108237 -318.863338) (xy 56.078672 -318.902682) (xy 56.043179 -318.936774) (xy 56.002676 -318.96473)
			(xy 55.958214 -318.985828) (xy 55.910943 -318.99952) (xy 55.862088 -319.005452) (xy 55.812913 -319.003471)
			(xy 55.764694 -318.993627) (xy 55.718678 -318.976175) (xy 55.676057 -318.951568) (xy 55.637936 -318.920443)
			(xy 55.605301 -318.883606) (xy 55.578998 -318.84201) (xy 55.559707 -318.796734) (xy 55.54793 -318.74895)
			(xy 55.54397 -318.699896) (xy 54.255162 -318.699896) (xy 54.254667 -318.724503) (xy 54.246772 -318.77308)
			(xy 54.231188 -318.819761) (xy 54.208317 -318.863338) (xy 54.178752 -318.902682) (xy 54.143259 -318.936774)
			(xy 54.102756 -318.96473) (xy 54.058294 -318.985828) (xy 54.011023 -318.99952) (xy 53.962168 -319.005452)
			(xy 53.912993 -319.003471) (xy 53.864774 -318.993627) (xy 53.818758 -318.976175) (xy 53.776137 -318.951568)
			(xy 53.738016 -318.920443) (xy 53.705381 -318.883606) (xy 53.679078 -318.84201) (xy 53.659787 -318.796734)
			(xy 53.64801 -318.74895) (xy 53.64405 -318.699896) (xy 52.355242 -318.699896) (xy 52.354747 -318.724503)
			(xy 52.346852 -318.77308) (xy 52.331268 -318.819761) (xy 52.308397 -318.863338) (xy 52.278832 -318.902682)
			(xy 52.243339 -318.936774) (xy 52.202836 -318.96473) (xy 52.158374 -318.985828) (xy 52.111103 -318.99952)
			(xy 52.062248 -319.005452) (xy 52.013073 -319.003471) (xy 51.964854 -318.993627) (xy 51.918838 -318.976175)
			(xy 51.876217 -318.951568) (xy 51.838096 -318.920443) (xy 51.805461 -318.883606) (xy 51.779158 -318.84201)
			(xy 51.759867 -318.796734) (xy 51.74809 -318.74895) (xy 51.74413 -318.699896) (xy 50.455068 -318.699896)
			(xy 50.454573 -318.724503) (xy 50.446678 -318.77308) (xy 50.431094 -318.819761) (xy 50.408223 -318.863338)
			(xy 50.378658 -318.902682) (xy 50.343165 -318.936774) (xy 50.302662 -318.96473) (xy 50.2582 -318.985828)
			(xy 50.210929 -318.99952) (xy 50.162074 -319.005452) (xy 50.112899 -319.003471) (xy 50.06468 -318.993627)
			(xy 50.018664 -318.976175) (xy 49.976043 -318.951568) (xy 49.937922 -318.920443) (xy 49.905287 -318.883606)
			(xy 49.878984 -318.84201) (xy 49.859693 -318.796734) (xy 49.847916 -318.74895) (xy 49.843956 -318.699896)
			(xy 48.555148 -318.699896) (xy 48.554653 -318.724503) (xy 48.546758 -318.77308) (xy 48.531174 -318.819761)
			(xy 48.508303 -318.863338) (xy 48.478738 -318.902682) (xy 48.443245 -318.936774) (xy 48.402742 -318.96473)
			(xy 48.35828 -318.985828) (xy 48.311009 -318.99952) (xy 48.262154 -319.005452) (xy 48.212979 -319.003471)
			(xy 48.16476 -318.993627) (xy 48.118744 -318.976175) (xy 48.076123 -318.951568) (xy 48.038002 -318.920443)
			(xy 48.005367 -318.883606) (xy 47.979064 -318.84201) (xy 47.959773 -318.796734) (xy 47.947996 -318.74895)
			(xy 47.944036 -318.699896) (xy 46.655228 -318.699896) (xy 46.654733 -318.724503) (xy 46.646838 -318.77308)
			(xy 46.631254 -318.819761) (xy 46.608383 -318.863338) (xy 46.578818 -318.902682) (xy 46.543325 -318.936774)
			(xy 46.502822 -318.96473) (xy 46.45836 -318.985828) (xy 46.411089 -318.99952) (xy 46.362234 -319.005452)
			(xy 46.313059 -319.003471) (xy 46.26484 -318.993627) (xy 46.218824 -318.976175) (xy 46.176203 -318.951568)
			(xy 46.138082 -318.920443) (xy 46.105447 -318.883606) (xy 46.079144 -318.84201) (xy 46.059853 -318.796734)
			(xy 46.048076 -318.74895) (xy 46.044116 -318.699896) (xy 44.755054 -318.699896) (xy 44.754559 -318.724503)
			(xy 44.746664 -318.77308) (xy 44.73108 -318.819761) (xy 44.708209 -318.863338) (xy 44.678644 -318.902682)
			(xy 44.643151 -318.936774) (xy 44.602648 -318.96473) (xy 44.558186 -318.985828) (xy 44.510915 -318.99952)
			(xy 44.46206 -319.005452) (xy 44.412885 -319.003471) (xy 44.364666 -318.993627) (xy 44.31865 -318.976175)
			(xy 44.276029 -318.951568) (xy 44.237908 -318.920443) (xy 44.205273 -318.883606) (xy 44.17897 -318.84201)
			(xy 44.159679 -318.796734) (xy 44.147902 -318.74895) (xy 44.143942 -318.699896) (xy 42.855134 -318.699896)
			(xy 42.854639 -318.724503) (xy 42.846744 -318.77308) (xy 42.83116 -318.819761) (xy 42.808289 -318.863338)
			(xy 42.778724 -318.902682) (xy 42.743231 -318.936774) (xy 42.702728 -318.96473) (xy 42.658266 -318.985828)
			(xy 42.610995 -318.99952) (xy 42.56214 -319.005452) (xy 42.512965 -319.003471) (xy 42.464746 -318.993627)
			(xy 42.41873 -318.976175) (xy 42.376109 -318.951568) (xy 42.337988 -318.920443) (xy 42.305353 -318.883606)
			(xy 42.27905 -318.84201) (xy 42.259759 -318.796734) (xy 42.247982 -318.74895) (xy 42.244022 -318.699896)
			(xy 40.955214 -318.699896) (xy 40.954719 -318.724503) (xy 40.946824 -318.77308) (xy 40.93124 -318.819761)
			(xy 40.908369 -318.863338) (xy 40.878804 -318.902682) (xy 40.843311 -318.936774) (xy 40.802808 -318.96473)
			(xy 40.758346 -318.985828) (xy 40.711075 -318.99952) (xy 40.66222 -319.005452) (xy 40.613045 -319.003471)
			(xy 40.564826 -318.993627) (xy 40.51881 -318.976175) (xy 40.476189 -318.951568) (xy 40.438068 -318.920443)
			(xy 40.405433 -318.883606) (xy 40.37913 -318.84201) (xy 40.359839 -318.796734) (xy 40.348062 -318.74895)
			(xy 40.344102 -318.699896) (xy 39.055294 -318.699896) (xy 39.054799 -318.724503) (xy 39.046904 -318.77308)
			(xy 39.03132 -318.819761) (xy 39.008449 -318.863338) (xy 38.978884 -318.902682) (xy 38.943391 -318.936774)
			(xy 38.902888 -318.96473) (xy 38.858426 -318.985828) (xy 38.811155 -318.99952) (xy 38.7623 -319.005452)
			(xy 38.713125 -319.003471) (xy 38.664906 -318.993627) (xy 38.61889 -318.976175) (xy 38.576269 -318.951568)
			(xy 38.538148 -318.920443) (xy 38.505513 -318.883606) (xy 38.47921 -318.84201) (xy 38.459919 -318.796734)
			(xy 38.448142 -318.74895) (xy 38.444182 -318.699896) (xy 31.326643 -318.699896) (xy 31.399853 -318.756463)
			(xy 31.51239 -318.853497) (xy 31.619557 -318.956432) (xy 31.721044 -319.064971) (xy 31.816558 -319.1788)
			(xy 31.905825 -319.297593) (xy 31.988586 -319.421005) (xy 32.064604 -319.548683) (xy 32.133659 -319.680256)
			(xy 32.195552 -319.815347) (xy 32.250105 -319.953564) (xy 32.29716 -320.094511) (xy 32.336582 -320.237781)
			(xy 32.368256 -320.38296) (xy 32.392092 -320.529629) (xy 32.408021 -320.677367) (xy 32.415997 -320.825747)
			(xy 32.416496 -320.900044) (xy 86.882487 -320.900044) (xy 86.886476 -320.751504) (xy 86.898433 -320.603391)
			(xy 86.918323 -320.456134) (xy 86.946088 -320.310158) (xy 86.981649 -320.165881) (xy 87.024903 -320.023722)
			(xy 87.075725 -319.884089) (xy 87.133969 -319.747386) (xy 87.199467 -319.614006) (xy 87.27203 -319.484334)
			(xy 87.351448 -319.358744) (xy 87.437493 -319.237597) (xy 87.529917 -319.121244) (xy 87.628453 -319.01002)
			(xy 87.732817 -318.904245) (xy 87.842709 -318.804225) (xy 87.95781 -318.710247) (xy 88.07779 -318.622583)
			(xy 88.202303 -318.541486) (xy 88.330989 -318.467189) (xy 88.463478 -318.399907) (xy 88.599387 -318.339833)
			(xy 88.738325 -318.287141) (xy 88.879891 -318.241982) (xy 89.023677 -318.204487) (xy 89.169268 -318.174765)
			(xy 89.316244 -318.1529) (xy 89.464183 -318.138956) (xy 89.612656 -318.132972) (xy 89.761237 -318.134967)
			(xy 89.909496 -318.144935) (xy 90.057007 -318.162846) (xy 90.203343 -318.188649) (xy 90.348084 -318.222269)
			(xy 90.490811 -318.263611) (xy 90.631114 -318.312554) (xy 90.768587 -318.368957) (xy 90.902834 -318.432658)
			(xy 91.033469 -318.503474) (xy 91.160114 -318.581199) (xy 91.282404 -318.66561) (xy 91.399987 -318.756463)
			(xy 91.512524 -318.853497) (xy 91.619691 -318.956432) (xy 91.721178 -319.064971) (xy 91.816692 -319.1788)
			(xy 91.905959 -319.297593) (xy 91.98872 -319.421005) (xy 92.064738 -319.548683) (xy 92.133793 -319.680256)
			(xy 92.195686 -319.815347) (xy 92.250239 -319.953564) (xy 92.297294 -320.094511) (xy 92.336716 -320.237781)
			(xy 92.36839 -320.38296) (xy 92.392226 -320.529629) (xy 92.408155 -320.677367) (xy 92.416131 -320.825747)
			(xy 92.41663 -320.900044) (xy 142.982451 -320.900044) (xy 142.98644 -320.751504) (xy 142.998397 -320.603391)
			(xy 143.018287 -320.456134) (xy 143.046052 -320.310158) (xy 143.081613 -320.165881) (xy 143.124867 -320.023722)
			(xy 143.175689 -319.884089) (xy 143.233933 -319.747386) (xy 143.299431 -319.614006) (xy 143.371994 -319.484334)
			(xy 143.451412 -319.358744) (xy 143.537457 -319.237597) (xy 143.629881 -319.121244) (xy 143.728417 -319.01002)
			(xy 143.832781 -318.904245) (xy 143.942673 -318.804225) (xy 144.057774 -318.710247) (xy 144.177754 -318.622583)
			(xy 144.302267 -318.541486) (xy 144.430953 -318.467189) (xy 144.563442 -318.399907) (xy 144.699351 -318.339833)
			(xy 144.838289 -318.287141) (xy 144.979855 -318.241982) (xy 145.123641 -318.204487) (xy 145.269232 -318.174765)
			(xy 145.416208 -318.1529) (xy 145.564147 -318.138956) (xy 145.71262 -318.132972) (xy 145.861201 -318.134967)
			(xy 146.00946 -318.144935) (xy 146.156971 -318.162846) (xy 146.303307 -318.188649) (xy 146.448048 -318.222269)
			(xy 146.590775 -318.263611) (xy 146.731078 -318.312554) (xy 146.868551 -318.368957) (xy 147.002798 -318.432658)
			(xy 147.133433 -318.503474) (xy 147.260078 -318.581199) (xy 147.382368 -318.66561) (xy 147.426741 -318.699896)
			(xy 154.54428 -318.699896) (xy 154.54824 -318.650842) (xy 154.560017 -318.603058) (xy 154.579308 -318.557782)
			(xy 154.605611 -318.516186) (xy 154.638246 -318.479349) (xy 154.676367 -318.448224) (xy 154.718988 -318.423617)
			(xy 154.765004 -318.406165) (xy 154.813223 -318.396321) (xy 154.862398 -318.39434) (xy 154.911253 -318.400272)
			(xy 154.958524 -318.413964) (xy 155.002986 -318.435062) (xy 155.043489 -318.463018) (xy 155.078982 -318.49711)
			(xy 155.108547 -318.536454) (xy 155.131418 -318.580031) (xy 155.147002 -318.626712) (xy 155.154897 -318.675289)
			(xy 155.155392 -318.699896) (xy 156.4442 -318.699896) (xy 156.44816 -318.650842) (xy 156.459937 -318.603058)
			(xy 156.479228 -318.557782) (xy 156.505531 -318.516186) (xy 156.538166 -318.479349) (xy 156.576287 -318.448224)
			(xy 156.618908 -318.423617) (xy 156.664924 -318.406165) (xy 156.713143 -318.396321) (xy 156.762318 -318.39434)
			(xy 156.811173 -318.400272) (xy 156.858444 -318.413964) (xy 156.902906 -318.435062) (xy 156.943409 -318.463018)
			(xy 156.978902 -318.49711) (xy 157.008467 -318.536454) (xy 157.031338 -318.580031) (xy 157.046922 -318.626712)
			(xy 157.054817 -318.675289) (xy 157.055312 -318.699896) (xy 158.34412 -318.699896) (xy 158.34808 -318.650842)
			(xy 158.359857 -318.603058) (xy 158.379148 -318.557782) (xy 158.405451 -318.516186) (xy 158.438086 -318.479349)
			(xy 158.476207 -318.448224) (xy 158.518828 -318.423617) (xy 158.564844 -318.406165) (xy 158.613063 -318.396321)
			(xy 158.662238 -318.39434) (xy 158.711093 -318.400272) (xy 158.758364 -318.413964) (xy 158.802826 -318.435062)
			(xy 158.843329 -318.463018) (xy 158.878822 -318.49711) (xy 158.908387 -318.536454) (xy 158.931258 -318.580031)
			(xy 158.946842 -318.626712) (xy 158.954737 -318.675289) (xy 158.955232 -318.699896) (xy 160.24404 -318.699896)
			(xy 160.248 -318.650842) (xy 160.259777 -318.603058) (xy 160.279068 -318.557782) (xy 160.305371 -318.516186)
			(xy 160.338006 -318.479349) (xy 160.376127 -318.448224) (xy 160.418748 -318.423617) (xy 160.464764 -318.406165)
			(xy 160.512983 -318.396321) (xy 160.562158 -318.39434) (xy 160.611013 -318.400272) (xy 160.658284 -318.413964)
			(xy 160.702746 -318.435062) (xy 160.743249 -318.463018) (xy 160.778742 -318.49711) (xy 160.808307 -318.536454)
			(xy 160.831178 -318.580031) (xy 160.846762 -318.626712) (xy 160.854657 -318.675289) (xy 160.855152 -318.699896)
			(xy 162.144214 -318.699896) (xy 162.148174 -318.650842) (xy 162.159951 -318.603058) (xy 162.179242 -318.557782)
			(xy 162.205545 -318.516186) (xy 162.23818 -318.479349) (xy 162.276301 -318.448224) (xy 162.318922 -318.423617)
			(xy 162.364938 -318.406165) (xy 162.413157 -318.396321) (xy 162.462332 -318.39434) (xy 162.511187 -318.400272)
			(xy 162.558458 -318.413964) (xy 162.60292 -318.435062) (xy 162.643423 -318.463018) (xy 162.678916 -318.49711)
			(xy 162.708481 -318.536454) (xy 162.731352 -318.580031) (xy 162.746936 -318.626712) (xy 162.754831 -318.675289)
			(xy 162.755326 -318.699896) (xy 164.044134 -318.699896) (xy 164.048094 -318.650842) (xy 164.059871 -318.603058)
			(xy 164.079162 -318.557782) (xy 164.105465 -318.516186) (xy 164.1381 -318.479349) (xy 164.176221 -318.448224)
			(xy 164.218842 -318.423617) (xy 164.264858 -318.406165) (xy 164.313077 -318.396321) (xy 164.362252 -318.39434)
			(xy 164.411107 -318.400272) (xy 164.458378 -318.413964) (xy 164.50284 -318.435062) (xy 164.543343 -318.463018)
			(xy 164.578836 -318.49711) (xy 164.608401 -318.536454) (xy 164.631272 -318.580031) (xy 164.646856 -318.626712)
			(xy 164.654751 -318.675289) (xy 164.655246 -318.699896) (xy 165.944054 -318.699896) (xy 165.948014 -318.650842)
			(xy 165.959791 -318.603058) (xy 165.979082 -318.557782) (xy 166.005385 -318.516186) (xy 166.03802 -318.479349)
			(xy 166.076141 -318.448224) (xy 166.118762 -318.423617) (xy 166.164778 -318.406165) (xy 166.212997 -318.396321)
			(xy 166.262172 -318.39434) (xy 166.311027 -318.400272) (xy 166.358298 -318.413964) (xy 166.40276 -318.435062)
			(xy 166.443263 -318.463018) (xy 166.478756 -318.49711) (xy 166.508321 -318.536454) (xy 166.531192 -318.580031)
			(xy 166.546776 -318.626712) (xy 166.554671 -318.675289) (xy 166.555166 -318.699896) (xy 167.844228 -318.699896)
			(xy 167.848188 -318.650842) (xy 167.859965 -318.603058) (xy 167.879256 -318.557782) (xy 167.905559 -318.516186)
			(xy 167.938194 -318.479349) (xy 167.976315 -318.448224) (xy 168.018936 -318.423617) (xy 168.064952 -318.406165)
			(xy 168.113171 -318.396321) (xy 168.162346 -318.39434) (xy 168.211201 -318.400272) (xy 168.258472 -318.413964)
			(xy 168.302934 -318.435062) (xy 168.343437 -318.463018) (xy 168.37893 -318.49711) (xy 168.408495 -318.536454)
			(xy 168.431366 -318.580031) (xy 168.44695 -318.626712) (xy 168.454845 -318.675289) (xy 168.45534 -318.699896)
			(xy 169.744148 -318.699896) (xy 169.748108 -318.650842) (xy 169.759885 -318.603058) (xy 169.779176 -318.557782)
			(xy 169.805479 -318.516186) (xy 169.838114 -318.479349) (xy 169.876235 -318.448224) (xy 169.918856 -318.423617)
			(xy 169.964872 -318.406165) (xy 170.013091 -318.396321) (xy 170.062266 -318.39434) (xy 170.111121 -318.400272)
			(xy 170.158392 -318.413964) (xy 170.202854 -318.435062) (xy 170.243357 -318.463018) (xy 170.27885 -318.49711)
			(xy 170.308415 -318.536454) (xy 170.331286 -318.580031) (xy 170.34687 -318.626712) (xy 170.354765 -318.675289)
			(xy 170.35526 -318.699896) (xy 171.644068 -318.699896) (xy 171.648028 -318.650842) (xy 171.659805 -318.603058)
			(xy 171.679096 -318.557782) (xy 171.705399 -318.516186) (xy 171.738034 -318.479349) (xy 171.776155 -318.448224)
			(xy 171.818776 -318.423617) (xy 171.864792 -318.406165) (xy 171.913011 -318.396321) (xy 171.962186 -318.39434)
			(xy 172.011041 -318.400272) (xy 172.058312 -318.413964) (xy 172.102774 -318.435062) (xy 172.143277 -318.463018)
			(xy 172.17877 -318.49711) (xy 172.208335 -318.536454) (xy 172.231206 -318.580031) (xy 172.24679 -318.626712)
			(xy 172.254685 -318.675289) (xy 172.25518 -318.699896) (xy 173.544242 -318.699896) (xy 173.548202 -318.650842)
			(xy 173.559979 -318.603058) (xy 173.57927 -318.557782) (xy 173.605573 -318.516186) (xy 173.638208 -318.479349)
			(xy 173.676329 -318.448224) (xy 173.71895 -318.423617) (xy 173.764966 -318.406165) (xy 173.813185 -318.396321)
			(xy 173.86236 -318.39434) (xy 173.911215 -318.400272) (xy 173.958486 -318.413964) (xy 174.002948 -318.435062)
			(xy 174.043451 -318.463018) (xy 174.078944 -318.49711) (xy 174.108509 -318.536454) (xy 174.13138 -318.580031)
			(xy 174.146964 -318.626712) (xy 174.154859 -318.675289) (xy 174.155354 -318.699896) (xy 175.444162 -318.699896)
			(xy 175.448122 -318.650842) (xy 175.459899 -318.603058) (xy 175.47919 -318.557782) (xy 175.505493 -318.516186)
			(xy 175.538128 -318.479349) (xy 175.576249 -318.448224) (xy 175.61887 -318.423617) (xy 175.664886 -318.406165)
			(xy 175.713105 -318.396321) (xy 175.76228 -318.39434) (xy 175.811135 -318.400272) (xy 175.858406 -318.413964)
			(xy 175.902868 -318.435062) (xy 175.943371 -318.463018) (xy 175.978864 -318.49711) (xy 176.008429 -318.536454)
			(xy 176.0313 -318.580031) (xy 176.046884 -318.626712) (xy 176.054779 -318.675289) (xy 176.055274 -318.699896)
			(xy 177.344082 -318.699896) (xy 177.348042 -318.650842) (xy 177.359819 -318.603058) (xy 177.37911 -318.557782)
			(xy 177.405413 -318.516186) (xy 177.438048 -318.479349) (xy 177.476169 -318.448224) (xy 177.51879 -318.423617)
			(xy 177.564806 -318.406165) (xy 177.613025 -318.396321) (xy 177.6622 -318.39434) (xy 177.711055 -318.400272)
			(xy 177.758326 -318.413964) (xy 177.802788 -318.435062) (xy 177.843291 -318.463018) (xy 177.878784 -318.49711)
			(xy 177.908349 -318.536454) (xy 177.93122 -318.580031) (xy 177.946804 -318.626712) (xy 177.954699 -318.675289)
			(xy 177.955194 -318.699896) (xy 179.244256 -318.699896) (xy 179.248216 -318.650842) (xy 179.259993 -318.603058)
			(xy 179.279284 -318.557782) (xy 179.305587 -318.516186) (xy 179.338222 -318.479349) (xy 179.376343 -318.448224)
			(xy 179.418964 -318.423617) (xy 179.46498 -318.406165) (xy 179.513199 -318.396321) (xy 179.562374 -318.39434)
			(xy 179.611229 -318.400272) (xy 179.6585 -318.413964) (xy 179.702962 -318.435062) (xy 179.743465 -318.463018)
			(xy 179.778958 -318.49711) (xy 179.808523 -318.536454) (xy 179.831394 -318.580031) (xy 179.846978 -318.626712)
			(xy 179.854873 -318.675289) (xy 179.855368 -318.699896) (xy 181.144176 -318.699896) (xy 181.148136 -318.650842)
			(xy 181.159913 -318.603058) (xy 181.179204 -318.557782) (xy 181.205507 -318.516186) (xy 181.238142 -318.479349)
			(xy 181.276263 -318.448224) (xy 181.318884 -318.423617) (xy 181.3649 -318.406165) (xy 181.413119 -318.396321)
			(xy 181.462294 -318.39434) (xy 181.511149 -318.400272) (xy 181.55842 -318.413964) (xy 181.602882 -318.435062)
			(xy 181.643385 -318.463018) (xy 181.678878 -318.49711) (xy 181.708443 -318.536454) (xy 181.731314 -318.580031)
			(xy 181.746898 -318.626712) (xy 181.754793 -318.675289) (xy 181.755288 -318.699896) (xy 183.044096 -318.699896)
			(xy 183.048056 -318.650842) (xy 183.059833 -318.603058) (xy 183.079124 -318.557782) (xy 183.105427 -318.516186)
			(xy 183.138062 -318.479349) (xy 183.176183 -318.448224) (xy 183.218804 -318.423617) (xy 183.26482 -318.406165)
			(xy 183.313039 -318.396321) (xy 183.362214 -318.39434) (xy 183.411069 -318.400272) (xy 183.45834 -318.413964)
			(xy 183.502802 -318.435062) (xy 183.543305 -318.463018) (xy 183.578798 -318.49711) (xy 183.608363 -318.536454)
			(xy 183.631234 -318.580031) (xy 183.646818 -318.626712) (xy 183.654713 -318.675289) (xy 183.655208 -318.699896)
			(xy 184.94427 -318.699896) (xy 184.94823 -318.650842) (xy 184.960007 -318.603058) (xy 184.979298 -318.557782)
			(xy 185.005601 -318.516186) (xy 185.038236 -318.479349) (xy 185.076357 -318.448224) (xy 185.118978 -318.423617)
			(xy 185.164994 -318.406165) (xy 185.213213 -318.396321) (xy 185.262388 -318.39434) (xy 185.311243 -318.400272)
			(xy 185.358514 -318.413964) (xy 185.402976 -318.435062) (xy 185.443479 -318.463018) (xy 185.478972 -318.49711)
			(xy 185.508537 -318.536454) (xy 185.531408 -318.580031) (xy 185.546992 -318.626712) (xy 185.554887 -318.675289)
			(xy 185.555382 -318.699896) (xy 186.84419 -318.699896) (xy 186.84815 -318.650842) (xy 186.859927 -318.603058)
			(xy 186.879218 -318.557782) (xy 186.905521 -318.516186) (xy 186.938156 -318.479349) (xy 186.976277 -318.448224)
			(xy 187.018898 -318.423617) (xy 187.064914 -318.406165) (xy 187.113133 -318.396321) (xy 187.162308 -318.39434)
			(xy 187.211163 -318.400272) (xy 187.258434 -318.413964) (xy 187.302896 -318.435062) (xy 187.343399 -318.463018)
			(xy 187.378892 -318.49711) (xy 187.408457 -318.536454) (xy 187.431328 -318.580031) (xy 187.446912 -318.626712)
			(xy 187.454807 -318.675289) (xy 187.455302 -318.699896) (xy 188.74411 -318.699896) (xy 188.74807 -318.650842)
			(xy 188.759847 -318.603058) (xy 188.779138 -318.557782) (xy 188.805441 -318.516186) (xy 188.838076 -318.479349)
			(xy 188.876197 -318.448224) (xy 188.918818 -318.423617) (xy 188.964834 -318.406165) (xy 189.013053 -318.396321)
			(xy 189.062228 -318.39434) (xy 189.111083 -318.400272) (xy 189.158354 -318.413964) (xy 189.202816 -318.435062)
			(xy 189.243319 -318.463018) (xy 189.278812 -318.49711) (xy 189.308377 -318.536454) (xy 189.331248 -318.580031)
			(xy 189.346832 -318.626712) (xy 189.354727 -318.675289) (xy 189.355222 -318.699896) (xy 190.644284 -318.699896)
			(xy 190.648244 -318.650842) (xy 190.660021 -318.603058) (xy 190.679312 -318.557782) (xy 190.705615 -318.516186)
			(xy 190.73825 -318.479349) (xy 190.776371 -318.448224) (xy 190.818992 -318.423617) (xy 190.865008 -318.406165)
			(xy 190.913227 -318.396321) (xy 190.962402 -318.39434) (xy 191.011257 -318.400272) (xy 191.058528 -318.413964)
			(xy 191.10299 -318.435062) (xy 191.143493 -318.463018) (xy 191.178986 -318.49711) (xy 191.208551 -318.536454)
			(xy 191.231422 -318.580031) (xy 191.247006 -318.626712) (xy 191.254901 -318.675289) (xy 191.255396 -318.699896)
			(xy 192.544204 -318.699896) (xy 192.548164 -318.650842) (xy 192.559941 -318.603058) (xy 192.579232 -318.557782)
			(xy 192.605535 -318.516186) (xy 192.63817 -318.479349) (xy 192.676291 -318.448224) (xy 192.718912 -318.423617)
			(xy 192.764928 -318.406165) (xy 192.813147 -318.396321) (xy 192.862322 -318.39434) (xy 192.911177 -318.400272)
			(xy 192.958448 -318.413964) (xy 193.00291 -318.435062) (xy 193.043413 -318.463018) (xy 193.078906 -318.49711)
			(xy 193.108471 -318.536454) (xy 193.131342 -318.580031) (xy 193.146926 -318.626712) (xy 193.154821 -318.675289)
			(xy 193.155316 -318.699896) (xy 194.444124 -318.699896) (xy 194.448084 -318.650842) (xy 194.459861 -318.603058)
			(xy 194.479152 -318.557782) (xy 194.505455 -318.516186) (xy 194.53809 -318.479349) (xy 194.576211 -318.448224)
			(xy 194.618832 -318.423617) (xy 194.664848 -318.406165) (xy 194.713067 -318.396321) (xy 194.762242 -318.39434)
			(xy 194.811097 -318.400272) (xy 194.858368 -318.413964) (xy 194.90283 -318.435062) (xy 194.943333 -318.463018)
			(xy 194.978826 -318.49711) (xy 195.008391 -318.536454) (xy 195.031262 -318.580031) (xy 195.046846 -318.626712)
			(xy 195.054741 -318.675289) (xy 195.055236 -318.699896) (xy 196.344044 -318.699896) (xy 196.348004 -318.650842)
			(xy 196.359781 -318.603058) (xy 196.379072 -318.557782) (xy 196.405375 -318.516186) (xy 196.43801 -318.479349)
			(xy 196.476131 -318.448224) (xy 196.518752 -318.423617) (xy 196.564768 -318.406165) (xy 196.612987 -318.396321)
			(xy 196.662162 -318.39434) (xy 196.711017 -318.400272) (xy 196.758288 -318.413964) (xy 196.80275 -318.435062)
			(xy 196.843253 -318.463018) (xy 196.878746 -318.49711) (xy 196.908311 -318.536454) (xy 196.931182 -318.580031)
			(xy 196.946766 -318.626712) (xy 196.954661 -318.675289) (xy 196.955156 -318.699896) (xy 196.954661 -318.724503)
			(xy 196.946766 -318.77308) (xy 196.931182 -318.819761) (xy 196.908311 -318.863338) (xy 196.878746 -318.902682)
			(xy 196.843253 -318.936774) (xy 196.80275 -318.96473) (xy 196.758288 -318.985828) (xy 196.711017 -318.99952)
			(xy 196.662162 -319.005452) (xy 196.612987 -319.003471) (xy 196.564768 -318.993627) (xy 196.518752 -318.976175)
			(xy 196.476131 -318.951568) (xy 196.43801 -318.920443) (xy 196.405375 -318.883606) (xy 196.379072 -318.84201)
			(xy 196.359781 -318.796734) (xy 196.348004 -318.74895) (xy 196.344044 -318.699896) (xy 195.055236 -318.699896)
			(xy 195.054741 -318.724503) (xy 195.046846 -318.77308) (xy 195.031262 -318.819761) (xy 195.008391 -318.863338)
			(xy 194.978826 -318.902682) (xy 194.943333 -318.936774) (xy 194.90283 -318.96473) (xy 194.858368 -318.985828)
			(xy 194.811097 -318.99952) (xy 194.762242 -319.005452) (xy 194.713067 -319.003471) (xy 194.664848 -318.993627)
			(xy 194.618832 -318.976175) (xy 194.576211 -318.951568) (xy 194.53809 -318.920443) (xy 194.505455 -318.883606)
			(xy 194.479152 -318.84201) (xy 194.459861 -318.796734) (xy 194.448084 -318.74895) (xy 194.444124 -318.699896)
			(xy 193.155316 -318.699896) (xy 193.154821 -318.724503) (xy 193.146926 -318.77308) (xy 193.131342 -318.819761)
			(xy 193.108471 -318.863338) (xy 193.078906 -318.902682) (xy 193.043413 -318.936774) (xy 193.00291 -318.96473)
			(xy 192.958448 -318.985828) (xy 192.911177 -318.99952) (xy 192.862322 -319.005452) (xy 192.813147 -319.003471)
			(xy 192.764928 -318.993627) (xy 192.718912 -318.976175) (xy 192.676291 -318.951568) (xy 192.63817 -318.920443)
			(xy 192.605535 -318.883606) (xy 192.579232 -318.84201) (xy 192.559941 -318.796734) (xy 192.548164 -318.74895)
			(xy 192.544204 -318.699896) (xy 191.255396 -318.699896) (xy 191.254901 -318.724503) (xy 191.247006 -318.77308)
			(xy 191.231422 -318.819761) (xy 191.208551 -318.863338) (xy 191.178986 -318.902682) (xy 191.143493 -318.936774)
			(xy 191.10299 -318.96473) (xy 191.058528 -318.985828) (xy 191.011257 -318.99952) (xy 190.962402 -319.005452)
			(xy 190.913227 -319.003471) (xy 190.865008 -318.993627) (xy 190.818992 -318.976175) (xy 190.776371 -318.951568)
			(xy 190.73825 -318.920443) (xy 190.705615 -318.883606) (xy 190.679312 -318.84201) (xy 190.660021 -318.796734)
			(xy 190.648244 -318.74895) (xy 190.644284 -318.699896) (xy 189.355222 -318.699896) (xy 189.354727 -318.724503)
			(xy 189.346832 -318.77308) (xy 189.331248 -318.819761) (xy 189.308377 -318.863338) (xy 189.278812 -318.902682)
			(xy 189.243319 -318.936774) (xy 189.202816 -318.96473) (xy 189.158354 -318.985828) (xy 189.111083 -318.99952)
			(xy 189.062228 -319.005452) (xy 189.013053 -319.003471) (xy 188.964834 -318.993627) (xy 188.918818 -318.976175)
			(xy 188.876197 -318.951568) (xy 188.838076 -318.920443) (xy 188.805441 -318.883606) (xy 188.779138 -318.84201)
			(xy 188.759847 -318.796734) (xy 188.74807 -318.74895) (xy 188.74411 -318.699896) (xy 187.455302 -318.699896)
			(xy 187.454807 -318.724503) (xy 187.446912 -318.77308) (xy 187.431328 -318.819761) (xy 187.408457 -318.863338)
			(xy 187.378892 -318.902682) (xy 187.343399 -318.936774) (xy 187.302896 -318.96473) (xy 187.258434 -318.985828)
			(xy 187.211163 -318.99952) (xy 187.162308 -319.005452) (xy 187.113133 -319.003471) (xy 187.064914 -318.993627)
			(xy 187.018898 -318.976175) (xy 186.976277 -318.951568) (xy 186.938156 -318.920443) (xy 186.905521 -318.883606)
			(xy 186.879218 -318.84201) (xy 186.859927 -318.796734) (xy 186.84815 -318.74895) (xy 186.84419 -318.699896)
			(xy 185.555382 -318.699896) (xy 185.554887 -318.724503) (xy 185.546992 -318.77308) (xy 185.531408 -318.819761)
			(xy 185.508537 -318.863338) (xy 185.478972 -318.902682) (xy 185.443479 -318.936774) (xy 185.402976 -318.96473)
			(xy 185.358514 -318.985828) (xy 185.311243 -318.99952) (xy 185.262388 -319.005452) (xy 185.213213 -319.003471)
			(xy 185.164994 -318.993627) (xy 185.118978 -318.976175) (xy 185.076357 -318.951568) (xy 185.038236 -318.920443)
			(xy 185.005601 -318.883606) (xy 184.979298 -318.84201) (xy 184.960007 -318.796734) (xy 184.94823 -318.74895)
			(xy 184.94427 -318.699896) (xy 183.655208 -318.699896) (xy 183.654713 -318.724503) (xy 183.646818 -318.77308)
			(xy 183.631234 -318.819761) (xy 183.608363 -318.863338) (xy 183.578798 -318.902682) (xy 183.543305 -318.936774)
			(xy 183.502802 -318.96473) (xy 183.45834 -318.985828) (xy 183.411069 -318.99952) (xy 183.362214 -319.005452)
			(xy 183.313039 -319.003471) (xy 183.26482 -318.993627) (xy 183.218804 -318.976175) (xy 183.176183 -318.951568)
			(xy 183.138062 -318.920443) (xy 183.105427 -318.883606) (xy 183.079124 -318.84201) (xy 183.059833 -318.796734)
			(xy 183.048056 -318.74895) (xy 183.044096 -318.699896) (xy 181.755288 -318.699896) (xy 181.754793 -318.724503)
			(xy 181.746898 -318.77308) (xy 181.731314 -318.819761) (xy 181.708443 -318.863338) (xy 181.678878 -318.902682)
			(xy 181.643385 -318.936774) (xy 181.602882 -318.96473) (xy 181.55842 -318.985828) (xy 181.511149 -318.99952)
			(xy 181.462294 -319.005452) (xy 181.413119 -319.003471) (xy 181.3649 -318.993627) (xy 181.318884 -318.976175)
			(xy 181.276263 -318.951568) (xy 181.238142 -318.920443) (xy 181.205507 -318.883606) (xy 181.179204 -318.84201)
			(xy 181.159913 -318.796734) (xy 181.148136 -318.74895) (xy 181.144176 -318.699896) (xy 179.855368 -318.699896)
			(xy 179.854873 -318.724503) (xy 179.846978 -318.77308) (xy 179.831394 -318.819761) (xy 179.808523 -318.863338)
			(xy 179.778958 -318.902682) (xy 179.743465 -318.936774) (xy 179.702962 -318.96473) (xy 179.6585 -318.985828)
			(xy 179.611229 -318.99952) (xy 179.562374 -319.005452) (xy 179.513199 -319.003471) (xy 179.46498 -318.993627)
			(xy 179.418964 -318.976175) (xy 179.376343 -318.951568) (xy 179.338222 -318.920443) (xy 179.305587 -318.883606)
			(xy 179.279284 -318.84201) (xy 179.259993 -318.796734) (xy 179.248216 -318.74895) (xy 179.244256 -318.699896)
			(xy 177.955194 -318.699896) (xy 177.954699 -318.724503) (xy 177.946804 -318.77308) (xy 177.93122 -318.819761)
			(xy 177.908349 -318.863338) (xy 177.878784 -318.902682) (xy 177.843291 -318.936774) (xy 177.802788 -318.96473)
			(xy 177.758326 -318.985828) (xy 177.711055 -318.99952) (xy 177.6622 -319.005452) (xy 177.613025 -319.003471)
			(xy 177.564806 -318.993627) (xy 177.51879 -318.976175) (xy 177.476169 -318.951568) (xy 177.438048 -318.920443)
			(xy 177.405413 -318.883606) (xy 177.37911 -318.84201) (xy 177.359819 -318.796734) (xy 177.348042 -318.74895)
			(xy 177.344082 -318.699896) (xy 176.055274 -318.699896) (xy 176.054779 -318.724503) (xy 176.046884 -318.77308)
			(xy 176.0313 -318.819761) (xy 176.008429 -318.863338) (xy 175.978864 -318.902682) (xy 175.943371 -318.936774)
			(xy 175.902868 -318.96473) (xy 175.858406 -318.985828) (xy 175.811135 -318.99952) (xy 175.76228 -319.005452)
			(xy 175.713105 -319.003471) (xy 175.664886 -318.993627) (xy 175.61887 -318.976175) (xy 175.576249 -318.951568)
			(xy 175.538128 -318.920443) (xy 175.505493 -318.883606) (xy 175.47919 -318.84201) (xy 175.459899 -318.796734)
			(xy 175.448122 -318.74895) (xy 175.444162 -318.699896) (xy 174.155354 -318.699896) (xy 174.154859 -318.724503)
			(xy 174.146964 -318.77308) (xy 174.13138 -318.819761) (xy 174.108509 -318.863338) (xy 174.078944 -318.902682)
			(xy 174.043451 -318.936774) (xy 174.002948 -318.96473) (xy 173.958486 -318.985828) (xy 173.911215 -318.99952)
			(xy 173.86236 -319.005452) (xy 173.813185 -319.003471) (xy 173.764966 -318.993627) (xy 173.71895 -318.976175)
			(xy 173.676329 -318.951568) (xy 173.638208 -318.920443) (xy 173.605573 -318.883606) (xy 173.57927 -318.84201)
			(xy 173.559979 -318.796734) (xy 173.548202 -318.74895) (xy 173.544242 -318.699896) (xy 172.25518 -318.699896)
			(xy 172.254685 -318.724503) (xy 172.24679 -318.77308) (xy 172.231206 -318.819761) (xy 172.208335 -318.863338)
			(xy 172.17877 -318.902682) (xy 172.143277 -318.936774) (xy 172.102774 -318.96473) (xy 172.058312 -318.985828)
			(xy 172.011041 -318.99952) (xy 171.962186 -319.005452) (xy 171.913011 -319.003471) (xy 171.864792 -318.993627)
			(xy 171.818776 -318.976175) (xy 171.776155 -318.951568) (xy 171.738034 -318.920443) (xy 171.705399 -318.883606)
			(xy 171.679096 -318.84201) (xy 171.659805 -318.796734) (xy 171.648028 -318.74895) (xy 171.644068 -318.699896)
			(xy 170.35526 -318.699896) (xy 170.354765 -318.724503) (xy 170.34687 -318.77308) (xy 170.331286 -318.819761)
			(xy 170.308415 -318.863338) (xy 170.27885 -318.902682) (xy 170.243357 -318.936774) (xy 170.202854 -318.96473)
			(xy 170.158392 -318.985828) (xy 170.111121 -318.99952) (xy 170.062266 -319.005452) (xy 170.013091 -319.003471)
			(xy 169.964872 -318.993627) (xy 169.918856 -318.976175) (xy 169.876235 -318.951568) (xy 169.838114 -318.920443)
			(xy 169.805479 -318.883606) (xy 169.779176 -318.84201) (xy 169.759885 -318.796734) (xy 169.748108 -318.74895)
			(xy 169.744148 -318.699896) (xy 168.45534 -318.699896) (xy 168.454845 -318.724503) (xy 168.44695 -318.77308)
			(xy 168.431366 -318.819761) (xy 168.408495 -318.863338) (xy 168.37893 -318.902682) (xy 168.343437 -318.936774)
			(xy 168.302934 -318.96473) (xy 168.258472 -318.985828) (xy 168.211201 -318.99952) (xy 168.162346 -319.005452)
			(xy 168.113171 -319.003471) (xy 168.064952 -318.993627) (xy 168.018936 -318.976175) (xy 167.976315 -318.951568)
			(xy 167.938194 -318.920443) (xy 167.905559 -318.883606) (xy 167.879256 -318.84201) (xy 167.859965 -318.796734)
			(xy 167.848188 -318.74895) (xy 167.844228 -318.699896) (xy 166.555166 -318.699896) (xy 166.554671 -318.724503)
			(xy 166.546776 -318.77308) (xy 166.531192 -318.819761) (xy 166.508321 -318.863338) (xy 166.478756 -318.902682)
			(xy 166.443263 -318.936774) (xy 166.40276 -318.96473) (xy 166.358298 -318.985828) (xy 166.311027 -318.99952)
			(xy 166.262172 -319.005452) (xy 166.212997 -319.003471) (xy 166.164778 -318.993627) (xy 166.118762 -318.976175)
			(xy 166.076141 -318.951568) (xy 166.03802 -318.920443) (xy 166.005385 -318.883606) (xy 165.979082 -318.84201)
			(xy 165.959791 -318.796734) (xy 165.948014 -318.74895) (xy 165.944054 -318.699896) (xy 164.655246 -318.699896)
			(xy 164.654751 -318.724503) (xy 164.646856 -318.77308) (xy 164.631272 -318.819761) (xy 164.608401 -318.863338)
			(xy 164.578836 -318.902682) (xy 164.543343 -318.936774) (xy 164.50284 -318.96473) (xy 164.458378 -318.985828)
			(xy 164.411107 -318.99952) (xy 164.362252 -319.005452) (xy 164.313077 -319.003471) (xy 164.264858 -318.993627)
			(xy 164.218842 -318.976175) (xy 164.176221 -318.951568) (xy 164.1381 -318.920443) (xy 164.105465 -318.883606)
			(xy 164.079162 -318.84201) (xy 164.059871 -318.796734) (xy 164.048094 -318.74895) (xy 164.044134 -318.699896)
			(xy 162.755326 -318.699896) (xy 162.754831 -318.724503) (xy 162.746936 -318.77308) (xy 162.731352 -318.819761)
			(xy 162.708481 -318.863338) (xy 162.678916 -318.902682) (xy 162.643423 -318.936774) (xy 162.60292 -318.96473)
			(xy 162.558458 -318.985828) (xy 162.511187 -318.99952) (xy 162.462332 -319.005452) (xy 162.413157 -319.003471)
			(xy 162.364938 -318.993627) (xy 162.318922 -318.976175) (xy 162.276301 -318.951568) (xy 162.23818 -318.920443)
			(xy 162.205545 -318.883606) (xy 162.179242 -318.84201) (xy 162.159951 -318.796734) (xy 162.148174 -318.74895)
			(xy 162.144214 -318.699896) (xy 160.855152 -318.699896) (xy 160.854657 -318.724503) (xy 160.846762 -318.77308)
			(xy 160.831178 -318.819761) (xy 160.808307 -318.863338) (xy 160.778742 -318.902682) (xy 160.743249 -318.936774)
			(xy 160.702746 -318.96473) (xy 160.658284 -318.985828) (xy 160.611013 -318.99952) (xy 160.562158 -319.005452)
			(xy 160.512983 -319.003471) (xy 160.464764 -318.993627) (xy 160.418748 -318.976175) (xy 160.376127 -318.951568)
			(xy 160.338006 -318.920443) (xy 160.305371 -318.883606) (xy 160.279068 -318.84201) (xy 160.259777 -318.796734)
			(xy 160.248 -318.74895) (xy 160.24404 -318.699896) (xy 158.955232 -318.699896) (xy 158.954737 -318.724503)
			(xy 158.946842 -318.77308) (xy 158.931258 -318.819761) (xy 158.908387 -318.863338) (xy 158.878822 -318.902682)
			(xy 158.843329 -318.936774) (xy 158.802826 -318.96473) (xy 158.758364 -318.985828) (xy 158.711093 -318.99952)
			(xy 158.662238 -319.005452) (xy 158.613063 -319.003471) (xy 158.564844 -318.993627) (xy 158.518828 -318.976175)
			(xy 158.476207 -318.951568) (xy 158.438086 -318.920443) (xy 158.405451 -318.883606) (xy 158.379148 -318.84201)
			(xy 158.359857 -318.796734) (xy 158.34808 -318.74895) (xy 158.34412 -318.699896) (xy 157.055312 -318.699896)
			(xy 157.054817 -318.724503) (xy 157.046922 -318.77308) (xy 157.031338 -318.819761) (xy 157.008467 -318.863338)
			(xy 156.978902 -318.902682) (xy 156.943409 -318.936774) (xy 156.902906 -318.96473) (xy 156.858444 -318.985828)
			(xy 156.811173 -318.99952) (xy 156.762318 -319.005452) (xy 156.713143 -319.003471) (xy 156.664924 -318.993627)
			(xy 156.618908 -318.976175) (xy 156.576287 -318.951568) (xy 156.538166 -318.920443) (xy 156.505531 -318.883606)
			(xy 156.479228 -318.84201) (xy 156.459937 -318.796734) (xy 156.44816 -318.74895) (xy 156.4442 -318.699896)
			(xy 155.155392 -318.699896) (xy 155.154897 -318.724503) (xy 155.147002 -318.77308) (xy 155.131418 -318.819761)
			(xy 155.108547 -318.863338) (xy 155.078982 -318.902682) (xy 155.043489 -318.936774) (xy 155.002986 -318.96473)
			(xy 154.958524 -318.985828) (xy 154.911253 -318.99952) (xy 154.862398 -319.005452) (xy 154.813223 -319.003471)
			(xy 154.765004 -318.993627) (xy 154.718988 -318.976175) (xy 154.676367 -318.951568) (xy 154.638246 -318.920443)
			(xy 154.605611 -318.883606) (xy 154.579308 -318.84201) (xy 154.560017 -318.796734) (xy 154.54824 -318.74895)
			(xy 154.54428 -318.699896) (xy 147.426741 -318.699896) (xy 147.499951 -318.756463) (xy 147.612488 -318.853497)
			(xy 147.719655 -318.956432) (xy 147.821142 -319.064971) (xy 147.916656 -319.1788) (xy 148.005923 -319.297593)
			(xy 148.088684 -319.421005) (xy 148.164702 -319.548683) (xy 148.233757 -319.680256) (xy 148.29565 -319.815347)
			(xy 148.350203 -319.953564) (xy 148.397258 -320.094511) (xy 148.43668 -320.237781) (xy 148.468354 -320.38296)
			(xy 148.49219 -320.529629) (xy 148.508119 -320.677367) (xy 148.516095 -320.825747) (xy 148.516594 -320.900044)
			(xy 202.982331 -320.900044) (xy 202.98632 -320.751504) (xy 202.998277 -320.603391) (xy 203.018167 -320.456134)
			(xy 203.045932 -320.310158) (xy 203.081493 -320.165881) (xy 203.124747 -320.023722) (xy 203.175569 -319.884089)
			(xy 203.233813 -319.747386) (xy 203.299311 -319.614006) (xy 203.371874 -319.484334) (xy 203.451292 -319.358744)
			(xy 203.537337 -319.237597) (xy 203.629761 -319.121244) (xy 203.728297 -319.01002) (xy 203.832661 -318.904245)
			(xy 203.942553 -318.804225) (xy 204.057654 -318.710247) (xy 204.177634 -318.622583) (xy 204.302147 -318.541486)
			(xy 204.430833 -318.467189) (xy 204.563322 -318.399907) (xy 204.699231 -318.339833) (xy 204.838169 -318.287141)
			(xy 204.979735 -318.241982) (xy 205.123521 -318.204487) (xy 205.269112 -318.174765) (xy 205.416088 -318.1529)
			(xy 205.564027 -318.138956) (xy 205.7125 -318.132972) (xy 205.861081 -318.134967) (xy 206.00934 -318.144935)
			(xy 206.156851 -318.162846) (xy 206.303187 -318.188649) (xy 206.447928 -318.222269) (xy 206.590655 -318.263611)
			(xy 206.730958 -318.312554) (xy 206.868431 -318.368957) (xy 207.002678 -318.432658) (xy 207.133313 -318.503474)
			(xy 207.259958 -318.581199) (xy 207.382248 -318.66561) (xy 207.499831 -318.756463) (xy 207.612368 -318.853497)
			(xy 207.719535 -318.956432) (xy 207.821022 -319.064971) (xy 207.916536 -319.1788) (xy 208.005803 -319.297593)
			(xy 208.088564 -319.421005) (xy 208.164582 -319.548683) (xy 208.233637 -319.680256) (xy 208.29553 -319.815347)
			(xy 208.350083 -319.953564) (xy 208.397138 -320.094511) (xy 208.43656 -320.237781) (xy 208.468234 -320.38296)
			(xy 208.49207 -320.529629) (xy 208.507999 -320.677367) (xy 208.515975 -320.825747) (xy 208.516474 -320.900044)
			(xy 259.082549 -320.900044) (xy 259.086538 -320.751504) (xy 259.098495 -320.603391) (xy 259.118385 -320.456134)
			(xy 259.14615 -320.310158) (xy 259.181711 -320.165881) (xy 259.224965 -320.023722) (xy 259.275787 -319.884089)
			(xy 259.334031 -319.747386) (xy 259.399529 -319.614006) (xy 259.472092 -319.484334) (xy 259.55151 -319.358744)
			(xy 259.637555 -319.237597) (xy 259.729979 -319.121244) (xy 259.828515 -319.01002) (xy 259.932879 -318.904245)
			(xy 260.042771 -318.804225) (xy 260.157872 -318.710247) (xy 260.277852 -318.622583) (xy 260.402365 -318.541486)
			(xy 260.531051 -318.467189) (xy 260.66354 -318.399907) (xy 260.799449 -318.339833) (xy 260.938387 -318.287141)
			(xy 261.079953 -318.241982) (xy 261.223739 -318.204487) (xy 261.36933 -318.174765) (xy 261.516306 -318.1529)
			(xy 261.664245 -318.138956) (xy 261.812718 -318.132972) (xy 261.961299 -318.134967) (xy 262.109558 -318.144935)
			(xy 262.257069 -318.162846) (xy 262.403405 -318.188649) (xy 262.548146 -318.222269) (xy 262.690873 -318.263611)
			(xy 262.831176 -318.312554) (xy 262.968649 -318.368957) (xy 263.102896 -318.432658) (xy 263.233531 -318.503474)
			(xy 263.360176 -318.581199) (xy 263.482466 -318.66561) (xy 263.526839 -318.699896) (xy 270.644124 -318.699896)
			(xy 270.648084 -318.650842) (xy 270.659861 -318.603058) (xy 270.679152 -318.557782) (xy 270.705455 -318.516186)
			(xy 270.73809 -318.479349) (xy 270.776211 -318.448224) (xy 270.818832 -318.423617) (xy 270.864848 -318.406165)
			(xy 270.913067 -318.396321) (xy 270.962242 -318.39434) (xy 271.011097 -318.400272) (xy 271.058368 -318.413964)
			(xy 271.10283 -318.435062) (xy 271.143333 -318.463018) (xy 271.178826 -318.49711) (xy 271.208391 -318.536454)
			(xy 271.231262 -318.580031) (xy 271.246846 -318.626712) (xy 271.254741 -318.675289) (xy 271.255236 -318.699896)
			(xy 272.544044 -318.699896) (xy 272.548004 -318.650842) (xy 272.559781 -318.603058) (xy 272.579072 -318.557782)
			(xy 272.605375 -318.516186) (xy 272.63801 -318.479349) (xy 272.676131 -318.448224) (xy 272.718752 -318.423617)
			(xy 272.764768 -318.406165) (xy 272.812987 -318.396321) (xy 272.862162 -318.39434) (xy 272.911017 -318.400272)
			(xy 272.958288 -318.413964) (xy 273.00275 -318.435062) (xy 273.043253 -318.463018) (xy 273.078746 -318.49711)
			(xy 273.108311 -318.536454) (xy 273.131182 -318.580031) (xy 273.146766 -318.626712) (xy 273.154661 -318.675289)
			(xy 273.155156 -318.699896) (xy 274.443964 -318.699896) (xy 274.447924 -318.650842) (xy 274.459701 -318.603058)
			(xy 274.478992 -318.557782) (xy 274.505295 -318.516186) (xy 274.53793 -318.479349) (xy 274.576051 -318.448224)
			(xy 274.618672 -318.423617) (xy 274.664688 -318.406165) (xy 274.712907 -318.396321) (xy 274.762082 -318.39434)
			(xy 274.810937 -318.400272) (xy 274.858208 -318.413964) (xy 274.90267 -318.435062) (xy 274.943173 -318.463018)
			(xy 274.978666 -318.49711) (xy 275.008231 -318.536454) (xy 275.031102 -318.580031) (xy 275.046686 -318.626712)
			(xy 275.054581 -318.675289) (xy 275.055076 -318.699896) (xy 276.343884 -318.699896) (xy 276.347844 -318.650842)
			(xy 276.359621 -318.603058) (xy 276.378912 -318.557782) (xy 276.405215 -318.516186) (xy 276.43785 -318.479349)
			(xy 276.475971 -318.448224) (xy 276.518592 -318.423617) (xy 276.564608 -318.406165) (xy 276.612827 -318.396321)
			(xy 276.662002 -318.39434) (xy 276.710857 -318.400272) (xy 276.758128 -318.413964) (xy 276.80259 -318.435062)
			(xy 276.843093 -318.463018) (xy 276.878586 -318.49711) (xy 276.908151 -318.536454) (xy 276.931022 -318.580031)
			(xy 276.946606 -318.626712) (xy 276.954501 -318.675289) (xy 276.954996 -318.699896) (xy 278.244058 -318.699896)
			(xy 278.248018 -318.650842) (xy 278.259795 -318.603058) (xy 278.279086 -318.557782) (xy 278.305389 -318.516186)
			(xy 278.338024 -318.479349) (xy 278.376145 -318.448224) (xy 278.418766 -318.423617) (xy 278.464782 -318.406165)
			(xy 278.513001 -318.396321) (xy 278.562176 -318.39434) (xy 278.611031 -318.400272) (xy 278.658302 -318.413964)
			(xy 278.702764 -318.435062) (xy 278.743267 -318.463018) (xy 278.77876 -318.49711) (xy 278.808325 -318.536454)
			(xy 278.831196 -318.580031) (xy 278.84678 -318.626712) (xy 278.854675 -318.675289) (xy 278.85517 -318.699896)
			(xy 280.143978 -318.699896) (xy 280.147938 -318.650842) (xy 280.159715 -318.603058) (xy 280.179006 -318.557782)
			(xy 280.205309 -318.516186) (xy 280.237944 -318.479349) (xy 280.276065 -318.448224) (xy 280.318686 -318.423617)
			(xy 280.364702 -318.406165) (xy 280.412921 -318.396321) (xy 280.462096 -318.39434) (xy 280.510951 -318.400272)
			(xy 280.558222 -318.413964) (xy 280.602684 -318.435062) (xy 280.643187 -318.463018) (xy 280.67868 -318.49711)
			(xy 280.708245 -318.536454) (xy 280.731116 -318.580031) (xy 280.7467 -318.626712) (xy 280.754595 -318.675289)
			(xy 280.75509 -318.699896) (xy 282.043898 -318.699896) (xy 282.047858 -318.650842) (xy 282.059635 -318.603058)
			(xy 282.078926 -318.557782) (xy 282.105229 -318.516186) (xy 282.137864 -318.479349) (xy 282.175985 -318.448224)
			(xy 282.218606 -318.423617) (xy 282.264622 -318.406165) (xy 282.312841 -318.396321) (xy 282.362016 -318.39434)
			(xy 282.410871 -318.400272) (xy 282.458142 -318.413964) (xy 282.502604 -318.435062) (xy 282.543107 -318.463018)
			(xy 282.5786 -318.49711) (xy 282.608165 -318.536454) (xy 282.631036 -318.580031) (xy 282.64662 -318.626712)
			(xy 282.654515 -318.675289) (xy 282.65501 -318.699896) (xy 283.944072 -318.699896) (xy 283.948032 -318.650842)
			(xy 283.959809 -318.603058) (xy 283.9791 -318.557782) (xy 284.005403 -318.516186) (xy 284.038038 -318.479349)
			(xy 284.076159 -318.448224) (xy 284.11878 -318.423617) (xy 284.164796 -318.406165) (xy 284.213015 -318.396321)
			(xy 284.26219 -318.39434) (xy 284.311045 -318.400272) (xy 284.358316 -318.413964) (xy 284.402778 -318.435062)
			(xy 284.443281 -318.463018) (xy 284.478774 -318.49711) (xy 284.508339 -318.536454) (xy 284.53121 -318.580031)
			(xy 284.546794 -318.626712) (xy 284.554689 -318.675289) (xy 284.555184 -318.699896) (xy 285.843992 -318.699896)
			(xy 285.847952 -318.650842) (xy 285.859729 -318.603058) (xy 285.87902 -318.557782) (xy 285.905323 -318.516186)
			(xy 285.937958 -318.479349) (xy 285.976079 -318.448224) (xy 286.0187 -318.423617) (xy 286.064716 -318.406165)
			(xy 286.112935 -318.396321) (xy 286.16211 -318.39434) (xy 286.210965 -318.400272) (xy 286.258236 -318.413964)
			(xy 286.302698 -318.435062) (xy 286.343201 -318.463018) (xy 286.378694 -318.49711) (xy 286.408259 -318.536454)
			(xy 286.43113 -318.580031) (xy 286.446714 -318.626712) (xy 286.454609 -318.675289) (xy 286.455104 -318.699896)
			(xy 287.743912 -318.699896) (xy 287.747872 -318.650842) (xy 287.759649 -318.603058) (xy 287.77894 -318.557782)
			(xy 287.805243 -318.516186) (xy 287.837878 -318.479349) (xy 287.875999 -318.448224) (xy 287.91862 -318.423617)
			(xy 287.964636 -318.406165) (xy 288.012855 -318.396321) (xy 288.06203 -318.39434) (xy 288.110885 -318.400272)
			(xy 288.158156 -318.413964) (xy 288.202618 -318.435062) (xy 288.243121 -318.463018) (xy 288.278614 -318.49711)
			(xy 288.308179 -318.536454) (xy 288.33105 -318.580031) (xy 288.346634 -318.626712) (xy 288.354529 -318.675289)
			(xy 288.355024 -318.699896) (xy 289.644086 -318.699896) (xy 289.648046 -318.650842) (xy 289.659823 -318.603058)
			(xy 289.679114 -318.557782) (xy 289.705417 -318.516186) (xy 289.738052 -318.479349) (xy 289.776173 -318.448224)
			(xy 289.818794 -318.423617) (xy 289.86481 -318.406165) (xy 289.913029 -318.396321) (xy 289.962204 -318.39434)
			(xy 290.011059 -318.400272) (xy 290.05833 -318.413964) (xy 290.102792 -318.435062) (xy 290.143295 -318.463018)
			(xy 290.178788 -318.49711) (xy 290.208353 -318.536454) (xy 290.231224 -318.580031) (xy 290.246808 -318.626712)
			(xy 290.254703 -318.675289) (xy 290.255198 -318.699896) (xy 291.544006 -318.699896) (xy 291.547966 -318.650842)
			(xy 291.559743 -318.603058) (xy 291.579034 -318.557782) (xy 291.605337 -318.516186) (xy 291.637972 -318.479349)
			(xy 291.676093 -318.448224) (xy 291.718714 -318.423617) (xy 291.76473 -318.406165) (xy 291.812949 -318.396321)
			(xy 291.862124 -318.39434) (xy 291.910979 -318.400272) (xy 291.95825 -318.413964) (xy 292.002712 -318.435062)
			(xy 292.043215 -318.463018) (xy 292.078708 -318.49711) (xy 292.108273 -318.536454) (xy 292.131144 -318.580031)
			(xy 292.146728 -318.626712) (xy 292.154623 -318.675289) (xy 292.155118 -318.699896) (xy 293.443926 -318.699896)
			(xy 293.447886 -318.650842) (xy 293.459663 -318.603058) (xy 293.478954 -318.557782) (xy 293.505257 -318.516186)
			(xy 293.537892 -318.479349) (xy 293.576013 -318.448224) (xy 293.618634 -318.423617) (xy 293.66465 -318.406165)
			(xy 293.712869 -318.396321) (xy 293.762044 -318.39434) (xy 293.810899 -318.400272) (xy 293.85817 -318.413964)
			(xy 293.902632 -318.435062) (xy 293.943135 -318.463018) (xy 293.978628 -318.49711) (xy 294.008193 -318.536454)
			(xy 294.031064 -318.580031) (xy 294.046648 -318.626712) (xy 294.054543 -318.675289) (xy 294.055038 -318.699896)
			(xy 295.3441 -318.699896) (xy 295.34806 -318.650842) (xy 295.359837 -318.603058) (xy 295.379128 -318.557782)
			(xy 295.405431 -318.516186) (xy 295.438066 -318.479349) (xy 295.476187 -318.448224) (xy 295.518808 -318.423617)
			(xy 295.564824 -318.406165) (xy 295.613043 -318.396321) (xy 295.662218 -318.39434) (xy 295.711073 -318.400272)
			(xy 295.758344 -318.413964) (xy 295.802806 -318.435062) (xy 295.843309 -318.463018) (xy 295.878802 -318.49711)
			(xy 295.908367 -318.536454) (xy 295.931238 -318.580031) (xy 295.946822 -318.626712) (xy 295.954717 -318.675289)
			(xy 295.955212 -318.699896) (xy 297.24402 -318.699896) (xy 297.24798 -318.650842) (xy 297.259757 -318.603058)
			(xy 297.279048 -318.557782) (xy 297.305351 -318.516186) (xy 297.337986 -318.479349) (xy 297.376107 -318.448224)
			(xy 297.418728 -318.423617) (xy 297.464744 -318.406165) (xy 297.512963 -318.396321) (xy 297.562138 -318.39434)
			(xy 297.610993 -318.400272) (xy 297.658264 -318.413964) (xy 297.702726 -318.435062) (xy 297.743229 -318.463018)
			(xy 297.778722 -318.49711) (xy 297.808287 -318.536454) (xy 297.831158 -318.580031) (xy 297.846742 -318.626712)
			(xy 297.854637 -318.675289) (xy 297.855132 -318.699896) (xy 299.14394 -318.699896) (xy 299.1479 -318.650842)
			(xy 299.159677 -318.603058) (xy 299.178968 -318.557782) (xy 299.205271 -318.516186) (xy 299.237906 -318.479349)
			(xy 299.276027 -318.448224) (xy 299.318648 -318.423617) (xy 299.364664 -318.406165) (xy 299.412883 -318.396321)
			(xy 299.462058 -318.39434) (xy 299.510913 -318.400272) (xy 299.558184 -318.413964) (xy 299.602646 -318.435062)
			(xy 299.643149 -318.463018) (xy 299.678642 -318.49711) (xy 299.708207 -318.536454) (xy 299.731078 -318.580031)
			(xy 299.746662 -318.626712) (xy 299.754557 -318.675289) (xy 299.755052 -318.699896) (xy 301.044114 -318.699896)
			(xy 301.048074 -318.650842) (xy 301.059851 -318.603058) (xy 301.079142 -318.557782) (xy 301.105445 -318.516186)
			(xy 301.13808 -318.479349) (xy 301.176201 -318.448224) (xy 301.218822 -318.423617) (xy 301.264838 -318.406165)
			(xy 301.313057 -318.396321) (xy 301.362232 -318.39434) (xy 301.411087 -318.400272) (xy 301.458358 -318.413964)
			(xy 301.50282 -318.435062) (xy 301.543323 -318.463018) (xy 301.578816 -318.49711) (xy 301.608381 -318.536454)
			(xy 301.631252 -318.580031) (xy 301.646836 -318.626712) (xy 301.654731 -318.675289) (xy 301.655226 -318.699896)
			(xy 302.944034 -318.699896) (xy 302.947994 -318.650842) (xy 302.959771 -318.603058) (xy 302.979062 -318.557782)
			(xy 303.005365 -318.516186) (xy 303.038 -318.479349) (xy 303.076121 -318.448224) (xy 303.118742 -318.423617)
			(xy 303.164758 -318.406165) (xy 303.212977 -318.396321) (xy 303.262152 -318.39434) (xy 303.311007 -318.400272)
			(xy 303.358278 -318.413964) (xy 303.40274 -318.435062) (xy 303.443243 -318.463018) (xy 303.478736 -318.49711)
			(xy 303.508301 -318.536454) (xy 303.531172 -318.580031) (xy 303.546756 -318.626712) (xy 303.554651 -318.675289)
			(xy 303.555146 -318.699896) (xy 304.843954 -318.699896) (xy 304.847914 -318.650842) (xy 304.859691 -318.603058)
			(xy 304.878982 -318.557782) (xy 304.905285 -318.516186) (xy 304.93792 -318.479349) (xy 304.976041 -318.448224)
			(xy 305.018662 -318.423617) (xy 305.064678 -318.406165) (xy 305.112897 -318.396321) (xy 305.162072 -318.39434)
			(xy 305.210927 -318.400272) (xy 305.258198 -318.413964) (xy 305.30266 -318.435062) (xy 305.343163 -318.463018)
			(xy 305.378656 -318.49711) (xy 305.408221 -318.536454) (xy 305.431092 -318.580031) (xy 305.446676 -318.626712)
			(xy 305.454571 -318.675289) (xy 305.455066 -318.699896) (xy 306.744128 -318.699896) (xy 306.748088 -318.650842)
			(xy 306.759865 -318.603058) (xy 306.779156 -318.557782) (xy 306.805459 -318.516186) (xy 306.838094 -318.479349)
			(xy 306.876215 -318.448224) (xy 306.918836 -318.423617) (xy 306.964852 -318.406165) (xy 307.013071 -318.396321)
			(xy 307.062246 -318.39434) (xy 307.111101 -318.400272) (xy 307.158372 -318.413964) (xy 307.202834 -318.435062)
			(xy 307.243337 -318.463018) (xy 307.27883 -318.49711) (xy 307.308395 -318.536454) (xy 307.331266 -318.580031)
			(xy 307.34685 -318.626712) (xy 307.354745 -318.675289) (xy 307.35524 -318.699896) (xy 308.644048 -318.699896)
			(xy 308.648008 -318.650842) (xy 308.659785 -318.603058) (xy 308.679076 -318.557782) (xy 308.705379 -318.516186)
			(xy 308.738014 -318.479349) (xy 308.776135 -318.448224) (xy 308.818756 -318.423617) (xy 308.864772 -318.406165)
			(xy 308.912991 -318.396321) (xy 308.962166 -318.39434) (xy 309.011021 -318.400272) (xy 309.058292 -318.413964)
			(xy 309.102754 -318.435062) (xy 309.143257 -318.463018) (xy 309.17875 -318.49711) (xy 309.208315 -318.536454)
			(xy 309.231186 -318.580031) (xy 309.24677 -318.626712) (xy 309.254665 -318.675289) (xy 309.25516 -318.699896)
			(xy 310.543968 -318.699896) (xy 310.547928 -318.650842) (xy 310.559705 -318.603058) (xy 310.578996 -318.557782)
			(xy 310.605299 -318.516186) (xy 310.637934 -318.479349) (xy 310.676055 -318.448224) (xy 310.718676 -318.423617)
			(xy 310.764692 -318.406165) (xy 310.812911 -318.396321) (xy 310.862086 -318.39434) (xy 310.910941 -318.400272)
			(xy 310.958212 -318.413964) (xy 311.002674 -318.435062) (xy 311.043177 -318.463018) (xy 311.07867 -318.49711)
			(xy 311.108235 -318.536454) (xy 311.131106 -318.580031) (xy 311.14669 -318.626712) (xy 311.154585 -318.675289)
			(xy 311.15508 -318.699896) (xy 312.443888 -318.699896) (xy 312.447848 -318.650842) (xy 312.459625 -318.603058)
			(xy 312.478916 -318.557782) (xy 312.505219 -318.516186) (xy 312.537854 -318.479349) (xy 312.575975 -318.448224)
			(xy 312.618596 -318.423617) (xy 312.664612 -318.406165) (xy 312.712831 -318.396321) (xy 312.762006 -318.39434)
			(xy 312.810861 -318.400272) (xy 312.858132 -318.413964) (xy 312.902594 -318.435062) (xy 312.943097 -318.463018)
			(xy 312.97859 -318.49711) (xy 313.008155 -318.536454) (xy 313.031026 -318.580031) (xy 313.04661 -318.626712)
			(xy 313.054505 -318.675289) (xy 313.055 -318.699896) (xy 313.054505 -318.724503) (xy 313.04661 -318.77308)
			(xy 313.031026 -318.819761) (xy 313.008155 -318.863338) (xy 312.97859 -318.902682) (xy 312.943097 -318.936774)
			(xy 312.902594 -318.96473) (xy 312.858132 -318.985828) (xy 312.810861 -318.99952) (xy 312.762006 -319.005452)
			(xy 312.712831 -319.003471) (xy 312.664612 -318.993627) (xy 312.618596 -318.976175) (xy 312.575975 -318.951568)
			(xy 312.537854 -318.920443) (xy 312.505219 -318.883606) (xy 312.478916 -318.84201) (xy 312.459625 -318.796734)
			(xy 312.447848 -318.74895) (xy 312.443888 -318.699896) (xy 311.15508 -318.699896) (xy 311.154585 -318.724503)
			(xy 311.14669 -318.77308) (xy 311.131106 -318.819761) (xy 311.108235 -318.863338) (xy 311.07867 -318.902682)
			(xy 311.043177 -318.936774) (xy 311.002674 -318.96473) (xy 310.958212 -318.985828) (xy 310.910941 -318.99952)
			(xy 310.862086 -319.005452) (xy 310.812911 -319.003471) (xy 310.764692 -318.993627) (xy 310.718676 -318.976175)
			(xy 310.676055 -318.951568) (xy 310.637934 -318.920443) (xy 310.605299 -318.883606) (xy 310.578996 -318.84201)
			(xy 310.559705 -318.796734) (xy 310.547928 -318.74895) (xy 310.543968 -318.699896) (xy 309.25516 -318.699896)
			(xy 309.254665 -318.724503) (xy 309.24677 -318.77308) (xy 309.231186 -318.819761) (xy 309.208315 -318.863338)
			(xy 309.17875 -318.902682) (xy 309.143257 -318.936774) (xy 309.102754 -318.96473) (xy 309.058292 -318.985828)
			(xy 309.011021 -318.99952) (xy 308.962166 -319.005452) (xy 308.912991 -319.003471) (xy 308.864772 -318.993627)
			(xy 308.818756 -318.976175) (xy 308.776135 -318.951568) (xy 308.738014 -318.920443) (xy 308.705379 -318.883606)
			(xy 308.679076 -318.84201) (xy 308.659785 -318.796734) (xy 308.648008 -318.74895) (xy 308.644048 -318.699896)
			(xy 307.35524 -318.699896) (xy 307.354745 -318.724503) (xy 307.34685 -318.77308) (xy 307.331266 -318.819761)
			(xy 307.308395 -318.863338) (xy 307.27883 -318.902682) (xy 307.243337 -318.936774) (xy 307.202834 -318.96473)
			(xy 307.158372 -318.985828) (xy 307.111101 -318.99952) (xy 307.062246 -319.005452) (xy 307.013071 -319.003471)
			(xy 306.964852 -318.993627) (xy 306.918836 -318.976175) (xy 306.876215 -318.951568) (xy 306.838094 -318.920443)
			(xy 306.805459 -318.883606) (xy 306.779156 -318.84201) (xy 306.759865 -318.796734) (xy 306.748088 -318.74895)
			(xy 306.744128 -318.699896) (xy 305.455066 -318.699896) (xy 305.454571 -318.724503) (xy 305.446676 -318.77308)
			(xy 305.431092 -318.819761) (xy 305.408221 -318.863338) (xy 305.378656 -318.902682) (xy 305.343163 -318.936774)
			(xy 305.30266 -318.96473) (xy 305.258198 -318.985828) (xy 305.210927 -318.99952) (xy 305.162072 -319.005452)
			(xy 305.112897 -319.003471) (xy 305.064678 -318.993627) (xy 305.018662 -318.976175) (xy 304.976041 -318.951568)
			(xy 304.93792 -318.920443) (xy 304.905285 -318.883606) (xy 304.878982 -318.84201) (xy 304.859691 -318.796734)
			(xy 304.847914 -318.74895) (xy 304.843954 -318.699896) (xy 303.555146 -318.699896) (xy 303.554651 -318.724503)
			(xy 303.546756 -318.77308) (xy 303.531172 -318.819761) (xy 303.508301 -318.863338) (xy 303.478736 -318.902682)
			(xy 303.443243 -318.936774) (xy 303.40274 -318.96473) (xy 303.358278 -318.985828) (xy 303.311007 -318.99952)
			(xy 303.262152 -319.005452) (xy 303.212977 -319.003471) (xy 303.164758 -318.993627) (xy 303.118742 -318.976175)
			(xy 303.076121 -318.951568) (xy 303.038 -318.920443) (xy 303.005365 -318.883606) (xy 302.979062 -318.84201)
			(xy 302.959771 -318.796734) (xy 302.947994 -318.74895) (xy 302.944034 -318.699896) (xy 301.655226 -318.699896)
			(xy 301.654731 -318.724503) (xy 301.646836 -318.77308) (xy 301.631252 -318.819761) (xy 301.608381 -318.863338)
			(xy 301.578816 -318.902682) (xy 301.543323 -318.936774) (xy 301.50282 -318.96473) (xy 301.458358 -318.985828)
			(xy 301.411087 -318.99952) (xy 301.362232 -319.005452) (xy 301.313057 -319.003471) (xy 301.264838 -318.993627)
			(xy 301.218822 -318.976175) (xy 301.176201 -318.951568) (xy 301.13808 -318.920443) (xy 301.105445 -318.883606)
			(xy 301.079142 -318.84201) (xy 301.059851 -318.796734) (xy 301.048074 -318.74895) (xy 301.044114 -318.699896)
			(xy 299.755052 -318.699896) (xy 299.754557 -318.724503) (xy 299.746662 -318.77308) (xy 299.731078 -318.819761)
			(xy 299.708207 -318.863338) (xy 299.678642 -318.902682) (xy 299.643149 -318.936774) (xy 299.602646 -318.96473)
			(xy 299.558184 -318.985828) (xy 299.510913 -318.99952) (xy 299.462058 -319.005452) (xy 299.412883 -319.003471)
			(xy 299.364664 -318.993627) (xy 299.318648 -318.976175) (xy 299.276027 -318.951568) (xy 299.237906 -318.920443)
			(xy 299.205271 -318.883606) (xy 299.178968 -318.84201) (xy 299.159677 -318.796734) (xy 299.1479 -318.74895)
			(xy 299.14394 -318.699896) (xy 297.855132 -318.699896) (xy 297.854637 -318.724503) (xy 297.846742 -318.77308)
			(xy 297.831158 -318.819761) (xy 297.808287 -318.863338) (xy 297.778722 -318.902682) (xy 297.743229 -318.936774)
			(xy 297.702726 -318.96473) (xy 297.658264 -318.985828) (xy 297.610993 -318.99952) (xy 297.562138 -319.005452)
			(xy 297.512963 -319.003471) (xy 297.464744 -318.993627) (xy 297.418728 -318.976175) (xy 297.376107 -318.951568)
			(xy 297.337986 -318.920443) (xy 297.305351 -318.883606) (xy 297.279048 -318.84201) (xy 297.259757 -318.796734)
			(xy 297.24798 -318.74895) (xy 297.24402 -318.699896) (xy 295.955212 -318.699896) (xy 295.954717 -318.724503)
			(xy 295.946822 -318.77308) (xy 295.931238 -318.819761) (xy 295.908367 -318.863338) (xy 295.878802 -318.902682)
			(xy 295.843309 -318.936774) (xy 295.802806 -318.96473) (xy 295.758344 -318.985828) (xy 295.711073 -318.99952)
			(xy 295.662218 -319.005452) (xy 295.613043 -319.003471) (xy 295.564824 -318.993627) (xy 295.518808 -318.976175)
			(xy 295.476187 -318.951568) (xy 295.438066 -318.920443) (xy 295.405431 -318.883606) (xy 295.379128 -318.84201)
			(xy 295.359837 -318.796734) (xy 295.34806 -318.74895) (xy 295.3441 -318.699896) (xy 294.055038 -318.699896)
			(xy 294.054543 -318.724503) (xy 294.046648 -318.77308) (xy 294.031064 -318.819761) (xy 294.008193 -318.863338)
			(xy 293.978628 -318.902682) (xy 293.943135 -318.936774) (xy 293.902632 -318.96473) (xy 293.85817 -318.985828)
			(xy 293.810899 -318.99952) (xy 293.762044 -319.005452) (xy 293.712869 -319.003471) (xy 293.66465 -318.993627)
			(xy 293.618634 -318.976175) (xy 293.576013 -318.951568) (xy 293.537892 -318.920443) (xy 293.505257 -318.883606)
			(xy 293.478954 -318.84201) (xy 293.459663 -318.796734) (xy 293.447886 -318.74895) (xy 293.443926 -318.699896)
			(xy 292.155118 -318.699896) (xy 292.154623 -318.724503) (xy 292.146728 -318.77308) (xy 292.131144 -318.819761)
			(xy 292.108273 -318.863338) (xy 292.078708 -318.902682) (xy 292.043215 -318.936774) (xy 292.002712 -318.96473)
			(xy 291.95825 -318.985828) (xy 291.910979 -318.99952) (xy 291.862124 -319.005452) (xy 291.812949 -319.003471)
			(xy 291.76473 -318.993627) (xy 291.718714 -318.976175) (xy 291.676093 -318.951568) (xy 291.637972 -318.920443)
			(xy 291.605337 -318.883606) (xy 291.579034 -318.84201) (xy 291.559743 -318.796734) (xy 291.547966 -318.74895)
			(xy 291.544006 -318.699896) (xy 290.255198 -318.699896) (xy 290.254703 -318.724503) (xy 290.246808 -318.77308)
			(xy 290.231224 -318.819761) (xy 290.208353 -318.863338) (xy 290.178788 -318.902682) (xy 290.143295 -318.936774)
			(xy 290.102792 -318.96473) (xy 290.05833 -318.985828) (xy 290.011059 -318.99952) (xy 289.962204 -319.005452)
			(xy 289.913029 -319.003471) (xy 289.86481 -318.993627) (xy 289.818794 -318.976175) (xy 289.776173 -318.951568)
			(xy 289.738052 -318.920443) (xy 289.705417 -318.883606) (xy 289.679114 -318.84201) (xy 289.659823 -318.796734)
			(xy 289.648046 -318.74895) (xy 289.644086 -318.699896) (xy 288.355024 -318.699896) (xy 288.354529 -318.724503)
			(xy 288.346634 -318.77308) (xy 288.33105 -318.819761) (xy 288.308179 -318.863338) (xy 288.278614 -318.902682)
			(xy 288.243121 -318.936774) (xy 288.202618 -318.96473) (xy 288.158156 -318.985828) (xy 288.110885 -318.99952)
			(xy 288.06203 -319.005452) (xy 288.012855 -319.003471) (xy 287.964636 -318.993627) (xy 287.91862 -318.976175)
			(xy 287.875999 -318.951568) (xy 287.837878 -318.920443) (xy 287.805243 -318.883606) (xy 287.77894 -318.84201)
			(xy 287.759649 -318.796734) (xy 287.747872 -318.74895) (xy 287.743912 -318.699896) (xy 286.455104 -318.699896)
			(xy 286.454609 -318.724503) (xy 286.446714 -318.77308) (xy 286.43113 -318.819761) (xy 286.408259 -318.863338)
			(xy 286.378694 -318.902682) (xy 286.343201 -318.936774) (xy 286.302698 -318.96473) (xy 286.258236 -318.985828)
			(xy 286.210965 -318.99952) (xy 286.16211 -319.005452) (xy 286.112935 -319.003471) (xy 286.064716 -318.993627)
			(xy 286.0187 -318.976175) (xy 285.976079 -318.951568) (xy 285.937958 -318.920443) (xy 285.905323 -318.883606)
			(xy 285.87902 -318.84201) (xy 285.859729 -318.796734) (xy 285.847952 -318.74895) (xy 285.843992 -318.699896)
			(xy 284.555184 -318.699896) (xy 284.554689 -318.724503) (xy 284.546794 -318.77308) (xy 284.53121 -318.819761)
			(xy 284.508339 -318.863338) (xy 284.478774 -318.902682) (xy 284.443281 -318.936774) (xy 284.402778 -318.96473)
			(xy 284.358316 -318.985828) (xy 284.311045 -318.99952) (xy 284.26219 -319.005452) (xy 284.213015 -319.003471)
			(xy 284.164796 -318.993627) (xy 284.11878 -318.976175) (xy 284.076159 -318.951568) (xy 284.038038 -318.920443)
			(xy 284.005403 -318.883606) (xy 283.9791 -318.84201) (xy 283.959809 -318.796734) (xy 283.948032 -318.74895)
			(xy 283.944072 -318.699896) (xy 282.65501 -318.699896) (xy 282.654515 -318.724503) (xy 282.64662 -318.77308)
			(xy 282.631036 -318.819761) (xy 282.608165 -318.863338) (xy 282.5786 -318.902682) (xy 282.543107 -318.936774)
			(xy 282.502604 -318.96473) (xy 282.458142 -318.985828) (xy 282.410871 -318.99952) (xy 282.362016 -319.005452)
			(xy 282.312841 -319.003471) (xy 282.264622 -318.993627) (xy 282.218606 -318.976175) (xy 282.175985 -318.951568)
			(xy 282.137864 -318.920443) (xy 282.105229 -318.883606) (xy 282.078926 -318.84201) (xy 282.059635 -318.796734)
			(xy 282.047858 -318.74895) (xy 282.043898 -318.699896) (xy 280.75509 -318.699896) (xy 280.754595 -318.724503)
			(xy 280.7467 -318.77308) (xy 280.731116 -318.819761) (xy 280.708245 -318.863338) (xy 280.67868 -318.902682)
			(xy 280.643187 -318.936774) (xy 280.602684 -318.96473) (xy 280.558222 -318.985828) (xy 280.510951 -318.99952)
			(xy 280.462096 -319.005452) (xy 280.412921 -319.003471) (xy 280.364702 -318.993627) (xy 280.318686 -318.976175)
			(xy 280.276065 -318.951568) (xy 280.237944 -318.920443) (xy 280.205309 -318.883606) (xy 280.179006 -318.84201)
			(xy 280.159715 -318.796734) (xy 280.147938 -318.74895) (xy 280.143978 -318.699896) (xy 278.85517 -318.699896)
			(xy 278.854675 -318.724503) (xy 278.84678 -318.77308) (xy 278.831196 -318.819761) (xy 278.808325 -318.863338)
			(xy 278.77876 -318.902682) (xy 278.743267 -318.936774) (xy 278.702764 -318.96473) (xy 278.658302 -318.985828)
			(xy 278.611031 -318.99952) (xy 278.562176 -319.005452) (xy 278.513001 -319.003471) (xy 278.464782 -318.993627)
			(xy 278.418766 -318.976175) (xy 278.376145 -318.951568) (xy 278.338024 -318.920443) (xy 278.305389 -318.883606)
			(xy 278.279086 -318.84201) (xy 278.259795 -318.796734) (xy 278.248018 -318.74895) (xy 278.244058 -318.699896)
			(xy 276.954996 -318.699896) (xy 276.954501 -318.724503) (xy 276.946606 -318.77308) (xy 276.931022 -318.819761)
			(xy 276.908151 -318.863338) (xy 276.878586 -318.902682) (xy 276.843093 -318.936774) (xy 276.80259 -318.96473)
			(xy 276.758128 -318.985828) (xy 276.710857 -318.99952) (xy 276.662002 -319.005452) (xy 276.612827 -319.003471)
			(xy 276.564608 -318.993627) (xy 276.518592 -318.976175) (xy 276.475971 -318.951568) (xy 276.43785 -318.920443)
			(xy 276.405215 -318.883606) (xy 276.378912 -318.84201) (xy 276.359621 -318.796734) (xy 276.347844 -318.74895)
			(xy 276.343884 -318.699896) (xy 275.055076 -318.699896) (xy 275.054581 -318.724503) (xy 275.046686 -318.77308)
			(xy 275.031102 -318.819761) (xy 275.008231 -318.863338) (xy 274.978666 -318.902682) (xy 274.943173 -318.936774)
			(xy 274.90267 -318.96473) (xy 274.858208 -318.985828) (xy 274.810937 -318.99952) (xy 274.762082 -319.005452)
			(xy 274.712907 -319.003471) (xy 274.664688 -318.993627) (xy 274.618672 -318.976175) (xy 274.576051 -318.951568)
			(xy 274.53793 -318.920443) (xy 274.505295 -318.883606) (xy 274.478992 -318.84201) (xy 274.459701 -318.796734)
			(xy 274.447924 -318.74895) (xy 274.443964 -318.699896) (xy 273.155156 -318.699896) (xy 273.154661 -318.724503)
			(xy 273.146766 -318.77308) (xy 273.131182 -318.819761) (xy 273.108311 -318.863338) (xy 273.078746 -318.902682)
			(xy 273.043253 -318.936774) (xy 273.00275 -318.96473) (xy 272.958288 -318.985828) (xy 272.911017 -318.99952)
			(xy 272.862162 -319.005452) (xy 272.812987 -319.003471) (xy 272.764768 -318.993627) (xy 272.718752 -318.976175)
			(xy 272.676131 -318.951568) (xy 272.63801 -318.920443) (xy 272.605375 -318.883606) (xy 272.579072 -318.84201)
			(xy 272.559781 -318.796734) (xy 272.548004 -318.74895) (xy 272.544044 -318.699896) (xy 271.255236 -318.699896)
			(xy 271.254741 -318.724503) (xy 271.246846 -318.77308) (xy 271.231262 -318.819761) (xy 271.208391 -318.863338)
			(xy 271.178826 -318.902682) (xy 271.143333 -318.936774) (xy 271.10283 -318.96473) (xy 271.058368 -318.985828)
			(xy 271.011097 -318.99952) (xy 270.962242 -319.005452) (xy 270.913067 -319.003471) (xy 270.864848 -318.993627)
			(xy 270.818832 -318.976175) (xy 270.776211 -318.951568) (xy 270.73809 -318.920443) (xy 270.705455 -318.883606)
			(xy 270.679152 -318.84201) (xy 270.659861 -318.796734) (xy 270.648084 -318.74895) (xy 270.644124 -318.699896)
			(xy 263.526839 -318.699896) (xy 263.600049 -318.756463) (xy 263.712586 -318.853497) (xy 263.819753 -318.956432)
			(xy 263.92124 -319.064971) (xy 264.016754 -319.1788) (xy 264.106021 -319.297593) (xy 264.188782 -319.421005)
			(xy 264.2648 -319.548683) (xy 264.333855 -319.680256) (xy 264.395748 -319.815347) (xy 264.450301 -319.953564)
			(xy 264.497356 -320.094511) (xy 264.536778 -320.237781) (xy 264.568452 -320.38296) (xy 264.592288 -320.529629)
			(xy 264.608217 -320.677367) (xy 264.616193 -320.825747) (xy 264.616692 -320.900044) (xy 319.082429 -320.900044)
			(xy 319.086418 -320.751504) (xy 319.098375 -320.603391) (xy 319.118265 -320.456134) (xy 319.14603 -320.310158)
			(xy 319.181591 -320.165881) (xy 319.224845 -320.023722) (xy 319.275667 -319.884089) (xy 319.333911 -319.747386)
			(xy 319.399409 -319.614006) (xy 319.471972 -319.484334) (xy 319.55139 -319.358744) (xy 319.637435 -319.237597)
			(xy 319.729859 -319.121244) (xy 319.828395 -319.01002) (xy 319.932759 -318.904245) (xy 320.042651 -318.804225)
			(xy 320.157752 -318.710247) (xy 320.277732 -318.622583) (xy 320.402245 -318.541486) (xy 320.530931 -318.467189)
			(xy 320.66342 -318.399907) (xy 320.799329 -318.339833) (xy 320.938267 -318.287141) (xy 321.079833 -318.241982)
			(xy 321.223619 -318.204487) (xy 321.36921 -318.174765) (xy 321.516186 -318.1529) (xy 321.664125 -318.138956)
			(xy 321.812598 -318.132972) (xy 321.961179 -318.134967) (xy 322.109438 -318.144935) (xy 322.256949 -318.162846)
			(xy 322.403285 -318.188649) (xy 322.548026 -318.222269) (xy 322.690753 -318.263611) (xy 322.831056 -318.312554)
			(xy 322.968529 -318.368957) (xy 323.102776 -318.432658) (xy 323.233411 -318.503474) (xy 323.360056 -318.581199)
			(xy 323.482346 -318.66561) (xy 323.599929 -318.756463) (xy 323.712466 -318.853497) (xy 323.819633 -318.956432)
			(xy 323.92112 -319.064971) (xy 324.016634 -319.1788) (xy 324.105901 -319.297593) (xy 324.188662 -319.421005)
			(xy 324.26468 -319.548683) (xy 324.333735 -319.680256) (xy 324.395628 -319.815347) (xy 324.450181 -319.953564)
			(xy 324.497236 -320.094511) (xy 324.536658 -320.237781) (xy 324.568332 -320.38296) (xy 324.592168 -320.529629)
			(xy 324.608097 -320.677367) (xy 324.616073 -320.825747) (xy 324.616572 -320.900044) (xy 375.182393 -320.900044)
			(xy 375.186382 -320.751504) (xy 375.198339 -320.603391) (xy 375.218229 -320.456134) (xy 375.245994 -320.310158)
			(xy 375.281555 -320.165881) (xy 375.324809 -320.023722) (xy 375.375631 -319.884089) (xy 375.433875 -319.747386)
			(xy 375.499373 -319.614006) (xy 375.571936 -319.484334) (xy 375.651354 -319.358744) (xy 375.737399 -319.237597)
			(xy 375.829823 -319.121244) (xy 375.928359 -319.01002) (xy 376.032723 -318.904245) (xy 376.142615 -318.804225)
			(xy 376.257716 -318.710247) (xy 376.377696 -318.622583) (xy 376.502209 -318.541486) (xy 376.630895 -318.467189)
			(xy 376.763384 -318.399907) (xy 376.899293 -318.339833) (xy 377.038231 -318.287141) (xy 377.179797 -318.241982)
			(xy 377.323583 -318.204487) (xy 377.469174 -318.174765) (xy 377.61615 -318.1529) (xy 377.764089 -318.138956)
			(xy 377.912562 -318.132972) (xy 378.061143 -318.134967) (xy 378.209402 -318.144935) (xy 378.356913 -318.162846)
			(xy 378.503249 -318.188649) (xy 378.64799 -318.222269) (xy 378.790717 -318.263611) (xy 378.93102 -318.312554)
			(xy 379.068493 -318.368957) (xy 379.20274 -318.432658) (xy 379.333375 -318.503474) (xy 379.46002 -318.581199)
			(xy 379.58231 -318.66561) (xy 379.626683 -318.699896) (xy 386.744222 -318.699896) (xy 386.748182 -318.650842)
			(xy 386.759959 -318.603058) (xy 386.77925 -318.557782) (xy 386.805553 -318.516186) (xy 386.838188 -318.479349)
			(xy 386.876309 -318.448224) (xy 386.91893 -318.423617) (xy 386.964946 -318.406165) (xy 387.013165 -318.396321)
			(xy 387.06234 -318.39434) (xy 387.111195 -318.400272) (xy 387.158466 -318.413964) (xy 387.202928 -318.435062)
			(xy 387.243431 -318.463018) (xy 387.278924 -318.49711) (xy 387.308489 -318.536454) (xy 387.33136 -318.580031)
			(xy 387.346944 -318.626712) (xy 387.354839 -318.675289) (xy 387.355334 -318.699896) (xy 388.644142 -318.699896)
			(xy 388.648102 -318.650842) (xy 388.659879 -318.603058) (xy 388.67917 -318.557782) (xy 388.705473 -318.516186)
			(xy 388.738108 -318.479349) (xy 388.776229 -318.448224) (xy 388.81885 -318.423617) (xy 388.864866 -318.406165)
			(xy 388.913085 -318.396321) (xy 388.96226 -318.39434) (xy 389.011115 -318.400272) (xy 389.058386 -318.413964)
			(xy 389.102848 -318.435062) (xy 389.143351 -318.463018) (xy 389.178844 -318.49711) (xy 389.208409 -318.536454)
			(xy 389.23128 -318.580031) (xy 389.246864 -318.626712) (xy 389.254759 -318.675289) (xy 389.255254 -318.699896)
			(xy 390.544062 -318.699896) (xy 390.548022 -318.650842) (xy 390.559799 -318.603058) (xy 390.57909 -318.557782)
			(xy 390.605393 -318.516186) (xy 390.638028 -318.479349) (xy 390.676149 -318.448224) (xy 390.71877 -318.423617)
			(xy 390.764786 -318.406165) (xy 390.813005 -318.396321) (xy 390.86218 -318.39434) (xy 390.911035 -318.400272)
			(xy 390.958306 -318.413964) (xy 391.002768 -318.435062) (xy 391.043271 -318.463018) (xy 391.078764 -318.49711)
			(xy 391.108329 -318.536454) (xy 391.1312 -318.580031) (xy 391.146784 -318.626712) (xy 391.154679 -318.675289)
			(xy 391.155174 -318.699896) (xy 392.443982 -318.699896) (xy 392.447942 -318.650842) (xy 392.459719 -318.603058)
			(xy 392.47901 -318.557782) (xy 392.505313 -318.516186) (xy 392.537948 -318.479349) (xy 392.576069 -318.448224)
			(xy 392.61869 -318.423617) (xy 392.664706 -318.406165) (xy 392.712925 -318.396321) (xy 392.7621 -318.39434)
			(xy 392.810955 -318.400272) (xy 392.858226 -318.413964) (xy 392.902688 -318.435062) (xy 392.943191 -318.463018)
			(xy 392.978684 -318.49711) (xy 393.008249 -318.536454) (xy 393.03112 -318.580031) (xy 393.046704 -318.626712)
			(xy 393.054599 -318.675289) (xy 393.055094 -318.699896) (xy 394.344156 -318.699896) (xy 394.348116 -318.650842)
			(xy 394.359893 -318.603058) (xy 394.379184 -318.557782) (xy 394.405487 -318.516186) (xy 394.438122 -318.479349)
			(xy 394.476243 -318.448224) (xy 394.518864 -318.423617) (xy 394.56488 -318.406165) (xy 394.613099 -318.396321)
			(xy 394.662274 -318.39434) (xy 394.711129 -318.400272) (xy 394.7584 -318.413964) (xy 394.802862 -318.435062)
			(xy 394.843365 -318.463018) (xy 394.878858 -318.49711) (xy 394.908423 -318.536454) (xy 394.931294 -318.580031)
			(xy 394.946878 -318.626712) (xy 394.954773 -318.675289) (xy 394.955268 -318.699896) (xy 396.244076 -318.699896)
			(xy 396.248036 -318.650842) (xy 396.259813 -318.603058) (xy 396.279104 -318.557782) (xy 396.305407 -318.516186)
			(xy 396.338042 -318.479349) (xy 396.376163 -318.448224) (xy 396.418784 -318.423617) (xy 396.4648 -318.406165)
			(xy 396.513019 -318.396321) (xy 396.562194 -318.39434) (xy 396.611049 -318.400272) (xy 396.65832 -318.413964)
			(xy 396.702782 -318.435062) (xy 396.743285 -318.463018) (xy 396.778778 -318.49711) (xy 396.808343 -318.536454)
			(xy 396.831214 -318.580031) (xy 396.846798 -318.626712) (xy 396.854693 -318.675289) (xy 396.855188 -318.699896)
			(xy 398.143996 -318.699896) (xy 398.147956 -318.650842) (xy 398.159733 -318.603058) (xy 398.179024 -318.557782)
			(xy 398.205327 -318.516186) (xy 398.237962 -318.479349) (xy 398.276083 -318.448224) (xy 398.318704 -318.423617)
			(xy 398.36472 -318.406165) (xy 398.412939 -318.396321) (xy 398.462114 -318.39434) (xy 398.510969 -318.400272)
			(xy 398.55824 -318.413964) (xy 398.602702 -318.435062) (xy 398.643205 -318.463018) (xy 398.678698 -318.49711)
			(xy 398.708263 -318.536454) (xy 398.731134 -318.580031) (xy 398.746718 -318.626712) (xy 398.754613 -318.675289)
			(xy 398.755108 -318.699896) (xy 400.04417 -318.699896) (xy 400.04813 -318.650842) (xy 400.059907 -318.603058)
			(xy 400.079198 -318.557782) (xy 400.105501 -318.516186) (xy 400.138136 -318.479349) (xy 400.176257 -318.448224)
			(xy 400.218878 -318.423617) (xy 400.264894 -318.406165) (xy 400.313113 -318.396321) (xy 400.362288 -318.39434)
			(xy 400.411143 -318.400272) (xy 400.458414 -318.413964) (xy 400.502876 -318.435062) (xy 400.543379 -318.463018)
			(xy 400.578872 -318.49711) (xy 400.608437 -318.536454) (xy 400.631308 -318.580031) (xy 400.646892 -318.626712)
			(xy 400.654787 -318.675289) (xy 400.655282 -318.699896) (xy 401.94409 -318.699896) (xy 401.94805 -318.650842)
			(xy 401.959827 -318.603058) (xy 401.979118 -318.557782) (xy 402.005421 -318.516186) (xy 402.038056 -318.479349)
			(xy 402.076177 -318.448224) (xy 402.118798 -318.423617) (xy 402.164814 -318.406165) (xy 402.213033 -318.396321)
			(xy 402.262208 -318.39434) (xy 402.311063 -318.400272) (xy 402.358334 -318.413964) (xy 402.402796 -318.435062)
			(xy 402.443299 -318.463018) (xy 402.478792 -318.49711) (xy 402.508357 -318.536454) (xy 402.531228 -318.580031)
			(xy 402.546812 -318.626712) (xy 402.554707 -318.675289) (xy 402.555202 -318.699896) (xy 403.84401 -318.699896)
			(xy 403.84797 -318.650842) (xy 403.859747 -318.603058) (xy 403.879038 -318.557782) (xy 403.905341 -318.516186)
			(xy 403.937976 -318.479349) (xy 403.976097 -318.448224) (xy 404.018718 -318.423617) (xy 404.064734 -318.406165)
			(xy 404.112953 -318.396321) (xy 404.162128 -318.39434) (xy 404.210983 -318.400272) (xy 404.258254 -318.413964)
			(xy 404.302716 -318.435062) (xy 404.343219 -318.463018) (xy 404.378712 -318.49711) (xy 404.408277 -318.536454)
			(xy 404.431148 -318.580031) (xy 404.446732 -318.626712) (xy 404.454627 -318.675289) (xy 404.455122 -318.699896)
			(xy 405.744184 -318.699896) (xy 405.748144 -318.650842) (xy 405.759921 -318.603058) (xy 405.779212 -318.557782)
			(xy 405.805515 -318.516186) (xy 405.83815 -318.479349) (xy 405.876271 -318.448224) (xy 405.918892 -318.423617)
			(xy 405.964908 -318.406165) (xy 406.013127 -318.396321) (xy 406.062302 -318.39434) (xy 406.111157 -318.400272)
			(xy 406.158428 -318.413964) (xy 406.20289 -318.435062) (xy 406.243393 -318.463018) (xy 406.278886 -318.49711)
			(xy 406.308451 -318.536454) (xy 406.331322 -318.580031) (xy 406.346906 -318.626712) (xy 406.354801 -318.675289)
			(xy 406.355296 -318.699896) (xy 407.644104 -318.699896) (xy 407.648064 -318.650842) (xy 407.659841 -318.603058)
			(xy 407.679132 -318.557782) (xy 407.705435 -318.516186) (xy 407.73807 -318.479349) (xy 407.776191 -318.448224)
			(xy 407.818812 -318.423617) (xy 407.864828 -318.406165) (xy 407.913047 -318.396321) (xy 407.962222 -318.39434)
			(xy 408.011077 -318.400272) (xy 408.058348 -318.413964) (xy 408.10281 -318.435062) (xy 408.143313 -318.463018)
			(xy 408.178806 -318.49711) (xy 408.208371 -318.536454) (xy 408.231242 -318.580031) (xy 408.246826 -318.626712)
			(xy 408.254721 -318.675289) (xy 408.255216 -318.699896) (xy 409.544024 -318.699896) (xy 409.547984 -318.650842)
			(xy 409.559761 -318.603058) (xy 409.579052 -318.557782) (xy 409.605355 -318.516186) (xy 409.63799 -318.479349)
			(xy 409.676111 -318.448224) (xy 409.718732 -318.423617) (xy 409.764748 -318.406165) (xy 409.812967 -318.396321)
			(xy 409.862142 -318.39434) (xy 409.910997 -318.400272) (xy 409.958268 -318.413964) (xy 410.00273 -318.435062)
			(xy 410.043233 -318.463018) (xy 410.078726 -318.49711) (xy 410.108291 -318.536454) (xy 410.131162 -318.580031)
			(xy 410.146746 -318.626712) (xy 410.154641 -318.675289) (xy 410.155136 -318.699896) (xy 411.444198 -318.699896)
			(xy 411.448158 -318.650842) (xy 411.459935 -318.603058) (xy 411.479226 -318.557782) (xy 411.505529 -318.516186)
			(xy 411.538164 -318.479349) (xy 411.576285 -318.448224) (xy 411.618906 -318.423617) (xy 411.664922 -318.406165)
			(xy 411.713141 -318.396321) (xy 411.762316 -318.39434) (xy 411.811171 -318.400272) (xy 411.858442 -318.413964)
			(xy 411.902904 -318.435062) (xy 411.943407 -318.463018) (xy 411.9789 -318.49711) (xy 412.008465 -318.536454)
			(xy 412.031336 -318.580031) (xy 412.04692 -318.626712) (xy 412.054815 -318.675289) (xy 412.05531 -318.699896)
			(xy 413.344118 -318.699896) (xy 413.348078 -318.650842) (xy 413.359855 -318.603058) (xy 413.379146 -318.557782)
			(xy 413.405449 -318.516186) (xy 413.438084 -318.479349) (xy 413.476205 -318.448224) (xy 413.518826 -318.423617)
			(xy 413.564842 -318.406165) (xy 413.613061 -318.396321) (xy 413.662236 -318.39434) (xy 413.711091 -318.400272)
			(xy 413.758362 -318.413964) (xy 413.802824 -318.435062) (xy 413.843327 -318.463018) (xy 413.87882 -318.49711)
			(xy 413.908385 -318.536454) (xy 413.931256 -318.580031) (xy 413.94684 -318.626712) (xy 413.954735 -318.675289)
			(xy 413.95523 -318.699896) (xy 415.244038 -318.699896) (xy 415.247998 -318.650842) (xy 415.259775 -318.603058)
			(xy 415.279066 -318.557782) (xy 415.305369 -318.516186) (xy 415.338004 -318.479349) (xy 415.376125 -318.448224)
			(xy 415.418746 -318.423617) (xy 415.464762 -318.406165) (xy 415.512981 -318.396321) (xy 415.562156 -318.39434)
			(xy 415.611011 -318.400272) (xy 415.658282 -318.413964) (xy 415.702744 -318.435062) (xy 415.743247 -318.463018)
			(xy 415.77874 -318.49711) (xy 415.808305 -318.536454) (xy 415.831176 -318.580031) (xy 415.84676 -318.626712)
			(xy 415.854655 -318.675289) (xy 415.85515 -318.699896) (xy 417.144212 -318.699896) (xy 417.148172 -318.650842)
			(xy 417.159949 -318.603058) (xy 417.17924 -318.557782) (xy 417.205543 -318.516186) (xy 417.238178 -318.479349)
			(xy 417.276299 -318.448224) (xy 417.31892 -318.423617) (xy 417.364936 -318.406165) (xy 417.413155 -318.396321)
			(xy 417.46233 -318.39434) (xy 417.511185 -318.400272) (xy 417.558456 -318.413964) (xy 417.602918 -318.435062)
			(xy 417.643421 -318.463018) (xy 417.678914 -318.49711) (xy 417.708479 -318.536454) (xy 417.73135 -318.580031)
			(xy 417.746934 -318.626712) (xy 417.754829 -318.675289) (xy 417.755324 -318.699896) (xy 419.044132 -318.699896)
			(xy 419.048092 -318.650842) (xy 419.059869 -318.603058) (xy 419.07916 -318.557782) (xy 419.105463 -318.516186)
			(xy 419.138098 -318.479349) (xy 419.176219 -318.448224) (xy 419.21884 -318.423617) (xy 419.264856 -318.406165)
			(xy 419.313075 -318.396321) (xy 419.36225 -318.39434) (xy 419.411105 -318.400272) (xy 419.458376 -318.413964)
			(xy 419.502838 -318.435062) (xy 419.543341 -318.463018) (xy 419.578834 -318.49711) (xy 419.608399 -318.536454)
			(xy 419.63127 -318.580031) (xy 419.646854 -318.626712) (xy 419.654749 -318.675289) (xy 419.655244 -318.699896)
			(xy 420.944052 -318.699896) (xy 420.948012 -318.650842) (xy 420.959789 -318.603058) (xy 420.97908 -318.557782)
			(xy 421.005383 -318.516186) (xy 421.038018 -318.479349) (xy 421.076139 -318.448224) (xy 421.11876 -318.423617)
			(xy 421.164776 -318.406165) (xy 421.212995 -318.396321) (xy 421.26217 -318.39434) (xy 421.311025 -318.400272)
			(xy 421.358296 -318.413964) (xy 421.402758 -318.435062) (xy 421.443261 -318.463018) (xy 421.478754 -318.49711)
			(xy 421.508319 -318.536454) (xy 421.53119 -318.580031) (xy 421.546774 -318.626712) (xy 421.554669 -318.675289)
			(xy 421.555164 -318.699896) (xy 422.844226 -318.699896) (xy 422.848186 -318.650842) (xy 422.859963 -318.603058)
			(xy 422.879254 -318.557782) (xy 422.905557 -318.516186) (xy 422.938192 -318.479349) (xy 422.976313 -318.448224)
			(xy 423.018934 -318.423617) (xy 423.06495 -318.406165) (xy 423.113169 -318.396321) (xy 423.162344 -318.39434)
			(xy 423.211199 -318.400272) (xy 423.25847 -318.413964) (xy 423.302932 -318.435062) (xy 423.343435 -318.463018)
			(xy 423.378928 -318.49711) (xy 423.408493 -318.536454) (xy 423.431364 -318.580031) (xy 423.446948 -318.626712)
			(xy 423.454843 -318.675289) (xy 423.455338 -318.699896) (xy 424.744146 -318.699896) (xy 424.748106 -318.650842)
			(xy 424.759883 -318.603058) (xy 424.779174 -318.557782) (xy 424.805477 -318.516186) (xy 424.838112 -318.479349)
			(xy 424.876233 -318.448224) (xy 424.918854 -318.423617) (xy 424.96487 -318.406165) (xy 425.013089 -318.396321)
			(xy 425.062264 -318.39434) (xy 425.111119 -318.400272) (xy 425.15839 -318.413964) (xy 425.202852 -318.435062)
			(xy 425.243355 -318.463018) (xy 425.278848 -318.49711) (xy 425.308413 -318.536454) (xy 425.331284 -318.580031)
			(xy 425.346868 -318.626712) (xy 425.354763 -318.675289) (xy 425.355258 -318.699896) (xy 426.644066 -318.699896)
			(xy 426.648026 -318.650842) (xy 426.659803 -318.603058) (xy 426.679094 -318.557782) (xy 426.705397 -318.516186)
			(xy 426.738032 -318.479349) (xy 426.776153 -318.448224) (xy 426.818774 -318.423617) (xy 426.86479 -318.406165)
			(xy 426.913009 -318.396321) (xy 426.962184 -318.39434) (xy 427.011039 -318.400272) (xy 427.05831 -318.413964)
			(xy 427.102772 -318.435062) (xy 427.143275 -318.463018) (xy 427.178768 -318.49711) (xy 427.208333 -318.536454)
			(xy 427.231204 -318.580031) (xy 427.246788 -318.626712) (xy 427.254683 -318.675289) (xy 427.255178 -318.699896)
			(xy 428.543986 -318.699896) (xy 428.547946 -318.650842) (xy 428.559723 -318.603058) (xy 428.579014 -318.557782)
			(xy 428.605317 -318.516186) (xy 428.637952 -318.479349) (xy 428.676073 -318.448224) (xy 428.718694 -318.423617)
			(xy 428.76471 -318.406165) (xy 428.812929 -318.396321) (xy 428.862104 -318.39434) (xy 428.910959 -318.400272)
			(xy 428.95823 -318.413964) (xy 429.002692 -318.435062) (xy 429.043195 -318.463018) (xy 429.078688 -318.49711)
			(xy 429.108253 -318.536454) (xy 429.131124 -318.580031) (xy 429.146708 -318.626712) (xy 429.154603 -318.675289)
			(xy 429.155098 -318.699896) (xy 429.154603 -318.724503) (xy 429.146708 -318.77308) (xy 429.131124 -318.819761)
			(xy 429.108253 -318.863338) (xy 429.078688 -318.902682) (xy 429.043195 -318.936774) (xy 429.002692 -318.96473)
			(xy 428.95823 -318.985828) (xy 428.910959 -318.99952) (xy 428.862104 -319.005452) (xy 428.812929 -319.003471)
			(xy 428.76471 -318.993627) (xy 428.718694 -318.976175) (xy 428.676073 -318.951568) (xy 428.637952 -318.920443)
			(xy 428.605317 -318.883606) (xy 428.579014 -318.84201) (xy 428.559723 -318.796734) (xy 428.547946 -318.74895)
			(xy 428.543986 -318.699896) (xy 427.255178 -318.699896) (xy 427.254683 -318.724503) (xy 427.246788 -318.77308)
			(xy 427.231204 -318.819761) (xy 427.208333 -318.863338) (xy 427.178768 -318.902682) (xy 427.143275 -318.936774)
			(xy 427.102772 -318.96473) (xy 427.05831 -318.985828) (xy 427.011039 -318.99952) (xy 426.962184 -319.005452)
			(xy 426.913009 -319.003471) (xy 426.86479 -318.993627) (xy 426.818774 -318.976175) (xy 426.776153 -318.951568)
			(xy 426.738032 -318.920443) (xy 426.705397 -318.883606) (xy 426.679094 -318.84201) (xy 426.659803 -318.796734)
			(xy 426.648026 -318.74895) (xy 426.644066 -318.699896) (xy 425.355258 -318.699896) (xy 425.354763 -318.724503)
			(xy 425.346868 -318.77308) (xy 425.331284 -318.819761) (xy 425.308413 -318.863338) (xy 425.278848 -318.902682)
			(xy 425.243355 -318.936774) (xy 425.202852 -318.96473) (xy 425.15839 -318.985828) (xy 425.111119 -318.99952)
			(xy 425.062264 -319.005452) (xy 425.013089 -319.003471) (xy 424.96487 -318.993627) (xy 424.918854 -318.976175)
			(xy 424.876233 -318.951568) (xy 424.838112 -318.920443) (xy 424.805477 -318.883606) (xy 424.779174 -318.84201)
			(xy 424.759883 -318.796734) (xy 424.748106 -318.74895) (xy 424.744146 -318.699896) (xy 423.455338 -318.699896)
			(xy 423.454843 -318.724503) (xy 423.446948 -318.77308) (xy 423.431364 -318.819761) (xy 423.408493 -318.863338)
			(xy 423.378928 -318.902682) (xy 423.343435 -318.936774) (xy 423.302932 -318.96473) (xy 423.25847 -318.985828)
			(xy 423.211199 -318.99952) (xy 423.162344 -319.005452) (xy 423.113169 -319.003471) (xy 423.06495 -318.993627)
			(xy 423.018934 -318.976175) (xy 422.976313 -318.951568) (xy 422.938192 -318.920443) (xy 422.905557 -318.883606)
			(xy 422.879254 -318.84201) (xy 422.859963 -318.796734) (xy 422.848186 -318.74895) (xy 422.844226 -318.699896)
			(xy 421.555164 -318.699896) (xy 421.554669 -318.724503) (xy 421.546774 -318.77308) (xy 421.53119 -318.819761)
			(xy 421.508319 -318.863338) (xy 421.478754 -318.902682) (xy 421.443261 -318.936774) (xy 421.402758 -318.96473)
			(xy 421.358296 -318.985828) (xy 421.311025 -318.99952) (xy 421.26217 -319.005452) (xy 421.212995 -319.003471)
			(xy 421.164776 -318.993627) (xy 421.11876 -318.976175) (xy 421.076139 -318.951568) (xy 421.038018 -318.920443)
			(xy 421.005383 -318.883606) (xy 420.97908 -318.84201) (xy 420.959789 -318.796734) (xy 420.948012 -318.74895)
			(xy 420.944052 -318.699896) (xy 419.655244 -318.699896) (xy 419.654749 -318.724503) (xy 419.646854 -318.77308)
			(xy 419.63127 -318.819761) (xy 419.608399 -318.863338) (xy 419.578834 -318.902682) (xy 419.543341 -318.936774)
			(xy 419.502838 -318.96473) (xy 419.458376 -318.985828) (xy 419.411105 -318.99952) (xy 419.36225 -319.005452)
			(xy 419.313075 -319.003471) (xy 419.264856 -318.993627) (xy 419.21884 -318.976175) (xy 419.176219 -318.951568)
			(xy 419.138098 -318.920443) (xy 419.105463 -318.883606) (xy 419.07916 -318.84201) (xy 419.059869 -318.796734)
			(xy 419.048092 -318.74895) (xy 419.044132 -318.699896) (xy 417.755324 -318.699896) (xy 417.754829 -318.724503)
			(xy 417.746934 -318.77308) (xy 417.73135 -318.819761) (xy 417.708479 -318.863338) (xy 417.678914 -318.902682)
			(xy 417.643421 -318.936774) (xy 417.602918 -318.96473) (xy 417.558456 -318.985828) (xy 417.511185 -318.99952)
			(xy 417.46233 -319.005452) (xy 417.413155 -319.003471) (xy 417.364936 -318.993627) (xy 417.31892 -318.976175)
			(xy 417.276299 -318.951568) (xy 417.238178 -318.920443) (xy 417.205543 -318.883606) (xy 417.17924 -318.84201)
			(xy 417.159949 -318.796734) (xy 417.148172 -318.74895) (xy 417.144212 -318.699896) (xy 415.85515 -318.699896)
			(xy 415.854655 -318.724503) (xy 415.84676 -318.77308) (xy 415.831176 -318.819761) (xy 415.808305 -318.863338)
			(xy 415.77874 -318.902682) (xy 415.743247 -318.936774) (xy 415.702744 -318.96473) (xy 415.658282 -318.985828)
			(xy 415.611011 -318.99952) (xy 415.562156 -319.005452) (xy 415.512981 -319.003471) (xy 415.464762 -318.993627)
			(xy 415.418746 -318.976175) (xy 415.376125 -318.951568) (xy 415.338004 -318.920443) (xy 415.305369 -318.883606)
			(xy 415.279066 -318.84201) (xy 415.259775 -318.796734) (xy 415.247998 -318.74895) (xy 415.244038 -318.699896)
			(xy 413.95523 -318.699896) (xy 413.954735 -318.724503) (xy 413.94684 -318.77308) (xy 413.931256 -318.819761)
			(xy 413.908385 -318.863338) (xy 413.87882 -318.902682) (xy 413.843327 -318.936774) (xy 413.802824 -318.96473)
			(xy 413.758362 -318.985828) (xy 413.711091 -318.99952) (xy 413.662236 -319.005452) (xy 413.613061 -319.003471)
			(xy 413.564842 -318.993627) (xy 413.518826 -318.976175) (xy 413.476205 -318.951568) (xy 413.438084 -318.920443)
			(xy 413.405449 -318.883606) (xy 413.379146 -318.84201) (xy 413.359855 -318.796734) (xy 413.348078 -318.74895)
			(xy 413.344118 -318.699896) (xy 412.05531 -318.699896) (xy 412.054815 -318.724503) (xy 412.04692 -318.77308)
			(xy 412.031336 -318.819761) (xy 412.008465 -318.863338) (xy 411.9789 -318.902682) (xy 411.943407 -318.936774)
			(xy 411.902904 -318.96473) (xy 411.858442 -318.985828) (xy 411.811171 -318.99952) (xy 411.762316 -319.005452)
			(xy 411.713141 -319.003471) (xy 411.664922 -318.993627) (xy 411.618906 -318.976175) (xy 411.576285 -318.951568)
			(xy 411.538164 -318.920443) (xy 411.505529 -318.883606) (xy 411.479226 -318.84201) (xy 411.459935 -318.796734)
			(xy 411.448158 -318.74895) (xy 411.444198 -318.699896) (xy 410.155136 -318.699896) (xy 410.154641 -318.724503)
			(xy 410.146746 -318.77308) (xy 410.131162 -318.819761) (xy 410.108291 -318.863338) (xy 410.078726 -318.902682)
			(xy 410.043233 -318.936774) (xy 410.00273 -318.96473) (xy 409.958268 -318.985828) (xy 409.910997 -318.99952)
			(xy 409.862142 -319.005452) (xy 409.812967 -319.003471) (xy 409.764748 -318.993627) (xy 409.718732 -318.976175)
			(xy 409.676111 -318.951568) (xy 409.63799 -318.920443) (xy 409.605355 -318.883606) (xy 409.579052 -318.84201)
			(xy 409.559761 -318.796734) (xy 409.547984 -318.74895) (xy 409.544024 -318.699896) (xy 408.255216 -318.699896)
			(xy 408.254721 -318.724503) (xy 408.246826 -318.77308) (xy 408.231242 -318.819761) (xy 408.208371 -318.863338)
			(xy 408.178806 -318.902682) (xy 408.143313 -318.936774) (xy 408.10281 -318.96473) (xy 408.058348 -318.985828)
			(xy 408.011077 -318.99952) (xy 407.962222 -319.005452) (xy 407.913047 -319.003471) (xy 407.864828 -318.993627)
			(xy 407.818812 -318.976175) (xy 407.776191 -318.951568) (xy 407.73807 -318.920443) (xy 407.705435 -318.883606)
			(xy 407.679132 -318.84201) (xy 407.659841 -318.796734) (xy 407.648064 -318.74895) (xy 407.644104 -318.699896)
			(xy 406.355296 -318.699896) (xy 406.354801 -318.724503) (xy 406.346906 -318.77308) (xy 406.331322 -318.819761)
			(xy 406.308451 -318.863338) (xy 406.278886 -318.902682) (xy 406.243393 -318.936774) (xy 406.20289 -318.96473)
			(xy 406.158428 -318.985828) (xy 406.111157 -318.99952) (xy 406.062302 -319.005452) (xy 406.013127 -319.003471)
			(xy 405.964908 -318.993627) (xy 405.918892 -318.976175) (xy 405.876271 -318.951568) (xy 405.83815 -318.920443)
			(xy 405.805515 -318.883606) (xy 405.779212 -318.84201) (xy 405.759921 -318.796734) (xy 405.748144 -318.74895)
			(xy 405.744184 -318.699896) (xy 404.455122 -318.699896) (xy 404.454627 -318.724503) (xy 404.446732 -318.77308)
			(xy 404.431148 -318.819761) (xy 404.408277 -318.863338) (xy 404.378712 -318.902682) (xy 404.343219 -318.936774)
			(xy 404.302716 -318.96473) (xy 404.258254 -318.985828) (xy 404.210983 -318.99952) (xy 404.162128 -319.005452)
			(xy 404.112953 -319.003471) (xy 404.064734 -318.993627) (xy 404.018718 -318.976175) (xy 403.976097 -318.951568)
			(xy 403.937976 -318.920443) (xy 403.905341 -318.883606) (xy 403.879038 -318.84201) (xy 403.859747 -318.796734)
			(xy 403.84797 -318.74895) (xy 403.84401 -318.699896) (xy 402.555202 -318.699896) (xy 402.554707 -318.724503)
			(xy 402.546812 -318.77308) (xy 402.531228 -318.819761) (xy 402.508357 -318.863338) (xy 402.478792 -318.902682)
			(xy 402.443299 -318.936774) (xy 402.402796 -318.96473) (xy 402.358334 -318.985828) (xy 402.311063 -318.99952)
			(xy 402.262208 -319.005452) (xy 402.213033 -319.003471) (xy 402.164814 -318.993627) (xy 402.118798 -318.976175)
			(xy 402.076177 -318.951568) (xy 402.038056 -318.920443) (xy 402.005421 -318.883606) (xy 401.979118 -318.84201)
			(xy 401.959827 -318.796734) (xy 401.94805 -318.74895) (xy 401.94409 -318.699896) (xy 400.655282 -318.699896)
			(xy 400.654787 -318.724503) (xy 400.646892 -318.77308) (xy 400.631308 -318.819761) (xy 400.608437 -318.863338)
			(xy 400.578872 -318.902682) (xy 400.543379 -318.936774) (xy 400.502876 -318.96473) (xy 400.458414 -318.985828)
			(xy 400.411143 -318.99952) (xy 400.362288 -319.005452) (xy 400.313113 -319.003471) (xy 400.264894 -318.993627)
			(xy 400.218878 -318.976175) (xy 400.176257 -318.951568) (xy 400.138136 -318.920443) (xy 400.105501 -318.883606)
			(xy 400.079198 -318.84201) (xy 400.059907 -318.796734) (xy 400.04813 -318.74895) (xy 400.04417 -318.699896)
			(xy 398.755108 -318.699896) (xy 398.754613 -318.724503) (xy 398.746718 -318.77308) (xy 398.731134 -318.819761)
			(xy 398.708263 -318.863338) (xy 398.678698 -318.902682) (xy 398.643205 -318.936774) (xy 398.602702 -318.96473)
			(xy 398.55824 -318.985828) (xy 398.510969 -318.99952) (xy 398.462114 -319.005452) (xy 398.412939 -319.003471)
			(xy 398.36472 -318.993627) (xy 398.318704 -318.976175) (xy 398.276083 -318.951568) (xy 398.237962 -318.920443)
			(xy 398.205327 -318.883606) (xy 398.179024 -318.84201) (xy 398.159733 -318.796734) (xy 398.147956 -318.74895)
			(xy 398.143996 -318.699896) (xy 396.855188 -318.699896) (xy 396.854693 -318.724503) (xy 396.846798 -318.77308)
			(xy 396.831214 -318.819761) (xy 396.808343 -318.863338) (xy 396.778778 -318.902682) (xy 396.743285 -318.936774)
			(xy 396.702782 -318.96473) (xy 396.65832 -318.985828) (xy 396.611049 -318.99952) (xy 396.562194 -319.005452)
			(xy 396.513019 -319.003471) (xy 396.4648 -318.993627) (xy 396.418784 -318.976175) (xy 396.376163 -318.951568)
			(xy 396.338042 -318.920443) (xy 396.305407 -318.883606) (xy 396.279104 -318.84201) (xy 396.259813 -318.796734)
			(xy 396.248036 -318.74895) (xy 396.244076 -318.699896) (xy 394.955268 -318.699896) (xy 394.954773 -318.724503)
			(xy 394.946878 -318.77308) (xy 394.931294 -318.819761) (xy 394.908423 -318.863338) (xy 394.878858 -318.902682)
			(xy 394.843365 -318.936774) (xy 394.802862 -318.96473) (xy 394.7584 -318.985828) (xy 394.711129 -318.99952)
			(xy 394.662274 -319.005452) (xy 394.613099 -319.003471) (xy 394.56488 -318.993627) (xy 394.518864 -318.976175)
			(xy 394.476243 -318.951568) (xy 394.438122 -318.920443) (xy 394.405487 -318.883606) (xy 394.379184 -318.84201)
			(xy 394.359893 -318.796734) (xy 394.348116 -318.74895) (xy 394.344156 -318.699896) (xy 393.055094 -318.699896)
			(xy 393.054599 -318.724503) (xy 393.046704 -318.77308) (xy 393.03112 -318.819761) (xy 393.008249 -318.863338)
			(xy 392.978684 -318.902682) (xy 392.943191 -318.936774) (xy 392.902688 -318.96473) (xy 392.858226 -318.985828)
			(xy 392.810955 -318.99952) (xy 392.7621 -319.005452) (xy 392.712925 -319.003471) (xy 392.664706 -318.993627)
			(xy 392.61869 -318.976175) (xy 392.576069 -318.951568) (xy 392.537948 -318.920443) (xy 392.505313 -318.883606)
			(xy 392.47901 -318.84201) (xy 392.459719 -318.796734) (xy 392.447942 -318.74895) (xy 392.443982 -318.699896)
			(xy 391.155174 -318.699896) (xy 391.154679 -318.724503) (xy 391.146784 -318.77308) (xy 391.1312 -318.819761)
			(xy 391.108329 -318.863338) (xy 391.078764 -318.902682) (xy 391.043271 -318.936774) (xy 391.002768 -318.96473)
			(xy 390.958306 -318.985828) (xy 390.911035 -318.99952) (xy 390.86218 -319.005452) (xy 390.813005 -319.003471)
			(xy 390.764786 -318.993627) (xy 390.71877 -318.976175) (xy 390.676149 -318.951568) (xy 390.638028 -318.920443)
			(xy 390.605393 -318.883606) (xy 390.57909 -318.84201) (xy 390.559799 -318.796734) (xy 390.548022 -318.74895)
			(xy 390.544062 -318.699896) (xy 389.255254 -318.699896) (xy 389.254759 -318.724503) (xy 389.246864 -318.77308)
			(xy 389.23128 -318.819761) (xy 389.208409 -318.863338) (xy 389.178844 -318.902682) (xy 389.143351 -318.936774)
			(xy 389.102848 -318.96473) (xy 389.058386 -318.985828) (xy 389.011115 -318.99952) (xy 388.96226 -319.005452)
			(xy 388.913085 -319.003471) (xy 388.864866 -318.993627) (xy 388.81885 -318.976175) (xy 388.776229 -318.951568)
			(xy 388.738108 -318.920443) (xy 388.705473 -318.883606) (xy 388.67917 -318.84201) (xy 388.659879 -318.796734)
			(xy 388.648102 -318.74895) (xy 388.644142 -318.699896) (xy 387.355334 -318.699896) (xy 387.354839 -318.724503)
			(xy 387.346944 -318.77308) (xy 387.33136 -318.819761) (xy 387.308489 -318.863338) (xy 387.278924 -318.902682)
			(xy 387.243431 -318.936774) (xy 387.202928 -318.96473) (xy 387.158466 -318.985828) (xy 387.111195 -318.99952)
			(xy 387.06234 -319.005452) (xy 387.013165 -319.003471) (xy 386.964946 -318.993627) (xy 386.91893 -318.976175)
			(xy 386.876309 -318.951568) (xy 386.838188 -318.920443) (xy 386.805553 -318.883606) (xy 386.77925 -318.84201)
			(xy 386.759959 -318.796734) (xy 386.748182 -318.74895) (xy 386.744222 -318.699896) (xy 379.626683 -318.699896)
			(xy 379.699893 -318.756463) (xy 379.81243 -318.853497) (xy 379.919597 -318.956432) (xy 380.021084 -319.064971)
			(xy 380.116598 -319.1788) (xy 380.205865 -319.297593) (xy 380.288626 -319.421005) (xy 380.364644 -319.548683)
			(xy 380.433699 -319.680256) (xy 380.495592 -319.815347) (xy 380.550145 -319.953564) (xy 380.5972 -320.094511)
			(xy 380.636622 -320.237781) (xy 380.668296 -320.38296) (xy 380.692132 -320.529629) (xy 380.708061 -320.677367)
			(xy 380.716037 -320.825747) (xy 380.716536 -320.900044) (xy 435.182527 -320.900044) (xy 435.186516 -320.751504)
			(xy 435.198473 -320.603391) (xy 435.218363 -320.456134) (xy 435.246128 -320.310158) (xy 435.281689 -320.165881)
			(xy 435.324943 -320.023722) (xy 435.375765 -319.884089) (xy 435.434009 -319.747386) (xy 435.499507 -319.614006)
			(xy 435.57207 -319.484334) (xy 435.651488 -319.358744) (xy 435.737533 -319.237597) (xy 435.829957 -319.121244)
			(xy 435.928493 -319.01002) (xy 436.032857 -318.904245) (xy 436.142749 -318.804225) (xy 436.25785 -318.710247)
			(xy 436.37783 -318.622583) (xy 436.502343 -318.541486) (xy 436.631029 -318.467189) (xy 436.763518 -318.399907)
			(xy 436.899427 -318.339833) (xy 437.038365 -318.287141) (xy 437.179931 -318.241982) (xy 437.323717 -318.204487)
			(xy 437.469308 -318.174765) (xy 437.616284 -318.1529) (xy 437.764223 -318.138956) (xy 437.912696 -318.132972)
			(xy 438.061277 -318.134967) (xy 438.209536 -318.144935) (xy 438.357047 -318.162846) (xy 438.503383 -318.188649)
			(xy 438.648124 -318.222269) (xy 438.790851 -318.263611) (xy 438.931154 -318.312554) (xy 439.068627 -318.368957)
			(xy 439.202874 -318.432658) (xy 439.333509 -318.503474) (xy 439.460154 -318.581199) (xy 439.582444 -318.66561)
			(xy 439.700027 -318.756463) (xy 439.812564 -318.853497) (xy 439.919731 -318.956432) (xy 440.021218 -319.064971)
			(xy 440.116732 -319.1788) (xy 440.205999 -319.297593) (xy 440.28876 -319.421005) (xy 440.364778 -319.548683)
			(xy 440.433833 -319.680256) (xy 440.495726 -319.815347) (xy 440.550279 -319.953564) (xy 440.597334 -320.094511)
			(xy 440.636756 -320.237781) (xy 440.66843 -320.38296) (xy 440.692266 -320.529629) (xy 440.708195 -320.677367)
			(xy 440.716171 -320.825747) (xy 440.71667 -320.900044) (xy 440.716171 -320.974341) (xy 440.708195 -321.122721)
			(xy 440.692266 -321.270459) (xy 440.66843 -321.417128) (xy 440.636756 -321.562307) (xy 440.597334 -321.705577)
			(xy 440.550279 -321.846524) (xy 440.495726 -321.984741) (xy 440.433833 -322.119832) (xy 440.364778 -322.251405)
			(xy 440.28876 -322.379083) (xy 440.205999 -322.502495) (xy 440.116732 -322.621288) (xy 440.021218 -322.735117)
			(xy 439.919731 -322.843656) (xy 439.812564 -322.946591) (xy 439.700027 -323.043625) (xy 439.582444 -323.134478)
			(xy 439.460154 -323.218889) (xy 439.333509 -323.296614) (xy 439.202874 -323.36743) (xy 439.068627 -323.431131)
			(xy 438.931154 -323.487534) (xy 438.790851 -323.536477) (xy 438.648124 -323.577819) (xy 438.503383 -323.611439)
			(xy 438.357047 -323.637242) (xy 438.209536 -323.655153) (xy 438.061277 -323.665121) (xy 437.912696 -323.667116)
			(xy 437.764223 -323.661132) (xy 437.616284 -323.647188) (xy 437.469308 -323.625323) (xy 437.323717 -323.595601)
			(xy 437.179931 -323.558106) (xy 437.038365 -323.512947) (xy 436.899427 -323.460255) (xy 436.763518 -323.400181)
			(xy 436.631029 -323.332899) (xy 436.502343 -323.258602) (xy 436.37783 -323.177505) (xy 436.25785 -323.089841)
			(xy 436.142749 -322.995863) (xy 436.032857 -322.895843) (xy 435.928493 -322.790068) (xy 435.829957 -322.678844)
			(xy 435.737533 -322.562491) (xy 435.651488 -322.441344) (xy 435.57207 -322.315754) (xy 435.499507 -322.186082)
			(xy 435.434009 -322.052702) (xy 435.375765 -321.915999) (xy 435.324943 -321.776366) (xy 435.281689 -321.634207)
			(xy 435.246128 -321.48993) (xy 435.218363 -321.343954) (xy 435.198473 -321.196697) (xy 435.186516 -321.048584)
			(xy 435.182527 -320.900044) (xy 380.716536 -320.900044) (xy 380.716037 -320.974341) (xy 380.708061 -321.122721)
			(xy 380.692132 -321.270459) (xy 380.668296 -321.417128) (xy 380.636622 -321.562307) (xy 380.5972 -321.705577)
			(xy 380.550145 -321.846524) (xy 380.495592 -321.984741) (xy 380.433699 -322.119832) (xy 380.364644 -322.251405)
			(xy 380.288626 -322.379083) (xy 380.205865 -322.502495) (xy 380.116598 -322.621288) (xy 380.021084 -322.735117)
			(xy 379.919597 -322.843656) (xy 379.81243 -322.946591) (xy 379.699893 -323.043625) (xy 379.58231 -323.134478)
			(xy 379.46002 -323.218889) (xy 379.333375 -323.296614) (xy 379.20274 -323.36743) (xy 379.068493 -323.431131)
			(xy 378.93102 -323.487534) (xy 378.790717 -323.536477) (xy 378.64799 -323.577819) (xy 378.503249 -323.611439)
			(xy 378.356913 -323.637242) (xy 378.209402 -323.655153) (xy 378.061143 -323.665121) (xy 377.912562 -323.667116)
			(xy 377.764089 -323.661132) (xy 377.61615 -323.647188) (xy 377.469174 -323.625323) (xy 377.323583 -323.595601)
			(xy 377.179797 -323.558106) (xy 377.038231 -323.512947) (xy 376.899293 -323.460255) (xy 376.763384 -323.400181)
			(xy 376.630895 -323.332899) (xy 376.502209 -323.258602) (xy 376.377696 -323.177505) (xy 376.257716 -323.089841)
			(xy 376.142615 -322.995863) (xy 376.032723 -322.895843) (xy 375.928359 -322.790068) (xy 375.829823 -322.678844)
			(xy 375.737399 -322.562491) (xy 375.651354 -322.441344) (xy 375.571936 -322.315754) (xy 375.499373 -322.186082)
			(xy 375.433875 -322.052702) (xy 375.375631 -321.915999) (xy 375.324809 -321.776366) (xy 375.281555 -321.634207)
			(xy 375.245994 -321.48993) (xy 375.218229 -321.343954) (xy 375.198339 -321.196697) (xy 375.186382 -321.048584)
			(xy 375.182393 -320.900044) (xy 324.616572 -320.900044) (xy 324.616073 -320.974341) (xy 324.608097 -321.122721)
			(xy 324.592168 -321.270459) (xy 324.568332 -321.417128) (xy 324.536658 -321.562307) (xy 324.497236 -321.705577)
			(xy 324.450181 -321.846524) (xy 324.395628 -321.984741) (xy 324.333735 -322.119832) (xy 324.26468 -322.251405)
			(xy 324.188662 -322.379083) (xy 324.105901 -322.502495) (xy 324.016634 -322.621288) (xy 323.92112 -322.735117)
			(xy 323.819633 -322.843656) (xy 323.712466 -322.946591) (xy 323.599929 -323.043625) (xy 323.482346 -323.134478)
			(xy 323.360056 -323.218889) (xy 323.233411 -323.296614) (xy 323.102776 -323.36743) (xy 322.968529 -323.431131)
			(xy 322.831056 -323.487534) (xy 322.690753 -323.536477) (xy 322.548026 -323.577819) (xy 322.403285 -323.611439)
			(xy 322.256949 -323.637242) (xy 322.109438 -323.655153) (xy 321.961179 -323.665121) (xy 321.812598 -323.667116)
			(xy 321.664125 -323.661132) (xy 321.516186 -323.647188) (xy 321.36921 -323.625323) (xy 321.223619 -323.595601)
			(xy 321.079833 -323.558106) (xy 320.938267 -323.512947) (xy 320.799329 -323.460255) (xy 320.66342 -323.400181)
			(xy 320.530931 -323.332899) (xy 320.402245 -323.258602) (xy 320.277732 -323.177505) (xy 320.157752 -323.089841)
			(xy 320.042651 -322.995863) (xy 319.932759 -322.895843) (xy 319.828395 -322.790068) (xy 319.729859 -322.678844)
			(xy 319.637435 -322.562491) (xy 319.55139 -322.441344) (xy 319.471972 -322.315754) (xy 319.399409 -322.186082)
			(xy 319.333911 -322.052702) (xy 319.275667 -321.915999) (xy 319.224845 -321.776366) (xy 319.181591 -321.634207)
			(xy 319.14603 -321.48993) (xy 319.118265 -321.343954) (xy 319.098375 -321.196697) (xy 319.086418 -321.048584)
			(xy 319.082429 -320.900044) (xy 264.616692 -320.900044) (xy 264.616193 -320.974341) (xy 264.608217 -321.122721)
			(xy 264.592288 -321.270459) (xy 264.568452 -321.417128) (xy 264.536778 -321.562307) (xy 264.497356 -321.705577)
			(xy 264.450301 -321.846524) (xy 264.395748 -321.984741) (xy 264.333855 -322.119832) (xy 264.2648 -322.251405)
			(xy 264.188782 -322.379083) (xy 264.106021 -322.502495) (xy 264.016754 -322.621288) (xy 263.92124 -322.735117)
			(xy 263.819753 -322.843656) (xy 263.712586 -322.946591) (xy 263.600049 -323.043625) (xy 263.482466 -323.134478)
			(xy 263.360176 -323.218889) (xy 263.233531 -323.296614) (xy 263.102896 -323.36743) (xy 262.968649 -323.431131)
			(xy 262.831176 -323.487534) (xy 262.690873 -323.536477) (xy 262.548146 -323.577819) (xy 262.403405 -323.611439)
			(xy 262.257069 -323.637242) (xy 262.109558 -323.655153) (xy 261.961299 -323.665121) (xy 261.812718 -323.667116)
			(xy 261.664245 -323.661132) (xy 261.516306 -323.647188) (xy 261.36933 -323.625323) (xy 261.223739 -323.595601)
			(xy 261.079953 -323.558106) (xy 260.938387 -323.512947) (xy 260.799449 -323.460255) (xy 260.66354 -323.400181)
			(xy 260.531051 -323.332899) (xy 260.402365 -323.258602) (xy 260.277852 -323.177505) (xy 260.157872 -323.089841)
			(xy 260.042771 -322.995863) (xy 259.932879 -322.895843) (xy 259.828515 -322.790068) (xy 259.729979 -322.678844)
			(xy 259.637555 -322.562491) (xy 259.55151 -322.441344) (xy 259.472092 -322.315754) (xy 259.399529 -322.186082)
			(xy 259.334031 -322.052702) (xy 259.275787 -321.915999) (xy 259.224965 -321.776366) (xy 259.181711 -321.634207)
			(xy 259.14615 -321.48993) (xy 259.118385 -321.343954) (xy 259.098495 -321.196697) (xy 259.086538 -321.048584)
			(xy 259.082549 -320.900044) (xy 208.516474 -320.900044) (xy 208.515975 -320.974341) (xy 208.507999 -321.122721)
			(xy 208.49207 -321.270459) (xy 208.468234 -321.417128) (xy 208.43656 -321.562307) (xy 208.397138 -321.705577)
			(xy 208.350083 -321.846524) (xy 208.29553 -321.984741) (xy 208.233637 -322.119832) (xy 208.164582 -322.251405)
			(xy 208.088564 -322.379083) (xy 208.005803 -322.502495) (xy 207.916536 -322.621288) (xy 207.821022 -322.735117)
			(xy 207.719535 -322.843656) (xy 207.612368 -322.946591) (xy 207.499831 -323.043625) (xy 207.382248 -323.134478)
			(xy 207.259958 -323.218889) (xy 207.133313 -323.296614) (xy 207.002678 -323.36743) (xy 206.868431 -323.431131)
			(xy 206.730958 -323.487534) (xy 206.590655 -323.536477) (xy 206.447928 -323.577819) (xy 206.303187 -323.611439)
			(xy 206.156851 -323.637242) (xy 206.00934 -323.655153) (xy 205.861081 -323.665121) (xy 205.7125 -323.667116)
			(xy 205.564027 -323.661132) (xy 205.416088 -323.647188) (xy 205.269112 -323.625323) (xy 205.123521 -323.595601)
			(xy 204.979735 -323.558106) (xy 204.838169 -323.512947) (xy 204.699231 -323.460255) (xy 204.563322 -323.400181)
			(xy 204.430833 -323.332899) (xy 204.302147 -323.258602) (xy 204.177634 -323.177505) (xy 204.057654 -323.089841)
			(xy 203.942553 -322.995863) (xy 203.832661 -322.895843) (xy 203.728297 -322.790068) (xy 203.629761 -322.678844)
			(xy 203.537337 -322.562491) (xy 203.451292 -322.441344) (xy 203.371874 -322.315754) (xy 203.299311 -322.186082)
			(xy 203.233813 -322.052702) (xy 203.175569 -321.915999) (xy 203.124747 -321.776366) (xy 203.081493 -321.634207)
			(xy 203.045932 -321.48993) (xy 203.018167 -321.343954) (xy 202.998277 -321.196697) (xy 202.98632 -321.048584)
			(xy 202.982331 -320.900044) (xy 148.516594 -320.900044) (xy 148.516095 -320.974341) (xy 148.508119 -321.122721)
			(xy 148.49219 -321.270459) (xy 148.468354 -321.417128) (xy 148.43668 -321.562307) (xy 148.397258 -321.705577)
			(xy 148.350203 -321.846524) (xy 148.29565 -321.984741) (xy 148.233757 -322.119832) (xy 148.164702 -322.251405)
			(xy 148.088684 -322.379083) (xy 148.005923 -322.502495) (xy 147.916656 -322.621288) (xy 147.821142 -322.735117)
			(xy 147.719655 -322.843656) (xy 147.612488 -322.946591) (xy 147.499951 -323.043625) (xy 147.382368 -323.134478)
			(xy 147.260078 -323.218889) (xy 147.133433 -323.296614) (xy 147.002798 -323.36743) (xy 146.868551 -323.431131)
			(xy 146.731078 -323.487534) (xy 146.590775 -323.536477) (xy 146.448048 -323.577819) (xy 146.303307 -323.611439)
			(xy 146.156971 -323.637242) (xy 146.00946 -323.655153) (xy 145.861201 -323.665121) (xy 145.71262 -323.667116)
			(xy 145.564147 -323.661132) (xy 145.416208 -323.647188) (xy 145.269232 -323.625323) (xy 145.123641 -323.595601)
			(xy 144.979855 -323.558106) (xy 144.838289 -323.512947) (xy 144.699351 -323.460255) (xy 144.563442 -323.400181)
			(xy 144.430953 -323.332899) (xy 144.302267 -323.258602) (xy 144.177754 -323.177505) (xy 144.057774 -323.089841)
			(xy 143.942673 -322.995863) (xy 143.832781 -322.895843) (xy 143.728417 -322.790068) (xy 143.629881 -322.678844)
			(xy 143.537457 -322.562491) (xy 143.451412 -322.441344) (xy 143.371994 -322.315754) (xy 143.299431 -322.186082)
			(xy 143.233933 -322.052702) (xy 143.175689 -321.915999) (xy 143.124867 -321.776366) (xy 143.081613 -321.634207)
			(xy 143.046052 -321.48993) (xy 143.018287 -321.343954) (xy 142.998397 -321.196697) (xy 142.98644 -321.048584)
			(xy 142.982451 -320.900044) (xy 92.41663 -320.900044) (xy 92.416131 -320.974341) (xy 92.408155 -321.122721)
			(xy 92.392226 -321.270459) (xy 92.36839 -321.417128) (xy 92.336716 -321.562307) (xy 92.297294 -321.705577)
			(xy 92.250239 -321.846524) (xy 92.195686 -321.984741) (xy 92.133793 -322.119832) (xy 92.064738 -322.251405)
			(xy 91.98872 -322.379083) (xy 91.905959 -322.502495) (xy 91.816692 -322.621288) (xy 91.721178 -322.735117)
			(xy 91.619691 -322.843656) (xy 91.512524 -322.946591) (xy 91.399987 -323.043625) (xy 91.282404 -323.134478)
			(xy 91.160114 -323.218889) (xy 91.033469 -323.296614) (xy 90.902834 -323.36743) (xy 90.768587 -323.431131)
			(xy 90.631114 -323.487534) (xy 90.490811 -323.536477) (xy 90.348084 -323.577819) (xy 90.203343 -323.611439)
			(xy 90.057007 -323.637242) (xy 89.909496 -323.655153) (xy 89.761237 -323.665121) (xy 89.612656 -323.667116)
			(xy 89.464183 -323.661132) (xy 89.316244 -323.647188) (xy 89.169268 -323.625323) (xy 89.023677 -323.595601)
			(xy 88.879891 -323.558106) (xy 88.738325 -323.512947) (xy 88.599387 -323.460255) (xy 88.463478 -323.400181)
			(xy 88.330989 -323.332899) (xy 88.202303 -323.258602) (xy 88.07779 -323.177505) (xy 87.95781 -323.089841)
			(xy 87.842709 -322.995863) (xy 87.732817 -322.895843) (xy 87.628453 -322.790068) (xy 87.529917 -322.678844)
			(xy 87.437493 -322.562491) (xy 87.351448 -322.441344) (xy 87.27203 -322.315754) (xy 87.199467 -322.186082)
			(xy 87.133969 -322.052702) (xy 87.075725 -321.915999) (xy 87.024903 -321.776366) (xy 86.981649 -321.634207)
			(xy 86.946088 -321.48993) (xy 86.918323 -321.343954) (xy 86.898433 -321.196697) (xy 86.886476 -321.048584)
			(xy 86.882487 -320.900044) (xy 32.416496 -320.900044) (xy 32.415997 -320.974341) (xy 32.408021 -321.122721)
			(xy 32.392092 -321.270459) (xy 32.368256 -321.417128) (xy 32.336582 -321.562307) (xy 32.29716 -321.705577)
			(xy 32.250105 -321.846524) (xy 32.195552 -321.984741) (xy 32.133659 -322.119832) (xy 32.064604 -322.251405)
			(xy 31.988586 -322.379083) (xy 31.905825 -322.502495) (xy 31.816558 -322.621288) (xy 31.721044 -322.735117)
			(xy 31.619557 -322.843656) (xy 31.51239 -322.946591) (xy 31.399853 -323.043625) (xy 31.28227 -323.134478)
			(xy 31.15998 -323.218889) (xy 31.033335 -323.296614) (xy 30.9027 -323.36743) (xy 30.768453 -323.431131)
			(xy 30.63098 -323.487534) (xy 30.490677 -323.536477) (xy 30.34795 -323.577819) (xy 30.203209 -323.611439)
			(xy 30.056873 -323.637242) (xy 29.909362 -323.655153) (xy 29.761103 -323.665121) (xy 29.612522 -323.667116)
			(xy 29.464049 -323.661132) (xy 29.31611 -323.647188) (xy 29.169134 -323.625323) (xy 29.023543 -323.595601)
			(xy 28.879757 -323.558106) (xy 28.738191 -323.512947) (xy 28.599253 -323.460255) (xy 28.463344 -323.400181)
			(xy 28.330855 -323.332899) (xy 28.202169 -323.258602) (xy 28.077656 -323.177505) (xy 27.957676 -323.089841)
			(xy 27.842575 -322.995863) (xy 27.732683 -322.895843) (xy 27.628319 -322.790068) (xy 27.529783 -322.678844)
			(xy 27.437359 -322.562491) (xy 27.351314 -322.441344) (xy 27.271896 -322.315754) (xy 27.199333 -322.186082)
			(xy 27.133835 -322.052702) (xy 27.075591 -321.915999) (xy 27.024769 -321.776366) (xy 26.981515 -321.634207)
			(xy 26.945954 -321.48993) (xy 26.918189 -321.343954) (xy 26.898299 -321.196697) (xy 26.886342 -321.048584)
			(xy 26.882353 -320.900044) (xy 0.508 -320.900044) (xy 0.508 -330.416662) (xy 97.355152 -330.416662)
			(xy 97.355152 -329.553062) (xy 97.355642 -329.523078) (xy 97.36347 -329.463622) (xy 97.378991 -329.405697)
			(xy 97.40194 -329.350293) (xy 97.431924 -329.298359) (xy 97.46843 -329.250783) (xy 97.510835 -329.208378)
			(xy 97.558411 -329.171872) (xy 97.610345 -329.141888) (xy 97.665749 -329.118939) (xy 97.723674 -329.103418)
			(xy 97.78313 -329.09559) (xy 97.843098 -329.09559) (xy 97.902554 -329.103418) (xy 97.960479 -329.118939)
			(xy 98.015883 -329.141888) (xy 98.067817 -329.171872) (xy 98.115393 -329.208378) (xy 98.157798 -329.250783)
			(xy 98.194304 -329.298359) (xy 98.224288 -329.350293) (xy 98.247237 -329.405697) (xy 98.262758 -329.463622)
			(xy 98.270586 -329.523078) (xy 98.271076 -329.553062) (xy 98.271076 -330.416662) (xy 98.270586 -330.446646)
			(xy 98.262758 -330.506102) (xy 98.247237 -330.564027) (xy 98.224288 -330.619431) (xy 98.194304 -330.671365)
			(xy 98.157798 -330.718941) (xy 98.115393 -330.761346) (xy 98.067817 -330.797852) (xy 98.015883 -330.827836)
			(xy 97.960479 -330.850785) (xy 97.902554 -330.866306) (xy 97.843098 -330.874134) (xy 97.78313 -330.874134)
			(xy 97.723674 -330.866306) (xy 97.665749 -330.850785) (xy 97.610345 -330.827836) (xy 97.558411 -330.797852)
			(xy 97.510835 -330.761346) (xy 97.46843 -330.718941) (xy 97.431924 -330.671365) (xy 97.40194 -330.619431)
			(xy 97.378991 -330.564027) (xy 97.36347 -330.506102) (xy 97.355642 -330.446646) (xy 97.355152 -330.416662)
			(xy 0.508 -330.416662) (xy 0.508 -331.53223) (xy 114.955828 -331.53223) (xy 114.955828 -330.66863)
			(xy 114.956318 -330.638646) (xy 114.964146 -330.57919) (xy 114.979667 -330.521265) (xy 115.002616 -330.465861)
			(xy 115.0326 -330.413927) (xy 115.069106 -330.366351) (xy 115.111511 -330.323946) (xy 115.159087 -330.28744)
			(xy 115.211021 -330.257456) (xy 115.266425 -330.234507) (xy 115.32435 -330.218986) (xy 115.383806 -330.211158)
			(xy 115.443774 -330.211158) (xy 115.50323 -330.218986) (xy 115.561155 -330.234507) (xy 115.616559 -330.257456)
			(xy 115.668493 -330.28744) (xy 115.716069 -330.323946) (xy 115.758474 -330.366351) (xy 115.79498 -330.413927)
			(xy 115.824964 -330.465861) (xy 115.847913 -330.521265) (xy 115.863434 -330.57919) (xy 115.871262 -330.638646)
			(xy 115.871752 -330.66863) (xy 115.871752 -331.53223) (xy 115.871262 -331.562214) (xy 115.863434 -331.62167)
			(xy 115.847913 -331.679595) (xy 115.824964 -331.734999) (xy 115.79498 -331.786933) (xy 115.758474 -331.834509)
			(xy 115.716069 -331.876914) (xy 115.668493 -331.91342) (xy 115.616559 -331.943404) (xy 115.561155 -331.966353)
			(xy 115.50323 -331.981874) (xy 115.443774 -331.989702) (xy 115.383806 -331.989702) (xy 115.32435 -331.981874)
			(xy 115.266425 -331.966353) (xy 115.211021 -331.943404) (xy 115.159087 -331.91342) (xy 115.111511 -331.876914)
			(xy 115.069106 -331.834509) (xy 115.0326 -331.786933) (xy 115.002616 -331.734999) (xy 114.979667 -331.679595)
			(xy 114.964146 -331.62167) (xy 114.956318 -331.562214) (xy 114.955828 -331.53223) (xy 0.508 -331.53223)
			(xy 0.508 -333.950056) (xy 93.5736 -333.950056) (xy 93.5736 -333.086456) (xy 93.57409 -333.056488)
			(xy 93.581913 -332.997066) (xy 93.597426 -332.939173) (xy 93.620362 -332.8838) (xy 93.650329 -332.831894)
			(xy 93.686816 -332.784344) (xy 93.729196 -332.741964) (xy 93.776746 -332.705477) (xy 93.828652 -332.67551)
			(xy 93.884025 -332.652574) (xy 93.941918 -332.637061) (xy 94.00134 -332.629238) (xy 94.061276 -332.629238)
			(xy 94.120698 -332.637061) (xy 94.178591 -332.652574) (xy 94.233964 -332.67551) (xy 94.28587 -332.705477)
			(xy 94.33342 -332.741964) (xy 94.3758 -332.784344) (xy 94.412287 -332.831894) (xy 94.442254 -332.8838)
			(xy 94.46519 -332.939173) (xy 94.46736 -332.947271) (xy 365.368753 -332.947271) (xy 365.368753 -332.887329)
			(xy 365.376578 -332.827899) (xy 365.392093 -332.77) (xy 365.415033 -332.71462) (xy 365.445006 -332.66271)
			(xy 365.481498 -332.615155) (xy 365.523886 -332.572772) (xy 365.571443 -332.536283) (xy 365.623356 -332.506315)
			(xy 365.678737 -332.48338) (xy 365.736639 -332.46787) (xy 365.796069 -332.460051) (xy 365.82604 -332.459584)
			(xy 366.68964 -332.459584) (xy 366.719605 -332.460093) (xy 366.779023 -332.46792) (xy 366.836911 -332.483435)
			(xy 366.892278 -332.506374) (xy 366.944178 -332.536342) (xy 366.991723 -332.572828) (xy 367.034098 -332.615207)
			(xy 367.07058 -332.662755) (xy 367.100544 -332.714658) (xy 367.123478 -332.770027) (xy 367.138988 -332.827916)
			(xy 367.14681 -332.887335) (xy 367.14681 -332.947265) (xy 367.138988 -333.006684) (xy 367.123478 -333.064573)
			(xy 367.100544 -333.119942) (xy 367.07058 -333.171845) (xy 367.034098 -333.219393) (xy 366.991723 -333.261772)
			(xy 366.944178 -333.298258) (xy 366.892278 -333.328226) (xy 366.836911 -333.351165) (xy 366.779023 -333.36668)
			(xy 366.719605 -333.374507) (xy 366.68964 -333.375) (xy 365.82604 -333.375) (xy 365.796069 -333.374549)
			(xy 365.736639 -333.36673) (xy 365.678737 -333.35122) (xy 365.623356 -333.328285) (xy 365.571443 -333.298317)
			(xy 365.523886 -333.261828) (xy 365.481498 -333.219445) (xy 365.445006 -333.17189) (xy 365.415033 -333.11998)
			(xy 365.392093 -333.0646) (xy 365.376578 -333.006701) (xy 365.368753 -332.947271) (xy 94.46736 -332.947271)
			(xy 94.480703 -332.997066) (xy 94.488526 -333.056488) (xy 94.489016 -333.086456) (xy 94.489016 -333.950056)
			(xy 94.488526 -333.980024) (xy 94.480703 -334.039446) (xy 94.46519 -334.097339) (xy 94.442254 -334.152712)
			(xy 94.412287 -334.204618) (xy 94.3758 -334.252168) (xy 94.33342 -334.294548) (xy 94.28587 -334.331035)
			(xy 94.233964 -334.361002) (xy 94.178591 -334.383938) (xy 94.120698 -334.399451) (xy 94.061276 -334.407274)
			(xy 94.00134 -334.407274) (xy 93.941918 -334.399451) (xy 93.884025 -334.383938) (xy 93.828652 -334.361002)
			(xy 93.776746 -334.331035) (xy 93.729196 -334.294548) (xy 93.686816 -334.252168) (xy 93.650329 -334.204618)
			(xy 93.620362 -334.152712) (xy 93.597426 -334.097339) (xy 93.581913 -334.039446) (xy 93.57409 -333.980024)
			(xy 93.5736 -333.950056) (xy 0.508 -333.950056) (xy 0.508 -337.266026) (xy 234.403392 -337.266026)
			(xy 234.403392 -336.402426) (xy 234.403882 -336.372458) (xy 234.411705 -336.313036) (xy 234.427218 -336.255143)
			(xy 234.450154 -336.19977) (xy 234.480121 -336.147864) (xy 234.516608 -336.100314) (xy 234.558988 -336.057934)
			(xy 234.606538 -336.021447) (xy 234.658444 -335.99148) (xy 234.713817 -335.968544) (xy 234.77171 -335.953031)
			(xy 234.831132 -335.945208) (xy 234.891068 -335.945208) (xy 234.95049 -335.953031) (xy 235.008383 -335.968544)
			(xy 235.063756 -335.99148) (xy 235.115662 -336.021447) (xy 235.163212 -336.057934) (xy 235.205592 -336.100314)
			(xy 235.242079 -336.147864) (xy 235.272046 -336.19977) (xy 235.294982 -336.255143) (xy 235.310495 -336.313036)
			(xy 235.318318 -336.372458) (xy 235.318808 -336.402426) (xy 235.318808 -337.266026) (xy 235.318318 -337.295994)
			(xy 235.310495 -337.355416) (xy 235.294982 -337.413309) (xy 235.272046 -337.468682) (xy 235.242079 -337.520588)
			(xy 235.205592 -337.568138) (xy 235.163212 -337.610518) (xy 235.115662 -337.647005) (xy 235.063756 -337.676972)
			(xy 235.008383 -337.699908) (xy 234.95049 -337.715421) (xy 234.891068 -337.723244) (xy 234.831132 -337.723244)
			(xy 234.77171 -337.715421) (xy 234.713817 -337.699908) (xy 234.658444 -337.676972) (xy 234.606538 -337.647005)
			(xy 234.558988 -337.610518) (xy 234.516608 -337.568138) (xy 234.480121 -337.520588) (xy 234.450154 -337.468682)
			(xy 234.427218 -337.413309) (xy 234.411705 -337.355416) (xy 234.403882 -337.295994) (xy 234.403392 -337.266026)
			(xy 0.508 -337.266026) (xy 0.508 -342.466769) (xy 18.951172 -342.466769) (xy 18.951172 -342.412231)
			(xy 18.958934 -342.358247) (xy 18.974299 -342.305917) (xy 18.996956 -342.256307) (xy 19.026441 -342.210426)
			(xy 19.062157 -342.169208) (xy 19.103374 -342.133493) (xy 19.149255 -342.104007) (xy 19.198865 -342.08135)
			(xy 19.251195 -342.065985) (xy 19.305179 -342.058223) (xy 19.332448 -342.057736) (xy 20.196048 -342.057736)
			(xy 20.223319 -342.058203) (xy 20.277306 -342.065965) (xy 20.329638 -342.081331) (xy 20.379252 -342.103989)
			(xy 20.425135 -342.133476) (xy 20.466355 -342.169193) (xy 20.502073 -342.210413) (xy 20.53156 -342.256297)
			(xy 20.554218 -342.30591) (xy 20.569584 -342.358242) (xy 20.577347 -342.412229) (xy 20.577347 -342.466771)
			(xy 20.577347 -342.466772) (xy 22.0601 -342.466772) (xy 22.0601 -342.412228) (xy 22.067862 -342.358241)
			(xy 22.083229 -342.305907) (xy 22.105887 -342.256293) (xy 22.135375 -342.210409) (xy 22.171094 -342.169188)
			(xy 22.212315 -342.133471) (xy 22.2582 -342.103983) (xy 22.307815 -342.081326) (xy 22.360148 -342.06596)
			(xy 22.414136 -342.058199) (xy 22.441408 -342.057736) (xy 23.305008 -342.057736) (xy 23.332277 -342.058227)
			(xy 23.386259 -342.06599) (xy 23.438588 -342.081355) (xy 23.488197 -342.104012) (xy 23.534076 -342.133498)
			(xy 23.575293 -342.169213) (xy 23.611007 -342.21043) (xy 23.640492 -342.256311) (xy 23.663147 -342.30592)
			(xy 23.678512 -342.358249) (xy 23.686274 -342.412231) (xy 23.686274 -342.466768) (xy 25.169122 -342.466768)
			(xy 25.169122 -342.412232) (xy 25.176883 -342.358251) (xy 25.192247 -342.305924) (xy 25.214901 -342.256315)
			(xy 25.244384 -342.210436) (xy 25.280096 -342.169219) (xy 25.32131 -342.133503) (xy 25.367187 -342.104016)
			(xy 25.416794 -342.081358) (xy 25.46912 -342.06599) (xy 25.5231 -342.058225) (xy 25.550368 -342.057736)
			(xy 26.413968 -342.057736) (xy 26.44124 -342.058201) (xy 26.49523 -342.06596) (xy 26.547567 -342.081323)
			(xy 26.597184 -342.103979) (xy 26.643071 -342.133465) (xy 26.684295 -342.169183) (xy 26.720015 -342.210403)
			(xy 26.749506 -342.256288) (xy 26.772166 -342.305903) (xy 26.787533 -342.358238) (xy 26.795296 -342.412228)
			(xy 26.795296 -342.466772) (xy 28.278 -342.466772) (xy 28.278 -342.412228) (xy 28.285762 -342.358238)
			(xy 28.30113 -342.305903) (xy 28.32379 -342.256288) (xy 28.35328 -342.210402) (xy 28.389001 -342.169181)
			(xy 28.430225 -342.133464) (xy 28.476112 -342.103977) (xy 28.525729 -342.08132) (xy 28.578065 -342.065957)
			(xy 28.632056 -342.058198) (xy 28.659328 -342.057736) (xy 29.522928 -342.057736) (xy 29.550196 -342.058228)
			(xy 29.604176 -342.065993) (xy 29.656502 -342.081361) (xy 29.706109 -342.104019) (xy 29.751986 -342.133505)
			(xy 29.7932 -342.16922) (xy 29.828912 -342.210437) (xy 29.858395 -342.256316) (xy 29.881049 -342.305924)
			(xy 29.896413 -342.358251) (xy 29.904174 -342.412232) (xy 29.904174 -342.466768) (xy 29.904174 -342.466769)
			(xy 31.387022 -342.466769) (xy 31.387022 -342.412231) (xy 31.394784 -342.358248) (xy 31.410149 -342.305919)
			(xy 31.432804 -342.25631) (xy 31.462289 -342.210429) (xy 31.498003 -342.169212) (xy 31.53922 -342.133496)
			(xy 31.585099 -342.10401) (xy 31.634708 -342.081353) (xy 31.687036 -342.065986) (xy 31.741019 -342.058223)
			(xy 31.768288 -342.057736) (xy 32.631888 -342.057736) (xy 32.659159 -342.058203) (xy 32.713147 -342.065963)
			(xy 32.765481 -342.081329) (xy 32.815096 -342.103985) (xy 32.86098 -342.133472) (xy 32.902202 -342.16919)
			(xy 32.93792 -342.21041) (xy 32.967409 -342.256294) (xy 32.990067 -342.305908) (xy 33.005434 -342.358241)
			(xy 33.013196 -342.412229) (xy 33.013196 -342.466771) (xy 33.013196 -342.466773) (xy 34.4959 -342.466773)
			(xy 34.4959 -342.412227) (xy 34.503663 -342.358235) (xy 34.519032 -342.305899) (xy 34.541693 -342.256282)
			(xy 34.571185 -342.210396) (xy 34.606908 -342.169174) (xy 34.648134 -342.133456) (xy 34.694024 -342.10397)
			(xy 34.743644 -342.081315) (xy 34.795982 -342.065953) (xy 34.849975 -342.058196) (xy 34.877248 -342.057736)
			(xy 35.740848 -342.057736) (xy 35.768115 -342.05823) (xy 35.822093 -342.065997) (xy 35.874417 -342.081366)
			(xy 35.92402 -342.104025) (xy 35.969895 -342.133512) (xy 36.011107 -342.169227) (xy 36.046817 -342.210443)
			(xy 36.076298 -342.256322) (xy 36.098951 -342.305928) (xy 36.114313 -342.358254) (xy 36.122074 -342.412233)
			(xy 36.122074 -342.466767) (xy 36.122073 -342.466772) (xy 37.6049 -342.466772) (xy 37.6049 -342.412228)
			(xy 37.612662 -342.358241) (xy 37.628029 -342.305907) (xy 37.650687 -342.256293) (xy 37.680175 -342.210409)
			(xy 37.715894 -342.169188) (xy 37.757115 -342.133471) (xy 37.803 -342.103983) (xy 37.852615 -342.081326)
			(xy 37.904948 -342.06596) (xy 37.958936 -342.058199) (xy 37.986208 -342.057736) (xy 38.849808 -342.057736)
			(xy 38.877077 -342.058227) (xy 38.931059 -342.06599) (xy 38.983388 -342.081355) (xy 39.032997 -342.104012)
			(xy 39.078876 -342.133498) (xy 39.120093 -342.169213) (xy 39.155807 -342.21043) (xy 39.185292 -342.256311)
			(xy 39.207947 -342.30592) (xy 39.223312 -342.358249) (xy 39.231074 -342.412231) (xy 39.231074 -342.466768)
			(xy 40.713922 -342.466768) (xy 40.713922 -342.412232) (xy 40.721683 -342.358251) (xy 40.737047 -342.305924)
			(xy 40.759701 -342.256315) (xy 40.789184 -342.210436) (xy 40.824896 -342.169219) (xy 40.86611 -342.133503)
			(xy 40.911987 -342.104016) (xy 40.961594 -342.081358) (xy 41.01392 -342.06599) (xy 41.0679 -342.058225)
			(xy 41.095168 -342.057736) (xy 41.958768 -342.057736) (xy 41.98604 -342.058201) (xy 42.04003 -342.06596)
			(xy 42.092367 -342.081323) (xy 42.141984 -342.103979) (xy 42.187871 -342.133465) (xy 42.229095 -342.169183)
			(xy 42.264815 -342.210403) (xy 42.294306 -342.256288) (xy 42.316966 -342.305903) (xy 42.332333 -342.358238)
			(xy 42.340096 -342.412228) (xy 42.340096 -342.466772) (xy 43.8228 -342.466772) (xy 43.8228 -342.412228)
			(xy 43.830562 -342.358238) (xy 43.84593 -342.305903) (xy 43.86859 -342.256288) (xy 43.89808 -342.210402)
			(xy 43.933801 -342.169181) (xy 43.975025 -342.133464) (xy 44.020912 -342.103977) (xy 44.070529 -342.08132)
			(xy 44.122865 -342.065957) (xy 44.176856 -342.058198) (xy 44.204128 -342.057736) (xy 45.067728 -342.057736)
			(xy 45.094996 -342.058228) (xy 45.148976 -342.065993) (xy 45.201302 -342.081361) (xy 45.250909 -342.104019)
			(xy 45.296786 -342.133505) (xy 45.338 -342.16922) (xy 45.373712 -342.210437) (xy 45.403195 -342.256316)
			(xy 45.425849 -342.305924) (xy 45.441213 -342.358251) (xy 45.448974 -342.412232) (xy 45.448974 -342.466768)
			(xy 45.448974 -342.466769) (xy 46.931822 -342.466769) (xy 46.931822 -342.412231) (xy 46.939584 -342.358248)
			(xy 46.954949 -342.305919) (xy 46.977604 -342.25631) (xy 47.007089 -342.210429) (xy 47.042803 -342.169212)
			(xy 47.08402 -342.133496) (xy 47.129899 -342.10401) (xy 47.179508 -342.081353) (xy 47.231836 -342.065986)
			(xy 47.285819 -342.058223) (xy 47.313088 -342.057736) (xy 48.176688 -342.057736) (xy 48.203959 -342.058203)
			(xy 48.257947 -342.065963) (xy 48.310281 -342.081329) (xy 48.359896 -342.103985) (xy 48.40578 -342.133472)
			(xy 48.447002 -342.16919) (xy 48.48272 -342.21041) (xy 48.512209 -342.256294) (xy 48.534867 -342.305908)
			(xy 48.550234 -342.358241) (xy 48.557996 -342.412229) (xy 48.557996 -342.466771) (xy 48.557996 -342.466773)
			(xy 50.0407 -342.466773) (xy 50.0407 -342.412227) (xy 50.048463 -342.358235) (xy 50.063832 -342.305899)
			(xy 50.086493 -342.256282) (xy 50.115985 -342.210396) (xy 50.151708 -342.169174) (xy 50.192934 -342.133456)
			(xy 50.238824 -342.10397) (xy 50.288444 -342.081315) (xy 50.340782 -342.065953) (xy 50.394775 -342.058196)
			(xy 50.422048 -342.057736) (xy 51.285648 -342.057736) (xy 51.312915 -342.05823) (xy 51.366893 -342.065997)
			(xy 51.419217 -342.081366) (xy 51.46882 -342.104025) (xy 51.514695 -342.133512) (xy 51.555907 -342.169227)
			(xy 51.591617 -342.210443) (xy 51.621098 -342.256322) (xy 51.643751 -342.305928) (xy 51.659113 -342.358254)
			(xy 51.666874 -342.412233) (xy 51.666874 -342.466767) (xy 51.666873 -342.466773) (xy 60.9909 -342.466773)
			(xy 60.9909 -342.412227) (xy 60.998663 -342.358236) (xy 61.014031 -342.3059) (xy 61.036692 -342.256284)
			(xy 61.066184 -342.210398) (xy 61.101906 -342.169176) (xy 61.143131 -342.133459) (xy 61.18902 -342.103972)
			(xy 61.238639 -342.081317) (xy 61.290977 -342.065954) (xy 61.344969 -342.058197) (xy 61.372242 -342.057736)
			(xy 62.235842 -342.057736) (xy 62.263109 -342.058229) (xy 62.317088 -342.065996) (xy 62.369412 -342.081365)
			(xy 62.419017 -342.104023) (xy 62.464892 -342.13351) (xy 62.506105 -342.169225) (xy 62.541815 -342.210441)
			(xy 62.571297 -342.25632) (xy 62.59395 -342.305927) (xy 62.609313 -342.358253) (xy 62.617074 -342.412233)
			(xy 62.617074 -342.466767) (xy 62.617073 -342.466771) (xy 64.099899 -342.466771) (xy 64.099899 -342.412229)
			(xy 64.107662 -342.358241) (xy 64.123028 -342.305908) (xy 64.145686 -342.256295) (xy 64.175174 -342.210411)
			(xy 64.210892 -342.16919) (xy 64.252112 -342.133473) (xy 64.297997 -342.103985) (xy 64.34761 -342.081327)
			(xy 64.399943 -342.065961) (xy 64.453931 -342.058199) (xy 64.481202 -342.057736) (xy 65.344802 -342.057736)
			(xy 65.372071 -342.058227) (xy 65.426054 -342.065988) (xy 65.478383 -342.081354) (xy 65.527993 -342.10401)
			(xy 65.573873 -342.133496) (xy 65.615091 -342.169211) (xy 65.650805 -342.210428) (xy 65.680291 -342.256309)
			(xy 65.702947 -342.305919) (xy 65.718312 -342.358248) (xy 65.726074 -342.412231) (xy 65.726074 -342.466768)
			(xy 67.208922 -342.466768) (xy 67.208922 -342.412232) (xy 67.216683 -342.358252) (xy 67.232047 -342.305925)
			(xy 67.2547 -342.256317) (xy 67.284183 -342.210438) (xy 67.319894 -342.169221) (xy 67.361107 -342.133505)
			(xy 67.406984 -342.104018) (xy 67.456589 -342.08136) (xy 67.508914 -342.065991) (xy 67.562894 -342.058225)
			(xy 67.590162 -342.057736) (xy 68.453762 -342.057736) (xy 68.481035 -342.058201) (xy 68.535025 -342.065959)
			(xy 68.587362 -342.081321) (xy 68.63698 -342.103977) (xy 68.682868 -342.133463) (xy 68.724093 -342.16918)
			(xy 68.759814 -342.210401) (xy 68.789305 -342.256287) (xy 68.811965 -342.305902) (xy 68.827333 -342.358237)
			(xy 68.835096 -342.412227) (xy 68.835096 -342.466772) (xy 70.3178 -342.466772) (xy 70.3178 -342.412228)
			(xy 70.325562 -342.358239) (xy 70.34093 -342.305904) (xy 70.363589 -342.256289) (xy 70.393079 -342.210404)
			(xy 70.428799 -342.169183) (xy 70.470022 -342.133466) (xy 70.515909 -342.103979) (xy 70.565525 -342.081322)
			(xy 70.61786 -342.065958) (xy 70.67185 -342.058198) (xy 70.699122 -342.057736) (xy 71.562722 -342.057736)
			(xy 71.58999 -342.058228) (xy 71.643971 -342.065992) (xy 71.696298 -342.081359) (xy 71.745905 -342.104017)
			(xy 71.791783 -342.133503) (xy 71.832998 -342.169218) (xy 71.86871 -342.210435) (xy 71.898194 -342.256314)
			(xy 71.920848 -342.305923) (xy 71.936213 -342.35825) (xy 71.943974 -342.412232) (xy 71.943974 -342.466768)
			(xy 71.943974 -342.466769) (xy 73.426822 -342.466769) (xy 73.426822 -342.412231) (xy 73.434584 -342.358249)
			(xy 73.449948 -342.305921) (xy 73.472603 -342.256311) (xy 73.502087 -342.210431) (xy 73.537801 -342.169214)
			(xy 73.579017 -342.133498) (xy 73.624896 -342.104012) (xy 73.674504 -342.081354) (xy 73.726831 -342.065987)
			(xy 73.780813 -342.058224) (xy 73.808082 -342.057736) (xy 74.671682 -342.057736) (xy 74.698954 -342.058202)
			(xy 74.752942 -342.065962) (xy 74.805277 -342.081327) (xy 74.854892 -342.103983) (xy 74.900778 -342.13347)
			(xy 74.942 -342.169188) (xy 74.977719 -342.210408) (xy 75.007208 -342.256292) (xy 75.029867 -342.305906)
			(xy 75.045234 -342.35824) (xy 75.052996 -342.412228) (xy 75.052996 -342.466772) (xy 75.052996 -342.466773)
			(xy 76.5357 -342.466773) (xy 76.5357 -342.412227) (xy 76.543463 -342.358236) (xy 76.558831 -342.3059)
			(xy 76.581492 -342.256284) (xy 76.610984 -342.210398) (xy 76.646706 -342.169176) (xy 76.687931 -342.133459)
			(xy 76.73382 -342.103972) (xy 76.783439 -342.081317) (xy 76.835777 -342.065954) (xy 76.889769 -342.058197)
			(xy 76.917042 -342.057736) (xy 77.780642 -342.057736) (xy 77.807909 -342.058229) (xy 77.861888 -342.065996)
			(xy 77.914212 -342.081365) (xy 77.963817 -342.104023) (xy 78.009692 -342.13351) (xy 78.050905 -342.169225)
			(xy 78.086615 -342.210441) (xy 78.116097 -342.25632) (xy 78.13875 -342.305927) (xy 78.154113 -342.358253)
			(xy 78.161874 -342.412233) (xy 78.161874 -342.466767) (xy 78.161873 -342.466771) (xy 79.644699 -342.466771)
			(xy 79.644699 -342.412229) (xy 79.652462 -342.358241) (xy 79.667828 -342.305908) (xy 79.690486 -342.256295)
			(xy 79.719974 -342.210411) (xy 79.755692 -342.16919) (xy 79.796912 -342.133473) (xy 79.842797 -342.103985)
			(xy 79.89241 -342.081327) (xy 79.944743 -342.065961) (xy 79.998731 -342.058199) (xy 80.026002 -342.057736)
			(xy 80.889602 -342.057736) (xy 80.916871 -342.058227) (xy 80.970854 -342.065988) (xy 81.023183 -342.081354)
			(xy 81.072793 -342.10401) (xy 81.118673 -342.133496) (xy 81.159891 -342.169211) (xy 81.195605 -342.210428)
			(xy 81.225091 -342.256309) (xy 81.247747 -342.305919) (xy 81.263112 -342.358248) (xy 81.270874 -342.412231)
			(xy 81.270874 -342.466768) (xy 82.753722 -342.466768) (xy 82.753722 -342.412232) (xy 82.761483 -342.358252)
			(xy 82.776847 -342.305925) (xy 82.7995 -342.256317) (xy 82.828983 -342.210438) (xy 82.864694 -342.169221)
			(xy 82.905907 -342.133505) (xy 82.951784 -342.104018) (xy 83.001389 -342.08136) (xy 83.053714 -342.065991)
			(xy 83.107694 -342.058225) (xy 83.134962 -342.057736) (xy 83.998562 -342.057736) (xy 84.025835 -342.058201)
			(xy 84.079825 -342.065959) (xy 84.132162 -342.081321) (xy 84.18178 -342.103977) (xy 84.227668 -342.133463)
			(xy 84.268893 -342.16918) (xy 84.304614 -342.210401) (xy 84.334105 -342.256287) (xy 84.356765 -342.305902)
			(xy 84.372133 -342.358237) (xy 84.379896 -342.412227) (xy 84.379896 -342.466772) (xy 85.8626 -342.466772)
			(xy 85.8626 -342.412228) (xy 85.870362 -342.358239) (xy 85.88573 -342.305904) (xy 85.908389 -342.256289)
			(xy 85.937879 -342.210404) (xy 85.973599 -342.169183) (xy 86.014822 -342.133466) (xy 86.060709 -342.103979)
			(xy 86.110325 -342.081322) (xy 86.16266 -342.065958) (xy 86.21665 -342.058198) (xy 86.243922 -342.057736)
			(xy 87.107522 -342.057736) (xy 87.13479 -342.058228) (xy 87.188771 -342.065992) (xy 87.241098 -342.081359)
			(xy 87.290705 -342.104017) (xy 87.336583 -342.133503) (xy 87.377798 -342.169218) (xy 87.41351 -342.210435)
			(xy 87.442994 -342.256314) (xy 87.465648 -342.305923) (xy 87.481013 -342.35825) (xy 87.488774 -342.412232)
			(xy 87.488774 -342.466768) (xy 87.488774 -342.466769) (xy 88.971622 -342.466769) (xy 88.971622 -342.412231)
			(xy 88.979384 -342.358249) (xy 88.994748 -342.305921) (xy 89.017403 -342.256311) (xy 89.046887 -342.210431)
			(xy 89.082601 -342.169214) (xy 89.123817 -342.133498) (xy 89.169696 -342.104012) (xy 89.219304 -342.081354)
			(xy 89.271631 -342.065987) (xy 89.325613 -342.058224) (xy 89.352882 -342.057736) (xy 90.216482 -342.057736)
			(xy 90.243754 -342.058202) (xy 90.297742 -342.065962) (xy 90.350077 -342.081327) (xy 90.399692 -342.103983)
			(xy 90.445578 -342.13347) (xy 90.4868 -342.169188) (xy 90.522519 -342.210408) (xy 90.552008 -342.256292)
			(xy 90.574667 -342.305906) (xy 90.590034 -342.35824) (xy 90.597796 -342.412228) (xy 90.597796 -342.466772)
			(xy 90.597796 -342.466773) (xy 92.0805 -342.466773) (xy 92.0805 -342.412227) (xy 92.088263 -342.358236)
			(xy 92.103631 -342.3059) (xy 92.126292 -342.256284) (xy 92.155784 -342.210398) (xy 92.191506 -342.169176)
			(xy 92.232731 -342.133459) (xy 92.27862 -342.103972) (xy 92.328239 -342.081317) (xy 92.380577 -342.065954)
			(xy 92.434569 -342.058197) (xy 92.461842 -342.057736) (xy 93.325442 -342.057736) (xy 93.352709 -342.058229)
			(xy 93.406688 -342.065996) (xy 93.459012 -342.081365) (xy 93.508617 -342.104023) (xy 93.554492 -342.13351)
			(xy 93.595705 -342.169225) (xy 93.631415 -342.210441) (xy 93.660897 -342.25632) (xy 93.68355 -342.305927)
			(xy 93.698913 -342.358253) (xy 93.706674 -342.412233) (xy 93.706674 -342.466767) (xy 93.698913 -342.520747)
			(xy 93.68355 -342.573073) (xy 93.660897 -342.62268) (xy 93.631415 -342.668559) (xy 93.60914 -342.694268)
			(xy 102.35157 -342.694268) (xy 102.35157 -342.634332) (xy 102.359393 -342.574909) (xy 102.374905 -342.517016)
			(xy 102.397841 -342.461642) (xy 102.427809 -342.409736) (xy 102.464294 -342.362185) (xy 102.506675 -342.319804)
			(xy 102.554224 -342.283316) (xy 102.60613 -342.253347) (xy 102.661502 -342.23041) (xy 102.719395 -342.214896)
			(xy 102.778818 -342.207071) (xy 102.808786 -342.20658) (xy 103.672386 -342.20658) (xy 103.702355 -342.207072)
			(xy 103.76178 -342.214894) (xy 103.819676 -342.230405) (xy 103.875051 -342.253341) (xy 103.926959 -342.283309)
			(xy 103.974512 -342.319796) (xy 104.016895 -342.362178) (xy 104.053383 -342.409729) (xy 104.083352 -342.461636)
			(xy 104.085479 -342.466772) (xy 111.4808 -342.466772) (xy 111.4808 -342.412228) (xy 111.488562 -342.358241)
			(xy 111.503929 -342.305907) (xy 111.526587 -342.256293) (xy 111.556075 -342.210409) (xy 111.591794 -342.169188)
			(xy 111.633015 -342.133471) (xy 111.6789 -342.103983) (xy 111.728515 -342.081326) (xy 111.780848 -342.06596)
			(xy 111.834836 -342.058199) (xy 111.862108 -342.057736) (xy 112.725708 -342.057736) (xy 112.752977 -342.058227)
			(xy 112.806959 -342.06599) (xy 112.859288 -342.081355) (xy 112.908897 -342.104012) (xy 112.954776 -342.133498)
			(xy 112.995993 -342.169213) (xy 113.031707 -342.21043) (xy 113.061192 -342.256311) (xy 113.083847 -342.30592)
			(xy 113.099212 -342.358249) (xy 113.106974 -342.412231) (xy 113.106974 -342.466768) (xy 114.589822 -342.466768)
			(xy 114.589822 -342.412232) (xy 114.597583 -342.358251) (xy 114.612947 -342.305924) (xy 114.635601 -342.256315)
			(xy 114.665084 -342.210436) (xy 114.700796 -342.169219) (xy 114.74201 -342.133503) (xy 114.787887 -342.104016)
			(xy 114.837494 -342.081358) (xy 114.88982 -342.06599) (xy 114.9438 -342.058225) (xy 114.971068 -342.057736)
			(xy 115.834668 -342.057736) (xy 115.86194 -342.058201) (xy 115.91593 -342.06596) (xy 115.968267 -342.081323)
			(xy 116.017884 -342.103979) (xy 116.063771 -342.133465) (xy 116.104995 -342.169183) (xy 116.140715 -342.210403)
			(xy 116.170206 -342.256288) (xy 116.192866 -342.305903) (xy 116.208233 -342.358238) (xy 116.215996 -342.412228)
			(xy 116.215996 -342.466772) (xy 117.6987 -342.466772) (xy 117.6987 -342.412228) (xy 117.706462 -342.358238)
			(xy 117.72183 -342.305903) (xy 117.74449 -342.256288) (xy 117.77398 -342.210402) (xy 117.809701 -342.169181)
			(xy 117.850925 -342.133464) (xy 117.896812 -342.103977) (xy 117.946429 -342.08132) (xy 117.998765 -342.065957)
			(xy 118.052756 -342.058198) (xy 118.080028 -342.057736) (xy 118.943628 -342.057736) (xy 118.970896 -342.058228)
			(xy 119.024876 -342.065993) (xy 119.077202 -342.081361) (xy 119.126809 -342.104019) (xy 119.172686 -342.133505)
			(xy 119.2139 -342.16922) (xy 119.249612 -342.210437) (xy 119.279095 -342.256316) (xy 119.301749 -342.305924)
			(xy 119.317113 -342.358251) (xy 119.324874 -342.412232) (xy 119.324874 -342.466768) (xy 119.324874 -342.466769)
			(xy 120.807722 -342.466769) (xy 120.807722 -342.412231) (xy 120.815484 -342.358248) (xy 120.830849 -342.305919)
			(xy 120.853504 -342.25631) (xy 120.882989 -342.210429) (xy 120.918703 -342.169212) (xy 120.95992 -342.133496)
			(xy 121.005799 -342.10401) (xy 121.055408 -342.081353) (xy 121.107736 -342.065986) (xy 121.161719 -342.058223)
			(xy 121.188988 -342.057736) (xy 122.052588 -342.057736) (xy 122.079859 -342.058203) (xy 122.133847 -342.065963)
			(xy 122.186181 -342.081329) (xy 122.235796 -342.103985) (xy 122.28168 -342.133472) (xy 122.322902 -342.16919)
			(xy 122.35862 -342.21041) (xy 122.388109 -342.256294) (xy 122.410767 -342.305908) (xy 122.426134 -342.358241)
			(xy 122.433896 -342.412229) (xy 122.433896 -342.466771) (xy 122.433896 -342.466773) (xy 123.9166 -342.466773)
			(xy 123.9166 -342.412227) (xy 123.924363 -342.358235) (xy 123.939732 -342.305899) (xy 123.962393 -342.256282)
			(xy 123.991885 -342.210396) (xy 124.027608 -342.169174) (xy 124.068834 -342.133456) (xy 124.114724 -342.10397)
			(xy 124.164344 -342.081315) (xy 124.216682 -342.065953) (xy 124.270675 -342.058196) (xy 124.297948 -342.057736)
			(xy 125.161548 -342.057736) (xy 125.188815 -342.05823) (xy 125.242793 -342.065997) (xy 125.295117 -342.081366)
			(xy 125.34472 -342.104025) (xy 125.390595 -342.133512) (xy 125.431807 -342.169227) (xy 125.467517 -342.210443)
			(xy 125.496998 -342.256322) (xy 125.519651 -342.305928) (xy 125.535013 -342.358254) (xy 125.542774 -342.412233)
			(xy 125.542774 -342.466767) (xy 125.542773 -342.466772) (xy 127.0256 -342.466772) (xy 127.0256 -342.412228)
			(xy 127.033362 -342.358241) (xy 127.048729 -342.305907) (xy 127.071387 -342.256293) (xy 127.100875 -342.210409)
			(xy 127.136594 -342.169188) (xy 127.177815 -342.133471) (xy 127.2237 -342.103983) (xy 127.273315 -342.081326)
			(xy 127.325648 -342.06596) (xy 127.379636 -342.058199) (xy 127.406908 -342.057736) (xy 128.270508 -342.057736)
			(xy 128.297777 -342.058227) (xy 128.351759 -342.06599) (xy 128.404088 -342.081355) (xy 128.453697 -342.104012)
			(xy 128.499576 -342.133498) (xy 128.540793 -342.169213) (xy 128.576507 -342.21043) (xy 128.605992 -342.256311)
			(xy 128.628647 -342.30592) (xy 128.644012 -342.358249) (xy 128.651774 -342.412231) (xy 128.651774 -342.466768)
			(xy 130.134622 -342.466768) (xy 130.134622 -342.412232) (xy 130.142383 -342.358251) (xy 130.157747 -342.305924)
			(xy 130.180401 -342.256315) (xy 130.209884 -342.210436) (xy 130.245596 -342.169219) (xy 130.28681 -342.133503)
			(xy 130.332687 -342.104016) (xy 130.382294 -342.081358) (xy 130.43462 -342.06599) (xy 130.4886 -342.058225)
			(xy 130.515868 -342.057736) (xy 131.379468 -342.057736) (xy 131.40674 -342.058201) (xy 131.46073 -342.06596)
			(xy 131.513067 -342.081323) (xy 131.562684 -342.103979) (xy 131.608571 -342.133465) (xy 131.649795 -342.169183)
			(xy 131.685515 -342.210403) (xy 131.715006 -342.256288) (xy 131.737666 -342.305903) (xy 131.753033 -342.358238)
			(xy 131.760796 -342.412228) (xy 131.760796 -342.466772) (xy 133.2435 -342.466772) (xy 133.2435 -342.412228)
			(xy 133.251262 -342.358238) (xy 133.26663 -342.305903) (xy 133.28929 -342.256288) (xy 133.31878 -342.210402)
			(xy 133.354501 -342.169181) (xy 133.395725 -342.133464) (xy 133.441612 -342.103977) (xy 133.491229 -342.08132)
			(xy 133.543565 -342.065957) (xy 133.597556 -342.058198) (xy 133.624828 -342.057736) (xy 134.488428 -342.057736)
			(xy 134.515696 -342.058228) (xy 134.569676 -342.065993) (xy 134.622002 -342.081361) (xy 134.671609 -342.104019)
			(xy 134.717486 -342.133505) (xy 134.7587 -342.16922) (xy 134.794412 -342.210437) (xy 134.823895 -342.256316)
			(xy 134.846549 -342.305924) (xy 134.861913 -342.358251) (xy 134.869674 -342.412232) (xy 134.869674 -342.466768)
			(xy 134.869674 -342.466769) (xy 136.352522 -342.466769) (xy 136.352522 -342.412231) (xy 136.360284 -342.358248)
			(xy 136.375649 -342.305919) (xy 136.398304 -342.25631) (xy 136.427789 -342.210429) (xy 136.463503 -342.169212)
			(xy 136.50472 -342.133496) (xy 136.550599 -342.10401) (xy 136.600208 -342.081353) (xy 136.652536 -342.065986)
			(xy 136.706519 -342.058223) (xy 136.733788 -342.057736) (xy 137.597388 -342.057736) (xy 137.624659 -342.058203)
			(xy 137.678647 -342.065963) (xy 137.730981 -342.081329) (xy 137.780596 -342.103985) (xy 137.82648 -342.133472)
			(xy 137.867702 -342.16919) (xy 137.90342 -342.21041) (xy 137.932909 -342.256294) (xy 137.955567 -342.305908)
			(xy 137.970934 -342.358241) (xy 137.978696 -342.412229) (xy 137.978696 -342.466771) (xy 137.978696 -342.466773)
			(xy 139.4614 -342.466773) (xy 139.4614 -342.412227) (xy 139.469163 -342.358235) (xy 139.484532 -342.305899)
			(xy 139.507193 -342.256282) (xy 139.536685 -342.210396) (xy 139.572408 -342.169174) (xy 139.613634 -342.133456)
			(xy 139.659524 -342.10397) (xy 139.709144 -342.081315) (xy 139.761482 -342.065953) (xy 139.815475 -342.058196)
			(xy 139.842748 -342.057736) (xy 140.706348 -342.057736) (xy 140.733615 -342.05823) (xy 140.787593 -342.065997)
			(xy 140.839917 -342.081366) (xy 140.88952 -342.104025) (xy 140.935395 -342.133512) (xy 140.976607 -342.169227)
			(xy 141.012317 -342.210443) (xy 141.041798 -342.256322) (xy 141.064451 -342.305928) (xy 141.079813 -342.358254)
			(xy 141.087574 -342.412233) (xy 141.087574 -342.466767) (xy 141.087573 -342.466772) (xy 142.5704 -342.466772)
			(xy 142.5704 -342.412228) (xy 142.578162 -342.358241) (xy 142.593529 -342.305907) (xy 142.616187 -342.256293)
			(xy 142.645675 -342.210409) (xy 142.681394 -342.169188) (xy 142.722615 -342.133471) (xy 142.7685 -342.103983)
			(xy 142.818115 -342.081326) (xy 142.870448 -342.06596) (xy 142.924436 -342.058199) (xy 142.951708 -342.057736)
			(xy 143.815308 -342.057736) (xy 143.842577 -342.058227) (xy 143.896559 -342.06599) (xy 143.948888 -342.081355)
			(xy 143.998497 -342.104012) (xy 144.044376 -342.133498) (xy 144.085593 -342.169213) (xy 144.121307 -342.21043)
			(xy 144.150792 -342.256311) (xy 144.173447 -342.30592) (xy 144.188812 -342.358249) (xy 144.196574 -342.412231)
			(xy 144.196574 -342.466768) (xy 164.913822 -342.466768) (xy 164.913822 -342.412232) (xy 164.921583 -342.35825)
			(xy 164.936947 -342.305923) (xy 164.959602 -342.256314) (xy 164.989085 -342.210434) (xy 165.024797 -342.169217)
			(xy 165.066012 -342.133502) (xy 165.11189 -342.104015) (xy 165.161496 -342.081357) (xy 165.213823 -342.065989)
			(xy 165.267804 -342.058224) (xy 165.295072 -342.057736) (xy 166.158672 -342.057736) (xy 166.185944 -342.058202)
			(xy 166.239934 -342.06596) (xy 166.29227 -342.081324) (xy 166.341886 -342.10398) (xy 166.387773 -342.133467)
			(xy 166.428996 -342.169184) (xy 166.464716 -342.210405) (xy 166.494207 -342.256289) (xy 166.516866 -342.305904)
			(xy 166.532234 -342.358239) (xy 166.539996 -342.412228) (xy 166.539996 -342.466772) (xy 166.539996 -342.466773)
			(xy 168.0227 -342.466773) (xy 168.0227 -342.412227) (xy 168.030463 -342.358237) (xy 168.045831 -342.305902)
			(xy 168.068491 -342.256286) (xy 168.097981 -342.210401) (xy 168.133702 -342.16918) (xy 168.174927 -342.133462)
			(xy 168.220815 -342.103975) (xy 168.270432 -342.081319) (xy 168.322769 -342.065956) (xy 168.376759 -342.058197)
			(xy 168.404032 -342.057736) (xy 169.267632 -342.057736) (xy 169.2949 -342.058229) (xy 169.34888 -342.065994)
			(xy 169.401205 -342.081362) (xy 169.450811 -342.10402) (xy 169.496688 -342.133506) (xy 169.537901 -342.169222)
			(xy 169.573613 -342.210438) (xy 169.603095 -342.256317) (xy 169.625749 -342.305925) (xy 169.641113 -342.358252)
			(xy 169.648874 -342.412232) (xy 169.648874 -342.466768) (xy 169.648874 -342.466769) (xy 171.131722 -342.466769)
			(xy 171.131722 -342.412231) (xy 171.139484 -342.358248) (xy 171.154849 -342.305918) (xy 171.177505 -342.256309)
			(xy 171.20699 -342.210428) (xy 171.242705 -342.16921) (xy 171.283921 -342.133495) (xy 171.329802 -342.104009)
			(xy 171.379411 -342.081352) (xy 171.43174 -342.065986) (xy 171.485723 -342.058223) (xy 171.512992 -342.057736)
			(xy 172.376592 -342.057736) (xy 172.403863 -342.058203) (xy 172.457851 -342.065964) (xy 172.510184 -342.08133)
			(xy 172.559798 -342.103987) (xy 172.605682 -342.133474) (xy 172.646903 -342.169191) (xy 172.682621 -342.210411)
			(xy 172.71211 -342.256295) (xy 172.734768 -342.305908) (xy 172.750134 -342.358241) (xy 172.757896 -342.412229)
			(xy 172.757896 -342.466767) (xy 174.240722 -342.466767) (xy 174.240722 -342.412233) (xy 174.248483 -342.358253)
			(xy 174.263846 -342.305927) (xy 174.286499 -342.25632) (xy 174.31598 -342.210441) (xy 174.35169 -342.169224)
			(xy 174.392902 -342.133509) (xy 174.438778 -342.104022) (xy 174.488382 -342.081363) (xy 174.540706 -342.065993)
			(xy 174.594685 -342.058226) (xy 174.621952 -342.057736) (xy 175.485552 -342.057736) (xy 175.512825 -342.0582)
			(xy 175.566817 -342.065957) (xy 175.619155 -342.081319) (xy 175.668774 -342.103974) (xy 175.714663 -342.13346)
			(xy 175.755889 -342.169177) (xy 175.791612 -342.210398) (xy 175.821103 -342.256284) (xy 175.843764 -342.3059)
			(xy 175.859133 -342.358236) (xy 175.866896 -342.412227) (xy 175.866896 -342.466772) (xy 177.3496 -342.466772)
			(xy 177.3496 -342.412228) (xy 177.357362 -342.35824) (xy 177.372729 -342.305906) (xy 177.395388 -342.256292)
			(xy 177.424876 -342.210407) (xy 177.460595 -342.169187) (xy 177.501817 -342.133469) (xy 177.547703 -342.103982)
			(xy 177.597317 -342.081325) (xy 177.649652 -342.065959) (xy 177.70364 -342.058199) (xy 177.730912 -342.057736)
			(xy 178.594512 -342.057736) (xy 178.621781 -342.058227) (xy 178.675763 -342.06599) (xy 178.728091 -342.081357)
			(xy 178.777699 -342.104013) (xy 178.823578 -342.133499) (xy 178.864794 -342.169214) (xy 178.900508 -342.210432)
			(xy 178.929992 -342.256312) (xy 178.952648 -342.305921) (xy 178.968012 -342.358249) (xy 178.975774 -342.412231)
			(xy 178.975774 -342.466768) (xy 180.458622 -342.466768) (xy 180.458622 -342.412232) (xy 180.466383 -342.35825)
			(xy 180.481747 -342.305923) (xy 180.504402 -342.256314) (xy 180.533885 -342.210434) (xy 180.569597 -342.169217)
			(xy 180.610812 -342.133502) (xy 180.65669 -342.104015) (xy 180.706296 -342.081357) (xy 180.758623 -342.065989)
			(xy 180.812604 -342.058224) (xy 180.839872 -342.057736) (xy 181.703472 -342.057736) (xy 181.730744 -342.058202)
			(xy 181.784734 -342.06596) (xy 181.83707 -342.081324) (xy 181.886686 -342.10398) (xy 181.932573 -342.133467)
			(xy 181.973796 -342.169184) (xy 182.009516 -342.210405) (xy 182.039007 -342.256289) (xy 182.061666 -342.305904)
			(xy 182.077034 -342.358239) (xy 182.084796 -342.412228) (xy 182.084796 -342.466772) (xy 182.084796 -342.466773)
			(xy 183.5675 -342.466773) (xy 183.5675 -342.412227) (xy 183.575263 -342.358237) (xy 183.590631 -342.305902)
			(xy 183.613291 -342.256286) (xy 183.642781 -342.210401) (xy 183.678502 -342.16918) (xy 183.719727 -342.133462)
			(xy 183.765615 -342.103975) (xy 183.815232 -342.081319) (xy 183.867569 -342.065956) (xy 183.921559 -342.058197)
			(xy 183.948832 -342.057736) (xy 184.812432 -342.057736) (xy 184.8397 -342.058229) (xy 184.89368 -342.065994)
			(xy 184.946005 -342.081362) (xy 184.995611 -342.10402) (xy 185.041488 -342.133506) (xy 185.082701 -342.169222)
			(xy 185.118413 -342.210438) (xy 185.147895 -342.256317) (xy 185.170549 -342.305925) (xy 185.185913 -342.358252)
			(xy 185.193674 -342.412232) (xy 185.193674 -342.466768) (xy 185.193674 -342.466769) (xy 186.676522 -342.466769)
			(xy 186.676522 -342.412231) (xy 186.684284 -342.358248) (xy 186.699649 -342.305918) (xy 186.722305 -342.256309)
			(xy 186.75179 -342.210428) (xy 186.787505 -342.16921) (xy 186.828721 -342.133495) (xy 186.874602 -342.104009)
			(xy 186.924211 -342.081352) (xy 186.97654 -342.065986) (xy 187.030523 -342.058223) (xy 187.057792 -342.057736)
			(xy 187.921392 -342.057736) (xy 187.948663 -342.058203) (xy 188.002651 -342.065964) (xy 188.054984 -342.08133)
			(xy 188.104598 -342.103987) (xy 188.150482 -342.133474) (xy 188.191703 -342.169191) (xy 188.227421 -342.210411)
			(xy 188.25691 -342.256295) (xy 188.279568 -342.305908) (xy 188.294934 -342.358241) (xy 188.302696 -342.412229)
			(xy 188.302696 -342.466767) (xy 189.785522 -342.466767) (xy 189.785522 -342.412233) (xy 189.793283 -342.358253)
			(xy 189.808646 -342.305927) (xy 189.831299 -342.25632) (xy 189.86078 -342.210441) (xy 189.89649 -342.169224)
			(xy 189.937702 -342.133509) (xy 189.983578 -342.104022) (xy 190.033182 -342.081363) (xy 190.085506 -342.065993)
			(xy 190.139485 -342.058226) (xy 190.166752 -342.057736) (xy 191.030352 -342.057736) (xy 191.057625 -342.0582)
			(xy 191.111617 -342.065957) (xy 191.163955 -342.081319) (xy 191.213574 -342.103974) (xy 191.259463 -342.13346)
			(xy 191.300689 -342.169177) (xy 191.336412 -342.210398) (xy 191.365903 -342.256284) (xy 191.388564 -342.3059)
			(xy 191.403933 -342.358236) (xy 191.411696 -342.412227) (xy 191.411696 -342.466772) (xy 192.8944 -342.466772)
			(xy 192.8944 -342.412228) (xy 192.902162 -342.35824) (xy 192.917529 -342.305906) (xy 192.940188 -342.256292)
			(xy 192.969676 -342.210407) (xy 193.005395 -342.169187) (xy 193.046617 -342.133469) (xy 193.092503 -342.103982)
			(xy 193.142117 -342.081325) (xy 193.194452 -342.065959) (xy 193.24844 -342.058199) (xy 193.275712 -342.057736)
			(xy 194.139312 -342.057736) (xy 194.166581 -342.058227) (xy 194.220563 -342.06599) (xy 194.272891 -342.081357)
			(xy 194.322499 -342.104013) (xy 194.368378 -342.133499) (xy 194.409594 -342.169214) (xy 194.445308 -342.210432)
			(xy 194.474792 -342.256312) (xy 194.497448 -342.305921) (xy 194.512812 -342.358249) (xy 194.520574 -342.412231)
			(xy 194.520574 -342.466768) (xy 196.003422 -342.466768) (xy 196.003422 -342.412232) (xy 196.011183 -342.35825)
			(xy 196.026547 -342.305923) (xy 196.049202 -342.256314) (xy 196.078685 -342.210434) (xy 196.114397 -342.169217)
			(xy 196.155612 -342.133502) (xy 196.20149 -342.104015) (xy 196.251096 -342.081357) (xy 196.303423 -342.065989)
			(xy 196.357404 -342.058224) (xy 196.384672 -342.057736) (xy 197.248272 -342.057736) (xy 197.275544 -342.058202)
			(xy 197.28821 -342.060022) (xy 255.91262 -342.060022) (xy 255.91262 -341.196422) (xy 255.91311 -341.166438)
			(xy 255.920938 -341.106982) (xy 255.936459 -341.049057) (xy 255.959408 -340.993653) (xy 255.989392 -340.941719)
			(xy 256.025898 -340.894143) (xy 256.068303 -340.851738) (xy 256.115879 -340.815232) (xy 256.167813 -340.785248)
			(xy 256.223217 -340.762299) (xy 256.281142 -340.746778) (xy 256.340598 -340.73895) (xy 256.400566 -340.73895)
			(xy 256.460022 -340.746778) (xy 256.517947 -340.762299) (xy 256.573351 -340.785248) (xy 256.625285 -340.815232)
			(xy 256.672861 -340.851738) (xy 256.715266 -340.894143) (xy 256.751772 -340.941719) (xy 256.781756 -340.993653)
			(xy 256.804705 -341.049057) (xy 256.820226 -341.106982) (xy 256.828054 -341.166438) (xy 256.828544 -341.196422)
			(xy 256.828544 -342.060022) (xy 256.828054 -342.090006) (xy 256.820226 -342.149462) (xy 256.804705 -342.207387)
			(xy 256.781756 -342.262791) (xy 256.751772 -342.314725) (xy 256.715266 -342.362301) (xy 256.672861 -342.404706)
			(xy 256.625285 -342.441212) (xy 256.581015 -342.466771) (xy 267.515799 -342.466771) (xy 267.515799 -342.412229)
			(xy 267.523562 -342.358241) (xy 267.538928 -342.305908) (xy 267.561586 -342.256295) (xy 267.591074 -342.210411)
			(xy 267.626792 -342.16919) (xy 267.668012 -342.133473) (xy 267.713897 -342.103985) (xy 267.76351 -342.081327)
			(xy 267.815843 -342.065961) (xy 267.869831 -342.058199) (xy 267.897102 -342.057736) (xy 268.760702 -342.057736)
			(xy 268.787971 -342.058227) (xy 268.841954 -342.065988) (xy 268.894283 -342.081354) (xy 268.943893 -342.10401)
			(xy 268.989773 -342.133496) (xy 269.030991 -342.169211) (xy 269.066705 -342.210428) (xy 269.096191 -342.256309)
			(xy 269.118847 -342.305919) (xy 269.134212 -342.358248) (xy 269.141974 -342.412231) (xy 269.141974 -342.466768)
			(xy 270.624822 -342.466768) (xy 270.624822 -342.412232) (xy 270.632583 -342.358252) (xy 270.647947 -342.305925)
			(xy 270.6706 -342.256317) (xy 270.700083 -342.210438) (xy 270.735794 -342.169221) (xy 270.777007 -342.133505)
			(xy 270.822884 -342.104018) (xy 270.872489 -342.08136) (xy 270.924814 -342.065991) (xy 270.978794 -342.058225)
			(xy 271.006062 -342.057736) (xy 271.869662 -342.057736) (xy 271.896935 -342.058201) (xy 271.950925 -342.065959)
			(xy 272.003262 -342.081321) (xy 272.05288 -342.103977) (xy 272.098768 -342.133463) (xy 272.139993 -342.16918)
			(xy 272.175714 -342.210401) (xy 272.205205 -342.256287) (xy 272.227865 -342.305902) (xy 272.243233 -342.358237)
			(xy 272.250996 -342.412227) (xy 272.250996 -342.466772) (xy 273.7337 -342.466772) (xy 273.7337 -342.412228)
			(xy 273.741462 -342.358239) (xy 273.75683 -342.305904) (xy 273.779489 -342.256289) (xy 273.808979 -342.210404)
			(xy 273.844699 -342.169183) (xy 273.885922 -342.133466) (xy 273.931809 -342.103979) (xy 273.981425 -342.081322)
			(xy 274.03376 -342.065958) (xy 274.08775 -342.058198) (xy 274.115022 -342.057736) (xy 274.978622 -342.057736)
			(xy 275.00589 -342.058228) (xy 275.059871 -342.065992) (xy 275.112198 -342.081359) (xy 275.161805 -342.104017)
			(xy 275.207683 -342.133503) (xy 275.248898 -342.169218) (xy 275.28461 -342.210435) (xy 275.314094 -342.256314)
			(xy 275.336748 -342.305923) (xy 275.352113 -342.35825) (xy 275.359874 -342.412232) (xy 275.359874 -342.466768)
			(xy 275.359874 -342.466769) (xy 276.842722 -342.466769) (xy 276.842722 -342.412231) (xy 276.850484 -342.358249)
			(xy 276.865848 -342.305921) (xy 276.888503 -342.256311) (xy 276.917987 -342.210431) (xy 276.953701 -342.169214)
			(xy 276.994917 -342.133498) (xy 277.040796 -342.104012) (xy 277.090404 -342.081354) (xy 277.142731 -342.065987)
			(xy 277.196713 -342.058224) (xy 277.223982 -342.057736) (xy 278.087582 -342.057736) (xy 278.114854 -342.058202)
			(xy 278.168842 -342.065962) (xy 278.221177 -342.081327) (xy 278.270792 -342.103983) (xy 278.316678 -342.13347)
			(xy 278.3579 -342.169188) (xy 278.393619 -342.210408) (xy 278.423108 -342.256292) (xy 278.445767 -342.305906)
			(xy 278.461134 -342.35824) (xy 278.468896 -342.412228) (xy 278.468896 -342.466772) (xy 278.468896 -342.466773)
			(xy 279.9516 -342.466773) (xy 279.9516 -342.412227) (xy 279.959363 -342.358236) (xy 279.974731 -342.3059)
			(xy 279.997392 -342.256284) (xy 280.026884 -342.210398) (xy 280.062606 -342.169176) (xy 280.103831 -342.133459)
			(xy 280.14972 -342.103972) (xy 280.199339 -342.081317) (xy 280.251677 -342.065954) (xy 280.305669 -342.058197)
			(xy 280.332942 -342.057736) (xy 281.196542 -342.057736) (xy 281.223809 -342.058229) (xy 281.277788 -342.065996)
			(xy 281.330112 -342.081365) (xy 281.379717 -342.104023) (xy 281.425592 -342.13351) (xy 281.466805 -342.169225)
			(xy 281.502515 -342.210441) (xy 281.531997 -342.25632) (xy 281.55465 -342.305927) (xy 281.570013 -342.358253)
			(xy 281.577774 -342.412233) (xy 281.577774 -342.466767) (xy 281.577773 -342.466771) (xy 283.060599 -342.466771)
			(xy 283.060599 -342.412229) (xy 283.068362 -342.358241) (xy 283.083728 -342.305908) (xy 283.106386 -342.256295)
			(xy 283.135874 -342.210411) (xy 283.171592 -342.16919) (xy 283.212812 -342.133473) (xy 283.258697 -342.103985)
			(xy 283.30831 -342.081327) (xy 283.360643 -342.065961) (xy 283.414631 -342.058199) (xy 283.441902 -342.057736)
			(xy 284.305502 -342.057736) (xy 284.332771 -342.058227) (xy 284.386754 -342.065988) (xy 284.439083 -342.081354)
			(xy 284.488693 -342.10401) (xy 284.534573 -342.133496) (xy 284.575791 -342.169211) (xy 284.611505 -342.210428)
			(xy 284.640991 -342.256309) (xy 284.663647 -342.305919) (xy 284.679012 -342.358248) (xy 284.686774 -342.412231)
			(xy 284.686774 -342.466768) (xy 286.169622 -342.466768) (xy 286.169622 -342.412232) (xy 286.177383 -342.358252)
			(xy 286.192747 -342.305925) (xy 286.2154 -342.256317) (xy 286.244883 -342.210438) (xy 286.280594 -342.169221)
			(xy 286.321807 -342.133505) (xy 286.367684 -342.104018) (xy 286.417289 -342.08136) (xy 286.469614 -342.065991)
			(xy 286.523594 -342.058225) (xy 286.550862 -342.057736) (xy 287.414462 -342.057736) (xy 287.441735 -342.058201)
			(xy 287.495725 -342.065959) (xy 287.548062 -342.081321) (xy 287.59768 -342.103977) (xy 287.643568 -342.133463)
			(xy 287.684793 -342.16918) (xy 287.720514 -342.210401) (xy 287.750005 -342.256287) (xy 287.772665 -342.305902)
			(xy 287.788033 -342.358237) (xy 287.795796 -342.412227) (xy 287.795796 -342.466772) (xy 289.2785 -342.466772)
			(xy 289.2785 -342.412228) (xy 289.286262 -342.358239) (xy 289.30163 -342.305904) (xy 289.324289 -342.256289)
			(xy 289.353779 -342.210404) (xy 289.389499 -342.169183) (xy 289.430722 -342.133466) (xy 289.476609 -342.103979)
			(xy 289.526225 -342.081322) (xy 289.57856 -342.065958) (xy 289.63255 -342.058198) (xy 289.659822 -342.057736)
			(xy 290.523422 -342.057736) (xy 290.55069 -342.058228) (xy 290.604671 -342.065992) (xy 290.656998 -342.081359)
			(xy 290.706605 -342.104017) (xy 290.752483 -342.133503) (xy 290.793698 -342.169218) (xy 290.82941 -342.210435)
			(xy 290.858894 -342.256314) (xy 290.881548 -342.305923) (xy 290.896913 -342.35825) (xy 290.904674 -342.412232)
			(xy 290.904674 -342.466768) (xy 290.904674 -342.466769) (xy 292.387522 -342.466769) (xy 292.387522 -342.412231)
			(xy 292.395284 -342.358249) (xy 292.410648 -342.305921) (xy 292.433303 -342.256311) (xy 292.462787 -342.210431)
			(xy 292.498501 -342.169214) (xy 292.539717 -342.133498) (xy 292.585596 -342.104012) (xy 292.635204 -342.081354)
			(xy 292.687531 -342.065987) (xy 292.741513 -342.058224) (xy 292.768782 -342.057736) (xy 293.632382 -342.057736)
			(xy 293.659654 -342.058202) (xy 293.713642 -342.065962) (xy 293.765977 -342.081327) (xy 293.815592 -342.103983)
			(xy 293.861478 -342.13347) (xy 293.9027 -342.169188) (xy 293.938419 -342.210408) (xy 293.967908 -342.256292)
			(xy 293.990567 -342.305906) (xy 294.005934 -342.35824) (xy 294.013696 -342.412228) (xy 294.013696 -342.466772)
			(xy 294.013696 -342.466773) (xy 295.4964 -342.466773) (xy 295.4964 -342.412227) (xy 295.504163 -342.358236)
			(xy 295.519531 -342.3059) (xy 295.542192 -342.256284) (xy 295.571684 -342.210398) (xy 295.607406 -342.169176)
			(xy 295.648631 -342.133459) (xy 295.69452 -342.103972) (xy 295.744139 -342.081317) (xy 295.796477 -342.065954)
			(xy 295.850469 -342.058197) (xy 295.877742 -342.057736) (xy 296.741342 -342.057736) (xy 296.768609 -342.058229)
			(xy 296.822588 -342.065996) (xy 296.874912 -342.081365) (xy 296.924517 -342.104023) (xy 296.970392 -342.13351)
			(xy 297.011605 -342.169225) (xy 297.047315 -342.210441) (xy 297.076797 -342.25632) (xy 297.09945 -342.305927)
			(xy 297.114813 -342.358253) (xy 297.122574 -342.412233) (xy 297.122574 -342.466767) (xy 297.122573 -342.466771)
			(xy 298.605399 -342.466771) (xy 298.605399 -342.412229) (xy 298.613162 -342.358241) (xy 298.628528 -342.305908)
			(xy 298.651186 -342.256295) (xy 298.680674 -342.210411) (xy 298.716392 -342.16919) (xy 298.757612 -342.133473)
			(xy 298.803497 -342.103985) (xy 298.85311 -342.081327) (xy 298.905443 -342.065961) (xy 298.959431 -342.058199)
			(xy 298.986702 -342.057736) (xy 299.850302 -342.057736) (xy 299.877571 -342.058227) (xy 299.931554 -342.065988)
			(xy 299.983883 -342.081354) (xy 300.033493 -342.10401) (xy 300.079373 -342.133496) (xy 300.120591 -342.169211)
			(xy 300.156305 -342.210428) (xy 300.185791 -342.256309) (xy 300.208447 -342.305919) (xy 300.223812 -342.358248)
			(xy 300.231574 -342.412231) (xy 300.231574 -342.466769) (xy 300.231574 -342.466771) (xy 312.1215 -342.466771)
			(xy 312.1215 -342.412229) (xy 312.129262 -342.358241) (xy 312.144628 -342.305908) (xy 312.167286 -342.256294)
			(xy 312.196774 -342.21041) (xy 312.232493 -342.16919) (xy 312.273713 -342.133472) (xy 312.319598 -342.103984)
			(xy 312.369212 -342.081327) (xy 312.421545 -342.065961) (xy 312.475533 -342.058199) (xy 312.502804 -342.057736)
			(xy 313.366404 -342.057736) (xy 313.393673 -342.058227) (xy 313.447656 -342.065989) (xy 313.499985 -342.081354)
			(xy 313.549594 -342.104011) (xy 313.595474 -342.133497) (xy 313.636691 -342.169212) (xy 313.672406 -342.210429)
			(xy 313.701891 -342.256309) (xy 313.724547 -342.305919) (xy 313.739912 -342.358248) (xy 313.747674 -342.412231)
			(xy 313.747674 -342.466768) (xy 315.230522 -342.466768) (xy 315.230522 -342.412232) (xy 315.238283 -342.358251)
			(xy 315.253647 -342.305924) (xy 315.2763 -342.256316) (xy 315.305783 -342.210437) (xy 315.341495 -342.16922)
			(xy 315.382708 -342.133505) (xy 315.428585 -342.104018) (xy 315.478191 -342.081359) (xy 315.530516 -342.065991)
			(xy 315.584496 -342.058225) (xy 315.611764 -342.057736) (xy 316.475364 -342.057736) (xy 316.502637 -342.058201)
			(xy 316.556627 -342.065959) (xy 316.608964 -342.081322) (xy 316.658581 -342.103977) (xy 316.704469 -342.133464)
			(xy 316.745693 -342.169181) (xy 316.781414 -342.210402) (xy 316.810905 -342.256287) (xy 316.833565 -342.305902)
			(xy 316.848933 -342.358238) (xy 316.856696 -342.412228) (xy 316.856696 -342.466772) (xy 318.3394 -342.466772)
			(xy 318.3394 -342.412228) (xy 318.347162 -342.358239) (xy 318.36253 -342.305904) (xy 318.385189 -342.256289)
			(xy 318.414679 -342.210404) (xy 318.4504 -342.169183) (xy 318.491623 -342.133465) (xy 318.53751 -342.103978)
			(xy 318.587126 -342.081322) (xy 318.639462 -342.065957) (xy 318.693452 -342.058198) (xy 318.720724 -342.057736)
			(xy 319.584324 -342.057736) (xy 319.611592 -342.058228) (xy 319.665573 -342.065992) (xy 319.717899 -342.08136)
			(xy 319.767506 -342.104017) (xy 319.813384 -342.133504) (xy 319.854598 -342.169219) (xy 319.890311 -342.210435)
			(xy 319.919794 -342.256315) (xy 319.942449 -342.305923) (xy 319.957813 -342.358251) (xy 319.965574 -342.412232)
			(xy 319.965574 -342.466768) (xy 319.965574 -342.466769) (xy 321.448422 -342.466769) (xy 321.448422 -342.412231)
			(xy 321.456184 -342.358249) (xy 321.471548 -342.30592) (xy 321.494203 -342.256311) (xy 321.523688 -342.21043)
			(xy 321.559402 -342.169213) (xy 321.600618 -342.133498) (xy 321.646497 -342.104011) (xy 321.696105 -342.081354)
			(xy 321.748433 -342.065987) (xy 321.802415 -342.058224) (xy 321.829684 -342.057736) (xy 322.693284 -342.057736)
			(xy 322.720556 -342.058202) (xy 322.774544 -342.065963) (xy 322.826878 -342.081327) (xy 322.876493 -342.103984)
			(xy 322.922379 -342.133471) (xy 322.9636 -342.169188) (xy 322.999319 -342.210409) (xy 323.028808 -342.256293)
			(xy 323.051467 -342.305907) (xy 323.066834 -342.35824) (xy 323.074596 -342.412228) (xy 323.074596 -342.466772)
			(xy 323.074596 -342.466773) (xy 324.5573 -342.466773) (xy 324.5573 -342.412227) (xy 324.565063 -342.358236)
			(xy 324.580432 -342.305899) (xy 324.603092 -342.256283) (xy 324.632584 -342.210397) (xy 324.668307 -342.169176)
			(xy 324.709532 -342.133458) (xy 324.755422 -342.103971) (xy 324.805041 -342.081316) (xy 324.857379 -342.065954)
			(xy 324.911371 -342.058196) (xy 324.938644 -342.057736) (xy 325.802244 -342.057736) (xy 325.829511 -342.058229)
			(xy 325.88349 -342.065996) (xy 325.935814 -342.081365) (xy 325.985418 -342.104024) (xy 326.031293 -342.133511)
			(xy 326.072505 -342.169226) (xy 326.108216 -342.210442) (xy 326.137697 -342.256321) (xy 326.16035 -342.305928)
			(xy 326.175713 -342.358253) (xy 326.183474 -342.412233) (xy 326.183474 -342.466767) (xy 326.183473 -342.466771)
			(xy 327.6663 -342.466771) (xy 327.6663 -342.412229) (xy 327.674062 -342.358241) (xy 327.689428 -342.305908)
			(xy 327.712086 -342.256294) (xy 327.741574 -342.21041) (xy 327.777293 -342.16919) (xy 327.818513 -342.133472)
			(xy 327.864398 -342.103984) (xy 327.914012 -342.081327) (xy 327.966345 -342.065961) (xy 328.020333 -342.058199)
			(xy 328.047604 -342.057736) (xy 328.911204 -342.057736) (xy 328.938473 -342.058227) (xy 328.992456 -342.065989)
			(xy 329.044785 -342.081354) (xy 329.094394 -342.104011) (xy 329.140274 -342.133497) (xy 329.181491 -342.169212)
			(xy 329.217206 -342.210429) (xy 329.246691 -342.256309) (xy 329.269347 -342.305919) (xy 329.284712 -342.358248)
			(xy 329.292474 -342.412231) (xy 329.292474 -342.466768) (xy 330.775322 -342.466768) (xy 330.775322 -342.412232)
			(xy 330.783083 -342.358251) (xy 330.798447 -342.305924) (xy 330.8211 -342.256316) (xy 330.850583 -342.210437)
			(xy 330.886295 -342.16922) (xy 330.927508 -342.133505) (xy 330.973385 -342.104018) (xy 331.022991 -342.081359)
			(xy 331.075316 -342.065991) (xy 331.129296 -342.058225) (xy 331.156564 -342.057736) (xy 332.020164 -342.057736)
			(xy 332.047437 -342.058201) (xy 332.101427 -342.065959) (xy 332.153764 -342.081322) (xy 332.203381 -342.103977)
			(xy 332.249269 -342.133464) (xy 332.290493 -342.169181) (xy 332.326214 -342.210402) (xy 332.355705 -342.256287)
			(xy 332.378365 -342.305902) (xy 332.393733 -342.358238) (xy 332.401496 -342.412228) (xy 332.401496 -342.466772)
			(xy 333.8842 -342.466772) (xy 333.8842 -342.412228) (xy 333.891962 -342.358239) (xy 333.90733 -342.305904)
			(xy 333.929989 -342.256289) (xy 333.959479 -342.210404) (xy 333.9952 -342.169183) (xy 334.036423 -342.133465)
			(xy 334.08231 -342.103978) (xy 334.131926 -342.081322) (xy 334.184262 -342.065957) (xy 334.238252 -342.058198)
			(xy 334.265524 -342.057736) (xy 335.129124 -342.057736) (xy 335.156392 -342.058228) (xy 335.210373 -342.065992)
			(xy 335.262699 -342.08136) (xy 335.312306 -342.104017) (xy 335.358184 -342.133504) (xy 335.399398 -342.169219)
			(xy 335.435111 -342.210435) (xy 335.464594 -342.256315) (xy 335.487249 -342.305923) (xy 335.502613 -342.358251)
			(xy 335.510374 -342.412232) (xy 335.510374 -342.466768) (xy 335.510374 -342.466769) (xy 336.993222 -342.466769)
			(xy 336.993222 -342.412231) (xy 337.000984 -342.358249) (xy 337.016348 -342.30592) (xy 337.039003 -342.256311)
			(xy 337.068488 -342.21043) (xy 337.104202 -342.169213) (xy 337.145418 -342.133498) (xy 337.191297 -342.104011)
			(xy 337.240905 -342.081354) (xy 337.293233 -342.065987) (xy 337.347215 -342.058224) (xy 337.374484 -342.057736)
			(xy 338.238084 -342.057736) (xy 338.265356 -342.058202) (xy 338.319344 -342.065963) (xy 338.371678 -342.081327)
			(xy 338.421293 -342.103984) (xy 338.467179 -342.133471) (xy 338.5084 -342.169188) (xy 338.544119 -342.210409)
			(xy 338.573608 -342.256293) (xy 338.596267 -342.305907) (xy 338.611634 -342.35824) (xy 338.619396 -342.412228)
			(xy 338.619396 -342.466772) (xy 338.619396 -342.466773) (xy 340.1021 -342.466773) (xy 340.1021 -342.412227)
			(xy 340.109863 -342.358236) (xy 340.125232 -342.305899) (xy 340.147892 -342.256283) (xy 340.177384 -342.210397)
			(xy 340.213107 -342.169176) (xy 340.254332 -342.133458) (xy 340.300222 -342.103971) (xy 340.349841 -342.081316)
			(xy 340.402179 -342.065954) (xy 340.456171 -342.058196) (xy 340.483444 -342.057736) (xy 341.347044 -342.057736)
			(xy 341.374311 -342.058229) (xy 341.42829 -342.065996) (xy 341.480614 -342.081365) (xy 341.530218 -342.104024)
			(xy 341.576093 -342.133511) (xy 341.617305 -342.169226) (xy 341.653016 -342.210442) (xy 341.682497 -342.256321)
			(xy 341.70515 -342.305928) (xy 341.720513 -342.358253) (xy 341.728274 -342.412233) (xy 341.728274 -342.466767)
			(xy 341.728273 -342.466771) (xy 343.2111 -342.466771) (xy 343.2111 -342.412229) (xy 343.218862 -342.358241)
			(xy 343.234228 -342.305908) (xy 343.256886 -342.256294) (xy 343.286374 -342.21041) (xy 343.322093 -342.16919)
			(xy 343.363313 -342.133472) (xy 343.409198 -342.103984) (xy 343.458812 -342.081327) (xy 343.511145 -342.065961)
			(xy 343.565133 -342.058199) (xy 343.592404 -342.057736) (xy 344.456004 -342.057736) (xy 344.483273 -342.058227)
			(xy 344.537256 -342.065989) (xy 344.589585 -342.081354) (xy 344.639194 -342.104011) (xy 344.685074 -342.133497)
			(xy 344.726291 -342.169212) (xy 344.762006 -342.210429) (xy 344.791491 -342.256309) (xy 344.814147 -342.305919)
			(xy 344.829512 -342.358248) (xy 344.837274 -342.412231) (xy 344.837274 -342.466769) (xy 370.806722 -342.466769)
			(xy 370.806722 -342.412231) (xy 370.814484 -342.358249) (xy 370.829848 -342.305921) (xy 370.852503 -342.256312)
			(xy 370.881987 -342.210432) (xy 370.9177 -342.169214) (xy 370.958916 -342.133499) (xy 371.004794 -342.104012)
			(xy 371.054402 -342.081355) (xy 371.10673 -342.065988) (xy 371.160711 -342.058224) (xy 371.18798 -342.057736)
			(xy 372.05158 -342.057736) (xy 372.078852 -342.058202) (xy 372.132841 -342.065962) (xy 372.185175 -342.081326)
			(xy 372.234791 -342.103983) (xy 372.280677 -342.13347) (xy 372.321899 -342.169187) (xy 372.357618 -342.210407)
			(xy 372.387108 -342.256292) (xy 372.409767 -342.305906) (xy 372.425134 -342.35824) (xy 372.432896 -342.412228)
			(xy 372.432896 -342.466772) (xy 372.432896 -342.466773) (xy 373.9156 -342.466773) (xy 373.9156 -342.412227)
			(xy 373.923363 -342.358236) (xy 373.938731 -342.3059) (xy 373.961392 -342.256284) (xy 373.990883 -342.210398)
			(xy 374.026605 -342.169177) (xy 374.06783 -342.133459) (xy 374.113719 -342.103973) (xy 374.163338 -342.081317)
			(xy 374.215676 -342.065954) (xy 374.269667 -342.058197) (xy 374.29694 -342.057736) (xy 375.16054 -342.057736)
			(xy 375.187807 -342.058229) (xy 375.241786 -342.065995) (xy 375.294111 -342.081364) (xy 375.343716 -342.104022)
			(xy 375.389591 -342.133509) (xy 375.430804 -342.169224) (xy 375.466515 -342.210441) (xy 375.495997 -342.256319)
			(xy 375.51865 -342.305927) (xy 375.534013 -342.358253) (xy 375.541774 -342.412233) (xy 375.541774 -342.466767)
			(xy 375.541774 -342.46677) (xy 377.024622 -342.46677) (xy 377.024622 -342.41223) (xy 377.032384 -342.358247)
			(xy 377.04775 -342.305917) (xy 377.070406 -342.256306) (xy 377.099892 -342.210425) (xy 377.135607 -342.169207)
			(xy 377.176825 -342.133492) (xy 377.222706 -342.104006) (xy 377.272317 -342.08135) (xy 377.324647 -342.065984)
			(xy 377.37863 -342.058222) (xy 377.4059 -342.057736) (xy 378.2695 -342.057736) (xy 378.296769 -342.058226)
			(xy 378.350753 -342.065988) (xy 378.403082 -342.081353) (xy 378.452692 -342.104009) (xy 378.498572 -342.133495)
			(xy 378.53979 -342.16921) (xy 378.575505 -342.210428) (xy 378.604991 -342.256308) (xy 378.627647 -342.305918)
			(xy 378.643012 -342.358247) (xy 378.650774 -342.412231) (xy 378.650774 -342.466768) (xy 380.133622 -342.466768)
			(xy 380.133622 -342.412232) (xy 380.141383 -342.358252) (xy 380.156746 -342.305925) (xy 380.1794 -342.256318)
			(xy 380.208882 -342.210438) (xy 380.244593 -342.169222) (xy 380.285806 -342.133506) (xy 380.331682 -342.104019)
			(xy 380.381288 -342.08136) (xy 380.433613 -342.065991) (xy 380.487592 -342.058225) (xy 380.51486 -342.057736)
			(xy 381.37846 -342.057736) (xy 381.405733 -342.058201) (xy 381.459724 -342.065958) (xy 381.512061 -342.081321)
			(xy 381.561679 -342.103976) (xy 381.607567 -342.133463) (xy 381.648792 -342.16918) (xy 381.684513 -342.210401)
			(xy 381.714005 -342.256286) (xy 381.736665 -342.305902) (xy 381.752033 -342.358237) (xy 381.759796 -342.412227)
			(xy 381.759796 -342.466772) (xy 383.2425 -342.466772) (xy 383.2425 -342.412228) (xy 383.250262 -342.358239)
			(xy 383.26563 -342.305904) (xy 383.288289 -342.25629) (xy 383.317778 -342.210405) (xy 383.353498 -342.169184)
			(xy 383.394721 -342.133466) (xy 383.440607 -342.103979) (xy 383.490223 -342.081323) (xy 383.542559 -342.065958)
			(xy 383.596548 -342.058198) (xy 383.62382 -342.057736) (xy 384.48742 -342.057736) (xy 384.514688 -342.058228)
			(xy 384.568669 -342.065992) (xy 384.620996 -342.081359) (xy 384.670604 -342.104016) (xy 384.716482 -342.133502)
			(xy 384.757697 -342.169217) (xy 384.79341 -342.210434) (xy 384.822894 -342.256314) (xy 384.845548 -342.305922)
			(xy 384.860913 -342.35825) (xy 384.868674 -342.412232) (xy 384.868674 -342.466768) (xy 384.868674 -342.466769)
			(xy 386.351522 -342.466769) (xy 386.351522 -342.412231) (xy 386.359284 -342.358249) (xy 386.374648 -342.305921)
			(xy 386.397303 -342.256312) (xy 386.426787 -342.210432) (xy 386.4625 -342.169214) (xy 386.503716 -342.133499)
			(xy 386.549594 -342.104012) (xy 386.599202 -342.081355) (xy 386.65153 -342.065988) (xy 386.705511 -342.058224)
			(xy 386.73278 -342.057736) (xy 387.59638 -342.057736) (xy 387.623652 -342.058202) (xy 387.677641 -342.065962)
			(xy 387.729975 -342.081326) (xy 387.779591 -342.103983) (xy 387.825477 -342.13347) (xy 387.866699 -342.169187)
			(xy 387.902418 -342.210407) (xy 387.931908 -342.256292) (xy 387.954567 -342.305906) (xy 387.969934 -342.35824)
			(xy 387.977696 -342.412228) (xy 387.977696 -342.466772) (xy 387.977696 -342.466773) (xy 389.4604 -342.466773)
			(xy 389.4604 -342.412227) (xy 389.468163 -342.358236) (xy 389.483531 -342.3059) (xy 389.506192 -342.256284)
			(xy 389.535683 -342.210398) (xy 389.571405 -342.169177) (xy 389.61263 -342.133459) (xy 389.658519 -342.103973)
			(xy 389.708138 -342.081317) (xy 389.760476 -342.065954) (xy 389.814467 -342.058197) (xy 389.84174 -342.057736)
			(xy 390.70534 -342.057736) (xy 390.732607 -342.058229) (xy 390.786586 -342.065995) (xy 390.838911 -342.081364)
			(xy 390.888516 -342.104022) (xy 390.934391 -342.133509) (xy 390.975604 -342.169224) (xy 391.011315 -342.210441)
			(xy 391.040797 -342.256319) (xy 391.06345 -342.305927) (xy 391.078813 -342.358253) (xy 391.086574 -342.412233)
			(xy 391.086574 -342.466767) (xy 391.086574 -342.46677) (xy 392.569422 -342.46677) (xy 392.569422 -342.41223)
			(xy 392.577184 -342.358247) (xy 392.59255 -342.305917) (xy 392.615206 -342.256306) (xy 392.644692 -342.210425)
			(xy 392.680407 -342.169207) (xy 392.721625 -342.133492) (xy 392.767506 -342.104006) (xy 392.817117 -342.08135)
			(xy 392.869447 -342.065984) (xy 392.92343 -342.058222) (xy 392.9507 -342.057736) (xy 393.8143 -342.057736)
			(xy 393.841569 -342.058226) (xy 393.895553 -342.065988) (xy 393.947882 -342.081353) (xy 393.997492 -342.104009)
			(xy 394.043372 -342.133495) (xy 394.08459 -342.16921) (xy 394.120305 -342.210428) (xy 394.149791 -342.256308)
			(xy 394.172447 -342.305918) (xy 394.187812 -342.358247) (xy 394.195574 -342.412231) (xy 394.195574 -342.466768)
			(xy 395.678422 -342.466768) (xy 395.678422 -342.412232) (xy 395.686183 -342.358252) (xy 395.701546 -342.305925)
			(xy 395.7242 -342.256318) (xy 395.753682 -342.210438) (xy 395.789393 -342.169222) (xy 395.830606 -342.133506)
			(xy 395.876482 -342.104019) (xy 395.926088 -342.08136) (xy 395.978413 -342.065991) (xy 396.032392 -342.058225)
			(xy 396.05966 -342.057736) (xy 396.92326 -342.057736) (xy 396.950533 -342.058201) (xy 397.004524 -342.065958)
			(xy 397.056861 -342.081321) (xy 397.106479 -342.103976) (xy 397.152367 -342.133463) (xy 397.193592 -342.16918)
			(xy 397.229313 -342.210401) (xy 397.258805 -342.256286) (xy 397.281465 -342.305902) (xy 397.296833 -342.358237)
			(xy 397.304596 -342.412227) (xy 397.304596 -342.466772) (xy 398.7873 -342.466772) (xy 398.7873 -342.412228)
			(xy 398.795062 -342.358239) (xy 398.81043 -342.305904) (xy 398.833089 -342.25629) (xy 398.862578 -342.210405)
			(xy 398.898298 -342.169184) (xy 398.939521 -342.133466) (xy 398.985407 -342.103979) (xy 399.035023 -342.081323)
			(xy 399.087359 -342.065958) (xy 399.141348 -342.058198) (xy 399.16862 -342.057736) (xy 400.03222 -342.057736)
			(xy 400.059488 -342.058228) (xy 400.113469 -342.065992) (xy 400.165796 -342.081359) (xy 400.215404 -342.104016)
			(xy 400.261282 -342.133502) (xy 400.302497 -342.169217) (xy 400.33821 -342.210434) (xy 400.367694 -342.256314)
			(xy 400.390348 -342.305922) (xy 400.405713 -342.35825) (xy 400.413474 -342.412232) (xy 400.413474 -342.466768)
			(xy 400.413474 -342.466769) (xy 401.896322 -342.466769) (xy 401.896322 -342.412231) (xy 401.904084 -342.358249)
			(xy 401.919448 -342.305921) (xy 401.942103 -342.256312) (xy 401.971587 -342.210432) (xy 402.0073 -342.169214)
			(xy 402.048516 -342.133499) (xy 402.094394 -342.104012) (xy 402.144002 -342.081355) (xy 402.19633 -342.065988)
			(xy 402.250311 -342.058224) (xy 402.27758 -342.057736) (xy 403.14118 -342.057736) (xy 403.168452 -342.058202)
			(xy 403.222441 -342.065962) (xy 403.274775 -342.081326) (xy 403.324391 -342.103983) (xy 403.370277 -342.13347)
			(xy 403.411499 -342.169187) (xy 403.447218 -342.210407) (xy 403.476708 -342.256292) (xy 403.499367 -342.305906)
			(xy 403.514734 -342.35824) (xy 403.522496 -342.412228) (xy 403.522496 -342.466769) (xy 408.913822 -342.466769)
			(xy 408.913822 -342.412231) (xy 408.921584 -342.358248) (xy 408.936949 -342.305918) (xy 408.959605 -342.256309)
			(xy 408.98909 -342.210428) (xy 409.024805 -342.16921) (xy 409.066021 -342.133495) (xy 409.111902 -342.104009)
			(xy 409.161511 -342.081352) (xy 409.21384 -342.065986) (xy 409.267823 -342.058223) (xy 409.295092 -342.057736)
			(xy 410.158692 -342.057736) (xy 410.185963 -342.058203) (xy 410.239951 -342.065964) (xy 410.292284 -342.08133)
			(xy 410.341898 -342.103987) (xy 410.387782 -342.133474) (xy 410.429003 -342.169191) (xy 410.464721 -342.210411)
			(xy 410.49421 -342.256295) (xy 410.516868 -342.305908) (xy 410.532234 -342.358241) (xy 410.539996 -342.412229)
			(xy 410.539996 -342.466767) (xy 412.022822 -342.466767) (xy 412.022822 -342.412233) (xy 412.030583 -342.358253)
			(xy 412.045946 -342.305927) (xy 412.068599 -342.25632) (xy 412.09808 -342.210441) (xy 412.13379 -342.169224)
			(xy 412.175002 -342.133509) (xy 412.220878 -342.104022) (xy 412.270482 -342.081363) (xy 412.322806 -342.065993)
			(xy 412.376785 -342.058226) (xy 412.404052 -342.057736) (xy 413.267652 -342.057736) (xy 413.294925 -342.0582)
			(xy 413.348917 -342.065957) (xy 413.401255 -342.081319) (xy 413.450874 -342.103974) (xy 413.496763 -342.13346)
			(xy 413.537989 -342.169177) (xy 413.573712 -342.210398) (xy 413.603203 -342.256284) (xy 413.625864 -342.3059)
			(xy 413.641233 -342.358236) (xy 413.648996 -342.412227) (xy 413.648996 -342.466772) (xy 415.1317 -342.466772)
			(xy 415.1317 -342.412228) (xy 415.139462 -342.35824) (xy 415.154829 -342.305906) (xy 415.177488 -342.256292)
			(xy 415.206976 -342.210407) (xy 415.242695 -342.169187) (xy 415.283917 -342.133469) (xy 415.329803 -342.103982)
			(xy 415.379417 -342.081325) (xy 415.431752 -342.065959) (xy 415.48574 -342.058199) (xy 415.513012 -342.057736)
			(xy 416.376612 -342.057736) (xy 416.403881 -342.058227) (xy 416.457863 -342.06599) (xy 416.510191 -342.081357)
			(xy 416.559799 -342.104013) (xy 416.605678 -342.133499) (xy 416.646894 -342.169214) (xy 416.682608 -342.210432)
			(xy 416.712092 -342.256312) (xy 416.734748 -342.305921) (xy 416.750112 -342.358249) (xy 416.757874 -342.412231)
			(xy 416.757874 -342.466768) (xy 418.240722 -342.466768) (xy 418.240722 -342.412232) (xy 418.248483 -342.35825)
			(xy 418.263847 -342.305923) (xy 418.286502 -342.256314) (xy 418.315985 -342.210434) (xy 418.351697 -342.169217)
			(xy 418.392912 -342.133502) (xy 418.43879 -342.104015) (xy 418.488396 -342.081357) (xy 418.540723 -342.065989)
			(xy 418.594704 -342.058224) (xy 418.621972 -342.057736) (xy 419.485572 -342.057736) (xy 419.512844 -342.058202)
			(xy 419.566834 -342.06596) (xy 419.61917 -342.081324) (xy 419.668786 -342.10398) (xy 419.714673 -342.133467)
			(xy 419.755896 -342.169184) (xy 419.791616 -342.210405) (xy 419.821107 -342.256289) (xy 419.843766 -342.305904)
			(xy 419.859134 -342.358239) (xy 419.866896 -342.412228) (xy 419.866896 -342.466772) (xy 419.866896 -342.466773)
			(xy 421.3496 -342.466773) (xy 421.3496 -342.412227) (xy 421.357363 -342.358237) (xy 421.372731 -342.305902)
			(xy 421.395391 -342.256286) (xy 421.424881 -342.210401) (xy 421.460602 -342.16918) (xy 421.501827 -342.133462)
			(xy 421.547715 -342.103975) (xy 421.597332 -342.081319) (xy 421.649669 -342.065956) (xy 421.703659 -342.058197)
			(xy 421.730932 -342.057736) (xy 422.594532 -342.057736) (xy 422.6218 -342.058229) (xy 422.67578 -342.065994)
			(xy 422.728105 -342.081362) (xy 422.777711 -342.10402) (xy 422.823588 -342.133506) (xy 422.864801 -342.169222)
			(xy 422.900513 -342.210438) (xy 422.929995 -342.256317) (xy 422.952649 -342.305925) (xy 422.968013 -342.358252)
			(xy 422.975774 -342.412232) (xy 422.975774 -342.466768) (xy 422.975774 -342.466769) (xy 424.458622 -342.466769)
			(xy 424.458622 -342.412231) (xy 424.466384 -342.358248) (xy 424.481749 -342.305918) (xy 424.504405 -342.256309)
			(xy 424.53389 -342.210428) (xy 424.569605 -342.16921) (xy 424.610821 -342.133495) (xy 424.656702 -342.104009)
			(xy 424.706311 -342.081352) (xy 424.75864 -342.065986) (xy 424.812623 -342.058223) (xy 424.839892 -342.057736)
			(xy 425.703492 -342.057736) (xy 425.730763 -342.058203) (xy 425.784751 -342.065964) (xy 425.837084 -342.08133)
			(xy 425.886698 -342.103987) (xy 425.932582 -342.133474) (xy 425.973803 -342.169191) (xy 426.009521 -342.210411)
			(xy 426.03901 -342.256295) (xy 426.061668 -342.305908) (xy 426.077034 -342.358241) (xy 426.084796 -342.412229)
			(xy 426.084796 -342.466767) (xy 427.567622 -342.466767) (xy 427.567622 -342.412233) (xy 427.575383 -342.358253)
			(xy 427.590746 -342.305927) (xy 427.613399 -342.25632) (xy 427.64288 -342.210441) (xy 427.67859 -342.169224)
			(xy 427.719802 -342.133509) (xy 427.765678 -342.104022) (xy 427.815282 -342.081363) (xy 427.867606 -342.065993)
			(xy 427.921585 -342.058226) (xy 427.948852 -342.057736) (xy 428.812452 -342.057736) (xy 428.839725 -342.0582)
			(xy 428.893717 -342.065957) (xy 428.946055 -342.081319) (xy 428.995674 -342.103974) (xy 429.041563 -342.13346)
			(xy 429.082789 -342.169177) (xy 429.118512 -342.210398) (xy 429.148003 -342.256284) (xy 429.170664 -342.3059)
			(xy 429.186033 -342.358236) (xy 429.193796 -342.412227) (xy 429.193796 -342.466772) (xy 430.6765 -342.466772)
			(xy 430.6765 -342.412228) (xy 430.684262 -342.35824) (xy 430.699629 -342.305906) (xy 430.722288 -342.256292)
			(xy 430.751776 -342.210407) (xy 430.787495 -342.169187) (xy 430.828717 -342.133469) (xy 430.874603 -342.103982)
			(xy 430.924217 -342.081325) (xy 430.976552 -342.065959) (xy 431.03054 -342.058199) (xy 431.057812 -342.057736)
			(xy 431.921412 -342.057736) (xy 431.948681 -342.058227) (xy 432.002663 -342.06599) (xy 432.054991 -342.081357)
			(xy 432.104599 -342.104013) (xy 432.150478 -342.133499) (xy 432.191694 -342.169214) (xy 432.227408 -342.210432)
			(xy 432.256892 -342.256312) (xy 432.279548 -342.305921) (xy 432.294912 -342.358249) (xy 432.302674 -342.412231)
			(xy 432.302674 -342.466768) (xy 433.785522 -342.466768) (xy 433.785522 -342.412232) (xy 433.793283 -342.35825)
			(xy 433.808647 -342.305923) (xy 433.831302 -342.256314) (xy 433.860785 -342.210434) (xy 433.896497 -342.169217)
			(xy 433.937712 -342.133502) (xy 433.98359 -342.104015) (xy 434.033196 -342.081357) (xy 434.085523 -342.065989)
			(xy 434.139504 -342.058224) (xy 434.166772 -342.057736) (xy 435.030372 -342.057736) (xy 435.057644 -342.058202)
			(xy 435.111634 -342.06596) (xy 435.16397 -342.081324) (xy 435.213586 -342.10398) (xy 435.259473 -342.133467)
			(xy 435.300696 -342.169184) (xy 435.336416 -342.210405) (xy 435.365907 -342.256289) (xy 435.388566 -342.305904)
			(xy 435.403934 -342.358239) (xy 435.411696 -342.412228) (xy 435.411696 -342.466772) (xy 435.411696 -342.466773)
			(xy 436.8944 -342.466773) (xy 436.8944 -342.412227) (xy 436.902163 -342.358237) (xy 436.917531 -342.305902)
			(xy 436.940191 -342.256286) (xy 436.969681 -342.210401) (xy 437.005402 -342.16918) (xy 437.046627 -342.133462)
			(xy 437.092515 -342.103975) (xy 437.142132 -342.081319) (xy 437.194469 -342.065956) (xy 437.248459 -342.058197)
			(xy 437.275732 -342.057736) (xy 438.139332 -342.057736) (xy 438.1666 -342.058229) (xy 438.22058 -342.065994)
			(xy 438.272905 -342.081362) (xy 438.322511 -342.10402) (xy 438.368388 -342.133506) (xy 438.409601 -342.169222)
			(xy 438.445313 -342.210438) (xy 438.474795 -342.256317) (xy 438.497449 -342.305925) (xy 438.512813 -342.358252)
			(xy 438.520574 -342.412232) (xy 438.520574 -342.466768) (xy 438.520574 -342.466769) (xy 440.003422 -342.466769)
			(xy 440.003422 -342.412231) (xy 440.011184 -342.358248) (xy 440.026549 -342.305918) (xy 440.049205 -342.256309)
			(xy 440.07869 -342.210428) (xy 440.114405 -342.16921) (xy 440.155621 -342.133495) (xy 440.201502 -342.104009)
			(xy 440.251111 -342.081352) (xy 440.30344 -342.065986) (xy 440.357423 -342.058223) (xy 440.384692 -342.057736)
			(xy 441.248292 -342.057736) (xy 441.275563 -342.058203) (xy 441.329551 -342.065964) (xy 441.381884 -342.08133)
			(xy 441.431498 -342.103987) (xy 441.477382 -342.133474) (xy 441.518603 -342.169191) (xy 441.554321 -342.210411)
			(xy 441.58381 -342.256295) (xy 441.606468 -342.305908) (xy 441.621834 -342.358241) (xy 441.629596 -342.412229)
			(xy 441.629596 -342.466771) (xy 441.621834 -342.520759) (xy 441.606468 -342.573092) (xy 441.58381 -342.622705)
			(xy 441.554321 -342.668589) (xy 441.518603 -342.709809) (xy 441.477382 -342.745526) (xy 441.431498 -342.775013)
			(xy 441.381884 -342.79767) (xy 441.329551 -342.813036) (xy 441.275563 -342.820797) (xy 441.248292 -342.82126)
			(xy 440.384692 -342.82126) (xy 440.357423 -342.820777) (xy 440.30344 -342.813014) (xy 440.251111 -342.797648)
			(xy 440.201502 -342.774991) (xy 440.155621 -342.745505) (xy 440.114405 -342.70979) (xy 440.07869 -342.668572)
			(xy 440.049205 -342.622691) (xy 440.026549 -342.573082) (xy 440.011184 -342.520752) (xy 440.003422 -342.466769)
			(xy 438.520574 -342.466769) (xy 438.512813 -342.520748) (xy 438.497449 -342.573075) (xy 438.474795 -342.622683)
			(xy 438.445313 -342.668562) (xy 438.409601 -342.709778) (xy 438.368388 -342.745494) (xy 438.322511 -342.77498)
			(xy 438.272905 -342.797638) (xy 438.22058 -342.813006) (xy 438.1666 -342.820771) (xy 438.139332 -342.82126)
			(xy 437.275732 -342.82126) (xy 437.248459 -342.820803) (xy 437.194469 -342.813044) (xy 437.142132 -342.797681)
			(xy 437.092515 -342.775025) (xy 437.046627 -342.745538) (xy 437.005402 -342.70982) (xy 436.969681 -342.668599)
			(xy 436.940191 -342.622714) (xy 436.917531 -342.573098) (xy 436.902163 -342.520763) (xy 436.8944 -342.466773)
			(xy 435.411696 -342.466773) (xy 435.403934 -342.520761) (xy 435.388566 -342.573096) (xy 435.365907 -342.622711)
			(xy 435.336416 -342.668595) (xy 435.300696 -342.709816) (xy 435.259473 -342.745533) (xy 435.213586 -342.77502)
			(xy 435.16397 -342.797676) (xy 435.111634 -342.81304) (xy 435.057644 -342.820798) (xy 435.030372 -342.82126)
			(xy 434.166772 -342.82126) (xy 434.139504 -342.820776) (xy 434.085523 -342.813011) (xy 434.033196 -342.797643)
			(xy 433.98359 -342.774985) (xy 433.937712 -342.745498) (xy 433.896497 -342.709783) (xy 433.860785 -342.668566)
			(xy 433.831302 -342.622686) (xy 433.808647 -342.573077) (xy 433.793283 -342.52075) (xy 433.785522 -342.466768)
			(xy 432.302674 -342.466768) (xy 432.302674 -342.466769) (xy 432.294912 -342.520751) (xy 432.279548 -342.573079)
			(xy 432.256892 -342.622688) (xy 432.227408 -342.668568) (xy 432.191694 -342.709786) (xy 432.150478 -342.745501)
			(xy 432.104599 -342.774987) (xy 432.054991 -342.797643) (xy 432.002663 -342.81301) (xy 431.948681 -342.820773)
			(xy 431.921412 -342.82126) (xy 431.057812 -342.82126) (xy 431.03054 -342.820801) (xy 430.976552 -342.813041)
			(xy 430.924217 -342.797675) (xy 430.874603 -342.775018) (xy 430.828717 -342.745531) (xy 430.787495 -342.709813)
			(xy 430.751776 -342.668593) (xy 430.722288 -342.622708) (xy 430.699629 -342.573094) (xy 430.684262 -342.52076)
			(xy 430.6765 -342.466772) (xy 429.193796 -342.466772) (xy 429.193796 -342.466773) (xy 429.186033 -342.520764)
			(xy 429.170664 -342.5731) (xy 429.148003 -342.622716) (xy 429.118512 -342.668602) (xy 429.082789 -342.709823)
			(xy 429.041563 -342.74554) (xy 428.995674 -342.775026) (xy 428.946055 -342.797681) (xy 428.893717 -342.813043)
			(xy 428.839725 -342.8208) (xy 428.812452 -342.82126) (xy 427.948852 -342.82126) (xy 427.921585 -342.820774)
			(xy 427.867606 -342.813007) (xy 427.815282 -342.797637) (xy 427.765678 -342.774978) (xy 427.719802 -342.745491)
			(xy 427.67859 -342.709776) (xy 427.64288 -342.668559) (xy 427.613399 -342.62268) (xy 427.590746 -342.573073)
			(xy 427.575383 -342.520747) (xy 427.567622 -342.466767) (xy 426.084796 -342.466767) (xy 426.084796 -342.466771)
			(xy 426.077034 -342.520759) (xy 426.061668 -342.573092) (xy 426.03901 -342.622705) (xy 426.009521 -342.668589)
			(xy 425.973803 -342.709809) (xy 425.932582 -342.745526) (xy 425.886698 -342.775013) (xy 425.837084 -342.79767)
			(xy 425.784751 -342.813036) (xy 425.730763 -342.820797) (xy 425.703492 -342.82126) (xy 424.839892 -342.82126)
			(xy 424.812623 -342.820777) (xy 424.75864 -342.813014) (xy 424.706311 -342.797648) (xy 424.656702 -342.774991)
			(xy 424.610821 -342.745505) (xy 424.569605 -342.70979) (xy 424.53389 -342.668572) (xy 424.504405 -342.622691)
			(xy 424.481749 -342.573082) (xy 424.466384 -342.520752) (xy 424.458622 -342.466769) (xy 422.975774 -342.466769)
			(xy 422.968013 -342.520748) (xy 422.952649 -342.573075) (xy 422.929995 -342.622683) (xy 422.900513 -342.668562)
			(xy 422.864801 -342.709778) (xy 422.823588 -342.745494) (xy 422.777711 -342.77498) (xy 422.728105 -342.797638)
			(xy 422.67578 -342.813006) (xy 422.6218 -342.820771) (xy 422.594532 -342.82126) (xy 421.730932 -342.82126)
			(xy 421.703659 -342.820803) (xy 421.649669 -342.813044) (xy 421.597332 -342.797681) (xy 421.547715 -342.775025)
			(xy 421.501827 -342.745538) (xy 421.460602 -342.70982) (xy 421.424881 -342.668599) (xy 421.395391 -342.622714)
			(xy 421.372731 -342.573098) (xy 421.357363 -342.520763) (xy 421.3496 -342.466773) (xy 419.866896 -342.466773)
			(xy 419.859134 -342.520761) (xy 419.843766 -342.573096) (xy 419.821107 -342.622711) (xy 419.791616 -342.668595)
			(xy 419.755896 -342.709816) (xy 419.714673 -342.745533) (xy 419.668786 -342.77502) (xy 419.61917 -342.797676)
			(xy 419.566834 -342.81304) (xy 419.512844 -342.820798) (xy 419.485572 -342.82126) (xy 418.621972 -342.82126)
			(xy 418.594704 -342.820776) (xy 418.540723 -342.813011) (xy 418.488396 -342.797643) (xy 418.43879 -342.774985)
			(xy 418.392912 -342.745498) (xy 418.351697 -342.709783) (xy 418.315985 -342.668566) (xy 418.286502 -342.622686)
			(xy 418.263847 -342.573077) (xy 418.248483 -342.52075) (xy 418.240722 -342.466768) (xy 416.757874 -342.466768)
			(xy 416.757874 -342.466769) (xy 416.750112 -342.520751) (xy 416.734748 -342.573079) (xy 416.712092 -342.622688)
			(xy 416.682608 -342.668568) (xy 416.646894 -342.709786) (xy 416.605678 -342.745501) (xy 416.559799 -342.774987)
			(xy 416.510191 -342.797643) (xy 416.457863 -342.81301) (xy 416.403881 -342.820773) (xy 416.376612 -342.82126)
			(xy 415.513012 -342.82126) (xy 415.48574 -342.820801) (xy 415.431752 -342.813041) (xy 415.379417 -342.797675)
			(xy 415.329803 -342.775018) (xy 415.283917 -342.745531) (xy 415.242695 -342.709813) (xy 415.206976 -342.668593)
			(xy 415.177488 -342.622708) (xy 415.154829 -342.573094) (xy 415.139462 -342.52076) (xy 415.1317 -342.466772)
			(xy 413.648996 -342.466772) (xy 413.648996 -342.466773) (xy 413.641233 -342.520764) (xy 413.625864 -342.5731)
			(xy 413.603203 -342.622716) (xy 413.573712 -342.668602) (xy 413.537989 -342.709823) (xy 413.496763 -342.74554)
			(xy 413.450874 -342.775026) (xy 413.401255 -342.797681) (xy 413.348917 -342.813043) (xy 413.294925 -342.8208)
			(xy 413.267652 -342.82126) (xy 412.404052 -342.82126) (xy 412.376785 -342.820774) (xy 412.322806 -342.813007)
			(xy 412.270482 -342.797637) (xy 412.220878 -342.774978) (xy 412.175002 -342.745491) (xy 412.13379 -342.709776)
			(xy 412.09808 -342.668559) (xy 412.068599 -342.62268) (xy 412.045946 -342.573073) (xy 412.030583 -342.520747)
			(xy 412.022822 -342.466767) (xy 410.539996 -342.466767) (xy 410.539996 -342.466771) (xy 410.532234 -342.520759)
			(xy 410.516868 -342.573092) (xy 410.49421 -342.622705) (xy 410.464721 -342.668589) (xy 410.429003 -342.709809)
			(xy 410.387782 -342.745526) (xy 410.341898 -342.775013) (xy 410.292284 -342.79767) (xy 410.239951 -342.813036)
			(xy 410.185963 -342.820797) (xy 410.158692 -342.82126) (xy 409.295092 -342.82126) (xy 409.267823 -342.820777)
			(xy 409.21384 -342.813014) (xy 409.161511 -342.797648) (xy 409.111902 -342.774991) (xy 409.066021 -342.745505)
			(xy 409.024805 -342.70979) (xy 408.98909 -342.668572) (xy 408.959605 -342.622691) (xy 408.936949 -342.573082)
			(xy 408.921584 -342.520752) (xy 408.913822 -342.466769) (xy 403.522496 -342.466769) (xy 403.522496 -342.466772)
			(xy 403.514734 -342.52076) (xy 403.499367 -342.573094) (xy 403.476708 -342.622708) (xy 403.447218 -342.668593)
			(xy 403.411499 -342.709813) (xy 403.370277 -342.74553) (xy 403.324391 -342.775017) (xy 403.274775 -342.797674)
			(xy 403.222441 -342.813038) (xy 403.168452 -342.820798) (xy 403.14118 -342.82126) (xy 402.27758 -342.82126)
			(xy 402.250311 -342.820776) (xy 402.19633 -342.813012) (xy 402.144002 -342.797645) (xy 402.094394 -342.774988)
			(xy 402.048516 -342.745501) (xy 402.0073 -342.709786) (xy 401.971587 -342.668568) (xy 401.942103 -342.622688)
			(xy 401.919448 -342.573079) (xy 401.904084 -342.520751) (xy 401.896322 -342.466769) (xy 400.413474 -342.466769)
			(xy 400.405713 -342.52075) (xy 400.390348 -342.573078) (xy 400.367694 -342.622686) (xy 400.33821 -342.668566)
			(xy 400.302497 -342.709783) (xy 400.261282 -342.745498) (xy 400.215404 -342.774984) (xy 400.165796 -342.797641)
			(xy 400.113469 -342.813008) (xy 400.059488 -342.820772) (xy 400.03222 -342.82126) (xy 399.16862 -342.82126)
			(xy 399.141348 -342.820802) (xy 399.087359 -342.813042) (xy 399.035023 -342.797677) (xy 398.985407 -342.775021)
			(xy 398.939521 -342.745534) (xy 398.898298 -342.709816) (xy 398.862578 -342.668595) (xy 398.833089 -342.62271)
			(xy 398.81043 -342.573096) (xy 398.795062 -342.520761) (xy 398.7873 -342.466772) (xy 397.304596 -342.466772)
			(xy 397.304596 -342.466773) (xy 397.296833 -342.520763) (xy 397.281465 -342.573098) (xy 397.258805 -342.622714)
			(xy 397.229313 -342.668599) (xy 397.193592 -342.70982) (xy 397.152367 -342.745537) (xy 397.106479 -342.775024)
			(xy 397.056861 -342.797679) (xy 397.004524 -342.813042) (xy 396.950533 -342.820799) (xy 396.92326 -342.82126)
			(xy 396.05966 -342.82126) (xy 396.032392 -342.820775) (xy 395.978413 -342.813009) (xy 395.926088 -342.79764)
			(xy 395.876482 -342.774981) (xy 395.830606 -342.745494) (xy 395.789393 -342.709778) (xy 395.753682 -342.668562)
			(xy 395.7242 -342.622682) (xy 395.701546 -342.573075) (xy 395.686183 -342.520748) (xy 395.678422 -342.466768)
			(xy 394.195574 -342.466768) (xy 394.195574 -342.466769) (xy 394.187812 -342.520753) (xy 394.172447 -342.573082)
			(xy 394.149791 -342.622692) (xy 394.120305 -342.668572) (xy 394.08459 -342.70979) (xy 394.043372 -342.745505)
			(xy 393.997492 -342.774991) (xy 393.947882 -342.797647) (xy 393.895553 -342.813012) (xy 393.841569 -342.820774)
			(xy 393.8143 -342.82126) (xy 392.9507 -342.82126) (xy 392.92343 -342.820778) (xy 392.869447 -342.813016)
			(xy 392.817117 -342.79765) (xy 392.767506 -342.774994) (xy 392.721625 -342.745508) (xy 392.680407 -342.709793)
			(xy 392.644692 -342.668575) (xy 392.615206 -342.622694) (xy 392.59255 -342.573083) (xy 392.577184 -342.520753)
			(xy 392.569422 -342.46677) (xy 391.086574 -342.46677) (xy 391.078813 -342.520747) (xy 391.06345 -342.573073)
			(xy 391.040797 -342.622681) (xy 391.011315 -342.668559) (xy 390.975604 -342.709776) (xy 390.934391 -342.745491)
			(xy 390.888516 -342.774978) (xy 390.838911 -342.797636) (xy 390.786586 -342.813005) (xy 390.732607 -342.820771)
			(xy 390.70534 -342.82126) (xy 389.84174 -342.82126) (xy 389.814467 -342.820803) (xy 389.760476 -342.813046)
			(xy 389.708138 -342.797683) (xy 389.658519 -342.775027) (xy 389.61263 -342.745541) (xy 389.571405 -342.709823)
			(xy 389.535683 -342.668602) (xy 389.506192 -342.622716) (xy 389.483531 -342.5731) (xy 389.468163 -342.520764)
			(xy 389.4604 -342.466773) (xy 387.977696 -342.466773) (xy 387.969934 -342.52076) (xy 387.954567 -342.573094)
			(xy 387.931908 -342.622708) (xy 387.902418 -342.668593) (xy 387.866699 -342.709813) (xy 387.825477 -342.74553)
			(xy 387.779591 -342.775017) (xy 387.729975 -342.797674) (xy 387.677641 -342.813038) (xy 387.623652 -342.820798)
			(xy 387.59638 -342.82126) (xy 386.73278 -342.82126) (xy 386.705511 -342.820776) (xy 386.65153 -342.813012)
			(xy 386.599202 -342.797645) (xy 386.549594 -342.774988) (xy 386.503716 -342.745501) (xy 386.4625 -342.709786)
			(xy 386.426787 -342.668568) (xy 386.397303 -342.622688) (xy 386.374648 -342.573079) (xy 386.359284 -342.520751)
			(xy 386.351522 -342.466769) (xy 384.868674 -342.466769) (xy 384.860913 -342.52075) (xy 384.845548 -342.573078)
			(xy 384.822894 -342.622686) (xy 384.79341 -342.668566) (xy 384.757697 -342.709783) (xy 384.716482 -342.745498)
			(xy 384.670604 -342.774984) (xy 384.620996 -342.797641) (xy 384.568669 -342.813008) (xy 384.514688 -342.820772)
			(xy 384.48742 -342.82126) (xy 383.62382 -342.82126) (xy 383.596548 -342.820802) (xy 383.542559 -342.813042)
			(xy 383.490223 -342.797677) (xy 383.440607 -342.775021) (xy 383.394721 -342.745534) (xy 383.353498 -342.709816)
			(xy 383.317778 -342.668595) (xy 383.288289 -342.62271) (xy 383.26563 -342.573096) (xy 383.250262 -342.520761)
			(xy 383.2425 -342.466772) (xy 381.759796 -342.466772) (xy 381.759796 -342.466773) (xy 381.752033 -342.520763)
			(xy 381.736665 -342.573098) (xy 381.714005 -342.622714) (xy 381.684513 -342.668599) (xy 381.648792 -342.70982)
			(xy 381.607567 -342.745537) (xy 381.561679 -342.775024) (xy 381.512061 -342.797679) (xy 381.459724 -342.813042)
			(xy 381.405733 -342.820799) (xy 381.37846 -342.82126) (xy 380.51486 -342.82126) (xy 380.487592 -342.820775)
			(xy 380.433613 -342.813009) (xy 380.381288 -342.79764) (xy 380.331682 -342.774981) (xy 380.285806 -342.745494)
			(xy 380.244593 -342.709778) (xy 380.208882 -342.668562) (xy 380.1794 -342.622682) (xy 380.156746 -342.573075)
			(xy 380.141383 -342.520748) (xy 380.133622 -342.466768) (xy 378.650774 -342.466768) (xy 378.650774 -342.466769)
			(xy 378.643012 -342.520753) (xy 378.627647 -342.573082) (xy 378.604991 -342.622692) (xy 378.575505 -342.668572)
			(xy 378.53979 -342.70979) (xy 378.498572 -342.745505) (xy 378.452692 -342.774991) (xy 378.403082 -342.797647)
			(xy 378.350753 -342.813012) (xy 378.296769 -342.820774) (xy 378.2695 -342.82126) (xy 377.4059 -342.82126)
			(xy 377.37863 -342.820778) (xy 377.324647 -342.813016) (xy 377.272317 -342.79765) (xy 377.222706 -342.774994)
			(xy 377.176825 -342.745508) (xy 377.135607 -342.709793) (xy 377.099892 -342.668575) (xy 377.070406 -342.622694)
			(xy 377.04775 -342.573083) (xy 377.032384 -342.520753) (xy 377.024622 -342.46677) (xy 375.541774 -342.46677)
			(xy 375.534013 -342.520747) (xy 375.51865 -342.573073) (xy 375.495997 -342.622681) (xy 375.466515 -342.668559)
			(xy 375.430804 -342.709776) (xy 375.389591 -342.745491) (xy 375.343716 -342.774978) (xy 375.294111 -342.797636)
			(xy 375.241786 -342.813005) (xy 375.187807 -342.820771) (xy 375.16054 -342.82126) (xy 374.29694 -342.82126)
			(xy 374.269667 -342.820803) (xy 374.215676 -342.813046) (xy 374.163338 -342.797683) (xy 374.113719 -342.775027)
			(xy 374.06783 -342.745541) (xy 374.026605 -342.709823) (xy 373.990883 -342.668602) (xy 373.961392 -342.622716)
			(xy 373.938731 -342.5731) (xy 373.923363 -342.520764) (xy 373.9156 -342.466773) (xy 372.432896 -342.466773)
			(xy 372.425134 -342.52076) (xy 372.409767 -342.573094) (xy 372.387108 -342.622708) (xy 372.357618 -342.668593)
			(xy 372.321899 -342.709813) (xy 372.280677 -342.74553) (xy 372.234791 -342.775017) (xy 372.185175 -342.797674)
			(xy 372.132841 -342.813038) (xy 372.078852 -342.820798) (xy 372.05158 -342.82126) (xy 371.18798 -342.82126)
			(xy 371.160711 -342.820776) (xy 371.10673 -342.813012) (xy 371.054402 -342.797645) (xy 371.004794 -342.774988)
			(xy 370.958916 -342.745501) (xy 370.9177 -342.709786) (xy 370.881987 -342.668568) (xy 370.852503 -342.622688)
			(xy 370.829848 -342.573079) (xy 370.814484 -342.520751) (xy 370.806722 -342.466769) (xy 344.837274 -342.466769)
			(xy 344.829512 -342.520752) (xy 344.814147 -342.573081) (xy 344.791491 -342.622691) (xy 344.762006 -342.668571)
			(xy 344.726291 -342.709788) (xy 344.685074 -342.745503) (xy 344.639194 -342.774989) (xy 344.589585 -342.797646)
			(xy 344.537256 -342.813011) (xy 344.483273 -342.820773) (xy 344.456004 -342.82126) (xy 343.592404 -342.82126)
			(xy 343.565133 -342.820801) (xy 343.511145 -342.813039) (xy 343.458812 -342.797673) (xy 343.409198 -342.775016)
			(xy 343.363313 -342.745528) (xy 343.322093 -342.70981) (xy 343.286374 -342.66859) (xy 343.256886 -342.622706)
			(xy 343.234228 -342.573092) (xy 343.218862 -342.520759) (xy 343.2111 -342.466771) (xy 341.728273 -342.466771)
			(xy 341.720513 -342.520747) (xy 341.70515 -342.573072) (xy 341.682497 -342.622679) (xy 341.653016 -342.668558)
			(xy 341.617305 -342.709774) (xy 341.576093 -342.745489) (xy 341.530218 -342.774976) (xy 341.480614 -342.797635)
			(xy 341.42829 -342.813004) (xy 341.374311 -342.820771) (xy 341.347044 -342.82126) (xy 340.483444 -342.82126)
			(xy 340.456171 -342.820804) (xy 340.402179 -342.813046) (xy 340.349841 -342.797684) (xy 340.300222 -342.775029)
			(xy 340.254332 -342.745542) (xy 340.213107 -342.709824) (xy 340.177384 -342.668603) (xy 340.147892 -342.622717)
			(xy 340.125232 -342.573101) (xy 340.109863 -342.520764) (xy 340.1021 -342.466773) (xy 338.619396 -342.466773)
			(xy 338.611634 -342.52076) (xy 338.596267 -342.573093) (xy 338.573608 -342.622707) (xy 338.544119 -342.668591)
			(xy 338.5084 -342.709812) (xy 338.467179 -342.745529) (xy 338.421293 -342.775016) (xy 338.371678 -342.797673)
			(xy 338.319344 -342.813037) (xy 338.265356 -342.820798) (xy 338.238084 -342.82126) (xy 337.374484 -342.82126)
			(xy 337.347215 -342.820776) (xy 337.293233 -342.813013) (xy 337.240905 -342.797646) (xy 337.191297 -342.774989)
			(xy 337.145418 -342.745502) (xy 337.104202 -342.709787) (xy 337.068488 -342.66857) (xy 337.039003 -342.622689)
			(xy 337.016348 -342.57308) (xy 337.000984 -342.520751) (xy 336.993222 -342.466769) (xy 335.510374 -342.466769)
			(xy 335.502613 -342.520749) (xy 335.487249 -342.573077) (xy 335.464594 -342.622685) (xy 335.435111 -342.668565)
			(xy 335.399398 -342.709781) (xy 335.358184 -342.745496) (xy 335.312306 -342.774983) (xy 335.262699 -342.79764)
			(xy 335.210373 -342.813008) (xy 335.156392 -342.820772) (xy 335.129124 -342.82126) (xy 334.265524 -342.82126)
			(xy 334.238252 -342.820802) (xy 334.184262 -342.813043) (xy 334.131926 -342.797678) (xy 334.08231 -342.775022)
			(xy 334.036423 -342.745535) (xy 333.9952 -342.709817) (xy 333.959479 -342.668596) (xy 333.929989 -342.622711)
			(xy 333.90733 -342.573096) (xy 333.891962 -342.520761) (xy 333.8842 -342.466772) (xy 332.401496 -342.466772)
			(xy 332.393733 -342.520762) (xy 332.378365 -342.573098) (xy 332.355705 -342.622713) (xy 332.326214 -342.668598)
			(xy 332.290493 -342.709819) (xy 332.249269 -342.745536) (xy 332.203381 -342.775023) (xy 332.153764 -342.797678)
			(xy 332.101427 -342.813041) (xy 332.047437 -342.820799) (xy 332.020164 -342.82126) (xy 331.156564 -342.82126)
			(xy 331.129296 -342.820775) (xy 331.075316 -342.813009) (xy 331.022991 -342.797641) (xy 330.973385 -342.774982)
			(xy 330.927508 -342.745495) (xy 330.886295 -342.70978) (xy 330.850583 -342.668563) (xy 330.8211 -342.622684)
			(xy 330.798447 -342.573076) (xy 330.783083 -342.520749) (xy 330.775322 -342.466768) (xy 329.292474 -342.466768)
			(xy 329.292474 -342.466769) (xy 329.284712 -342.520752) (xy 329.269347 -342.573081) (xy 329.246691 -342.622691)
			(xy 329.217206 -342.668571) (xy 329.181491 -342.709788) (xy 329.140274 -342.745503) (xy 329.094394 -342.774989)
			(xy 329.044785 -342.797646) (xy 328.992456 -342.813011) (xy 328.938473 -342.820773) (xy 328.911204 -342.82126)
			(xy 328.047604 -342.82126) (xy 328.020333 -342.820801) (xy 327.966345 -342.813039) (xy 327.914012 -342.797673)
			(xy 327.864398 -342.775016) (xy 327.818513 -342.745528) (xy 327.777293 -342.70981) (xy 327.741574 -342.66859)
			(xy 327.712086 -342.622706) (xy 327.689428 -342.573092) (xy 327.674062 -342.520759) (xy 327.6663 -342.466771)
			(xy 326.183473 -342.466771) (xy 326.175713 -342.520747) (xy 326.16035 -342.573072) (xy 326.137697 -342.622679)
			(xy 326.108216 -342.668558) (xy 326.072505 -342.709774) (xy 326.031293 -342.745489) (xy 325.985418 -342.774976)
			(xy 325.935814 -342.797635) (xy 325.88349 -342.813004) (xy 325.829511 -342.820771) (xy 325.802244 -342.82126)
			(xy 324.938644 -342.82126) (xy 324.911371 -342.820804) (xy 324.857379 -342.813046) (xy 324.805041 -342.797684)
			(xy 324.755422 -342.775029) (xy 324.709532 -342.745542) (xy 324.668307 -342.709824) (xy 324.632584 -342.668603)
			(xy 324.603092 -342.622717) (xy 324.580432 -342.573101) (xy 324.565063 -342.520764) (xy 324.5573 -342.466773)
			(xy 323.074596 -342.466773) (xy 323.066834 -342.52076) (xy 323.051467 -342.573093) (xy 323.028808 -342.622707)
			(xy 322.999319 -342.668591) (xy 322.9636 -342.709812) (xy 322.922379 -342.745529) (xy 322.876493 -342.775016)
			(xy 322.826878 -342.797673) (xy 322.774544 -342.813037) (xy 322.720556 -342.820798) (xy 322.693284 -342.82126)
			(xy 321.829684 -342.82126) (xy 321.802415 -342.820776) (xy 321.748433 -342.813013) (xy 321.696105 -342.797646)
			(xy 321.646497 -342.774989) (xy 321.600618 -342.745502) (xy 321.559402 -342.709787) (xy 321.523688 -342.66857)
			(xy 321.494203 -342.622689) (xy 321.471548 -342.57308) (xy 321.456184 -342.520751) (xy 321.448422 -342.466769)
			(xy 319.965574 -342.466769) (xy 319.957813 -342.520749) (xy 319.942449 -342.573077) (xy 319.919794 -342.622685)
			(xy 319.890311 -342.668565) (xy 319.854598 -342.709781) (xy 319.813384 -342.745496) (xy 319.767506 -342.774983)
			(xy 319.717899 -342.79764) (xy 319.665573 -342.813008) (xy 319.611592 -342.820772) (xy 319.584324 -342.82126)
			(xy 318.720724 -342.82126) (xy 318.693452 -342.820802) (xy 318.639462 -342.813043) (xy 318.587126 -342.797678)
			(xy 318.53751 -342.775022) (xy 318.491623 -342.745535) (xy 318.4504 -342.709817) (xy 318.414679 -342.668596)
			(xy 318.385189 -342.622711) (xy 318.36253 -342.573096) (xy 318.347162 -342.520761) (xy 318.3394 -342.466772)
			(xy 316.856696 -342.466772) (xy 316.848933 -342.520762) (xy 316.833565 -342.573098) (xy 316.810905 -342.622713)
			(xy 316.781414 -342.668598) (xy 316.745693 -342.709819) (xy 316.704469 -342.745536) (xy 316.658581 -342.775023)
			(xy 316.608964 -342.797678) (xy 316.556627 -342.813041) (xy 316.502637 -342.820799) (xy 316.475364 -342.82126)
			(xy 315.611764 -342.82126) (xy 315.584496 -342.820775) (xy 315.530516 -342.813009) (xy 315.478191 -342.797641)
			(xy 315.428585 -342.774982) (xy 315.382708 -342.745495) (xy 315.341495 -342.70978) (xy 315.305783 -342.668563)
			(xy 315.2763 -342.622684) (xy 315.253647 -342.573076) (xy 315.238283 -342.520749) (xy 315.230522 -342.466768)
			(xy 313.747674 -342.466768) (xy 313.747674 -342.466769) (xy 313.739912 -342.520752) (xy 313.724547 -342.573081)
			(xy 313.701891 -342.622691) (xy 313.672406 -342.668571) (xy 313.636691 -342.709788) (xy 313.595474 -342.745503)
			(xy 313.549594 -342.774989) (xy 313.499985 -342.797646) (xy 313.447656 -342.813011) (xy 313.393673 -342.820773)
			(xy 313.366404 -342.82126) (xy 312.502804 -342.82126) (xy 312.475533 -342.820801) (xy 312.421545 -342.813039)
			(xy 312.369212 -342.797673) (xy 312.319598 -342.775016) (xy 312.273713 -342.745528) (xy 312.232493 -342.70981)
			(xy 312.196774 -342.66859) (xy 312.167286 -342.622706) (xy 312.144628 -342.573092) (xy 312.129262 -342.520759)
			(xy 312.1215 -342.466771) (xy 300.231574 -342.466771) (xy 300.223812 -342.520752) (xy 300.208447 -342.573081)
			(xy 300.185791 -342.622691) (xy 300.156305 -342.668572) (xy 300.120591 -342.709789) (xy 300.079373 -342.745504)
			(xy 300.033493 -342.77499) (xy 299.983883 -342.797646) (xy 299.931554 -342.813012) (xy 299.877571 -342.820773)
			(xy 299.850302 -342.82126) (xy 298.986702 -342.82126) (xy 298.959431 -342.820801) (xy 298.905443 -342.813039)
			(xy 298.85311 -342.797673) (xy 298.803497 -342.775015) (xy 298.757612 -342.745527) (xy 298.716392 -342.70981)
			(xy 298.680674 -342.668589) (xy 298.651186 -342.622705) (xy 298.628528 -342.573092) (xy 298.613162 -342.520759)
			(xy 298.605399 -342.466771) (xy 297.122573 -342.466771) (xy 297.114813 -342.520747) (xy 297.09945 -342.573073)
			(xy 297.076797 -342.62268) (xy 297.047315 -342.668559) (xy 297.011605 -342.709775) (xy 296.970392 -342.74549)
			(xy 296.924517 -342.774977) (xy 296.874912 -342.797635) (xy 296.822588 -342.813004) (xy 296.768609 -342.820771)
			(xy 296.741342 -342.82126) (xy 295.877742 -342.82126) (xy 295.850469 -342.820803) (xy 295.796477 -342.813046)
			(xy 295.744139 -342.797683) (xy 295.694521 -342.775028) (xy 295.648631 -342.745541) (xy 295.607406 -342.709824)
			(xy 295.571684 -342.668602) (xy 295.542192 -342.622716) (xy 295.519531 -342.5731) (xy 295.504163 -342.520764)
			(xy 295.4964 -342.466773) (xy 294.013696 -342.466773) (xy 294.005934 -342.52076) (xy 293.990567 -342.573094)
			(xy 293.967908 -342.622708) (xy 293.938419 -342.668592) (xy 293.9027 -342.709812) (xy 293.861478 -342.74553)
			(xy 293.815592 -342.775017) (xy 293.765977 -342.797673) (xy 293.713642 -342.813038) (xy 293.659654 -342.820798)
			(xy 293.632382 -342.82126) (xy 292.768782 -342.82126) (xy 292.741513 -342.820776) (xy 292.687531 -342.813013)
			(xy 292.635204 -342.797646) (xy 292.585596 -342.774988) (xy 292.539717 -342.745502) (xy 292.498501 -342.709786)
			(xy 292.462787 -342.668569) (xy 292.433303 -342.622689) (xy 292.410648 -342.573079) (xy 292.395284 -342.520751)
			(xy 292.387522 -342.466769) (xy 290.904674 -342.466769) (xy 290.896913 -342.52075) (xy 290.881548 -342.573077)
			(xy 290.858894 -342.622686) (xy 290.82941 -342.668565) (xy 290.793698 -342.709782) (xy 290.752483 -342.745497)
			(xy 290.706605 -342.774983) (xy 290.656998 -342.797641) (xy 290.604671 -342.813008) (xy 290.55069 -342.820772)
			(xy 290.523422 -342.82126) (xy 289.659822 -342.82126) (xy 289.63255 -342.820802) (xy 289.57856 -342.813042)
			(xy 289.526225 -342.797678) (xy 289.476609 -342.775021) (xy 289.430722 -342.745534) (xy 289.389499 -342.709817)
			(xy 289.353779 -342.668596) (xy 289.324289 -342.622711) (xy 289.30163 -342.573096) (xy 289.286262 -342.520761)
			(xy 289.2785 -342.466772) (xy 287.795796 -342.466772) (xy 287.795796 -342.466773) (xy 287.788033 -342.520763)
			(xy 287.772665 -342.573098) (xy 287.750005 -342.622713) (xy 287.720514 -342.668599) (xy 287.684793 -342.70982)
			(xy 287.643568 -342.745537) (xy 287.59768 -342.775023) (xy 287.548062 -342.797679) (xy 287.495725 -342.813041)
			(xy 287.441735 -342.820799) (xy 287.414462 -342.82126) (xy 286.550862 -342.82126) (xy 286.523594 -342.820775)
			(xy 286.469614 -342.813009) (xy 286.417289 -342.79764) (xy 286.367684 -342.774982) (xy 286.321807 -342.745495)
			(xy 286.280594 -342.709779) (xy 286.244883 -342.668562) (xy 286.2154 -342.622683) (xy 286.192747 -342.573075)
			(xy 286.177383 -342.520748) (xy 286.169622 -342.466768) (xy 284.686774 -342.466768) (xy 284.686774 -342.466769)
			(xy 284.679012 -342.520752) (xy 284.663647 -342.573081) (xy 284.640991 -342.622691) (xy 284.611505 -342.668572)
			(xy 284.575791 -342.709789) (xy 284.534573 -342.745504) (xy 284.488693 -342.77499) (xy 284.439083 -342.797646)
			(xy 284.386754 -342.813012) (xy 284.332771 -342.820773) (xy 284.305502 -342.82126) (xy 283.441902 -342.82126)
			(xy 283.414631 -342.820801) (xy 283.360643 -342.813039) (xy 283.30831 -342.797673) (xy 283.258697 -342.775015)
			(xy 283.212812 -342.745527) (xy 283.171592 -342.70981) (xy 283.135874 -342.668589) (xy 283.106386 -342.622705)
			(xy 283.083728 -342.573092) (xy 283.068362 -342.520759) (xy 283.060599 -342.466771) (xy 281.577773 -342.466771)
			(xy 281.570013 -342.520747) (xy 281.55465 -342.573073) (xy 281.531997 -342.62268) (xy 281.502515 -342.668559)
			(xy 281.466805 -342.709775) (xy 281.425592 -342.74549) (xy 281.379717 -342.774977) (xy 281.330112 -342.797635)
			(xy 281.277788 -342.813004) (xy 281.223809 -342.820771) (xy 281.196542 -342.82126) (xy 280.332942 -342.82126)
			(xy 280.305669 -342.820803) (xy 280.251677 -342.813046) (xy 280.199339 -342.797683) (xy 280.149721 -342.775028)
			(xy 280.103831 -342.745541) (xy 280.062606 -342.709824) (xy 280.026884 -342.668602) (xy 279.997392 -342.622716)
			(xy 279.974731 -342.5731) (xy 279.959363 -342.520764) (xy 279.9516 -342.466773) (xy 278.468896 -342.466773)
			(xy 278.461134 -342.52076) (xy 278.445767 -342.573094) (xy 278.423108 -342.622708) (xy 278.393619 -342.668592)
			(xy 278.3579 -342.709812) (xy 278.316678 -342.74553) (xy 278.270792 -342.775017) (xy 278.221177 -342.797673)
			(xy 278.168842 -342.813038) (xy 278.114854 -342.820798) (xy 278.087582 -342.82126) (xy 277.223982 -342.82126)
			(xy 277.196713 -342.820776) (xy 277.142731 -342.813013) (xy 277.090404 -342.797646) (xy 277.040796 -342.774988)
			(xy 276.994917 -342.745502) (xy 276.953701 -342.709786) (xy 276.917987 -342.668569) (xy 276.888503 -342.622689)
			(xy 276.865848 -342.573079) (xy 276.850484 -342.520751) (xy 276.842722 -342.466769) (xy 275.359874 -342.466769)
			(xy 275.352113 -342.52075) (xy 275.336748 -342.573077) (xy 275.314094 -342.622686) (xy 275.28461 -342.668565)
			(xy 275.248898 -342.709782) (xy 275.207683 -342.745497) (xy 275.161805 -342.774983) (xy 275.112198 -342.797641)
			(xy 275.059871 -342.813008) (xy 275.00589 -342.820772) (xy 274.978622 -342.82126) (xy 274.115022 -342.82126)
			(xy 274.08775 -342.820802) (xy 274.03376 -342.813042) (xy 273.981425 -342.797678) (xy 273.931809 -342.775021)
			(xy 273.885922 -342.745534) (xy 273.844699 -342.709817) (xy 273.808979 -342.668596) (xy 273.779489 -342.622711)
			(xy 273.75683 -342.573096) (xy 273.741462 -342.520761) (xy 273.7337 -342.466772) (xy 272.250996 -342.466772)
			(xy 272.250996 -342.466773) (xy 272.243233 -342.520763) (xy 272.227865 -342.573098) (xy 272.205205 -342.622713)
			(xy 272.175714 -342.668599) (xy 272.139993 -342.70982) (xy 272.098768 -342.745537) (xy 272.05288 -342.775023)
			(xy 272.003262 -342.797679) (xy 271.950925 -342.813041) (xy 271.896935 -342.820799) (xy 271.869662 -342.82126)
			(xy 271.006062 -342.82126) (xy 270.978794 -342.820775) (xy 270.924814 -342.813009) (xy 270.872489 -342.79764)
			(xy 270.822884 -342.774982) (xy 270.777007 -342.745495) (xy 270.735794 -342.709779) (xy 270.700083 -342.668562)
			(xy 270.6706 -342.622683) (xy 270.647947 -342.573075) (xy 270.632583 -342.520748) (xy 270.624822 -342.466768)
			(xy 269.141974 -342.466768) (xy 269.141974 -342.466769) (xy 269.134212 -342.520752) (xy 269.118847 -342.573081)
			(xy 269.096191 -342.622691) (xy 269.066705 -342.668572) (xy 269.030991 -342.709789) (xy 268.989773 -342.745504)
			(xy 268.943893 -342.77499) (xy 268.894283 -342.797646) (xy 268.841954 -342.813012) (xy 268.787971 -342.820773)
			(xy 268.760702 -342.82126) (xy 267.897102 -342.82126) (xy 267.869831 -342.820801) (xy 267.815843 -342.813039)
			(xy 267.76351 -342.797673) (xy 267.713897 -342.775015) (xy 267.668012 -342.745527) (xy 267.626792 -342.70981)
			(xy 267.591074 -342.668589) (xy 267.561586 -342.622705) (xy 267.538928 -342.573092) (xy 267.523562 -342.520759)
			(xy 267.515799 -342.466771) (xy 256.581015 -342.466771) (xy 256.573351 -342.471196) (xy 256.517947 -342.494145)
			(xy 256.460022 -342.509666) (xy 256.400566 -342.517494) (xy 256.340598 -342.517494) (xy 256.281142 -342.509666)
			(xy 256.223217 -342.494145) (xy 256.167813 -342.471196) (xy 256.115879 -342.441212) (xy 256.068303 -342.404706)
			(xy 256.025898 -342.362301) (xy 255.989392 -342.314725) (xy 255.959408 -342.262791) (xy 255.936459 -342.207387)
			(xy 255.920938 -342.149462) (xy 255.91311 -342.090006) (xy 255.91262 -342.060022) (xy 197.28821 -342.060022)
			(xy 197.329534 -342.06596) (xy 197.38187 -342.081324) (xy 197.431486 -342.10398) (xy 197.477373 -342.133467)
			(xy 197.518596 -342.169184) (xy 197.554316 -342.210405) (xy 197.583807 -342.256289) (xy 197.606466 -342.305904)
			(xy 197.621834 -342.358239) (xy 197.629596 -342.412228) (xy 197.629596 -342.466772) (xy 197.621834 -342.520761)
			(xy 197.606466 -342.573096) (xy 197.583807 -342.622711) (xy 197.554316 -342.668595) (xy 197.518596 -342.709816)
			(xy 197.477373 -342.745533) (xy 197.431486 -342.77502) (xy 197.38187 -342.797676) (xy 197.329534 -342.81304)
			(xy 197.275544 -342.820798) (xy 197.248272 -342.82126) (xy 196.384672 -342.82126) (xy 196.357404 -342.820776)
			(xy 196.303423 -342.813011) (xy 196.251096 -342.797643) (xy 196.20149 -342.774985) (xy 196.155612 -342.745498)
			(xy 196.114397 -342.709783) (xy 196.078685 -342.668566) (xy 196.049202 -342.622686) (xy 196.026547 -342.573077)
			(xy 196.011183 -342.52075) (xy 196.003422 -342.466768) (xy 194.520574 -342.466768) (xy 194.520574 -342.466769)
			(xy 194.512812 -342.520751) (xy 194.497448 -342.573079) (xy 194.474792 -342.622688) (xy 194.445308 -342.668568)
			(xy 194.409594 -342.709786) (xy 194.368378 -342.745501) (xy 194.322499 -342.774987) (xy 194.272891 -342.797643)
			(xy 194.220563 -342.81301) (xy 194.166581 -342.820773) (xy 194.139312 -342.82126) (xy 193.275712 -342.82126)
			(xy 193.24844 -342.820801) (xy 193.194452 -342.813041) (xy 193.142117 -342.797675) (xy 193.092503 -342.775018)
			(xy 193.046617 -342.745531) (xy 193.005395 -342.709813) (xy 192.969676 -342.668593) (xy 192.940188 -342.622708)
			(xy 192.917529 -342.573094) (xy 192.902162 -342.52076) (xy 192.8944 -342.466772) (xy 191.411696 -342.466772)
			(xy 191.411696 -342.466773) (xy 191.403933 -342.520764) (xy 191.388564 -342.5731) (xy 191.365903 -342.622716)
			(xy 191.336412 -342.668602) (xy 191.300689 -342.709823) (xy 191.259463 -342.74554) (xy 191.213574 -342.775026)
			(xy 191.163955 -342.797681) (xy 191.111617 -342.813043) (xy 191.057625 -342.8208) (xy 191.030352 -342.82126)
			(xy 190.166752 -342.82126) (xy 190.139485 -342.820774) (xy 190.085506 -342.813007) (xy 190.033182 -342.797637)
			(xy 189.983578 -342.774978) (xy 189.937702 -342.745491) (xy 189.89649 -342.709776) (xy 189.86078 -342.668559)
			(xy 189.831299 -342.62268) (xy 189.808646 -342.573073) (xy 189.793283 -342.520747) (xy 189.785522 -342.466767)
			(xy 188.302696 -342.466767) (xy 188.302696 -342.466771) (xy 188.294934 -342.520759) (xy 188.279568 -342.573092)
			(xy 188.25691 -342.622705) (xy 188.227421 -342.668589) (xy 188.191703 -342.709809) (xy 188.150482 -342.745526)
			(xy 188.104598 -342.775013) (xy 188.054984 -342.79767) (xy 188.002651 -342.813036) (xy 187.948663 -342.820797)
			(xy 187.921392 -342.82126) (xy 187.057792 -342.82126) (xy 187.030523 -342.820777) (xy 186.97654 -342.813014)
			(xy 186.924211 -342.797648) (xy 186.874602 -342.774991) (xy 186.828721 -342.745505) (xy 186.787505 -342.70979)
			(xy 186.75179 -342.668572) (xy 186.722305 -342.622691) (xy 186.699649 -342.573082) (xy 186.684284 -342.520752)
			(xy 186.676522 -342.466769) (xy 185.193674 -342.466769) (xy 185.185913 -342.520748) (xy 185.170549 -342.573075)
			(xy 185.147895 -342.622683) (xy 185.118413 -342.668562) (xy 185.082701 -342.709778) (xy 185.041488 -342.745494)
			(xy 184.995611 -342.77498) (xy 184.946005 -342.797638) (xy 184.89368 -342.813006) (xy 184.8397 -342.820771)
			(xy 184.812432 -342.82126) (xy 183.948832 -342.82126) (xy 183.921559 -342.820803) (xy 183.867569 -342.813044)
			(xy 183.815232 -342.797681) (xy 183.765615 -342.775025) (xy 183.719727 -342.745538) (xy 183.678502 -342.70982)
			(xy 183.642781 -342.668599) (xy 183.613291 -342.622714) (xy 183.590631 -342.573098) (xy 183.575263 -342.520763)
			(xy 183.5675 -342.466773) (xy 182.084796 -342.466773) (xy 182.077034 -342.520761) (xy 182.061666 -342.573096)
			(xy 182.039007 -342.622711) (xy 182.009516 -342.668595) (xy 181.973796 -342.709816) (xy 181.932573 -342.745533)
			(xy 181.886686 -342.77502) (xy 181.83707 -342.797676) (xy 181.784734 -342.81304) (xy 181.730744 -342.820798)
			(xy 181.703472 -342.82126) (xy 180.839872 -342.82126) (xy 180.812604 -342.820776) (xy 180.758623 -342.813011)
			(xy 180.706296 -342.797643) (xy 180.65669 -342.774985) (xy 180.610812 -342.745498) (xy 180.569597 -342.709783)
			(xy 180.533885 -342.668566) (xy 180.504402 -342.622686) (xy 180.481747 -342.573077) (xy 180.466383 -342.52075)
			(xy 180.458622 -342.466768) (xy 178.975774 -342.466768) (xy 178.975774 -342.466769) (xy 178.968012 -342.520751)
			(xy 178.952648 -342.573079) (xy 178.929992 -342.622688) (xy 178.900508 -342.668568) (xy 178.864794 -342.709786)
			(xy 178.823578 -342.745501) (xy 178.777699 -342.774987) (xy 178.728091 -342.797643) (xy 178.675763 -342.81301)
			(xy 178.621781 -342.820773) (xy 178.594512 -342.82126) (xy 177.730912 -342.82126) (xy 177.70364 -342.820801)
			(xy 177.649652 -342.813041) (xy 177.597317 -342.797675) (xy 177.547703 -342.775018) (xy 177.501817 -342.745531)
			(xy 177.460595 -342.709813) (xy 177.424876 -342.668593) (xy 177.395388 -342.622708) (xy 177.372729 -342.573094)
			(xy 177.357362 -342.52076) (xy 177.3496 -342.466772) (xy 175.866896 -342.466772) (xy 175.866896 -342.466773)
			(xy 175.859133 -342.520764) (xy 175.843764 -342.5731) (xy 175.821103 -342.622716) (xy 175.791612 -342.668602)
			(xy 175.755889 -342.709823) (xy 175.714663 -342.74554) (xy 175.668774 -342.775026) (xy 175.619155 -342.797681)
			(xy 175.566817 -342.813043) (xy 175.512825 -342.8208) (xy 175.485552 -342.82126) (xy 174.621952 -342.82126)
			(xy 174.594685 -342.820774) (xy 174.540706 -342.813007) (xy 174.488382 -342.797637) (xy 174.438778 -342.774978)
			(xy 174.392902 -342.745491) (xy 174.35169 -342.709776) (xy 174.31598 -342.668559) (xy 174.286499 -342.62268)
			(xy 174.263846 -342.573073) (xy 174.248483 -342.520747) (xy 174.240722 -342.466767) (xy 172.757896 -342.466767)
			(xy 172.757896 -342.466771) (xy 172.750134 -342.520759) (xy 172.734768 -342.573092) (xy 172.71211 -342.622705)
			(xy 172.682621 -342.668589) (xy 172.646903 -342.709809) (xy 172.605682 -342.745526) (xy 172.559798 -342.775013)
			(xy 172.510184 -342.79767) (xy 172.457851 -342.813036) (xy 172.403863 -342.820797) (xy 172.376592 -342.82126)
			(xy 171.512992 -342.82126) (xy 171.485723 -342.820777) (xy 171.43174 -342.813014) (xy 171.379411 -342.797648)
			(xy 171.329802 -342.774991) (xy 171.283921 -342.745505) (xy 171.242705 -342.70979) (xy 171.20699 -342.668572)
			(xy 171.177505 -342.622691) (xy 171.154849 -342.573082) (xy 171.139484 -342.520752) (xy 171.131722 -342.466769)
			(xy 169.648874 -342.466769) (xy 169.641113 -342.520748) (xy 169.625749 -342.573075) (xy 169.603095 -342.622683)
			(xy 169.573613 -342.668562) (xy 169.537901 -342.709778) (xy 169.496688 -342.745494) (xy 169.450811 -342.77498)
			(xy 169.401205 -342.797638) (xy 169.34888 -342.813006) (xy 169.2949 -342.820771) (xy 169.267632 -342.82126)
			(xy 168.404032 -342.82126) (xy 168.376759 -342.820803) (xy 168.322769 -342.813044) (xy 168.270432 -342.797681)
			(xy 168.220815 -342.775025) (xy 168.174927 -342.745538) (xy 168.133702 -342.70982) (xy 168.097981 -342.668599)
			(xy 168.068491 -342.622714) (xy 168.045831 -342.573098) (xy 168.030463 -342.520763) (xy 168.0227 -342.466773)
			(xy 166.539996 -342.466773) (xy 166.532234 -342.520761) (xy 166.516866 -342.573096) (xy 166.494207 -342.622711)
			(xy 166.464716 -342.668595) (xy 166.428996 -342.709816) (xy 166.387773 -342.745533) (xy 166.341886 -342.77502)
			(xy 166.29227 -342.797676) (xy 166.239934 -342.81304) (xy 166.185944 -342.820798) (xy 166.158672 -342.82126)
			(xy 165.295072 -342.82126) (xy 165.267804 -342.820776) (xy 165.213823 -342.813011) (xy 165.161496 -342.797643)
			(xy 165.11189 -342.774985) (xy 165.066012 -342.745498) (xy 165.024797 -342.709783) (xy 164.989085 -342.668566)
			(xy 164.959602 -342.622686) (xy 164.936947 -342.573077) (xy 164.921583 -342.52075) (xy 164.913822 -342.466768)
			(xy 144.196574 -342.466768) (xy 144.196574 -342.466769) (xy 144.188812 -342.520751) (xy 144.173447 -342.57308)
			(xy 144.150792 -342.622689) (xy 144.121307 -342.66857) (xy 144.085593 -342.709787) (xy 144.044376 -342.745502)
			(xy 143.998497 -342.774988) (xy 143.948888 -342.797645) (xy 143.896559 -342.81301) (xy 143.842577 -342.820773)
			(xy 143.815308 -342.82126) (xy 142.951708 -342.82126) (xy 142.924436 -342.820801) (xy 142.870448 -342.81304)
			(xy 142.818115 -342.797674) (xy 142.7685 -342.775017) (xy 142.722615 -342.745529) (xy 142.681394 -342.709812)
			(xy 142.645675 -342.668591) (xy 142.616187 -342.622707) (xy 142.593529 -342.573093) (xy 142.578162 -342.520759)
			(xy 142.5704 -342.466772) (xy 141.087573 -342.466772) (xy 141.079813 -342.520746) (xy 141.064451 -342.573072)
			(xy 141.041798 -342.622678) (xy 141.012317 -342.668557) (xy 140.976607 -342.709773) (xy 140.935395 -342.745488)
			(xy 140.88952 -342.774975) (xy 140.839917 -342.797634) (xy 140.787593 -342.813003) (xy 140.733615 -342.82077)
			(xy 140.706348 -342.82126) (xy 139.842748 -342.82126) (xy 139.815475 -342.820804) (xy 139.761482 -342.813047)
			(xy 139.709144 -342.797685) (xy 139.659524 -342.77503) (xy 139.613634 -342.745544) (xy 139.572408 -342.709826)
			(xy 139.536685 -342.668604) (xy 139.507193 -342.622718) (xy 139.484532 -342.573101) (xy 139.469163 -342.520765)
			(xy 139.4614 -342.466773) (xy 137.978696 -342.466773) (xy 137.970934 -342.520759) (xy 137.955567 -342.573092)
			(xy 137.932909 -342.622706) (xy 137.90342 -342.66859) (xy 137.867702 -342.70981) (xy 137.82648 -342.745528)
			(xy 137.780596 -342.775015) (xy 137.730981 -342.797671) (xy 137.678647 -342.813037) (xy 137.624659 -342.820797)
			(xy 137.597388 -342.82126) (xy 136.733788 -342.82126) (xy 136.706519 -342.820777) (xy 136.652536 -342.813014)
			(xy 136.600208 -342.797647) (xy 136.550599 -342.77499) (xy 136.50472 -342.745504) (xy 136.463503 -342.709788)
			(xy 136.427789 -342.668571) (xy 136.398304 -342.62269) (xy 136.375649 -342.573081) (xy 136.360284 -342.520752)
			(xy 136.352522 -342.466769) (xy 134.869674 -342.466769) (xy 134.861913 -342.520749) (xy 134.846549 -342.573076)
			(xy 134.823895 -342.622684) (xy 134.794412 -342.668563) (xy 134.7587 -342.70978) (xy 134.717486 -342.745495)
			(xy 134.671609 -342.774981) (xy 134.622002 -342.797639) (xy 134.569676 -342.813007) (xy 134.515696 -342.820772)
			(xy 134.488428 -342.82126) (xy 133.624828 -342.82126) (xy 133.597556 -342.820802) (xy 133.543565 -342.813043)
			(xy 133.491229 -342.79768) (xy 133.441612 -342.775023) (xy 133.395725 -342.745536) (xy 133.354501 -342.709819)
			(xy 133.31878 -342.668598) (xy 133.28929 -342.622712) (xy 133.26663 -342.573097) (xy 133.251262 -342.520762)
			(xy 133.2435 -342.466772) (xy 131.760796 -342.466772) (xy 131.753033 -342.520762) (xy 131.737666 -342.573097)
			(xy 131.715006 -342.622712) (xy 131.685515 -342.668597) (xy 131.649795 -342.709817) (xy 131.608571 -342.745535)
			(xy 131.562684 -342.775021) (xy 131.513067 -342.797677) (xy 131.46073 -342.81304) (xy 131.40674 -342.820799)
			(xy 131.379468 -342.82126) (xy 130.515868 -342.82126) (xy 130.4886 -342.820775) (xy 130.43462 -342.81301)
			(xy 130.382294 -342.797642) (xy 130.332687 -342.774984) (xy 130.28681 -342.745497) (xy 130.245596 -342.709781)
			(xy 130.209884 -342.668564) (xy 130.180401 -342.622685) (xy 130.157747 -342.573076) (xy 130.142383 -342.520749)
			(xy 130.134622 -342.466768) (xy 128.651774 -342.466768) (xy 128.651774 -342.466769) (xy 128.644012 -342.520751)
			(xy 128.628647 -342.57308) (xy 128.605992 -342.622689) (xy 128.576507 -342.66857) (xy 128.540793 -342.709787)
			(xy 128.499576 -342.745502) (xy 128.453697 -342.774988) (xy 128.404088 -342.797645) (xy 128.351759 -342.81301)
			(xy 128.297777 -342.820773) (xy 128.270508 -342.82126) (xy 127.406908 -342.82126) (xy 127.379636 -342.820801)
			(xy 127.325648 -342.81304) (xy 127.273315 -342.797674) (xy 127.2237 -342.775017) (xy 127.177815 -342.745529)
			(xy 127.136594 -342.709812) (xy 127.100875 -342.668591) (xy 127.071387 -342.622707) (xy 127.048729 -342.573093)
			(xy 127.033362 -342.520759) (xy 127.0256 -342.466772) (xy 125.542773 -342.466772) (xy 125.535013 -342.520746)
			(xy 125.519651 -342.573072) (xy 125.496998 -342.622678) (xy 125.467517 -342.668557) (xy 125.431807 -342.709773)
			(xy 125.390595 -342.745488) (xy 125.34472 -342.774975) (xy 125.295117 -342.797634) (xy 125.242793 -342.813003)
			(xy 125.188815 -342.82077) (xy 125.161548 -342.82126) (xy 124.297948 -342.82126) (xy 124.270675 -342.820804)
			(xy 124.216682 -342.813047) (xy 124.164344 -342.797685) (xy 124.114724 -342.77503) (xy 124.068834 -342.745544)
			(xy 124.027608 -342.709826) (xy 123.991885 -342.668604) (xy 123.962393 -342.622718) (xy 123.939732 -342.573101)
			(xy 123.924363 -342.520765) (xy 123.9166 -342.466773) (xy 122.433896 -342.466773) (xy 122.426134 -342.520759)
			(xy 122.410767 -342.573092) (xy 122.388109 -342.622706) (xy 122.35862 -342.66859) (xy 122.322902 -342.70981)
			(xy 122.28168 -342.745528) (xy 122.235796 -342.775015) (xy 122.186181 -342.797671) (xy 122.133847 -342.813037)
			(xy 122.079859 -342.820797) (xy 122.052588 -342.82126) (xy 121.188988 -342.82126) (xy 121.161719 -342.820777)
			(xy 121.107736 -342.813014) (xy 121.055408 -342.797647) (xy 121.005799 -342.77499) (xy 120.95992 -342.745504)
			(xy 120.918703 -342.709788) (xy 120.882989 -342.668571) (xy 120.853504 -342.62269) (xy 120.830849 -342.573081)
			(xy 120.815484 -342.520752) (xy 120.807722 -342.466769) (xy 119.324874 -342.466769) (xy 119.317113 -342.520749)
			(xy 119.301749 -342.573076) (xy 119.279095 -342.622684) (xy 119.249612 -342.668563) (xy 119.2139 -342.70978)
			(xy 119.172686 -342.745495) (xy 119.126809 -342.774981) (xy 119.077202 -342.797639) (xy 119.024876 -342.813007)
			(xy 118.970896 -342.820772) (xy 118.943628 -342.82126) (xy 118.080028 -342.82126) (xy 118.052756 -342.820802)
			(xy 117.998765 -342.813043) (xy 117.946429 -342.79768) (xy 117.896812 -342.775023) (xy 117.850925 -342.745536)
			(xy 117.809701 -342.709819) (xy 117.77398 -342.668598) (xy 117.74449 -342.622712) (xy 117.72183 -342.573097)
			(xy 117.706462 -342.520762) (xy 117.6987 -342.466772) (xy 116.215996 -342.466772) (xy 116.208233 -342.520762)
			(xy 116.192866 -342.573097) (xy 116.170206 -342.622712) (xy 116.140715 -342.668597) (xy 116.104995 -342.709817)
			(xy 116.063771 -342.745535) (xy 116.017884 -342.775021) (xy 115.968267 -342.797677) (xy 115.91593 -342.81304)
			(xy 115.86194 -342.820799) (xy 115.834668 -342.82126) (xy 114.971068 -342.82126) (xy 114.9438 -342.820775)
			(xy 114.88982 -342.81301) (xy 114.837494 -342.797642) (xy 114.787887 -342.774984) (xy 114.74201 -342.745497)
			(xy 114.700796 -342.709781) (xy 114.665084 -342.668564) (xy 114.635601 -342.622685) (xy 114.612947 -342.573076)
			(xy 114.597583 -342.520749) (xy 114.589822 -342.466768) (xy 113.106974 -342.466768) (xy 113.106974 -342.466769)
			(xy 113.099212 -342.520751) (xy 113.083847 -342.57308) (xy 113.061192 -342.622689) (xy 113.031707 -342.66857)
			(xy 112.995993 -342.709787) (xy 112.954776 -342.745502) (xy 112.908897 -342.774988) (xy 112.859288 -342.797645)
			(xy 112.806959 -342.81301) (xy 112.752977 -342.820773) (xy 112.725708 -342.82126) (xy 111.862108 -342.82126)
			(xy 111.834836 -342.820801) (xy 111.780848 -342.81304) (xy 111.728515 -342.797674) (xy 111.6789 -342.775017)
			(xy 111.633015 -342.745529) (xy 111.591794 -342.709812) (xy 111.556075 -342.668591) (xy 111.526587 -342.622707)
			(xy 111.503929 -342.573093) (xy 111.488562 -342.520759) (xy 111.4808 -342.466772) (xy 104.085479 -342.466772)
			(xy 104.10629 -342.517011) (xy 104.121803 -342.574906) (xy 104.129627 -342.634331) (xy 104.129627 -342.694269)
			(xy 104.121803 -342.753694) (xy 104.10629 -342.811589) (xy 104.083352 -342.866964) (xy 104.053383 -342.918871)
			(xy 104.016895 -342.966422) (xy 103.974512 -343.008804) (xy 103.926959 -343.045291) (xy 103.875051 -343.075259)
			(xy 103.819676 -343.098195) (xy 103.76178 -343.113706) (xy 103.702355 -343.121528) (xy 103.672386 -343.121996)
			(xy 102.808786 -343.121996) (xy 102.778818 -343.121529) (xy 102.719395 -343.113704) (xy 102.661502 -343.09819)
			(xy 102.60613 -343.075253) (xy 102.554224 -343.045284) (xy 102.506675 -343.008796) (xy 102.464294 -342.966415)
			(xy 102.427809 -342.918864) (xy 102.397841 -342.866958) (xy 102.374905 -342.811584) (xy 102.359393 -342.753691)
			(xy 102.35157 -342.694268) (xy 93.60914 -342.694268) (xy 93.595705 -342.709775) (xy 93.554492 -342.74549)
			(xy 93.508617 -342.774977) (xy 93.459012 -342.797635) (xy 93.406688 -342.813004) (xy 93.352709 -342.820771)
			(xy 93.325442 -342.82126) (xy 92.461842 -342.82126) (xy 92.434569 -342.820803) (xy 92.380577 -342.813046)
			(xy 92.328239 -342.797683) (xy 92.278621 -342.775028) (xy 92.232731 -342.745541) (xy 92.191506 -342.709824)
			(xy 92.155784 -342.668602) (xy 92.126292 -342.622716) (xy 92.103631 -342.5731) (xy 92.088263 -342.520764)
			(xy 92.0805 -342.466773) (xy 90.597796 -342.466773) (xy 90.590034 -342.52076) (xy 90.574667 -342.573094)
			(xy 90.552008 -342.622708) (xy 90.522519 -342.668592) (xy 90.4868 -342.709812) (xy 90.445578 -342.74553)
			(xy 90.399692 -342.775017) (xy 90.350077 -342.797673) (xy 90.297742 -342.813038) (xy 90.243754 -342.820798)
			(xy 90.216482 -342.82126) (xy 89.352882 -342.82126) (xy 89.325613 -342.820776) (xy 89.271631 -342.813013)
			(xy 89.219304 -342.797646) (xy 89.169696 -342.774988) (xy 89.123817 -342.745502) (xy 89.082601 -342.709786)
			(xy 89.046887 -342.668569) (xy 89.017403 -342.622689) (xy 88.994748 -342.573079) (xy 88.979384 -342.520751)
			(xy 88.971622 -342.466769) (xy 87.488774 -342.466769) (xy 87.481013 -342.52075) (xy 87.465648 -342.573077)
			(xy 87.442994 -342.622686) (xy 87.41351 -342.668565) (xy 87.377798 -342.709782) (xy 87.336583 -342.745497)
			(xy 87.290705 -342.774983) (xy 87.241098 -342.797641) (xy 87.188771 -342.813008) (xy 87.13479 -342.820772)
			(xy 87.107522 -342.82126) (xy 86.243922 -342.82126) (xy 86.21665 -342.820802) (xy 86.16266 -342.813042)
			(xy 86.110325 -342.797678) (xy 86.060709 -342.775021) (xy 86.014822 -342.745534) (xy 85.973599 -342.709817)
			(xy 85.937879 -342.668596) (xy 85.908389 -342.622711) (xy 85.88573 -342.573096) (xy 85.870362 -342.520761)
			(xy 85.8626 -342.466772) (xy 84.379896 -342.466772) (xy 84.379896 -342.466773) (xy 84.372133 -342.520763)
			(xy 84.356765 -342.573098) (xy 84.334105 -342.622713) (xy 84.304614 -342.668599) (xy 84.268893 -342.70982)
			(xy 84.227668 -342.745537) (xy 84.18178 -342.775023) (xy 84.132162 -342.797679) (xy 84.079825 -342.813041)
			(xy 84.025835 -342.820799) (xy 83.998562 -342.82126) (xy 83.134962 -342.82126) (xy 83.107694 -342.820775)
			(xy 83.053714 -342.813009) (xy 83.001389 -342.79764) (xy 82.951784 -342.774982) (xy 82.905907 -342.745495)
			(xy 82.864694 -342.709779) (xy 82.828983 -342.668562) (xy 82.7995 -342.622683) (xy 82.776847 -342.573075)
			(xy 82.761483 -342.520748) (xy 82.753722 -342.466768) (xy 81.270874 -342.466768) (xy 81.270874 -342.466769)
			(xy 81.263112 -342.520752) (xy 81.247747 -342.573081) (xy 81.225091 -342.622691) (xy 81.195605 -342.668572)
			(xy 81.159891 -342.709789) (xy 81.118673 -342.745504) (xy 81.072793 -342.77499) (xy 81.023183 -342.797646)
			(xy 80.970854 -342.813012) (xy 80.916871 -342.820773) (xy 80.889602 -342.82126) (xy 80.026002 -342.82126)
			(xy 79.998731 -342.820801) (xy 79.944743 -342.813039) (xy 79.89241 -342.797673) (xy 79.842797 -342.775015)
			(xy 79.796912 -342.745527) (xy 79.755692 -342.70981) (xy 79.719974 -342.668589) (xy 79.690486 -342.622705)
			(xy 79.667828 -342.573092) (xy 79.652462 -342.520759) (xy 79.644699 -342.466771) (xy 78.161873 -342.466771)
			(xy 78.154113 -342.520747) (xy 78.13875 -342.573073) (xy 78.116097 -342.62268) (xy 78.086615 -342.668559)
			(xy 78.050905 -342.709775) (xy 78.009692 -342.74549) (xy 77.963817 -342.774977) (xy 77.914212 -342.797635)
			(xy 77.861888 -342.813004) (xy 77.807909 -342.820771) (xy 77.780642 -342.82126) (xy 76.917042 -342.82126)
			(xy 76.889769 -342.820803) (xy 76.835777 -342.813046) (xy 76.783439 -342.797683) (xy 76.733821 -342.775028)
			(xy 76.687931 -342.745541) (xy 76.646706 -342.709824) (xy 76.610984 -342.668602) (xy 76.581492 -342.622716)
			(xy 76.558831 -342.5731) (xy 76.543463 -342.520764) (xy 76.5357 -342.466773) (xy 75.052996 -342.466773)
			(xy 75.045234 -342.52076) (xy 75.029867 -342.573094) (xy 75.007208 -342.622708) (xy 74.977719 -342.668592)
			(xy 74.942 -342.709812) (xy 74.900778 -342.74553) (xy 74.854892 -342.775017) (xy 74.805277 -342.797673)
			(xy 74.752942 -342.813038) (xy 74.698954 -342.820798) (xy 74.671682 -342.82126) (xy 73.808082 -342.82126)
			(xy 73.780813 -342.820776) (xy 73.726831 -342.813013) (xy 73.674504 -342.797646) (xy 73.624896 -342.774988)
			(xy 73.579017 -342.745502) (xy 73.537801 -342.709786) (xy 73.502087 -342.668569) (xy 73.472603 -342.622689)
			(xy 73.449948 -342.573079) (xy 73.434584 -342.520751) (xy 73.426822 -342.466769) (xy 71.943974 -342.466769)
			(xy 71.936213 -342.52075) (xy 71.920848 -342.573077) (xy 71.898194 -342.622686) (xy 71.86871 -342.668565)
			(xy 71.832998 -342.709782) (xy 71.791783 -342.745497) (xy 71.745905 -342.774983) (xy 71.696298 -342.797641)
			(xy 71.643971 -342.813008) (xy 71.58999 -342.820772) (xy 71.562722 -342.82126) (xy 70.699122 -342.82126)
			(xy 70.67185 -342.820802) (xy 70.61786 -342.813042) (xy 70.565525 -342.797678) (xy 70.515909 -342.775021)
			(xy 70.470022 -342.745534) (xy 70.428799 -342.709817) (xy 70.393079 -342.668596) (xy 70.363589 -342.622711)
			(xy 70.34093 -342.573096) (xy 70.325562 -342.520761) (xy 70.3178 -342.466772) (xy 68.835096 -342.466772)
			(xy 68.835096 -342.466773) (xy 68.827333 -342.520763) (xy 68.811965 -342.573098) (xy 68.789305 -342.622713)
			(xy 68.759814 -342.668599) (xy 68.724093 -342.70982) (xy 68.682868 -342.745537) (xy 68.63698 -342.775023)
			(xy 68.587362 -342.797679) (xy 68.535025 -342.813041) (xy 68.481035 -342.820799) (xy 68.453762 -342.82126)
			(xy 67.590162 -342.82126) (xy 67.562894 -342.820775) (xy 67.508914 -342.813009) (xy 67.456589 -342.79764)
			(xy 67.406984 -342.774982) (xy 67.361107 -342.745495) (xy 67.319894 -342.709779) (xy 67.284183 -342.668562)
			(xy 67.2547 -342.622683) (xy 67.232047 -342.573075) (xy 67.216683 -342.520748) (xy 67.208922 -342.466768)
			(xy 65.726074 -342.466768) (xy 65.726074 -342.466769) (xy 65.718312 -342.520752) (xy 65.702947 -342.573081)
			(xy 65.680291 -342.622691) (xy 65.650805 -342.668572) (xy 65.615091 -342.709789) (xy 65.573873 -342.745504)
			(xy 65.527993 -342.77499) (xy 65.478383 -342.797646) (xy 65.426054 -342.813012) (xy 65.372071 -342.820773)
			(xy 65.344802 -342.82126) (xy 64.481202 -342.82126) (xy 64.453931 -342.820801) (xy 64.399943 -342.813039)
			(xy 64.34761 -342.797673) (xy 64.297997 -342.775015) (xy 64.252112 -342.745527) (xy 64.210892 -342.70981)
			(xy 64.175174 -342.668589) (xy 64.145686 -342.622705) (xy 64.123028 -342.573092) (xy 64.107662 -342.520759)
			(xy 64.099899 -342.466771) (xy 62.617073 -342.466771) (xy 62.609313 -342.520747) (xy 62.59395 -342.573073)
			(xy 62.571297 -342.62268) (xy 62.541815 -342.668559) (xy 62.506105 -342.709775) (xy 62.464892 -342.74549)
			(xy 62.419017 -342.774977) (xy 62.369412 -342.797635) (xy 62.317088 -342.813004) (xy 62.263109 -342.820771)
			(xy 62.235842 -342.82126) (xy 61.372242 -342.82126) (xy 61.344969 -342.820803) (xy 61.290977 -342.813046)
			(xy 61.238639 -342.797683) (xy 61.189021 -342.775028) (xy 61.143131 -342.745541) (xy 61.101906 -342.709824)
			(xy 61.066184 -342.668602) (xy 61.036692 -342.622716) (xy 61.014031 -342.5731) (xy 60.998663 -342.520764)
			(xy 60.9909 -342.466773) (xy 51.666873 -342.466773) (xy 51.659113 -342.520746) (xy 51.643751 -342.573072)
			(xy 51.621098 -342.622678) (xy 51.591617 -342.668557) (xy 51.555907 -342.709773) (xy 51.514695 -342.745488)
			(xy 51.46882 -342.774975) (xy 51.419217 -342.797634) (xy 51.366893 -342.813003) (xy 51.312915 -342.82077)
			(xy 51.285648 -342.82126) (xy 50.422048 -342.82126) (xy 50.394775 -342.820804) (xy 50.340782 -342.813047)
			(xy 50.288444 -342.797685) (xy 50.238824 -342.77503) (xy 50.192934 -342.745544) (xy 50.151708 -342.709826)
			(xy 50.115985 -342.668604) (xy 50.086493 -342.622718) (xy 50.063832 -342.573101) (xy 50.048463 -342.520765)
			(xy 50.0407 -342.466773) (xy 48.557996 -342.466773) (xy 48.550234 -342.520759) (xy 48.534867 -342.573092)
			(xy 48.512209 -342.622706) (xy 48.48272 -342.66859) (xy 48.447002 -342.70981) (xy 48.40578 -342.745528)
			(xy 48.359896 -342.775015) (xy 48.310281 -342.797671) (xy 48.257947 -342.813037) (xy 48.203959 -342.820797)
			(xy 48.176688 -342.82126) (xy 47.313088 -342.82126) (xy 47.285819 -342.820777) (xy 47.231836 -342.813014)
			(xy 47.179508 -342.797647) (xy 47.129899 -342.77499) (xy 47.08402 -342.745504) (xy 47.042803 -342.709788)
			(xy 47.007089 -342.668571) (xy 46.977604 -342.62269) (xy 46.954949 -342.573081) (xy 46.939584 -342.520752)
			(xy 46.931822 -342.466769) (xy 45.448974 -342.466769) (xy 45.441213 -342.520749) (xy 45.425849 -342.573076)
			(xy 45.403195 -342.622684) (xy 45.373712 -342.668563) (xy 45.338 -342.70978) (xy 45.296786 -342.745495)
			(xy 45.250909 -342.774981) (xy 45.201302 -342.797639) (xy 45.148976 -342.813007) (xy 45.094996 -342.820772)
			(xy 45.067728 -342.82126) (xy 44.204128 -342.82126) (xy 44.176856 -342.820802) (xy 44.122865 -342.813043)
			(xy 44.070529 -342.79768) (xy 44.020912 -342.775023) (xy 43.975025 -342.745536) (xy 43.933801 -342.709819)
			(xy 43.89808 -342.668598) (xy 43.86859 -342.622712) (xy 43.84593 -342.573097) (xy 43.830562 -342.520762)
			(xy 43.8228 -342.466772) (xy 42.340096 -342.466772) (xy 42.332333 -342.520762) (xy 42.316966 -342.573097)
			(xy 42.294306 -342.622712) (xy 42.264815 -342.668597) (xy 42.229095 -342.709817) (xy 42.187871 -342.745535)
			(xy 42.141984 -342.775021) (xy 42.092367 -342.797677) (xy 42.04003 -342.81304) (xy 41.98604 -342.820799)
			(xy 41.958768 -342.82126) (xy 41.095168 -342.82126) (xy 41.0679 -342.820775) (xy 41.01392 -342.81301)
			(xy 40.961594 -342.797642) (xy 40.911987 -342.774984) (xy 40.86611 -342.745497) (xy 40.824896 -342.709781)
			(xy 40.789184 -342.668564) (xy 40.759701 -342.622685) (xy 40.737047 -342.573076) (xy 40.721683 -342.520749)
			(xy 40.713922 -342.466768) (xy 39.231074 -342.466768) (xy 39.231074 -342.466769) (xy 39.223312 -342.520751)
			(xy 39.207947 -342.57308) (xy 39.185292 -342.622689) (xy 39.155807 -342.66857) (xy 39.120093 -342.709787)
			(xy 39.078876 -342.745502) (xy 39.032997 -342.774988) (xy 38.983388 -342.797645) (xy 38.931059 -342.81301)
			(xy 38.877077 -342.820773) (xy 38.849808 -342.82126) (xy 37.986208 -342.82126) (xy 37.958936 -342.820801)
			(xy 37.904948 -342.81304) (xy 37.852615 -342.797674) (xy 37.803 -342.775017) (xy 37.757115 -342.745529)
			(xy 37.715894 -342.709812) (xy 37.680175 -342.668591) (xy 37.650687 -342.622707) (xy 37.628029 -342.573093)
			(xy 37.612662 -342.520759) (xy 37.6049 -342.466772) (xy 36.122073 -342.466772) (xy 36.114313 -342.520746)
			(xy 36.098951 -342.573072) (xy 36.076298 -342.622678) (xy 36.046817 -342.668557) (xy 36.011107 -342.709773)
			(xy 35.969895 -342.745488) (xy 35.92402 -342.774975) (xy 35.874417 -342.797634) (xy 35.822093 -342.813003)
			(xy 35.768115 -342.82077) (xy 35.740848 -342.82126) (xy 34.877248 -342.82126) (xy 34.849975 -342.820804)
			(xy 34.795982 -342.813047) (xy 34.743644 -342.797685) (xy 34.694024 -342.77503) (xy 34.648134 -342.745544)
			(xy 34.606908 -342.709826) (xy 34.571185 -342.668604) (xy 34.541693 -342.622718) (xy 34.519032 -342.573101)
			(xy 34.503663 -342.520765) (xy 34.4959 -342.466773) (xy 33.013196 -342.466773) (xy 33.005434 -342.520759)
			(xy 32.990067 -342.573092) (xy 32.967409 -342.622706) (xy 32.93792 -342.66859) (xy 32.902202 -342.70981)
			(xy 32.86098 -342.745528) (xy 32.815096 -342.775015) (xy 32.765481 -342.797671) (xy 32.713147 -342.813037)
			(xy 32.659159 -342.820797) (xy 32.631888 -342.82126) (xy 31.768288 -342.82126) (xy 31.741019 -342.820777)
			(xy 31.687036 -342.813014) (xy 31.634708 -342.797647) (xy 31.585099 -342.77499) (xy 31.53922 -342.745504)
			(xy 31.498003 -342.709788) (xy 31.462289 -342.668571) (xy 31.432804 -342.62269) (xy 31.410149 -342.573081)
			(xy 31.394784 -342.520752) (xy 31.387022 -342.466769) (xy 29.904174 -342.466769) (xy 29.896413 -342.520749)
			(xy 29.881049 -342.573076) (xy 29.858395 -342.622684) (xy 29.828912 -342.668563) (xy 29.7932 -342.70978)
			(xy 29.751986 -342.745495) (xy 29.706109 -342.774981) (xy 29.656502 -342.797639) (xy 29.604176 -342.813007)
			(xy 29.550196 -342.820772) (xy 29.522928 -342.82126) (xy 28.659328 -342.82126) (xy 28.632056 -342.820802)
			(xy 28.578065 -342.813043) (xy 28.525729 -342.79768) (xy 28.476112 -342.775023) (xy 28.430225 -342.745536)
			(xy 28.389001 -342.709819) (xy 28.35328 -342.668598) (xy 28.32379 -342.622712) (xy 28.30113 -342.573097)
			(xy 28.285762 -342.520762) (xy 28.278 -342.466772) (xy 26.795296 -342.466772) (xy 26.787533 -342.520762)
			(xy 26.772166 -342.573097) (xy 26.749506 -342.622712) (xy 26.720015 -342.668597) (xy 26.684295 -342.709817)
			(xy 26.643071 -342.745535) (xy 26.597184 -342.775021) (xy 26.547567 -342.797677) (xy 26.49523 -342.81304)
			(xy 26.44124 -342.820799) (xy 26.413968 -342.82126) (xy 25.550368 -342.82126) (xy 25.5231 -342.820775)
			(xy 25.46912 -342.81301) (xy 25.416794 -342.797642) (xy 25.367187 -342.774984) (xy 25.32131 -342.745497)
			(xy 25.280096 -342.709781) (xy 25.244384 -342.668564) (xy 25.214901 -342.622685) (xy 25.192247 -342.573076)
			(xy 25.176883 -342.520749) (xy 25.169122 -342.466768) (xy 23.686274 -342.466768) (xy 23.686274 -342.466769)
			(xy 23.678512 -342.520751) (xy 23.663147 -342.57308) (xy 23.640492 -342.622689) (xy 23.611007 -342.66857)
			(xy 23.575293 -342.709787) (xy 23.534076 -342.745502) (xy 23.488197 -342.774988) (xy 23.438588 -342.797645)
			(xy 23.386259 -342.81301) (xy 23.332277 -342.820773) (xy 23.305008 -342.82126) (xy 22.441408 -342.82126)
			(xy 22.414136 -342.820801) (xy 22.360148 -342.81304) (xy 22.307815 -342.797674) (xy 22.2582 -342.775017)
			(xy 22.212315 -342.745529) (xy 22.171094 -342.709812) (xy 22.135375 -342.668591) (xy 22.105887 -342.622707)
			(xy 22.083229 -342.573093) (xy 22.067862 -342.520759) (xy 22.0601 -342.466772) (xy 20.577347 -342.466772)
			(xy 20.569584 -342.520758) (xy 20.554218 -342.57309) (xy 20.53156 -342.622703) (xy 20.502073 -342.668587)
			(xy 20.466355 -342.709807) (xy 20.425135 -342.745524) (xy 20.379252 -342.775011) (xy 20.329638 -342.797669)
			(xy 20.277306 -342.813035) (xy 20.223319 -342.820797) (xy 20.196048 -342.82126) (xy 19.332448 -342.82126)
			(xy 19.305179 -342.820777) (xy 19.251195 -342.813015) (xy 19.198865 -342.79765) (xy 19.149255 -342.774993)
			(xy 19.103374 -342.745507) (xy 19.062157 -342.709792) (xy 19.026441 -342.668574) (xy 18.996956 -342.622693)
			(xy 18.974299 -342.573083) (xy 18.958934 -342.520753) (xy 18.951172 -342.466769) (xy 0.508 -342.466769)
			(xy 0.508 -345.49242) (xy 18.95117 -345.49242) (xy 18.95117 -345.43788) (xy 18.958932 -345.383896)
			(xy 18.974298 -345.331567) (xy 18.996954 -345.281956) (xy 19.02644 -345.236075) (xy 19.062155 -345.194857)
			(xy 19.103373 -345.159141) (xy 19.149254 -345.129655) (xy 19.198865 -345.106998) (xy 19.251194 -345.091633)
			(xy 19.305178 -345.083871) (xy 19.332448 -345.083384) (xy 20.196048 -345.083384) (xy 20.223319 -345.083855)
			(xy 20.277305 -345.091617) (xy 20.329638 -345.106983) (xy 20.379251 -345.12964) (xy 20.425134 -345.159128)
			(xy 20.466354 -345.194845) (xy 20.502071 -345.236064) (xy 20.531559 -345.281948) (xy 20.554216 -345.33156)
			(xy 20.569582 -345.383893) (xy 20.577345 -345.437879) (xy 20.577345 -345.49242) (xy 22.06013 -345.49242)
			(xy 22.06013 -345.43788) (xy 22.067892 -345.383896) (xy 22.083258 -345.331567) (xy 22.105914 -345.281956)
			(xy 22.1354 -345.236075) (xy 22.171115 -345.194857) (xy 22.212333 -345.159141) (xy 22.258214 -345.129655)
			(xy 22.307825 -345.106998) (xy 22.360154 -345.091633) (xy 22.414138 -345.083871) (xy 22.441408 -345.083384)
			(xy 23.305008 -345.083384) (xy 23.332279 -345.083855) (xy 23.386265 -345.091617) (xy 23.438598 -345.106983)
			(xy 23.488211 -345.12964) (xy 23.534094 -345.159128) (xy 23.575314 -345.194845) (xy 23.611031 -345.236064)
			(xy 23.640519 -345.281948) (xy 23.663176 -345.33156) (xy 23.678542 -345.383893) (xy 23.686305 -345.437879)
			(xy 23.686305 -345.492365) (xy 25.16917 -345.492365) (xy 25.16917 -345.437835) (xy 25.17693 -345.383861)
			(xy 25.192292 -345.33154) (xy 25.214943 -345.281938) (xy 25.244422 -345.236064) (xy 25.28013 -345.194853)
			(xy 25.321339 -345.159142) (xy 25.36721 -345.129658) (xy 25.41681 -345.107003) (xy 25.46913 -345.091637)
			(xy 25.523103 -345.083872) (xy 25.550368 -345.083384) (xy 26.413968 -345.083384) (xy 26.441244 -345.083753)
			(xy 26.495241 -345.091513) (xy 26.547583 -345.106878) (xy 26.597207 -345.129537) (xy 26.6431 -345.159027)
			(xy 26.684329 -345.194749) (xy 26.720054 -345.235975) (xy 26.749548 -345.281865) (xy 26.772211 -345.331487)
			(xy 26.78758 -345.383828) (xy 26.795344 -345.437824) (xy 26.795344 -345.492369) (xy 28.278047 -345.492369)
			(xy 28.278047 -345.437831) (xy 28.285809 -345.383848) (xy 28.301175 -345.33152) (xy 28.323832 -345.281911)
			(xy 28.353319 -345.236031) (xy 28.389035 -345.194815) (xy 28.430253 -345.159102) (xy 28.476135 -345.129619)
			(xy 28.525746 -345.106965) (xy 28.578076 -345.091603) (xy 28.632059 -345.083845) (xy 28.659328 -345.083384)
			(xy 29.522928 -345.083384) (xy 29.550199 -345.08378) (xy 29.604186 -345.091546) (xy 29.656519 -345.106916)
			(xy 29.706132 -345.129576) (xy 29.752014 -345.159067) (xy 29.793234 -345.194786) (xy 29.82895 -345.236008)
			(xy 29.858437 -345.281893) (xy 29.881094 -345.331507) (xy 29.89646 -345.383841) (xy 29.904222 -345.437829)
			(xy 29.904222 -345.492366) (xy 31.38707 -345.492366) (xy 31.38707 -345.437834) (xy 31.394831 -345.383858)
			(xy 31.410194 -345.331536) (xy 31.432846 -345.281933) (xy 31.462327 -345.236058) (xy 31.498037 -345.194846)
			(xy 31.539248 -345.159135) (xy 31.585122 -345.129652) (xy 31.634725 -345.106998) (xy 31.687047 -345.091633)
			(xy 31.741022 -345.083871) (xy 31.768288 -345.083384) (xy 32.631888 -345.083384) (xy 32.659163 -345.083755)
			(xy 32.713157 -345.091516) (xy 32.765498 -345.106884) (xy 32.815119 -345.129543) (xy 32.861009 -345.159034)
			(xy 32.902236 -345.194756) (xy 32.937959 -345.235981) (xy 32.967451 -345.281871) (xy 32.990112 -345.331491)
			(xy 33.005481 -345.383831) (xy 33.013244 -345.437825) (xy 33.013244 -345.49237) (xy 34.495948 -345.49237)
			(xy 34.495948 -345.43783) (xy 34.50371 -345.383846) (xy 34.519077 -345.331515) (xy 34.541735 -345.281905)
			(xy 34.571224 -345.236024) (xy 34.606942 -345.194808) (xy 34.648163 -345.159095) (xy 34.694047 -345.129612)
			(xy 34.74366 -345.10696) (xy 34.795992 -345.0916) (xy 34.849978 -345.083844) (xy 34.877248 -345.083384)
			(xy 35.740848 -345.083384) (xy 35.768118 -345.083782) (xy 35.822103 -345.09155) (xy 35.874433 -345.106921)
			(xy 35.924044 -345.129583) (xy 35.969924 -345.159074) (xy 36.011141 -345.194793) (xy 36.046855 -345.236015)
			(xy 36.07634 -345.281899) (xy 36.098995 -345.331512) (xy 36.11436 -345.383844) (xy 36.122122 -345.43783)
			(xy 36.122122 -345.492368) (xy 37.604947 -345.492368) (xy 37.604947 -345.437832) (xy 37.612709 -345.383851)
			(xy 37.628074 -345.331524) (xy 37.650729 -345.281916) (xy 37.680214 -345.236038) (xy 37.715928 -345.194822)
			(xy 37.757144 -345.159109) (xy 37.803023 -345.129625) (xy 37.852631 -345.106971) (xy 37.904959 -345.091607)
			(xy 37.95894 -345.083847) (xy 37.986208 -345.083384) (xy 38.849808 -345.083384) (xy 38.87708 -345.083779)
			(xy 38.93107 -345.091543) (xy 38.983404 -345.106911) (xy 39.03302 -345.12957) (xy 39.078905 -345.15906)
			(xy 39.120127 -345.194779) (xy 39.155845 -345.236001) (xy 39.185334 -345.281888) (xy 39.207992 -345.331503)
			(xy 39.223359 -345.383838) (xy 39.231121 -345.437828) (xy 39.231121 -345.492365) (xy 40.71397 -345.492365)
			(xy 40.71397 -345.437835) (xy 40.72173 -345.383861) (xy 40.737092 -345.33154) (xy 40.759743 -345.281938)
			(xy 40.789222 -345.236064) (xy 40.82493 -345.194853) (xy 40.866139 -345.159142) (xy 40.91201 -345.129658)
			(xy 40.96161 -345.107003) (xy 41.01393 -345.091637) (xy 41.067903 -345.083872) (xy 41.095168 -345.083384)
			(xy 41.958768 -345.083384) (xy 41.986044 -345.083753) (xy 42.040041 -345.091513) (xy 42.092383 -345.106878)
			(xy 42.142007 -345.129537) (xy 42.1879 -345.159027) (xy 42.229129 -345.194749) (xy 42.264854 -345.235975)
			(xy 42.294348 -345.281865) (xy 42.317011 -345.331487) (xy 42.33238 -345.383828) (xy 42.340144 -345.437824)
			(xy 42.340144 -345.492369) (xy 43.822847 -345.492369) (xy 43.822847 -345.437831) (xy 43.830609 -345.383848)
			(xy 43.845975 -345.33152) (xy 43.868632 -345.281911) (xy 43.898119 -345.236031) (xy 43.933835 -345.194815)
			(xy 43.975053 -345.159102) (xy 44.020935 -345.129619) (xy 44.070546 -345.106965) (xy 44.122876 -345.091603)
			(xy 44.176859 -345.083845) (xy 44.204128 -345.083384) (xy 45.067728 -345.083384) (xy 45.094999 -345.08378)
			(xy 45.148986 -345.091546) (xy 45.201319 -345.106916) (xy 45.250932 -345.129576) (xy 45.296814 -345.159067)
			(xy 45.338034 -345.194786) (xy 45.37375 -345.236008) (xy 45.403237 -345.281893) (xy 45.425894 -345.331507)
			(xy 45.44126 -345.383841) (xy 45.449022 -345.437829) (xy 45.449022 -345.492366) (xy 46.93187 -345.492366)
			(xy 46.93187 -345.437834) (xy 46.939631 -345.383858) (xy 46.954994 -345.331536) (xy 46.977646 -345.281933)
			(xy 47.007127 -345.236058) (xy 47.042837 -345.194846) (xy 47.084048 -345.159135) (xy 47.129922 -345.129652)
			(xy 47.179525 -345.106998) (xy 47.231847 -345.091633) (xy 47.285822 -345.083871) (xy 47.313088 -345.083384)
			(xy 48.176688 -345.083384) (xy 48.203963 -345.083755) (xy 48.257957 -345.091516) (xy 48.310298 -345.106884)
			(xy 48.359919 -345.129543) (xy 48.405809 -345.159034) (xy 48.447036 -345.194756) (xy 48.482759 -345.235981)
			(xy 48.512251 -345.281871) (xy 48.534912 -345.331491) (xy 48.550281 -345.383831) (xy 48.558044 -345.437825)
			(xy 48.558044 -345.49237) (xy 50.040748 -345.49237) (xy 50.040748 -345.43783) (xy 50.04851 -345.383846)
			(xy 50.063877 -345.331515) (xy 50.086535 -345.281905) (xy 50.116024 -345.236024) (xy 50.151742 -345.194808)
			(xy 50.192963 -345.159095) (xy 50.238847 -345.129612) (xy 50.28846 -345.10696) (xy 50.340792 -345.0916)
			(xy 50.394778 -345.083844) (xy 50.422048 -345.083384) (xy 51.285648 -345.083384) (xy 51.312918 -345.083782)
			(xy 51.366903 -345.09155) (xy 51.419233 -345.106921) (xy 51.468844 -345.129583) (xy 51.514724 -345.159074)
			(xy 51.555941 -345.194793) (xy 51.591655 -345.236015) (xy 51.62114 -345.281899) (xy 51.643795 -345.331512)
			(xy 51.65916 -345.383844) (xy 51.666922 -345.43783) (xy 51.666922 -345.49237) (xy 60.990948 -345.49237)
			(xy 60.990948 -345.43783) (xy 60.99871 -345.383846) (xy 61.014076 -345.331517) (xy 61.036734 -345.281907)
			(xy 61.066222 -345.236026) (xy 61.10194 -345.19481) (xy 61.14316 -345.159097) (xy 61.189044 -345.129614)
			(xy 61.238656 -345.106962) (xy 61.290987 -345.091601) (xy 61.344972 -345.083845) (xy 61.372242 -345.083384)
			(xy 62.235842 -345.083384) (xy 62.263113 -345.083781) (xy 62.317098 -345.091549) (xy 62.369429 -345.10692)
			(xy 62.41904 -345.129581) (xy 62.464921 -345.159072) (xy 62.506139 -345.194791) (xy 62.541854 -345.236013)
			(xy 62.571339 -345.281897) (xy 62.593995 -345.33151) (xy 62.60936 -345.383843) (xy 62.617122 -345.437829)
			(xy 62.617122 -345.492368) (xy 64.099947 -345.492368) (xy 64.099947 -345.437832) (xy 64.107709 -345.383852)
			(xy 64.123073 -345.331525) (xy 64.145728 -345.281918) (xy 64.175212 -345.23604) (xy 64.210926 -345.194824)
			(xy 64.252141 -345.159111) (xy 64.29802 -345.129627) (xy 64.347627 -345.106972) (xy 64.399954 -345.091608)
			(xy 64.453934 -345.083847) (xy 64.481202 -345.083384) (xy 65.344802 -345.083384) (xy 65.372075 -345.083779)
			(xy 65.426064 -345.091542) (xy 65.4784 -345.106909) (xy 65.528016 -345.129568) (xy 65.573902 -345.159057)
			(xy 65.615124 -345.194777) (xy 65.650844 -345.236) (xy 65.680333 -345.281886) (xy 65.702992 -345.331502)
			(xy 65.718359 -345.383838) (xy 65.726121 -345.437827) (xy 65.726121 -345.492364) (xy 67.20897 -345.492364)
			(xy 67.20897 -345.437836) (xy 67.21673 -345.383862) (xy 67.232092 -345.331542) (xy 67.254742 -345.28194)
			(xy 67.284221 -345.236066) (xy 67.319928 -345.194855) (xy 67.361136 -345.159144) (xy 67.407007 -345.12966)
			(xy 67.456606 -345.107005) (xy 67.508925 -345.091638) (xy 67.562898 -345.083873) (xy 67.590162 -345.083384)
			(xy 68.453762 -345.083384) (xy 68.481038 -345.083753) (xy 68.535036 -345.091512) (xy 68.587379 -345.106877)
			(xy 68.637003 -345.129535) (xy 68.682897 -345.159025) (xy 68.724127 -345.194747) (xy 68.759852 -345.235973)
			(xy 68.789347 -345.281864) (xy 68.81201 -345.331485) (xy 68.82738 -345.383827) (xy 68.835144 -345.437824)
			(xy 68.835144 -345.492369) (xy 70.317847 -345.492369) (xy 70.317847 -345.437831) (xy 70.325609 -345.383849)
			(xy 70.340975 -345.331521) (xy 70.363631 -345.281912) (xy 70.393117 -345.236033) (xy 70.428833 -345.194817)
			(xy 70.470051 -345.159104) (xy 70.515932 -345.129621) (xy 70.565541 -345.106967) (xy 70.617871 -345.091605)
			(xy 70.671853 -345.083846) (xy 70.699122 -345.083384) (xy 71.562722 -345.083384) (xy 71.589994 -345.08378)
			(xy 71.643981 -345.091545) (xy 71.696315 -345.106914) (xy 71.745928 -345.129574) (xy 71.791812 -345.159064)
			(xy 71.833032 -345.194784) (xy 71.868749 -345.236006) (xy 71.898236 -345.281891) (xy 71.920893 -345.331506)
			(xy 71.936259 -345.38384) (xy 71.944022 -345.437828) (xy 71.944022 -345.492365) (xy 73.42687 -345.492365)
			(xy 73.42687 -345.437835) (xy 73.434631 -345.383859) (xy 73.449993 -345.331537) (xy 73.472645 -345.281934)
			(xy 73.502126 -345.23606) (xy 73.537835 -345.194848) (xy 73.579045 -345.159137) (xy 73.624919 -345.129654)
			(xy 73.674521 -345.106999) (xy 73.726842 -345.091634) (xy 73.780817 -345.083872) (xy 73.808082 -345.083384)
			(xy 74.671682 -345.083384) (xy 74.698957 -345.083754) (xy 74.752952 -345.091515) (xy 74.805294 -345.106882)
			(xy 74.854915 -345.129541) (xy 74.900806 -345.159032) (xy 74.942034 -345.194754) (xy 74.977757 -345.235979)
			(xy 75.00725 -345.281869) (xy 75.029912 -345.33149) (xy 75.045281 -345.38383) (xy 75.053044 -345.437825)
			(xy 75.053044 -345.49237) (xy 76.535748 -345.49237) (xy 76.535748 -345.43783) (xy 76.54351 -345.383846)
			(xy 76.558876 -345.331517) (xy 76.581534 -345.281907) (xy 76.611022 -345.236026) (xy 76.64674 -345.19481)
			(xy 76.68796 -345.159097) (xy 76.733844 -345.129614) (xy 76.783456 -345.106962) (xy 76.835787 -345.091601)
			(xy 76.889772 -345.083845) (xy 76.917042 -345.083384) (xy 77.780642 -345.083384) (xy 77.807913 -345.083781)
			(xy 77.861898 -345.091549) (xy 77.914229 -345.10692) (xy 77.96384 -345.129581) (xy 78.009721 -345.159072)
			(xy 78.050939 -345.194791) (xy 78.086654 -345.236013) (xy 78.116139 -345.281897) (xy 78.138795 -345.33151)
			(xy 78.15416 -345.383843) (xy 78.161922 -345.437829) (xy 78.161922 -345.492368) (xy 79.644747 -345.492368)
			(xy 79.644747 -345.437832) (xy 79.652509 -345.383852) (xy 79.667873 -345.331525) (xy 79.690528 -345.281918)
			(xy 79.720012 -345.23604) (xy 79.755726 -345.194824) (xy 79.796941 -345.159111) (xy 79.84282 -345.129627)
			(xy 79.892427 -345.106972) (xy 79.944754 -345.091608) (xy 79.998734 -345.083847) (xy 80.026002 -345.083384)
			(xy 80.889602 -345.083384) (xy 80.916875 -345.083779) (xy 80.970864 -345.091542) (xy 81.0232 -345.106909)
			(xy 81.072816 -345.129568) (xy 81.118702 -345.159057) (xy 81.159924 -345.194777) (xy 81.195644 -345.236)
			(xy 81.225133 -345.281886) (xy 81.247792 -345.331502) (xy 81.263159 -345.383838) (xy 81.270921 -345.437827)
			(xy 81.270921 -345.492364) (xy 82.75377 -345.492364) (xy 82.75377 -345.437836) (xy 82.76153 -345.383862)
			(xy 82.776892 -345.331542) (xy 82.799542 -345.28194) (xy 82.829021 -345.236066) (xy 82.864728 -345.194855)
			(xy 82.905936 -345.159144) (xy 82.951807 -345.12966) (xy 83.001406 -345.107005) (xy 83.053725 -345.091638)
			(xy 83.107698 -345.083873) (xy 83.134962 -345.083384) (xy 83.998562 -345.083384) (xy 84.025838 -345.083753)
			(xy 84.079836 -345.091512) (xy 84.132179 -345.106877) (xy 84.181803 -345.129535) (xy 84.227697 -345.159025)
			(xy 84.268927 -345.194747) (xy 84.304652 -345.235973) (xy 84.334147 -345.281864) (xy 84.35681 -345.331485)
			(xy 84.37218 -345.383827) (xy 84.379944 -345.437824) (xy 84.379944 -345.492369) (xy 85.862647 -345.492369)
			(xy 85.862647 -345.437831) (xy 85.870409 -345.383849) (xy 85.885775 -345.331521) (xy 85.908431 -345.281912)
			(xy 85.937917 -345.236033) (xy 85.973633 -345.194817) (xy 86.014851 -345.159104) (xy 86.060732 -345.129621)
			(xy 86.110341 -345.106967) (xy 86.162671 -345.091605) (xy 86.216653 -345.083846) (xy 86.243922 -345.083384)
			(xy 87.107522 -345.083384) (xy 87.134794 -345.08378) (xy 87.188781 -345.091545) (xy 87.241115 -345.106914)
			(xy 87.290728 -345.129574) (xy 87.336612 -345.159064) (xy 87.377832 -345.194784) (xy 87.413549 -345.236006)
			(xy 87.443036 -345.281891) (xy 87.465693 -345.331506) (xy 87.481059 -345.38384) (xy 87.488822 -345.437828)
			(xy 87.488822 -345.492365) (xy 88.97167 -345.492365) (xy 88.97167 -345.437835) (xy 88.979431 -345.383859)
			(xy 88.994793 -345.331537) (xy 89.017445 -345.281934) (xy 89.046926 -345.23606) (xy 89.082635 -345.194848)
			(xy 89.123845 -345.159137) (xy 89.169719 -345.129654) (xy 89.219321 -345.106999) (xy 89.271642 -345.091634)
			(xy 89.325617 -345.083872) (xy 89.352882 -345.083384) (xy 90.216482 -345.083384) (xy 90.243757 -345.083754)
			(xy 90.297752 -345.091515) (xy 90.350094 -345.106882) (xy 90.399715 -345.129541) (xy 90.445606 -345.159032)
			(xy 90.486834 -345.194754) (xy 90.522557 -345.235979) (xy 90.55205 -345.281869) (xy 90.574712 -345.33149)
			(xy 90.590081 -345.38383) (xy 90.597844 -345.437825) (xy 90.597844 -345.49237) (xy 92.080548 -345.49237)
			(xy 92.080548 -345.43783) (xy 92.08831 -345.383846) (xy 92.103676 -345.331517) (xy 92.126334 -345.281907)
			(xy 92.155822 -345.236026) (xy 92.19154 -345.19481) (xy 92.23276 -345.159097) (xy 92.278644 -345.129614)
			(xy 92.328256 -345.106962) (xy 92.380587 -345.091601) (xy 92.434572 -345.083845) (xy 92.461842 -345.083384)
			(xy 93.325442 -345.083384) (xy 93.352713 -345.083781) (xy 93.406698 -345.091549) (xy 93.459029 -345.10692)
			(xy 93.50864 -345.129581) (xy 93.554521 -345.159072) (xy 93.595739 -345.194791) (xy 93.631454 -345.236013)
			(xy 93.660939 -345.281897) (xy 93.683595 -345.33151) (xy 93.69896 -345.383843) (xy 93.706722 -345.437829)
			(xy 93.706722 -345.492368) (xy 111.480847 -345.492368) (xy 111.480847 -345.437832) (xy 111.488609 -345.383851)
			(xy 111.503974 -345.331524) (xy 111.526629 -345.281916) (xy 111.556114 -345.236038) (xy 111.591828 -345.194822)
			(xy 111.633044 -345.159109) (xy 111.678923 -345.129625) (xy 111.728531 -345.106971) (xy 111.780859 -345.091607)
			(xy 111.83484 -345.083847) (xy 111.862108 -345.083384) (xy 112.725708 -345.083384) (xy 112.75298 -345.083779)
			(xy 112.80697 -345.091543) (xy 112.859304 -345.106911) (xy 112.90892 -345.12957) (xy 112.954805 -345.15906)
			(xy 112.996027 -345.194779) (xy 113.031745 -345.236001) (xy 113.061234 -345.281888) (xy 113.083892 -345.331503)
			(xy 113.099259 -345.383838) (xy 113.107021 -345.437828) (xy 113.107021 -345.492365) (xy 114.58987 -345.492365)
			(xy 114.58987 -345.437835) (xy 114.59763 -345.383861) (xy 114.612992 -345.33154) (xy 114.635643 -345.281938)
			(xy 114.665122 -345.236064) (xy 114.70083 -345.194853) (xy 114.742039 -345.159142) (xy 114.78791 -345.129658)
			(xy 114.83751 -345.107003) (xy 114.88983 -345.091637) (xy 114.943803 -345.083872) (xy 114.971068 -345.083384)
			(xy 115.834668 -345.083384) (xy 115.861944 -345.083753) (xy 115.915941 -345.091513) (xy 115.968283 -345.106878)
			(xy 116.017907 -345.129537) (xy 116.0638 -345.159027) (xy 116.105029 -345.194749) (xy 116.140754 -345.235975)
			(xy 116.170248 -345.281865) (xy 116.192911 -345.331487) (xy 116.20828 -345.383828) (xy 116.216044 -345.437824)
			(xy 116.216044 -345.492369) (xy 117.698747 -345.492369) (xy 117.698747 -345.437831) (xy 117.706509 -345.383848)
			(xy 117.721875 -345.33152) (xy 117.744532 -345.281911) (xy 117.774019 -345.236031) (xy 117.809735 -345.194815)
			(xy 117.850953 -345.159102) (xy 117.896835 -345.129619) (xy 117.946446 -345.106965) (xy 117.998776 -345.091603)
			(xy 118.052759 -345.083845) (xy 118.080028 -345.083384) (xy 118.943628 -345.083384) (xy 118.970899 -345.08378)
			(xy 119.024886 -345.091546) (xy 119.077219 -345.106916) (xy 119.126832 -345.129576) (xy 119.172714 -345.159067)
			(xy 119.213934 -345.194786) (xy 119.24965 -345.236008) (xy 119.279137 -345.281893) (xy 119.301794 -345.331507)
			(xy 119.31716 -345.383841) (xy 119.324922 -345.437829) (xy 119.324922 -345.492366) (xy 120.80777 -345.492366)
			(xy 120.80777 -345.437834) (xy 120.815531 -345.383858) (xy 120.830894 -345.331536) (xy 120.853546 -345.281933)
			(xy 120.883027 -345.236058) (xy 120.918737 -345.194846) (xy 120.959948 -345.159135) (xy 121.005822 -345.129652)
			(xy 121.055425 -345.106998) (xy 121.107747 -345.091633) (xy 121.161722 -345.083871) (xy 121.188988 -345.083384)
			(xy 122.052588 -345.083384) (xy 122.079863 -345.083755) (xy 122.133857 -345.091516) (xy 122.186198 -345.106884)
			(xy 122.235819 -345.129543) (xy 122.281709 -345.159034) (xy 122.322936 -345.194756) (xy 122.358659 -345.235981)
			(xy 122.388151 -345.281871) (xy 122.410812 -345.331491) (xy 122.426181 -345.383831) (xy 122.433944 -345.437825)
			(xy 122.433944 -345.49237) (xy 123.916648 -345.49237) (xy 123.916648 -345.43783) (xy 123.92441 -345.383846)
			(xy 123.939777 -345.331515) (xy 123.962435 -345.281905) (xy 123.991924 -345.236024) (xy 124.027642 -345.194808)
			(xy 124.068863 -345.159095) (xy 124.114747 -345.129612) (xy 124.16436 -345.10696) (xy 124.216692 -345.0916)
			(xy 124.270678 -345.083844) (xy 124.297948 -345.083384) (xy 125.161548 -345.083384) (xy 125.188818 -345.083782)
			(xy 125.242803 -345.09155) (xy 125.295133 -345.106921) (xy 125.344744 -345.129583) (xy 125.390624 -345.159074)
			(xy 125.431841 -345.194793) (xy 125.467555 -345.236015) (xy 125.49704 -345.281899) (xy 125.519695 -345.331512)
			(xy 125.53506 -345.383844) (xy 125.542822 -345.43783) (xy 125.542822 -345.492368) (xy 127.025647 -345.492368)
			(xy 127.025647 -345.437832) (xy 127.033409 -345.383851) (xy 127.048774 -345.331524) (xy 127.071429 -345.281916)
			(xy 127.100914 -345.236038) (xy 127.136628 -345.194822) (xy 127.177844 -345.159109) (xy 127.223723 -345.129625)
			(xy 127.273331 -345.106971) (xy 127.325659 -345.091607) (xy 127.37964 -345.083847) (xy 127.406908 -345.083384)
			(xy 128.270508 -345.083384) (xy 128.29778 -345.083779) (xy 128.35177 -345.091543) (xy 128.404104 -345.106911)
			(xy 128.45372 -345.12957) (xy 128.499605 -345.15906) (xy 128.540827 -345.194779) (xy 128.576545 -345.236001)
			(xy 128.606034 -345.281888) (xy 128.628692 -345.331503) (xy 128.644059 -345.383838) (xy 128.651821 -345.437828)
			(xy 128.651821 -345.492365) (xy 130.13467 -345.492365) (xy 130.13467 -345.437835) (xy 130.14243 -345.383861)
			(xy 130.157792 -345.33154) (xy 130.180443 -345.281938) (xy 130.209922 -345.236064) (xy 130.24563 -345.194853)
			(xy 130.286839 -345.159142) (xy 130.33271 -345.129658) (xy 130.38231 -345.107003) (xy 130.43463 -345.091637)
			(xy 130.488603 -345.083872) (xy 130.515868 -345.083384) (xy 131.379468 -345.083384) (xy 131.406744 -345.083753)
			(xy 131.460741 -345.091513) (xy 131.513083 -345.106878) (xy 131.562707 -345.129537) (xy 131.6086 -345.159027)
			(xy 131.649829 -345.194749) (xy 131.685554 -345.235975) (xy 131.715048 -345.281865) (xy 131.737711 -345.331487)
			(xy 131.75308 -345.383828) (xy 131.760844 -345.437824) (xy 131.760844 -345.492369) (xy 133.243547 -345.492369)
			(xy 133.243547 -345.437831) (xy 133.251309 -345.383848) (xy 133.266675 -345.33152) (xy 133.289332 -345.281911)
			(xy 133.318819 -345.236031) (xy 133.354535 -345.194815) (xy 133.395753 -345.159102) (xy 133.441635 -345.129619)
			(xy 133.491246 -345.106965) (xy 133.543576 -345.091603) (xy 133.597559 -345.083845) (xy 133.624828 -345.083384)
			(xy 134.488428 -345.083384) (xy 134.515699 -345.08378) (xy 134.569686 -345.091546) (xy 134.622019 -345.106916)
			(xy 134.671632 -345.129576) (xy 134.717514 -345.159067) (xy 134.758734 -345.194786) (xy 134.79445 -345.236008)
			(xy 134.823937 -345.281893) (xy 134.846594 -345.331507) (xy 134.86196 -345.383841) (xy 134.869722 -345.437829)
			(xy 134.869722 -345.492366) (xy 136.35257 -345.492366) (xy 136.35257 -345.437834) (xy 136.360331 -345.383858)
			(xy 136.375694 -345.331536) (xy 136.398346 -345.281933) (xy 136.427827 -345.236058) (xy 136.463537 -345.194846)
			(xy 136.504748 -345.159135) (xy 136.550622 -345.129652) (xy 136.600225 -345.106998) (xy 136.652547 -345.091633)
			(xy 136.706522 -345.083871) (xy 136.733788 -345.083384) (xy 137.597388 -345.083384) (xy 137.624663 -345.083755)
			(xy 137.678657 -345.091516) (xy 137.730998 -345.106884) (xy 137.780619 -345.129543) (xy 137.826509 -345.159034)
			(xy 137.867736 -345.194756) (xy 137.903459 -345.235981) (xy 137.932951 -345.281871) (xy 137.955612 -345.331491)
			(xy 137.970981 -345.383831) (xy 137.978744 -345.437825) (xy 137.978744 -345.49237) (xy 139.461448 -345.49237)
			(xy 139.461448 -345.43783) (xy 139.46921 -345.383846) (xy 139.484577 -345.331515) (xy 139.507235 -345.281905)
			(xy 139.536724 -345.236024) (xy 139.572442 -345.194808) (xy 139.613663 -345.159095) (xy 139.659547 -345.129612)
			(xy 139.70916 -345.10696) (xy 139.761492 -345.0916) (xy 139.815478 -345.083844) (xy 139.842748 -345.083384)
			(xy 140.706348 -345.083384) (xy 140.733618 -345.083782) (xy 140.787603 -345.09155) (xy 140.839933 -345.106921)
			(xy 140.889544 -345.129583) (xy 140.935424 -345.159074) (xy 140.976641 -345.194793) (xy 141.012355 -345.236015)
			(xy 141.04184 -345.281899) (xy 141.064495 -345.331512) (xy 141.07986 -345.383844) (xy 141.087622 -345.43783)
			(xy 141.087622 -345.492368) (xy 142.570447 -345.492368) (xy 142.570447 -345.437832) (xy 142.578209 -345.383851)
			(xy 142.593574 -345.331524) (xy 142.616229 -345.281916) (xy 142.645714 -345.236038) (xy 142.681428 -345.194822)
			(xy 142.722644 -345.159109) (xy 142.768523 -345.129625) (xy 142.818131 -345.106971) (xy 142.870459 -345.091607)
			(xy 142.92444 -345.083847) (xy 142.951708 -345.083384) (xy 143.815308 -345.083384) (xy 143.84258 -345.083779)
			(xy 143.89657 -345.091543) (xy 143.948904 -345.106911) (xy 143.99852 -345.12957) (xy 144.044405 -345.15906)
			(xy 144.085627 -345.194779) (xy 144.121345 -345.236001) (xy 144.150834 -345.281888) (xy 144.173492 -345.331503)
			(xy 144.188859 -345.383838) (xy 144.196621 -345.437828) (xy 144.196621 -345.492365) (xy 164.91387 -345.492365)
			(xy 164.91387 -345.437835) (xy 164.92163 -345.383861) (xy 164.936992 -345.33154) (xy 164.959644 -345.281937)
			(xy 164.989123 -345.236063) (xy 165.024831 -345.194851) (xy 165.066041 -345.15914) (xy 165.111913 -345.129657)
			(xy 165.161513 -345.107002) (xy 165.213833 -345.091636) (xy 165.267807 -345.083872) (xy 165.295072 -345.083384)
			(xy 166.158672 -345.083384) (xy 166.185948 -345.083754) (xy 166.239944 -345.091514) (xy 166.292286 -345.106879)
			(xy 166.341909 -345.129538) (xy 166.387802 -345.159028) (xy 166.42903 -345.19475) (xy 166.464755 -345.235976)
			(xy 166.494249 -345.281866) (xy 166.516911 -345.331487) (xy 166.532281 -345.383829) (xy 166.540044 -345.437824)
			(xy 166.540044 -345.492369) (xy 168.022747 -345.492369) (xy 168.022747 -345.437831) (xy 168.03051 -345.383848)
			(xy 168.045876 -345.331519) (xy 168.068533 -345.281909) (xy 168.09802 -345.23603) (xy 168.133736 -345.194814)
			(xy 168.174955 -345.159101) (xy 168.220838 -345.129617) (xy 168.270449 -345.106964) (xy 168.322779 -345.091603)
			(xy 168.376763 -345.083845) (xy 168.404032 -345.083384) (xy 169.267632 -345.083384) (xy 169.294903 -345.083781)
			(xy 169.34889 -345.091547) (xy 169.401222 -345.106917) (xy 169.450834 -345.129578) (xy 169.496716 -345.159068)
			(xy 169.537935 -345.194788) (xy 169.573651 -345.236009) (xy 169.603138 -345.281894) (xy 169.625794 -345.331508)
			(xy 169.64116 -345.383842) (xy 169.648922 -345.437829) (xy 169.648922 -345.492366) (xy 171.13177 -345.492366)
			(xy 171.13177 -345.437834) (xy 171.139531 -345.383858) (xy 171.154894 -345.331535) (xy 171.177547 -345.281932)
			(xy 171.207028 -345.236057) (xy 171.242738 -345.194844) (xy 171.28395 -345.159133) (xy 171.329825 -345.129651)
			(xy 171.379428 -345.106997) (xy 171.43175 -345.091633) (xy 171.485726 -345.083871) (xy 171.512992 -345.083384)
			(xy 172.376592 -345.083384) (xy 172.403867 -345.083755) (xy 172.457861 -345.091517) (xy 172.510201 -345.106885)
			(xy 172.559821 -345.129544) (xy 172.605711 -345.159035) (xy 172.646937 -345.194757) (xy 172.68266 -345.235982)
			(xy 172.712152 -345.281872) (xy 172.734813 -345.331492) (xy 172.750181 -345.383831) (xy 172.757944 -345.437825)
			(xy 172.757944 -345.492364) (xy 174.24077 -345.492364) (xy 174.24077 -345.437836) (xy 174.24853 -345.383863)
			(xy 174.263891 -345.331544) (xy 174.286541 -345.281943) (xy 174.316019 -345.23607) (xy 174.351724 -345.194858)
			(xy 174.392931 -345.159147) (xy 174.438801 -345.129664) (xy 174.488399 -345.107008) (xy 174.540716 -345.09164)
			(xy 174.594688 -345.083874) (xy 174.621952 -345.083384) (xy 175.485552 -345.083384) (xy 175.512829 -345.083752)
			(xy 175.566827 -345.09151) (xy 175.619172 -345.106874) (xy 175.668797 -345.129531) (xy 175.714692 -345.159021)
			(xy 175.755923 -345.194743) (xy 175.79165 -345.235969) (xy 175.821146 -345.281861) (xy 175.843809 -345.331483)
			(xy 175.85918 -345.383826) (xy 175.866944 -345.437824) (xy 175.866944 -345.492368) (xy 177.349647 -345.492368)
			(xy 177.349647 -345.437832) (xy 177.357409 -345.38385) (xy 177.372774 -345.331523) (xy 177.39543 -345.281915)
			(xy 177.424915 -345.236036) (xy 177.460629 -345.194821) (xy 177.501846 -345.159108) (xy 177.547726 -345.129624)
			(xy 177.597334 -345.10697) (xy 177.649662 -345.091606) (xy 177.703644 -345.083847) (xy 177.730912 -345.083384)
			(xy 178.594512 -345.083384) (xy 178.621784 -345.083779) (xy 178.675773 -345.091543) (xy 178.728107 -345.106912)
			(xy 178.777722 -345.129571) (xy 178.823607 -345.159061) (xy 178.864828 -345.194781) (xy 178.900546 -345.236003)
			(xy 178.930035 -345.281889) (xy 178.952693 -345.331504) (xy 178.968059 -345.383839) (xy 178.975821 -345.437828)
			(xy 178.975821 -345.492365) (xy 180.45867 -345.492365) (xy 180.45867 -345.437835) (xy 180.46643 -345.383861)
			(xy 180.481792 -345.33154) (xy 180.504444 -345.281937) (xy 180.533923 -345.236063) (xy 180.569631 -345.194851)
			(xy 180.610841 -345.15914) (xy 180.656713 -345.129657) (xy 180.706313 -345.107002) (xy 180.758633 -345.091636)
			(xy 180.812607 -345.083872) (xy 180.839872 -345.083384) (xy 181.703472 -345.083384) (xy 181.730748 -345.083754)
			(xy 181.784744 -345.091514) (xy 181.837086 -345.106879) (xy 181.886709 -345.129538) (xy 181.932602 -345.159028)
			(xy 181.97383 -345.19475) (xy 182.009555 -345.235976) (xy 182.039049 -345.281866) (xy 182.061711 -345.331487)
			(xy 182.077081 -345.383829) (xy 182.084844 -345.437824) (xy 182.084844 -345.492369) (xy 183.567547 -345.492369)
			(xy 183.567547 -345.437831) (xy 183.57531 -345.383848) (xy 183.590676 -345.331519) (xy 183.613333 -345.281909)
			(xy 183.64282 -345.23603) (xy 183.678536 -345.194814) (xy 183.719755 -345.159101) (xy 183.765638 -345.129617)
			(xy 183.815249 -345.106964) (xy 183.867579 -345.091603) (xy 183.921563 -345.083845) (xy 183.948832 -345.083384)
			(xy 184.812432 -345.083384) (xy 184.839703 -345.083781) (xy 184.89369 -345.091547) (xy 184.946022 -345.106917)
			(xy 184.995634 -345.129578) (xy 185.041516 -345.159068) (xy 185.082735 -345.194788) (xy 185.118451 -345.236009)
			(xy 185.147938 -345.281894) (xy 185.170594 -345.331508) (xy 185.18596 -345.383842) (xy 185.193722 -345.437829)
			(xy 185.193722 -345.492366) (xy 186.67657 -345.492366) (xy 186.67657 -345.437834) (xy 186.684331 -345.383858)
			(xy 186.699694 -345.331535) (xy 186.722347 -345.281932) (xy 186.751828 -345.236057) (xy 186.787538 -345.194844)
			(xy 186.82875 -345.159133) (xy 186.874625 -345.129651) (xy 186.924228 -345.106997) (xy 186.97655 -345.091633)
			(xy 187.030526 -345.083871) (xy 187.057792 -345.083384) (xy 187.921392 -345.083384) (xy 187.948667 -345.083755)
			(xy 188.002661 -345.091517) (xy 188.055001 -345.106885) (xy 188.104621 -345.129544) (xy 188.150511 -345.159035)
			(xy 188.191737 -345.194757) (xy 188.22746 -345.235982) (xy 188.256952 -345.281872) (xy 188.279613 -345.331492)
			(xy 188.294981 -345.383831) (xy 188.302744 -345.437825) (xy 188.302744 -345.492364) (xy 189.78557 -345.492364)
			(xy 189.78557 -345.437836) (xy 189.79333 -345.383863) (xy 189.808691 -345.331544) (xy 189.831341 -345.281943)
			(xy 189.860819 -345.23607) (xy 189.896524 -345.194858) (xy 189.937731 -345.159147) (xy 189.983601 -345.129664)
			(xy 190.033199 -345.107008) (xy 190.085516 -345.09164) (xy 190.139488 -345.083874) (xy 190.166752 -345.083384)
			(xy 191.030352 -345.083384) (xy 191.057629 -345.083752) (xy 191.111627 -345.09151) (xy 191.163972 -345.106874)
			(xy 191.213597 -345.129531) (xy 191.259492 -345.159021) (xy 191.300723 -345.194743) (xy 191.33645 -345.235969)
			(xy 191.365946 -345.281861) (xy 191.388609 -345.331483) (xy 191.40398 -345.383826) (xy 191.411744 -345.437824)
			(xy 191.411744 -345.492368) (xy 192.894447 -345.492368) (xy 192.894447 -345.437832) (xy 192.902209 -345.38385)
			(xy 192.917574 -345.331523) (xy 192.94023 -345.281915) (xy 192.969715 -345.236036) (xy 193.005429 -345.194821)
			(xy 193.046646 -345.159108) (xy 193.092526 -345.129624) (xy 193.142134 -345.10697) (xy 193.194462 -345.091606)
			(xy 193.248444 -345.083847) (xy 193.275712 -345.083384) (xy 194.139312 -345.083384) (xy 194.166584 -345.083779)
			(xy 194.220573 -345.091543) (xy 194.272907 -345.106912) (xy 194.322522 -345.129571) (xy 194.368407 -345.159061)
			(xy 194.409628 -345.194781) (xy 194.445346 -345.236003) (xy 194.474835 -345.281889) (xy 194.497493 -345.331504)
			(xy 194.512859 -345.383839) (xy 194.520621 -345.437828) (xy 194.520621 -345.492365) (xy 196.00347 -345.492365)
			(xy 196.00347 -345.437835) (xy 196.01123 -345.383861) (xy 196.026592 -345.33154) (xy 196.049244 -345.281937)
			(xy 196.078723 -345.236063) (xy 196.114431 -345.194851) (xy 196.155641 -345.15914) (xy 196.201513 -345.129657)
			(xy 196.251113 -345.107002) (xy 196.303433 -345.091636) (xy 196.357407 -345.083872) (xy 196.384672 -345.083384)
			(xy 197.248272 -345.083384) (xy 197.275548 -345.083754) (xy 197.329544 -345.091514) (xy 197.381886 -345.106879)
			(xy 197.431509 -345.129538) (xy 197.477402 -345.159028) (xy 197.51863 -345.19475) (xy 197.554355 -345.235976)
			(xy 197.583849 -345.281866) (xy 197.606511 -345.331487) (xy 197.621881 -345.383829) (xy 197.629644 -345.437824)
			(xy 197.629644 -345.492368) (xy 267.515847 -345.492368) (xy 267.515847 -345.437832) (xy 267.523609 -345.383852)
			(xy 267.538973 -345.331525) (xy 267.561628 -345.281918) (xy 267.591112 -345.23604) (xy 267.626826 -345.194824)
			(xy 267.668041 -345.159111) (xy 267.71392 -345.129627) (xy 267.763527 -345.106972) (xy 267.815854 -345.091608)
			(xy 267.869834 -345.083847) (xy 267.897102 -345.083384) (xy 268.760702 -345.083384) (xy 268.787975 -345.083779)
			(xy 268.841964 -345.091542) (xy 268.8943 -345.106909) (xy 268.943916 -345.129568) (xy 268.989802 -345.159057)
			(xy 269.031024 -345.194777) (xy 269.066744 -345.236) (xy 269.096233 -345.281886) (xy 269.118892 -345.331502)
			(xy 269.134259 -345.383838) (xy 269.142021 -345.437827) (xy 269.142021 -345.492364) (xy 270.62487 -345.492364)
			(xy 270.62487 -345.437836) (xy 270.63263 -345.383862) (xy 270.647992 -345.331542) (xy 270.670642 -345.28194)
			(xy 270.700121 -345.236066) (xy 270.735828 -345.194855) (xy 270.777036 -345.159144) (xy 270.822907 -345.12966)
			(xy 270.872506 -345.107005) (xy 270.924825 -345.091638) (xy 270.978798 -345.083873) (xy 271.006062 -345.083384)
			(xy 271.869662 -345.083384) (xy 271.896938 -345.083753) (xy 271.950936 -345.091512) (xy 272.003279 -345.106877)
			(xy 272.052903 -345.129535) (xy 272.098797 -345.159025) (xy 272.140027 -345.194747) (xy 272.175752 -345.235973)
			(xy 272.205247 -345.281864) (xy 272.22791 -345.331485) (xy 272.24328 -345.383827) (xy 272.251044 -345.437824)
			(xy 272.251044 -345.492369) (xy 273.733747 -345.492369) (xy 273.733747 -345.437831) (xy 273.741509 -345.383849)
			(xy 273.756875 -345.331521) (xy 273.779531 -345.281912) (xy 273.809017 -345.236033) (xy 273.844733 -345.194817)
			(xy 273.885951 -345.159104) (xy 273.931832 -345.129621) (xy 273.981441 -345.106967) (xy 274.033771 -345.091605)
			(xy 274.087753 -345.083846) (xy 274.115022 -345.083384) (xy 274.978622 -345.083384) (xy 275.005894 -345.08378)
			(xy 275.059881 -345.091545) (xy 275.112215 -345.106914) (xy 275.161828 -345.129574) (xy 275.207712 -345.159064)
			(xy 275.248932 -345.194784) (xy 275.284649 -345.236006) (xy 275.314136 -345.281891) (xy 275.336793 -345.331506)
			(xy 275.352159 -345.38384) (xy 275.359922 -345.437828) (xy 275.359922 -345.492365) (xy 276.84277 -345.492365)
			(xy 276.84277 -345.437835) (xy 276.850531 -345.383859) (xy 276.865893 -345.331537) (xy 276.888545 -345.281934)
			(xy 276.918026 -345.23606) (xy 276.953735 -345.194848) (xy 276.994945 -345.159137) (xy 277.040819 -345.129654)
			(xy 277.090421 -345.106999) (xy 277.142742 -345.091634) (xy 277.196717 -345.083872) (xy 277.223982 -345.083384)
			(xy 278.087582 -345.083384) (xy 278.114857 -345.083754) (xy 278.168852 -345.091515) (xy 278.221194 -345.106882)
			(xy 278.270815 -345.129541) (xy 278.316706 -345.159032) (xy 278.357934 -345.194754) (xy 278.393657 -345.235979)
			(xy 278.42315 -345.281869) (xy 278.445812 -345.33149) (xy 278.461181 -345.38383) (xy 278.468944 -345.437825)
			(xy 278.468944 -345.49237) (xy 279.951648 -345.49237) (xy 279.951648 -345.43783) (xy 279.95941 -345.383846)
			(xy 279.974776 -345.331517) (xy 279.997434 -345.281907) (xy 280.026922 -345.236026) (xy 280.06264 -345.19481)
			(xy 280.10386 -345.159097) (xy 280.149744 -345.129614) (xy 280.199356 -345.106962) (xy 280.251687 -345.091601)
			(xy 280.305672 -345.083845) (xy 280.332942 -345.083384) (xy 281.196542 -345.083384) (xy 281.223813 -345.083781)
			(xy 281.277798 -345.091549) (xy 281.330129 -345.10692) (xy 281.37974 -345.129581) (xy 281.425621 -345.159072)
			(xy 281.466839 -345.194791) (xy 281.502554 -345.236013) (xy 281.532039 -345.281897) (xy 281.554695 -345.33151)
			(xy 281.57006 -345.383843) (xy 281.577822 -345.437829) (xy 281.577822 -345.492368) (xy 283.060647 -345.492368)
			(xy 283.060647 -345.437832) (xy 283.068409 -345.383852) (xy 283.083773 -345.331525) (xy 283.106428 -345.281918)
			(xy 283.135912 -345.23604) (xy 283.171626 -345.194824) (xy 283.212841 -345.159111) (xy 283.25872 -345.129627)
			(xy 283.308327 -345.106972) (xy 283.360654 -345.091608) (xy 283.414634 -345.083847) (xy 283.441902 -345.083384)
			(xy 284.305502 -345.083384) (xy 284.332775 -345.083779) (xy 284.386764 -345.091542) (xy 284.4391 -345.106909)
			(xy 284.488716 -345.129568) (xy 284.534602 -345.159057) (xy 284.575824 -345.194777) (xy 284.611544 -345.236)
			(xy 284.641033 -345.281886) (xy 284.663692 -345.331502) (xy 284.679059 -345.383838) (xy 284.686821 -345.437827)
			(xy 284.686821 -345.492364) (xy 286.16967 -345.492364) (xy 286.16967 -345.437836) (xy 286.17743 -345.383862)
			(xy 286.192792 -345.331542) (xy 286.215442 -345.28194) (xy 286.244921 -345.236066) (xy 286.280628 -345.194855)
			(xy 286.321836 -345.159144) (xy 286.367707 -345.12966) (xy 286.417306 -345.107005) (xy 286.469625 -345.091638)
			(xy 286.523598 -345.083873) (xy 286.550862 -345.083384) (xy 287.414462 -345.083384) (xy 287.441738 -345.083753)
			(xy 287.495736 -345.091512) (xy 287.548079 -345.106877) (xy 287.597703 -345.129535) (xy 287.643597 -345.159025)
			(xy 287.684827 -345.194747) (xy 287.720552 -345.235973) (xy 287.750047 -345.281864) (xy 287.77271 -345.331485)
			(xy 287.78808 -345.383827) (xy 287.795844 -345.437824) (xy 287.795844 -345.492369) (xy 289.278547 -345.492369)
			(xy 289.278547 -345.437831) (xy 289.286309 -345.383849) (xy 289.301675 -345.331521) (xy 289.324331 -345.281912)
			(xy 289.353817 -345.236033) (xy 289.389533 -345.194817) (xy 289.430751 -345.159104) (xy 289.476632 -345.129621)
			(xy 289.526241 -345.106967) (xy 289.578571 -345.091605) (xy 289.632553 -345.083846) (xy 289.659822 -345.083384)
			(xy 290.523422 -345.083384) (xy 290.550694 -345.08378) (xy 290.604681 -345.091545) (xy 290.657015 -345.106914)
			(xy 290.706628 -345.129574) (xy 290.752512 -345.159064) (xy 290.793732 -345.194784) (xy 290.829449 -345.236006)
			(xy 290.858936 -345.281891) (xy 290.881593 -345.331506) (xy 290.896959 -345.38384) (xy 290.904722 -345.437828)
			(xy 290.904722 -345.492365) (xy 292.38757 -345.492365) (xy 292.38757 -345.437835) (xy 292.395331 -345.383859)
			(xy 292.410693 -345.331537) (xy 292.433345 -345.281934) (xy 292.462826 -345.23606) (xy 292.498535 -345.194848)
			(xy 292.539745 -345.159137) (xy 292.585619 -345.129654) (xy 292.635221 -345.106999) (xy 292.687542 -345.091634)
			(xy 292.741517 -345.083872) (xy 292.768782 -345.083384) (xy 293.632382 -345.083384) (xy 293.659657 -345.083754)
			(xy 293.713652 -345.091515) (xy 293.765994 -345.106882) (xy 293.815615 -345.129541) (xy 293.861506 -345.159032)
			(xy 293.902734 -345.194754) (xy 293.938457 -345.235979) (xy 293.96795 -345.281869) (xy 293.990612 -345.33149)
			(xy 294.005981 -345.38383) (xy 294.013744 -345.437825) (xy 294.013744 -345.49237) (xy 295.496448 -345.49237)
			(xy 295.496448 -345.43783) (xy 295.50421 -345.383846) (xy 295.519576 -345.331517) (xy 295.542234 -345.281907)
			(xy 295.571722 -345.236026) (xy 295.60744 -345.19481) (xy 295.64866 -345.159097) (xy 295.694544 -345.129614)
			(xy 295.744156 -345.106962) (xy 295.796487 -345.091601) (xy 295.850472 -345.083845) (xy 295.877742 -345.083384)
			(xy 296.741342 -345.083384) (xy 296.768613 -345.083781) (xy 296.822598 -345.091549) (xy 296.874929 -345.10692)
			(xy 296.92454 -345.129581) (xy 296.970421 -345.159072) (xy 297.011639 -345.194791) (xy 297.047354 -345.236013)
			(xy 297.076839 -345.281897) (xy 297.099495 -345.33151) (xy 297.11486 -345.383843) (xy 297.122622 -345.437829)
			(xy 297.122622 -345.492368) (xy 298.605447 -345.492368) (xy 298.605447 -345.437832) (xy 298.613209 -345.383852)
			(xy 298.628573 -345.331525) (xy 298.651228 -345.281918) (xy 298.680712 -345.23604) (xy 298.716426 -345.194824)
			(xy 298.757641 -345.159111) (xy 298.80352 -345.129627) (xy 298.853127 -345.106972) (xy 298.905454 -345.091608)
			(xy 298.959434 -345.083847) (xy 298.986702 -345.083384) (xy 299.850302 -345.083384) (xy 299.877575 -345.083779)
			(xy 299.931564 -345.091542) (xy 299.9839 -345.106909) (xy 300.033516 -345.129568) (xy 300.079402 -345.159057)
			(xy 300.120624 -345.194777) (xy 300.156344 -345.236) (xy 300.185833 -345.281886) (xy 300.208492 -345.331502)
			(xy 300.223859 -345.383838) (xy 300.231621 -345.437827) (xy 300.231621 -345.492368) (xy 312.121547 -345.492368)
			(xy 312.121547 -345.437832) (xy 312.129309 -345.383851) (xy 312.144673 -345.331525) (xy 312.167328 -345.281917)
			(xy 312.196813 -345.236039) (xy 312.232526 -345.194824) (xy 312.273742 -345.159111) (xy 312.319621 -345.129627)
			(xy 312.369228 -345.106972) (xy 312.421555 -345.091608) (xy 312.475536 -345.083847) (xy 312.502804 -345.083384)
			(xy 313.366404 -345.083384) (xy 313.393676 -345.083779) (xy 313.447666 -345.091542) (xy 313.500001 -345.106909)
			(xy 313.549617 -345.129569) (xy 313.595503 -345.159058) (xy 313.636725 -345.194778) (xy 313.672444 -345.236)
			(xy 313.701933 -345.281886) (xy 313.724592 -345.331502) (xy 313.739959 -345.383838) (xy 313.747721 -345.437828)
			(xy 313.747721 -345.492364) (xy 315.23057 -345.492364) (xy 315.23057 -345.437836) (xy 315.23833 -345.383862)
			(xy 315.253692 -345.331541) (xy 315.276343 -345.281939) (xy 315.305821 -345.236066) (xy 315.341529 -345.194854)
			(xy 315.382737 -345.159143) (xy 315.428608 -345.12966) (xy 315.478207 -345.107004) (xy 315.530526 -345.091638)
			(xy 315.5845 -345.083873) (xy 315.611764 -345.083384) (xy 316.475364 -345.083384) (xy 316.50264 -345.083753)
			(xy 316.556637 -345.091512) (xy 316.608981 -345.106877) (xy 316.658604 -345.129535) (xy 316.704498 -345.159026)
			(xy 316.745727 -345.194747) (xy 316.781453 -345.235973) (xy 316.810947 -345.281864) (xy 316.83361 -345.331486)
			(xy 316.84898 -345.383828) (xy 316.856744 -345.437824) (xy 316.856744 -345.492369) (xy 318.339447 -345.492369)
			(xy 318.339447 -345.437831) (xy 318.347209 -345.383849) (xy 318.362575 -345.33152) (xy 318.385231 -345.281912)
			(xy 318.414718 -345.236032) (xy 318.450434 -345.194817) (xy 318.491652 -345.159103) (xy 318.537533 -345.12962)
			(xy 318.587143 -345.106966) (xy 318.639472 -345.091604) (xy 318.693455 -345.083846) (xy 318.720724 -345.083384)
			(xy 319.584324 -345.083384) (xy 319.611596 -345.08378) (xy 319.665583 -345.091546) (xy 319.717916 -345.106915)
			(xy 319.767529 -345.129575) (xy 319.813413 -345.159065) (xy 319.854632 -345.194785) (xy 319.890349 -345.236007)
			(xy 319.919836 -345.281892) (xy 319.942494 -345.331507) (xy 319.95786 -345.38384) (xy 319.965622 -345.437828)
			(xy 319.965622 -345.492365) (xy 321.44847 -345.492365) (xy 321.44847 -345.437835) (xy 321.456231 -345.383859)
			(xy 321.471593 -345.331537) (xy 321.494246 -345.281934) (xy 321.523726 -345.236059) (xy 321.559436 -345.194847)
			(xy 321.600646 -345.159136) (xy 321.64652 -345.129653) (xy 321.696122 -345.106999) (xy 321.748443 -345.091634)
			(xy 321.802419 -345.083871) (xy 321.829684 -345.083384) (xy 322.693284 -345.083384) (xy 322.720559 -345.083755)
			(xy 322.774554 -345.091516) (xy 322.826895 -345.106882) (xy 322.876516 -345.129542) (xy 322.922407 -345.159033)
			(xy 322.963634 -345.194754) (xy 322.999358 -345.23598) (xy 323.02885 -345.28187) (xy 323.051512 -345.33149)
			(xy 323.066881 -345.38383) (xy 323.074644 -345.437825) (xy 323.074644 -345.49237) (xy 324.557348 -345.49237)
			(xy 324.557348 -345.43783) (xy 324.56511 -345.383846) (xy 324.580476 -345.331516) (xy 324.603135 -345.281906)
			(xy 324.632623 -345.236026) (xy 324.668341 -345.194809) (xy 324.709561 -345.159096) (xy 324.755445 -345.129613)
			(xy 324.805057 -345.106961) (xy 324.857389 -345.0916) (xy 324.911374 -345.083844) (xy 324.938644 -345.083384)
			(xy 325.802244 -345.083384) (xy 325.829515 -345.083782) (xy 325.8835 -345.091549) (xy 325.93583 -345.10692)
			(xy 325.985441 -345.129582) (xy 326.031322 -345.159072) (xy 326.072539 -345.194792) (xy 326.108254 -345.236013)
			(xy 326.137739 -345.281898) (xy 326.160395 -345.331511) (xy 326.17576 -345.383843) (xy 326.183522 -345.437829)
			(xy 326.183522 -345.492368) (xy 327.666347 -345.492368) (xy 327.666347 -345.437832) (xy 327.674109 -345.383851)
			(xy 327.689473 -345.331525) (xy 327.712128 -345.281917) (xy 327.741613 -345.236039) (xy 327.777326 -345.194824)
			(xy 327.818542 -345.159111) (xy 327.864421 -345.129627) (xy 327.914028 -345.106972) (xy 327.966355 -345.091608)
			(xy 328.020336 -345.083847) (xy 328.047604 -345.083384) (xy 328.911204 -345.083384) (xy 328.938476 -345.083779)
			(xy 328.992466 -345.091542) (xy 329.044801 -345.106909) (xy 329.094417 -345.129569) (xy 329.140303 -345.159058)
			(xy 329.181525 -345.194778) (xy 329.217244 -345.236) (xy 329.246733 -345.281886) (xy 329.269392 -345.331502)
			(xy 329.284759 -345.383838) (xy 329.292521 -345.437828) (xy 329.292521 -345.492364) (xy 330.77537 -345.492364)
			(xy 330.77537 -345.437836) (xy 330.78313 -345.383862) (xy 330.798492 -345.331541) (xy 330.821143 -345.281939)
			(xy 330.850621 -345.236066) (xy 330.886329 -345.194854) (xy 330.927537 -345.159143) (xy 330.973408 -345.12966)
			(xy 331.023007 -345.107004) (xy 331.075326 -345.091638) (xy 331.1293 -345.083873) (xy 331.156564 -345.083384)
			(xy 332.020164 -345.083384) (xy 332.04744 -345.083753) (xy 332.101437 -345.091512) (xy 332.153781 -345.106877)
			(xy 332.203404 -345.129535) (xy 332.249298 -345.159026) (xy 332.290527 -345.194747) (xy 332.326253 -345.235973)
			(xy 332.355747 -345.281864) (xy 332.37841 -345.331486) (xy 332.39378 -345.383828) (xy 332.401544 -345.437824)
			(xy 332.401544 -345.492369) (xy 333.884247 -345.492369) (xy 333.884247 -345.437831) (xy 333.892009 -345.383849)
			(xy 333.907375 -345.33152) (xy 333.930031 -345.281912) (xy 333.959518 -345.236032) (xy 333.995234 -345.194817)
			(xy 334.036452 -345.159103) (xy 334.082333 -345.12962) (xy 334.131943 -345.106966) (xy 334.184272 -345.091604)
			(xy 334.238255 -345.083846) (xy 334.265524 -345.083384) (xy 335.129124 -345.083384) (xy 335.156396 -345.08378)
			(xy 335.210383 -345.091546) (xy 335.262716 -345.106915) (xy 335.312329 -345.129575) (xy 335.358213 -345.159065)
			(xy 335.399432 -345.194785) (xy 335.435149 -345.236007) (xy 335.464636 -345.281892) (xy 335.487294 -345.331507)
			(xy 335.50266 -345.38384) (xy 335.510422 -345.437828) (xy 335.510422 -345.492365) (xy 336.99327 -345.492365)
			(xy 336.99327 -345.437835) (xy 337.001031 -345.383859) (xy 337.016393 -345.331537) (xy 337.039046 -345.281934)
			(xy 337.068526 -345.236059) (xy 337.104236 -345.194847) (xy 337.145446 -345.159136) (xy 337.19132 -345.129653)
			(xy 337.240922 -345.106999) (xy 337.293243 -345.091634) (xy 337.347219 -345.083871) (xy 337.374484 -345.083384)
			(xy 338.238084 -345.083384) (xy 338.265359 -345.083755) (xy 338.319354 -345.091516) (xy 338.371695 -345.106882)
			(xy 338.421316 -345.129542) (xy 338.467207 -345.159033) (xy 338.508434 -345.194754) (xy 338.544158 -345.23598)
			(xy 338.57365 -345.28187) (xy 338.596312 -345.33149) (xy 338.611681 -345.38383) (xy 338.619444 -345.437825)
			(xy 338.619444 -345.49237) (xy 340.102148 -345.49237) (xy 340.102148 -345.43783) (xy 340.10991 -345.383846)
			(xy 340.125276 -345.331516) (xy 340.147935 -345.281906) (xy 340.177423 -345.236026) (xy 340.213141 -345.194809)
			(xy 340.254361 -345.159096) (xy 340.300245 -345.129613) (xy 340.349857 -345.106961) (xy 340.402189 -345.0916)
			(xy 340.456174 -345.083844) (xy 340.483444 -345.083384) (xy 341.347044 -345.083384) (xy 341.374315 -345.083782)
			(xy 341.4283 -345.091549) (xy 341.48063 -345.10692) (xy 341.530241 -345.129582) (xy 341.576122 -345.159072)
			(xy 341.617339 -345.194792) (xy 341.653054 -345.236013) (xy 341.682539 -345.281898) (xy 341.705195 -345.331511)
			(xy 341.72056 -345.383843) (xy 341.728322 -345.437829) (xy 341.728322 -345.492368) (xy 343.211147 -345.492368)
			(xy 343.211147 -345.437832) (xy 343.218909 -345.383851) (xy 343.234273 -345.331525) (xy 343.256928 -345.281917)
			(xy 343.286413 -345.236039) (xy 343.322126 -345.194824) (xy 343.363342 -345.159111) (xy 343.409221 -345.129627)
			(xy 343.458828 -345.106972) (xy 343.511155 -345.091608) (xy 343.565136 -345.083847) (xy 343.592404 -345.083384)
			(xy 344.456004 -345.083384) (xy 344.483276 -345.083779) (xy 344.537266 -345.091542) (xy 344.589601 -345.106909)
			(xy 344.639217 -345.129569) (xy 344.685103 -345.159058) (xy 344.726325 -345.194778) (xy 344.762044 -345.236)
			(xy 344.791533 -345.281886) (xy 344.814192 -345.331502) (xy 344.829559 -345.383838) (xy 344.837321 -345.437828)
			(xy 344.837321 -345.492365) (xy 370.80677 -345.492365) (xy 370.80677 -345.437835) (xy 370.81453 -345.383859)
			(xy 370.829893 -345.331538) (xy 370.852545 -345.281935) (xy 370.882025 -345.236061) (xy 370.917734 -345.194848)
			(xy 370.958945 -345.159137) (xy 371.004817 -345.129655) (xy 371.054419 -345.107) (xy 371.10674 -345.091635)
			(xy 371.160715 -345.083872) (xy 371.18798 -345.083384) (xy 372.05158 -345.083384) (xy 372.078855 -345.083754)
			(xy 372.132851 -345.091515) (xy 372.185192 -345.106881) (xy 372.234814 -345.129541) (xy 372.280705 -345.159031)
			(xy 372.321933 -345.194753) (xy 372.357657 -345.235978) (xy 372.38715 -345.281869) (xy 372.409812 -345.331489)
			(xy 372.425181 -345.38383) (xy 372.432944 -345.437825) (xy 372.432944 -345.49237) (xy 373.915647 -345.49237)
			(xy 373.915647 -345.43783) (xy 373.92341 -345.383847) (xy 373.938776 -345.331517) (xy 373.961434 -345.281907)
			(xy 373.990922 -345.236027) (xy 374.026639 -345.194811) (xy 374.067859 -345.159098) (xy 374.113742 -345.129615)
			(xy 374.163355 -345.106962) (xy 374.215686 -345.091601) (xy 374.26967 -345.083845) (xy 374.29694 -345.083384)
			(xy 375.16054 -345.083384) (xy 375.187811 -345.083781) (xy 375.241797 -345.091549) (xy 375.294128 -345.106919)
			(xy 375.343739 -345.12958) (xy 375.38962 -345.159071) (xy 375.430838 -345.19479) (xy 375.466553 -345.236012)
			(xy 375.496039 -345.281896) (xy 375.518695 -345.33151) (xy 375.53406 -345.383843) (xy 375.541822 -345.437829)
			(xy 375.541822 -345.492366) (xy 377.02467 -345.492366) (xy 377.02467 -345.437834) (xy 377.032431 -345.383857)
			(xy 377.047795 -345.331534) (xy 377.070448 -345.281929) (xy 377.09993 -345.236054) (xy 377.135641 -345.194841)
			(xy 377.176854 -345.15913) (xy 377.222729 -345.129648) (xy 377.272334 -345.106995) (xy 377.324657 -345.091631)
			(xy 377.378634 -345.08387) (xy 377.4059 -345.083384) (xy 378.2695 -345.083384) (xy 378.296773 -345.083779)
			(xy 378.350763 -345.091541) (xy 378.403099 -345.106908) (xy 378.452715 -345.129567) (xy 378.498601 -345.159057)
			(xy 378.539824 -345.194776) (xy 378.575543 -345.235999) (xy 378.605033 -345.281885) (xy 378.627692 -345.331501)
			(xy 378.643059 -345.383837) (xy 378.650821 -345.437827) (xy 378.650821 -345.492364) (xy 380.13367 -345.492364)
			(xy 380.13367 -345.437836) (xy 380.14143 -345.383862) (xy 380.156791 -345.331542) (xy 380.179442 -345.281941)
			(xy 380.208921 -345.236067) (xy 380.244627 -345.194855) (xy 380.285835 -345.159145) (xy 380.331705 -345.129661)
			(xy 380.381305 -345.107005) (xy 380.433623 -345.091638) (xy 380.487596 -345.083873) (xy 380.51486 -345.083384)
			(xy 381.37846 -345.083384) (xy 381.405736 -345.083753) (xy 381.459734 -345.091511) (xy 381.512078 -345.106876)
			(xy 381.561702 -345.129534) (xy 381.607596 -345.159024) (xy 381.648826 -345.194746) (xy 381.684552 -345.235972)
			(xy 381.714047 -345.281863) (xy 381.73671 -345.331485) (xy 381.75208 -345.383827) (xy 381.759844 -345.437824)
			(xy 381.759844 -345.492369) (xy 383.242547 -345.492369) (xy 383.242547 -345.437831) (xy 383.250309 -345.383849)
			(xy 383.265675 -345.331521) (xy 383.288331 -345.281913) (xy 383.317817 -345.236034) (xy 383.353532 -345.194818)
			(xy 383.39475 -345.159105) (xy 383.44063 -345.129621) (xy 383.49024 -345.106968) (xy 383.542569 -345.091605)
			(xy 383.596551 -345.083846) (xy 383.62382 -345.083384) (xy 384.48742 -345.083384) (xy 384.514692 -345.08378)
			(xy 384.56868 -345.091545) (xy 384.621013 -345.106914) (xy 384.670627 -345.129574) (xy 384.716511 -345.159064)
			(xy 384.757731 -345.194783) (xy 384.793448 -345.236005) (xy 384.822936 -345.281891) (xy 384.845593 -345.331506)
			(xy 384.860959 -345.38384) (xy 384.868722 -345.437828) (xy 384.868722 -345.492365) (xy 386.35157 -345.492365)
			(xy 386.35157 -345.437835) (xy 386.35933 -345.383859) (xy 386.374693 -345.331538) (xy 386.397345 -345.281935)
			(xy 386.426825 -345.236061) (xy 386.462534 -345.194848) (xy 386.503745 -345.159137) (xy 386.549617 -345.129655)
			(xy 386.599219 -345.107) (xy 386.65154 -345.091635) (xy 386.705515 -345.083872) (xy 386.73278 -345.083384)
			(xy 387.59638 -345.083384) (xy 387.623655 -345.083754) (xy 387.677651 -345.091515) (xy 387.729992 -345.106881)
			(xy 387.779614 -345.129541) (xy 387.825505 -345.159031) (xy 387.866733 -345.194753) (xy 387.902457 -345.235978)
			(xy 387.93195 -345.281869) (xy 387.954612 -345.331489) (xy 387.969981 -345.38383) (xy 387.977744 -345.437825)
			(xy 387.977744 -345.49237) (xy 389.460447 -345.49237) (xy 389.460447 -345.43783) (xy 389.46821 -345.383847)
			(xy 389.483576 -345.331517) (xy 389.506234 -345.281907) (xy 389.535722 -345.236027) (xy 389.571439 -345.194811)
			(xy 389.612659 -345.159098) (xy 389.658542 -345.129615) (xy 389.708155 -345.106962) (xy 389.760486 -345.091601)
			(xy 389.81447 -345.083845) (xy 389.84174 -345.083384) (xy 390.70534 -345.083384) (xy 390.732611 -345.083781)
			(xy 390.786597 -345.091549) (xy 390.838928 -345.106919) (xy 390.888539 -345.12958) (xy 390.93442 -345.159071)
			(xy 390.975638 -345.19479) (xy 391.011353 -345.236012) (xy 391.040839 -345.281896) (xy 391.063495 -345.33151)
			(xy 391.07886 -345.383843) (xy 391.086622 -345.437829) (xy 391.086622 -345.492366) (xy 392.56947 -345.492366)
			(xy 392.56947 -345.437834) (xy 392.577231 -345.383857) (xy 392.592595 -345.331534) (xy 392.615248 -345.281929)
			(xy 392.64473 -345.236054) (xy 392.680441 -345.194841) (xy 392.721654 -345.15913) (xy 392.767529 -345.129648)
			(xy 392.817134 -345.106995) (xy 392.869457 -345.091631) (xy 392.923434 -345.08387) (xy 392.9507 -345.083384)
			(xy 393.8143 -345.083384) (xy 393.841573 -345.083779) (xy 393.895563 -345.091541) (xy 393.947899 -345.106908)
			(xy 393.997515 -345.129567) (xy 394.043401 -345.159057) (xy 394.084624 -345.194776) (xy 394.120343 -345.235999)
			(xy 394.149833 -345.281885) (xy 394.172492 -345.331501) (xy 394.187859 -345.383837) (xy 394.195621 -345.437827)
			(xy 394.195621 -345.492364) (xy 395.67847 -345.492364) (xy 395.67847 -345.437836) (xy 395.68623 -345.383862)
			(xy 395.701591 -345.331542) (xy 395.724242 -345.281941) (xy 395.753721 -345.236067) (xy 395.789427 -345.194855)
			(xy 395.830635 -345.159145) (xy 395.876505 -345.129661) (xy 395.926105 -345.107005) (xy 395.978423 -345.091638)
			(xy 396.032396 -345.083873) (xy 396.05966 -345.083384) (xy 396.92326 -345.083384) (xy 396.950536 -345.083753)
			(xy 397.004534 -345.091511) (xy 397.056878 -345.106876) (xy 397.106502 -345.129534) (xy 397.152396 -345.159024)
			(xy 397.193626 -345.194746) (xy 397.229352 -345.235972) (xy 397.258847 -345.281863) (xy 397.28151 -345.331485)
			(xy 397.29688 -345.383827) (xy 397.304644 -345.437824) (xy 397.304644 -345.492369) (xy 398.787347 -345.492369)
			(xy 398.787347 -345.437831) (xy 398.795109 -345.383849) (xy 398.810475 -345.331521) (xy 398.833131 -345.281913)
			(xy 398.862617 -345.236034) (xy 398.898332 -345.194818) (xy 398.93955 -345.159105) (xy 398.98543 -345.129621)
			(xy 399.03504 -345.106968) (xy 399.087369 -345.091605) (xy 399.141351 -345.083846) (xy 399.16862 -345.083384)
			(xy 400.03222 -345.083384) (xy 400.059492 -345.08378) (xy 400.11348 -345.091545) (xy 400.165813 -345.106914)
			(xy 400.215427 -345.129574) (xy 400.261311 -345.159064) (xy 400.302531 -345.194783) (xy 400.338248 -345.236005)
			(xy 400.367736 -345.281891) (xy 400.390393 -345.331506) (xy 400.405759 -345.38384) (xy 400.413522 -345.437828)
			(xy 400.413522 -345.492365) (xy 401.89637 -345.492365) (xy 401.89637 -345.437835) (xy 401.90413 -345.383859)
			(xy 401.919493 -345.331538) (xy 401.942145 -345.281935) (xy 401.971625 -345.236061) (xy 402.007334 -345.194848)
			(xy 402.048545 -345.159137) (xy 402.094417 -345.129655) (xy 402.144019 -345.107) (xy 402.19634 -345.091635)
			(xy 402.250315 -345.083872) (xy 402.27758 -345.083384) (xy 403.14118 -345.083384) (xy 403.168455 -345.083754)
			(xy 403.222451 -345.091515) (xy 403.274792 -345.106881) (xy 403.324414 -345.129541) (xy 403.370305 -345.159031)
			(xy 403.411533 -345.194753) (xy 403.447257 -345.235978) (xy 403.47675 -345.281869) (xy 403.499412 -345.331489)
			(xy 403.514781 -345.38383) (xy 403.522544 -345.437825) (xy 403.522544 -345.492366) (xy 408.91387 -345.492366)
			(xy 408.91387 -345.437834) (xy 408.921631 -345.383858) (xy 408.936994 -345.331535) (xy 408.959647 -345.281932)
			(xy 408.989128 -345.236057) (xy 409.024838 -345.194844) (xy 409.06605 -345.159133) (xy 409.111925 -345.129651)
			(xy 409.161528 -345.106997) (xy 409.21385 -345.091633) (xy 409.267826 -345.083871) (xy 409.295092 -345.083384)
			(xy 410.158692 -345.083384) (xy 410.185967 -345.083755) (xy 410.239961 -345.091517) (xy 410.292301 -345.106885)
			(xy 410.341921 -345.129544) (xy 410.387811 -345.159035) (xy 410.429037 -345.194757) (xy 410.46476 -345.235982)
			(xy 410.494252 -345.281872) (xy 410.516913 -345.331492) (xy 410.532281 -345.383831) (xy 410.540044 -345.437825)
			(xy 410.540044 -345.492364) (xy 412.02287 -345.492364) (xy 412.02287 -345.437836) (xy 412.03063 -345.383863)
			(xy 412.045991 -345.331544) (xy 412.068641 -345.281943) (xy 412.098119 -345.23607) (xy 412.133824 -345.194858)
			(xy 412.175031 -345.159147) (xy 412.220901 -345.129664) (xy 412.270499 -345.107008) (xy 412.322816 -345.09164)
			(xy 412.376788 -345.083874) (xy 412.404052 -345.083384) (xy 413.267652 -345.083384) (xy 413.294929 -345.083752)
			(xy 413.348927 -345.09151) (xy 413.401272 -345.106874) (xy 413.450897 -345.129531) (xy 413.496792 -345.159021)
			(xy 413.538023 -345.194743) (xy 413.57375 -345.235969) (xy 413.603246 -345.281861) (xy 413.625909 -345.331483)
			(xy 413.64128 -345.383826) (xy 413.649044 -345.437824) (xy 413.649044 -345.492368) (xy 415.131747 -345.492368)
			(xy 415.131747 -345.437832) (xy 415.139509 -345.38385) (xy 415.154874 -345.331523) (xy 415.17753 -345.281915)
			(xy 415.207015 -345.236036) (xy 415.242729 -345.194821) (xy 415.283946 -345.159108) (xy 415.329826 -345.129624)
			(xy 415.379434 -345.10697) (xy 415.431762 -345.091606) (xy 415.485744 -345.083847) (xy 415.513012 -345.083384)
			(xy 416.376612 -345.083384) (xy 416.403884 -345.083779) (xy 416.457873 -345.091543) (xy 416.510207 -345.106912)
			(xy 416.559822 -345.129571) (xy 416.605707 -345.159061) (xy 416.646928 -345.194781) (xy 416.682646 -345.236003)
			(xy 416.712135 -345.281889) (xy 416.734793 -345.331504) (xy 416.750159 -345.383839) (xy 416.757921 -345.437828)
			(xy 416.757921 -345.492365) (xy 418.24077 -345.492365) (xy 418.24077 -345.437835) (xy 418.24853 -345.383861)
			(xy 418.263892 -345.33154) (xy 418.286544 -345.281937) (xy 418.316023 -345.236063) (xy 418.351731 -345.194851)
			(xy 418.392941 -345.15914) (xy 418.438813 -345.129657) (xy 418.488413 -345.107002) (xy 418.540733 -345.091636)
			(xy 418.594707 -345.083872) (xy 418.621972 -345.083384) (xy 419.485572 -345.083384) (xy 419.512848 -345.083754)
			(xy 419.566844 -345.091514) (xy 419.619186 -345.106879) (xy 419.668809 -345.129538) (xy 419.714702 -345.159028)
			(xy 419.75593 -345.19475) (xy 419.791655 -345.235976) (xy 419.821149 -345.281866) (xy 419.843811 -345.331487)
			(xy 419.859181 -345.383829) (xy 419.866944 -345.437824) (xy 419.866944 -345.492369) (xy 421.349647 -345.492369)
			(xy 421.349647 -345.437831) (xy 421.35741 -345.383848) (xy 421.372776 -345.331519) (xy 421.395433 -345.281909)
			(xy 421.42492 -345.23603) (xy 421.460636 -345.194814) (xy 421.501855 -345.159101) (xy 421.547738 -345.129617)
			(xy 421.597349 -345.106964) (xy 421.649679 -345.091603) (xy 421.703663 -345.083845) (xy 421.730932 -345.083384)
			(xy 422.594532 -345.083384) (xy 422.621803 -345.083781) (xy 422.67579 -345.091547) (xy 422.728122 -345.106917)
			(xy 422.777734 -345.129578) (xy 422.823616 -345.159068) (xy 422.864835 -345.194788) (xy 422.900551 -345.236009)
			(xy 422.930038 -345.281894) (xy 422.952694 -345.331508) (xy 422.96806 -345.383842) (xy 422.975822 -345.437829)
			(xy 422.975822 -345.492366) (xy 424.45867 -345.492366) (xy 424.45867 -345.437834) (xy 424.466431 -345.383858)
			(xy 424.481794 -345.331535) (xy 424.504447 -345.281932) (xy 424.533928 -345.236057) (xy 424.569638 -345.194844)
			(xy 424.61085 -345.159133) (xy 424.656725 -345.129651) (xy 424.706328 -345.106997) (xy 424.75865 -345.091633)
			(xy 424.812626 -345.083871) (xy 424.839892 -345.083384) (xy 425.703492 -345.083384) (xy 425.730767 -345.083755)
			(xy 425.784761 -345.091517) (xy 425.837101 -345.106885) (xy 425.886721 -345.129544) (xy 425.932611 -345.159035)
			(xy 425.973837 -345.194757) (xy 426.00956 -345.235982) (xy 426.039052 -345.281872) (xy 426.061713 -345.331492)
			(xy 426.077081 -345.383831) (xy 426.084844 -345.437825) (xy 426.084844 -345.492364) (xy 427.56767 -345.492364)
			(xy 427.56767 -345.437836) (xy 427.57543 -345.383863) (xy 427.590791 -345.331544) (xy 427.613441 -345.281943)
			(xy 427.642919 -345.23607) (xy 427.678624 -345.194858) (xy 427.719831 -345.159147) (xy 427.765701 -345.129664)
			(xy 427.815299 -345.107008) (xy 427.867616 -345.09164) (xy 427.921588 -345.083874) (xy 427.948852 -345.083384)
			(xy 428.812452 -345.083384) (xy 428.839729 -345.083752) (xy 428.893727 -345.09151) (xy 428.946072 -345.106874)
			(xy 428.995697 -345.129531) (xy 429.041592 -345.159021) (xy 429.082823 -345.194743) (xy 429.11855 -345.235969)
			(xy 429.148046 -345.281861) (xy 429.170709 -345.331483) (xy 429.18608 -345.383826) (xy 429.193844 -345.437824)
			(xy 429.193844 -345.492368) (xy 430.676547 -345.492368) (xy 430.676547 -345.437832) (xy 430.684309 -345.38385)
			(xy 430.699674 -345.331523) (xy 430.72233 -345.281915) (xy 430.751815 -345.236036) (xy 430.787529 -345.194821)
			(xy 430.828746 -345.159108) (xy 430.874626 -345.129624) (xy 430.924234 -345.10697) (xy 430.976562 -345.091606)
			(xy 431.030544 -345.083847) (xy 431.057812 -345.083384) (xy 431.921412 -345.083384) (xy 431.948684 -345.083779)
			(xy 432.002673 -345.091543) (xy 432.055007 -345.106912) (xy 432.104622 -345.129571) (xy 432.150507 -345.159061)
			(xy 432.191728 -345.194781) (xy 432.227446 -345.236003) (xy 432.256935 -345.281889) (xy 432.279593 -345.331504)
			(xy 432.294959 -345.383839) (xy 432.302721 -345.437828) (xy 432.302721 -345.492365) (xy 433.78557 -345.492365)
			(xy 433.78557 -345.437835) (xy 433.79333 -345.383861) (xy 433.808692 -345.33154) (xy 433.831344 -345.281937)
			(xy 433.860823 -345.236063) (xy 433.896531 -345.194851) (xy 433.937741 -345.15914) (xy 433.983613 -345.129657)
			(xy 434.033213 -345.107002) (xy 434.085533 -345.091636) (xy 434.139507 -345.083872) (xy 434.166772 -345.083384)
			(xy 435.030372 -345.083384) (xy 435.057648 -345.083754) (xy 435.111644 -345.091514) (xy 435.163986 -345.106879)
			(xy 435.213609 -345.129538) (xy 435.259502 -345.159028) (xy 435.30073 -345.19475) (xy 435.336455 -345.235976)
			(xy 435.365949 -345.281866) (xy 435.388611 -345.331487) (xy 435.403981 -345.383829) (xy 435.411744 -345.437824)
			(xy 435.411744 -345.492369) (xy 436.894447 -345.492369) (xy 436.894447 -345.437831) (xy 436.90221 -345.383848)
			(xy 436.917576 -345.331519) (xy 436.940233 -345.281909) (xy 436.96972 -345.23603) (xy 437.005436 -345.194814)
			(xy 437.046655 -345.159101) (xy 437.092538 -345.129617) (xy 437.142149 -345.106964) (xy 437.194479 -345.091603)
			(xy 437.248463 -345.083845) (xy 437.275732 -345.083384) (xy 438.139332 -345.083384) (xy 438.166603 -345.083781)
			(xy 438.22059 -345.091547) (xy 438.272922 -345.106917) (xy 438.322534 -345.129578) (xy 438.368416 -345.159068)
			(xy 438.409635 -345.194788) (xy 438.445351 -345.236009) (xy 438.474838 -345.281894) (xy 438.497494 -345.331508)
			(xy 438.51286 -345.383842) (xy 438.520622 -345.437829) (xy 438.520622 -345.492366) (xy 440.00347 -345.492366)
			(xy 440.00347 -345.437834) (xy 440.011231 -345.383858) (xy 440.026594 -345.331535) (xy 440.049247 -345.281932)
			(xy 440.078728 -345.236057) (xy 440.114438 -345.194844) (xy 440.15565 -345.159133) (xy 440.201525 -345.129651)
			(xy 440.251128 -345.106997) (xy 440.30345 -345.091633) (xy 440.357426 -345.083871) (xy 440.384692 -345.083384)
			(xy 441.248292 -345.083384) (xy 441.275567 -345.083755) (xy 441.329561 -345.091517) (xy 441.381901 -345.106885)
			(xy 441.431521 -345.129544) (xy 441.477411 -345.159035) (xy 441.518637 -345.194757) (xy 441.55436 -345.235982)
			(xy 441.583852 -345.281872) (xy 441.606513 -345.331492) (xy 441.621881 -345.383831) (xy 441.629644 -345.437825)
			(xy 441.629644 -345.492375) (xy 441.621881 -345.546369) (xy 441.606513 -345.598708) (xy 441.583852 -345.648328)
			(xy 441.55436 -345.694218) (xy 441.518637 -345.735443) (xy 441.477411 -345.771165) (xy 441.431521 -345.800656)
			(xy 441.381901 -345.823315) (xy 441.329561 -345.838683) (xy 441.275567 -345.846445) (xy 441.248292 -345.846908)
			(xy 440.384692 -345.846908) (xy 440.357426 -345.846329) (xy 440.30345 -345.838567) (xy 440.251128 -345.823203)
			(xy 440.201525 -345.800549) (xy 440.15565 -345.771067) (xy 440.114438 -345.735356) (xy 440.078728 -345.694143)
			(xy 440.049247 -345.648268) (xy 440.026594 -345.598665) (xy 440.011231 -345.546342) (xy 440.00347 -345.492366)
			(xy 438.520622 -345.492366) (xy 438.520622 -345.492371) (xy 438.51286 -345.546358) (xy 438.497494 -345.598692)
			(xy 438.474838 -345.648306) (xy 438.445351 -345.694191) (xy 438.409635 -345.735412) (xy 438.368416 -345.771132)
			(xy 438.322534 -345.800622) (xy 438.272922 -345.823283) (xy 438.22059 -345.838653) (xy 438.166603 -345.846419)
			(xy 438.139332 -345.846908) (xy 437.275732 -345.846908) (xy 437.248463 -345.846355) (xy 437.194479 -345.838597)
			(xy 437.142149 -345.823236) (xy 437.092538 -345.800583) (xy 437.046655 -345.771099) (xy 437.005436 -345.735386)
			(xy 436.96972 -345.69417) (xy 436.940233 -345.648291) (xy 436.917576 -345.598681) (xy 436.90221 -345.546352)
			(xy 436.894447 -345.492369) (xy 435.411744 -345.492369) (xy 435.411744 -345.492376) (xy 435.403981 -345.546371)
			(xy 435.388611 -345.598713) (xy 435.365949 -345.648334) (xy 435.336455 -345.694224) (xy 435.30073 -345.73545)
			(xy 435.259502 -345.771172) (xy 435.213609 -345.800662) (xy 435.163986 -345.823321) (xy 435.111644 -345.838686)
			(xy 435.057648 -345.846446) (xy 435.030372 -345.846908) (xy 434.166772 -345.846908) (xy 434.139507 -345.846328)
			(xy 434.085533 -345.838564) (xy 434.033213 -345.823198) (xy 433.983613 -345.800543) (xy 433.937741 -345.77106)
			(xy 433.896531 -345.735349) (xy 433.860823 -345.694137) (xy 433.831344 -345.648263) (xy 433.808692 -345.59866)
			(xy 433.79333 -345.546339) (xy 433.78557 -345.492365) (xy 432.302721 -345.492365) (xy 432.302721 -345.492372)
			(xy 432.294959 -345.546361) (xy 432.279593 -345.598696) (xy 432.256935 -345.648311) (xy 432.227446 -345.694197)
			(xy 432.191728 -345.735419) (xy 432.150507 -345.771139) (xy 432.104622 -345.800629) (xy 432.055007 -345.823288)
			(xy 432.002673 -345.838657) (xy 431.948684 -345.846421) (xy 431.921412 -345.846908) (xy 431.057812 -345.846908)
			(xy 431.030544 -345.846353) (xy 430.976562 -345.838594) (xy 430.924234 -345.82323) (xy 430.874626 -345.800576)
			(xy 430.828746 -345.771092) (xy 430.787529 -345.735379) (xy 430.751815 -345.694164) (xy 430.72233 -345.648285)
			(xy 430.699674 -345.598677) (xy 430.684309 -345.54635) (xy 430.676547 -345.492368) (xy 429.193844 -345.492368)
			(xy 429.193844 -345.492376) (xy 429.18608 -345.546374) (xy 429.170709 -345.598717) (xy 429.148046 -345.648339)
			(xy 429.11855 -345.694231) (xy 429.082823 -345.735457) (xy 429.041592 -345.771179) (xy 428.995697 -345.800669)
			(xy 428.946072 -345.823326) (xy 428.893727 -345.83869) (xy 428.839729 -345.846448) (xy 428.812452 -345.846908)
			(xy 427.948852 -345.846908) (xy 427.921588 -345.846326) (xy 427.867616 -345.83856) (xy 427.815299 -345.823192)
			(xy 427.765701 -345.800536) (xy 427.719831 -345.771053) (xy 427.678624 -345.735342) (xy 427.642919 -345.69413)
			(xy 427.613441 -345.648257) (xy 427.590791 -345.598656) (xy 427.57543 -345.546337) (xy 427.56767 -345.492364)
			(xy 426.084844 -345.492364) (xy 426.084844 -345.492375) (xy 426.077081 -345.546369) (xy 426.061713 -345.598708)
			(xy 426.039052 -345.648328) (xy 426.00956 -345.694218) (xy 425.973837 -345.735443) (xy 425.932611 -345.771165)
			(xy 425.886721 -345.800656) (xy 425.837101 -345.823315) (xy 425.784761 -345.838683) (xy 425.730767 -345.846445)
			(xy 425.703492 -345.846908) (xy 424.839892 -345.846908) (xy 424.812626 -345.846329) (xy 424.75865 -345.838567)
			(xy 424.706328 -345.823203) (xy 424.656725 -345.800549) (xy 424.61085 -345.771067) (xy 424.569638 -345.735356)
			(xy 424.533928 -345.694143) (xy 424.504447 -345.648268) (xy 424.481794 -345.598665) (xy 424.466431 -345.546342)
			(xy 424.45867 -345.492366) (xy 422.975822 -345.492366) (xy 422.975822 -345.492371) (xy 422.96806 -345.546358)
			(xy 422.952694 -345.598692) (xy 422.930038 -345.648306) (xy 422.900551 -345.694191) (xy 422.864835 -345.735412)
			(xy 422.823616 -345.771132) (xy 422.777734 -345.800622) (xy 422.728122 -345.823283) (xy 422.67579 -345.838653)
			(xy 422.621803 -345.846419) (xy 422.594532 -345.846908) (xy 421.730932 -345.846908) (xy 421.703663 -345.846355)
			(xy 421.649679 -345.838597) (xy 421.597349 -345.823236) (xy 421.547738 -345.800583) (xy 421.501855 -345.771099)
			(xy 421.460636 -345.735386) (xy 421.42492 -345.69417) (xy 421.395433 -345.648291) (xy 421.372776 -345.598681)
			(xy 421.35741 -345.546352) (xy 421.349647 -345.492369) (xy 419.866944 -345.492369) (xy 419.866944 -345.492376)
			(xy 419.859181 -345.546371) (xy 419.843811 -345.598713) (xy 419.821149 -345.648334) (xy 419.791655 -345.694224)
			(xy 419.75593 -345.73545) (xy 419.714702 -345.771172) (xy 419.668809 -345.800662) (xy 419.619186 -345.823321)
			(xy 419.566844 -345.838686) (xy 419.512848 -345.846446) (xy 419.485572 -345.846908) (xy 418.621972 -345.846908)
			(xy 418.594707 -345.846328) (xy 418.540733 -345.838564) (xy 418.488413 -345.823198) (xy 418.438813 -345.800543)
			(xy 418.392941 -345.77106) (xy 418.351731 -345.735349) (xy 418.316023 -345.694137) (xy 418.286544 -345.648263)
			(xy 418.263892 -345.59866) (xy 418.24853 -345.546339) (xy 418.24077 -345.492365) (xy 416.757921 -345.492365)
			(xy 416.757921 -345.492372) (xy 416.750159 -345.546361) (xy 416.734793 -345.598696) (xy 416.712135 -345.648311)
			(xy 416.682646 -345.694197) (xy 416.646928 -345.735419) (xy 416.605707 -345.771139) (xy 416.559822 -345.800629)
			(xy 416.510207 -345.823288) (xy 416.457873 -345.838657) (xy 416.403884 -345.846421) (xy 416.376612 -345.846908)
			(xy 415.513012 -345.846908) (xy 415.485744 -345.846353) (xy 415.431762 -345.838594) (xy 415.379434 -345.82323)
			(xy 415.329826 -345.800576) (xy 415.283946 -345.771092) (xy 415.242729 -345.735379) (xy 415.207015 -345.694164)
			(xy 415.17753 -345.648285) (xy 415.154874 -345.598677) (xy 415.139509 -345.54635) (xy 415.131747 -345.492368)
			(xy 413.649044 -345.492368) (xy 413.649044 -345.492376) (xy 413.64128 -345.546374) (xy 413.625909 -345.598717)
			(xy 413.603246 -345.648339) (xy 413.57375 -345.694231) (xy 413.538023 -345.735457) (xy 413.496792 -345.771179)
			(xy 413.450897 -345.800669) (xy 413.401272 -345.823326) (xy 413.348927 -345.83869) (xy 413.294929 -345.846448)
			(xy 413.267652 -345.846908) (xy 412.404052 -345.846908) (xy 412.376788 -345.846326) (xy 412.322816 -345.83856)
			(xy 412.270499 -345.823192) (xy 412.220901 -345.800536) (xy 412.175031 -345.771053) (xy 412.133824 -345.735342)
			(xy 412.098119 -345.69413) (xy 412.068641 -345.648257) (xy 412.045991 -345.598656) (xy 412.03063 -345.546337)
			(xy 412.02287 -345.492364) (xy 410.540044 -345.492364) (xy 410.540044 -345.492375) (xy 410.532281 -345.546369)
			(xy 410.516913 -345.598708) (xy 410.494252 -345.648328) (xy 410.46476 -345.694218) (xy 410.429037 -345.735443)
			(xy 410.387811 -345.771165) (xy 410.341921 -345.800656) (xy 410.292301 -345.823315) (xy 410.239961 -345.838683)
			(xy 410.185967 -345.846445) (xy 410.158692 -345.846908) (xy 409.295092 -345.846908) (xy 409.267826 -345.846329)
			(xy 409.21385 -345.838567) (xy 409.161528 -345.823203) (xy 409.111925 -345.800549) (xy 409.06605 -345.771067)
			(xy 409.024838 -345.735356) (xy 408.989128 -345.694143) (xy 408.959647 -345.648268) (xy 408.936994 -345.598665)
			(xy 408.921631 -345.546342) (xy 408.91387 -345.492366) (xy 403.522544 -345.492366) (xy 403.522544 -345.492375)
			(xy 403.514781 -345.54637) (xy 403.499412 -345.598711) (xy 403.47675 -345.648331) (xy 403.447257 -345.694221)
			(xy 403.411533 -345.735447) (xy 403.370305 -345.771169) (xy 403.324414 -345.800659) (xy 403.274792 -345.823319)
			(xy 403.222451 -345.838685) (xy 403.168455 -345.846446) (xy 403.14118 -345.846908) (xy 402.27758 -345.846908)
			(xy 402.250315 -345.846328) (xy 402.19634 -345.838565) (xy 402.144019 -345.8232) (xy 402.094417 -345.800545)
			(xy 402.048545 -345.771063) (xy 402.007334 -345.735352) (xy 401.971625 -345.694139) (xy 401.942145 -345.648265)
			(xy 401.919493 -345.598662) (xy 401.90413 -345.546341) (xy 401.89637 -345.492365) (xy 400.413522 -345.492365)
			(xy 400.413522 -345.492372) (xy 400.405759 -345.54636) (xy 400.390393 -345.598694) (xy 400.367736 -345.648309)
			(xy 400.338248 -345.694195) (xy 400.302531 -345.735417) (xy 400.261311 -345.771136) (xy 400.215427 -345.800626)
			(xy 400.165813 -345.823286) (xy 400.11348 -345.838655) (xy 400.059492 -345.84642) (xy 400.03222 -345.846908)
			(xy 399.16862 -345.846908) (xy 399.141351 -345.846354) (xy 399.087369 -345.838595) (xy 399.03504 -345.823232)
			(xy 398.98543 -345.800579) (xy 398.93955 -345.771095) (xy 398.898332 -345.735382) (xy 398.862617 -345.694166)
			(xy 398.833131 -345.648287) (xy 398.810475 -345.598679) (xy 398.795109 -345.546351) (xy 398.787347 -345.492369)
			(xy 397.304644 -345.492369) (xy 397.304644 -345.492376) (xy 397.29688 -345.546373) (xy 397.28151 -345.598715)
			(xy 397.258847 -345.648337) (xy 397.229352 -345.694228) (xy 397.193626 -345.735454) (xy 397.152396 -345.771176)
			(xy 397.106502 -345.800666) (xy 397.056878 -345.823324) (xy 397.004534 -345.838689) (xy 396.950536 -345.846447)
			(xy 396.92326 -345.846908) (xy 396.05966 -345.846908) (xy 396.032396 -345.846327) (xy 395.978423 -345.838562)
			(xy 395.926105 -345.823195) (xy 395.876505 -345.800539) (xy 395.830635 -345.771055) (xy 395.789427 -345.735345)
			(xy 395.753721 -345.694133) (xy 395.724242 -345.648259) (xy 395.701591 -345.598658) (xy 395.68623 -345.546338)
			(xy 395.67847 -345.492364) (xy 394.195621 -345.492364) (xy 394.195621 -345.492373) (xy 394.187859 -345.546363)
			(xy 394.172492 -345.598699) (xy 394.149833 -345.648315) (xy 394.120343 -345.694201) (xy 394.084624 -345.735424)
			(xy 394.043401 -345.771143) (xy 393.997515 -345.800633) (xy 393.947899 -345.823292) (xy 393.895563 -345.838659)
			(xy 393.841573 -345.846421) (xy 393.8143 -345.846908) (xy 392.9507 -345.846908) (xy 392.923434 -345.84633)
			(xy 392.869457 -345.838569) (xy 392.817134 -345.823205) (xy 392.767529 -345.800552) (xy 392.721654 -345.77107)
			(xy 392.680441 -345.735359) (xy 392.64473 -345.694146) (xy 392.615248 -345.648271) (xy 392.592595 -345.598666)
			(xy 392.577231 -345.546343) (xy 392.56947 -345.492366) (xy 391.086622 -345.492366) (xy 391.086622 -345.492371)
			(xy 391.07886 -345.546357) (xy 391.063495 -345.59869) (xy 391.040839 -345.648304) (xy 391.011353 -345.694188)
			(xy 390.975638 -345.73541) (xy 390.93442 -345.771129) (xy 390.888539 -345.80062) (xy 390.838928 -345.823281)
			(xy 390.786597 -345.838651) (xy 390.732611 -345.846419) (xy 390.70534 -345.846908) (xy 389.84174 -345.846908)
			(xy 389.81447 -345.846355) (xy 389.760486 -345.838599) (xy 389.708155 -345.823238) (xy 389.658542 -345.800585)
			(xy 389.612659 -345.771102) (xy 389.571439 -345.735389) (xy 389.535722 -345.694173) (xy 389.506234 -345.648293)
			(xy 389.483576 -345.598683) (xy 389.46821 -345.546353) (xy 389.460447 -345.49237) (xy 387.977744 -345.49237)
			(xy 387.977744 -345.492375) (xy 387.969981 -345.54637) (xy 387.954612 -345.598711) (xy 387.93195 -345.648331)
			(xy 387.902457 -345.694221) (xy 387.866733 -345.735447) (xy 387.825505 -345.771169) (xy 387.779614 -345.800659)
			(xy 387.729992 -345.823319) (xy 387.677651 -345.838685) (xy 387.623655 -345.846446) (xy 387.59638 -345.846908)
			(xy 386.73278 -345.846908) (xy 386.705515 -345.846328) (xy 386.65154 -345.838565) (xy 386.599219 -345.8232)
			(xy 386.549617 -345.800545) (xy 386.503745 -345.771063) (xy 386.462534 -345.735352) (xy 386.426825 -345.694139)
			(xy 386.397345 -345.648265) (xy 386.374693 -345.598662) (xy 386.35933 -345.546341) (xy 386.35157 -345.492365)
			(xy 384.868722 -345.492365) (xy 384.868722 -345.492372) (xy 384.860959 -345.54636) (xy 384.845593 -345.598694)
			(xy 384.822936 -345.648309) (xy 384.793448 -345.694195) (xy 384.757731 -345.735417) (xy 384.716511 -345.771136)
			(xy 384.670627 -345.800626) (xy 384.621013 -345.823286) (xy 384.56868 -345.838655) (xy 384.514692 -345.84642)
			(xy 384.48742 -345.846908) (xy 383.62382 -345.846908) (xy 383.596551 -345.846354) (xy 383.542569 -345.838595)
			(xy 383.49024 -345.823232) (xy 383.44063 -345.800579) (xy 383.39475 -345.771095) (xy 383.353532 -345.735382)
			(xy 383.317817 -345.694166) (xy 383.288331 -345.648287) (xy 383.265675 -345.598679) (xy 383.250309 -345.546351)
			(xy 383.242547 -345.492369) (xy 381.759844 -345.492369) (xy 381.759844 -345.492376) (xy 381.75208 -345.546373)
			(xy 381.73671 -345.598715) (xy 381.714047 -345.648337) (xy 381.684552 -345.694228) (xy 381.648826 -345.735454)
			(xy 381.607596 -345.771176) (xy 381.561702 -345.800666) (xy 381.512078 -345.823324) (xy 381.459734 -345.838689)
			(xy 381.405736 -345.846447) (xy 381.37846 -345.846908) (xy 380.51486 -345.846908) (xy 380.487596 -345.846327)
			(xy 380.433623 -345.838562) (xy 380.381305 -345.823195) (xy 380.331705 -345.800539) (xy 380.285835 -345.771055)
			(xy 380.244627 -345.735345) (xy 380.208921 -345.694133) (xy 380.179442 -345.648259) (xy 380.156791 -345.598658)
			(xy 380.14143 -345.546338) (xy 380.13367 -345.492364) (xy 378.650821 -345.492364) (xy 378.650821 -345.492373)
			(xy 378.643059 -345.546363) (xy 378.627692 -345.598699) (xy 378.605033 -345.648315) (xy 378.575543 -345.694201)
			(xy 378.539824 -345.735424) (xy 378.498601 -345.771143) (xy 378.452715 -345.800633) (xy 378.403099 -345.823292)
			(xy 378.350763 -345.838659) (xy 378.296773 -345.846421) (xy 378.2695 -345.846908) (xy 377.4059 -345.846908)
			(xy 377.378634 -345.84633) (xy 377.324657 -345.838569) (xy 377.272334 -345.823205) (xy 377.222729 -345.800552)
			(xy 377.176854 -345.77107) (xy 377.135641 -345.735359) (xy 377.09993 -345.694146) (xy 377.070448 -345.648271)
			(xy 377.047795 -345.598666) (xy 377.032431 -345.546343) (xy 377.02467 -345.492366) (xy 375.541822 -345.492366)
			(xy 375.541822 -345.492371) (xy 375.53406 -345.546357) (xy 375.518695 -345.59869) (xy 375.496039 -345.648304)
			(xy 375.466553 -345.694188) (xy 375.430838 -345.73541) (xy 375.38962 -345.771129) (xy 375.343739 -345.80062)
			(xy 375.294128 -345.823281) (xy 375.241797 -345.838651) (xy 375.187811 -345.846419) (xy 375.16054 -345.846908)
			(xy 374.29694 -345.846908) (xy 374.26967 -345.846355) (xy 374.215686 -345.838599) (xy 374.163355 -345.823238)
			(xy 374.113742 -345.800585) (xy 374.067859 -345.771102) (xy 374.026639 -345.735389) (xy 373.990922 -345.694173)
			(xy 373.961434 -345.648293) (xy 373.938776 -345.598683) (xy 373.92341 -345.546353) (xy 373.915647 -345.49237)
			(xy 372.432944 -345.49237) (xy 372.432944 -345.492375) (xy 372.425181 -345.54637) (xy 372.409812 -345.598711)
			(xy 372.38715 -345.648331) (xy 372.357657 -345.694221) (xy 372.321933 -345.735447) (xy 372.280705 -345.771169)
			(xy 372.234814 -345.800659) (xy 372.185192 -345.823319) (xy 372.132851 -345.838685) (xy 372.078855 -345.846446)
			(xy 372.05158 -345.846908) (xy 371.18798 -345.846908) (xy 371.160715 -345.846328) (xy 371.10674 -345.838565)
			(xy 371.054419 -345.8232) (xy 371.004817 -345.800545) (xy 370.958945 -345.771063) (xy 370.917734 -345.735352)
			(xy 370.882025 -345.694139) (xy 370.852545 -345.648265) (xy 370.829893 -345.598662) (xy 370.81453 -345.546341)
			(xy 370.80677 -345.492365) (xy 344.837321 -345.492365) (xy 344.837321 -345.492372) (xy 344.829559 -345.546362)
			(xy 344.814192 -345.598698) (xy 344.791533 -345.648314) (xy 344.762044 -345.6942) (xy 344.726325 -345.735422)
			(xy 344.685103 -345.771142) (xy 344.639217 -345.800631) (xy 344.589601 -345.823291) (xy 344.537266 -345.838658)
			(xy 344.483276 -345.846421) (xy 344.456004 -345.846908) (xy 343.592404 -345.846908) (xy 343.565136 -345.846353)
			(xy 343.511155 -345.838592) (xy 343.458828 -345.823228) (xy 343.409221 -345.800573) (xy 343.363342 -345.771089)
			(xy 343.322126 -345.735376) (xy 343.286413 -345.694161) (xy 343.256928 -345.648283) (xy 343.234273 -345.598675)
			(xy 343.218909 -345.546349) (xy 343.211147 -345.492368) (xy 341.728322 -345.492368) (xy 341.728322 -345.492371)
			(xy 341.72056 -345.546357) (xy 341.705195 -345.598689) (xy 341.682539 -345.648302) (xy 341.653054 -345.694187)
			(xy 341.617339 -345.735408) (xy 341.576122 -345.771128) (xy 341.530241 -345.800618) (xy 341.48063 -345.82328)
			(xy 341.4283 -345.838651) (xy 341.374315 -345.846418) (xy 341.347044 -345.846908) (xy 340.483444 -345.846908)
			(xy 340.456174 -345.846356) (xy 340.402189 -345.8386) (xy 340.349857 -345.823239) (xy 340.300245 -345.800587)
			(xy 340.254361 -345.771104) (xy 340.213141 -345.735391) (xy 340.177423 -345.694174) (xy 340.147935 -345.648294)
			(xy 340.125276 -345.598684) (xy 340.10991 -345.546354) (xy 340.102148 -345.49237) (xy 338.619444 -345.49237)
			(xy 338.619444 -345.492375) (xy 338.611681 -345.54637) (xy 338.596312 -345.59871) (xy 338.57365 -345.64833)
			(xy 338.544158 -345.69422) (xy 338.508434 -345.735446) (xy 338.467207 -345.771167) (xy 338.421316 -345.800658)
			(xy 338.371695 -345.823318) (xy 338.319354 -345.838684) (xy 338.265359 -345.846445) (xy 338.238084 -345.846908)
			(xy 337.374484 -345.846908) (xy 337.347219 -345.846329) (xy 337.293243 -345.838566) (xy 337.240922 -345.823201)
			(xy 337.19132 -345.800547) (xy 337.145446 -345.771064) (xy 337.104236 -345.735353) (xy 337.068526 -345.694141)
			(xy 337.039046 -345.648266) (xy 337.016393 -345.598663) (xy 337.001031 -345.546341) (xy 336.99327 -345.492365)
			(xy 335.510422 -345.492365) (xy 335.510422 -345.492372) (xy 335.50266 -345.54636) (xy 335.487294 -345.598693)
			(xy 335.464636 -345.648308) (xy 335.435149 -345.694193) (xy 335.399432 -345.735415) (xy 335.358213 -345.771135)
			(xy 335.312329 -345.800625) (xy 335.262716 -345.823285) (xy 335.210383 -345.838654) (xy 335.156396 -345.84642)
			(xy 335.129124 -345.846908) (xy 334.265524 -345.846908) (xy 334.238255 -345.846354) (xy 334.184272 -345.838596)
			(xy 334.131943 -345.823234) (xy 334.082333 -345.80058) (xy 334.036452 -345.771097) (xy 333.995234 -345.735383)
			(xy 333.959518 -345.694168) (xy 333.930031 -345.648288) (xy 333.907375 -345.59868) (xy 333.892009 -345.546351)
			(xy 333.884247 -345.492369) (xy 332.401544 -345.492369) (xy 332.401544 -345.492376) (xy 332.39378 -345.546372)
			(xy 332.37841 -345.598714) (xy 332.355747 -345.648336) (xy 332.326253 -345.694227) (xy 332.290527 -345.735453)
			(xy 332.249298 -345.771174) (xy 332.203404 -345.800665) (xy 332.153781 -345.823323) (xy 332.101437 -345.838688)
			(xy 332.04744 -345.846447) (xy 332.020164 -345.846908) (xy 331.156564 -345.846908) (xy 331.1293 -345.846327)
			(xy 331.075326 -345.838562) (xy 331.023007 -345.823196) (xy 330.973408 -345.80054) (xy 330.927537 -345.771057)
			(xy 330.886329 -345.735346) (xy 330.850622 -345.694134) (xy 330.821143 -345.648261) (xy 330.798492 -345.598659)
			(xy 330.78313 -345.546338) (xy 330.77537 -345.492364) (xy 329.292521 -345.492364) (xy 329.292521 -345.492372)
			(xy 329.284759 -345.546362) (xy 329.269392 -345.598698) (xy 329.246733 -345.648314) (xy 329.217244 -345.6942)
			(xy 329.181525 -345.735422) (xy 329.140303 -345.771142) (xy 329.094417 -345.800631) (xy 329.044801 -345.823291)
			(xy 328.992466 -345.838658) (xy 328.938476 -345.846421) (xy 328.911204 -345.846908) (xy 328.047604 -345.846908)
			(xy 328.020336 -345.846353) (xy 327.966355 -345.838592) (xy 327.914028 -345.823228) (xy 327.864421 -345.800573)
			(xy 327.818542 -345.771089) (xy 327.777326 -345.735376) (xy 327.741613 -345.694161) (xy 327.712128 -345.648283)
			(xy 327.689473 -345.598675) (xy 327.674109 -345.546349) (xy 327.666347 -345.492368) (xy 326.183522 -345.492368)
			(xy 326.183522 -345.492371) (xy 326.17576 -345.546357) (xy 326.160395 -345.598689) (xy 326.137739 -345.648302)
			(xy 326.108254 -345.694187) (xy 326.072539 -345.735408) (xy 326.031322 -345.771128) (xy 325.985441 -345.800618)
			(xy 325.93583 -345.82328) (xy 325.8835 -345.838651) (xy 325.829515 -345.846418) (xy 325.802244 -345.846908)
			(xy 324.938644 -345.846908) (xy 324.911374 -345.846356) (xy 324.857389 -345.8386) (xy 324.805057 -345.823239)
			(xy 324.755445 -345.800587) (xy 324.709561 -345.771104) (xy 324.668341 -345.735391) (xy 324.632623 -345.694174)
			(xy 324.603135 -345.648294) (xy 324.580476 -345.598684) (xy 324.56511 -345.546354) (xy 324.557348 -345.49237)
			(xy 323.074644 -345.49237) (xy 323.074644 -345.492375) (xy 323.066881 -345.54637) (xy 323.051512 -345.59871)
			(xy 323.02885 -345.64833) (xy 322.999358 -345.69422) (xy 322.963634 -345.735446) (xy 322.922407 -345.771167)
			(xy 322.876516 -345.800658) (xy 322.826895 -345.823318) (xy 322.774554 -345.838684) (xy 322.720559 -345.846445)
			(xy 322.693284 -345.846908) (xy 321.829684 -345.846908) (xy 321.802419 -345.846329) (xy 321.748443 -345.838566)
			(xy 321.696122 -345.823201) (xy 321.64652 -345.800547) (xy 321.600646 -345.771064) (xy 321.559436 -345.735353)
			(xy 321.523726 -345.694141) (xy 321.494246 -345.648266) (xy 321.471593 -345.598663) (xy 321.456231 -345.546341)
			(xy 321.44847 -345.492365) (xy 319.965622 -345.492365) (xy 319.965622 -345.492372) (xy 319.95786 -345.54636)
			(xy 319.942494 -345.598693) (xy 319.919836 -345.648308) (xy 319.890349 -345.694193) (xy 319.854632 -345.735415)
			(xy 319.813413 -345.771135) (xy 319.767529 -345.800625) (xy 319.717916 -345.823285) (xy 319.665583 -345.838654)
			(xy 319.611596 -345.84642) (xy 319.584324 -345.846908) (xy 318.720724 -345.846908) (xy 318.693455 -345.846354)
			(xy 318.639472 -345.838596) (xy 318.587143 -345.823234) (xy 318.537533 -345.80058) (xy 318.491652 -345.771097)
			(xy 318.450434 -345.735383) (xy 318.414718 -345.694168) (xy 318.385231 -345.648288) (xy 318.362575 -345.59868)
			(xy 318.347209 -345.546351) (xy 318.339447 -345.492369) (xy 316.856744 -345.492369) (xy 316.856744 -345.492376)
			(xy 316.84898 -345.546372) (xy 316.83361 -345.598714) (xy 316.810947 -345.648336) (xy 316.781453 -345.694227)
			(xy 316.745727 -345.735453) (xy 316.704498 -345.771174) (xy 316.658604 -345.800665) (xy 316.608981 -345.823323)
			(xy 316.556637 -345.838688) (xy 316.50264 -345.846447) (xy 316.475364 -345.846908) (xy 315.611764 -345.846908)
			(xy 315.5845 -345.846327) (xy 315.530526 -345.838562) (xy 315.478207 -345.823196) (xy 315.428608 -345.80054)
			(xy 315.382737 -345.771057) (xy 315.341529 -345.735346) (xy 315.305822 -345.694134) (xy 315.276343 -345.648261)
			(xy 315.253692 -345.598659) (xy 315.23833 -345.546338) (xy 315.23057 -345.492364) (xy 313.747721 -345.492364)
			(xy 313.747721 -345.492372) (xy 313.739959 -345.546362) (xy 313.724592 -345.598698) (xy 313.701933 -345.648314)
			(xy 313.672444 -345.6942) (xy 313.636725 -345.735422) (xy 313.595503 -345.771142) (xy 313.549617 -345.800631)
			(xy 313.500001 -345.823291) (xy 313.447666 -345.838658) (xy 313.393676 -345.846421) (xy 313.366404 -345.846908)
			(xy 312.502804 -345.846908) (xy 312.475536 -345.846353) (xy 312.421555 -345.838592) (xy 312.369228 -345.823228)
			(xy 312.319621 -345.800573) (xy 312.273742 -345.771089) (xy 312.232526 -345.735376) (xy 312.196813 -345.694161)
			(xy 312.167328 -345.648283) (xy 312.144673 -345.598675) (xy 312.129309 -345.546349) (xy 312.121547 -345.492368)
			(xy 300.231621 -345.492368) (xy 300.231621 -345.492373) (xy 300.223859 -345.546362) (xy 300.208492 -345.598698)
			(xy 300.185833 -345.648314) (xy 300.156344 -345.6942) (xy 300.120624 -345.735423) (xy 300.079402 -345.771143)
			(xy 300.033516 -345.800632) (xy 299.9839 -345.823291) (xy 299.931564 -345.838658) (xy 299.877575 -345.846421)
			(xy 299.850302 -345.846908) (xy 298.986702 -345.846908) (xy 298.959434 -345.846353) (xy 298.905454 -345.838592)
			(xy 298.853127 -345.823228) (xy 298.80352 -345.800573) (xy 298.757641 -345.771089) (xy 298.716426 -345.735376)
			(xy 298.680712 -345.69416) (xy 298.651228 -345.648282) (xy 298.628573 -345.598675) (xy 298.613209 -345.546348)
			(xy 298.605447 -345.492368) (xy 297.122622 -345.492368) (xy 297.122622 -345.492371) (xy 297.11486 -345.546357)
			(xy 297.099495 -345.59869) (xy 297.076839 -345.648303) (xy 297.047354 -345.694187) (xy 297.011639 -345.735409)
			(xy 296.970421 -345.771128) (xy 296.92454 -345.800619) (xy 296.874929 -345.82328) (xy 296.822598 -345.838651)
			(xy 296.768613 -345.846419) (xy 296.741342 -345.846908) (xy 295.877742 -345.846908) (xy 295.850472 -345.846355)
			(xy 295.796487 -345.838599) (xy 295.744156 -345.823238) (xy 295.694543 -345.800586) (xy 295.64866 -345.771103)
			(xy 295.60744 -345.73539) (xy 295.571722 -345.694174) (xy 295.542234 -345.648293) (xy 295.519576 -345.598683)
			(xy 295.50421 -345.546354) (xy 295.496448 -345.49237) (xy 294.013744 -345.49237) (xy 294.013744 -345.492375)
			(xy 294.005981 -345.54637) (xy 293.990612 -345.59871) (xy 293.96795 -345.648331) (xy 293.938457 -345.694221)
			(xy 293.902734 -345.735446) (xy 293.861506 -345.771168) (xy 293.815615 -345.800659) (xy 293.765994 -345.823318)
			(xy 293.713652 -345.838685) (xy 293.659657 -345.846446) (xy 293.632382 -345.846908) (xy 292.768782 -345.846908)
			(xy 292.741517 -345.846328) (xy 292.687542 -345.838566) (xy 292.635221 -345.823201) (xy 292.585619 -345.800546)
			(xy 292.539745 -345.771063) (xy 292.498535 -345.735352) (xy 292.462826 -345.69414) (xy 292.433345 -345.648266)
			(xy 292.410693 -345.598663) (xy 292.395331 -345.546341) (xy 292.38757 -345.492365) (xy 290.904722 -345.492365)
			(xy 290.904722 -345.492372) (xy 290.896959 -345.54636) (xy 290.881593 -345.598694) (xy 290.858936 -345.648309)
			(xy 290.829449 -345.694194) (xy 290.793732 -345.735416) (xy 290.752512 -345.771136) (xy 290.706628 -345.800626)
			(xy 290.657015 -345.823286) (xy 290.604681 -345.838655) (xy 290.550694 -345.84642) (xy 290.523422 -345.846908)
			(xy 289.659822 -345.846908) (xy 289.632553 -345.846354) (xy 289.57857 -345.838595) (xy 289.526241 -345.823233)
			(xy 289.476632 -345.800579) (xy 289.430751 -345.771096) (xy 289.389533 -345.735383) (xy 289.353817 -345.694167)
			(xy 289.324331 -345.648288) (xy 289.301675 -345.598679) (xy 289.286309 -345.546351) (xy 289.278547 -345.492369)
			(xy 287.795844 -345.492369) (xy 287.795844 -345.492376) (xy 287.78808 -345.546373) (xy 287.77271 -345.598715)
			(xy 287.750047 -345.648336) (xy 287.720552 -345.694227) (xy 287.684827 -345.735453) (xy 287.643597 -345.771175)
			(xy 287.597703 -345.800665) (xy 287.548079 -345.823323) (xy 287.495736 -345.838688) (xy 287.441738 -345.846447)
			(xy 287.414462 -345.846908) (xy 286.550862 -345.846908) (xy 286.523598 -345.846327) (xy 286.469625 -345.838562)
			(xy 286.417306 -345.823195) (xy 286.367707 -345.80054) (xy 286.321836 -345.771056) (xy 286.280628 -345.735345)
			(xy 286.244921 -345.694134) (xy 286.215442 -345.64826) (xy 286.192792 -345.598658) (xy 286.17743 -345.546338)
			(xy 286.16967 -345.492364) (xy 284.686821 -345.492364) (xy 284.686821 -345.492373) (xy 284.679059 -345.546362)
			(xy 284.663692 -345.598698) (xy 284.641033 -345.648314) (xy 284.611544 -345.6942) (xy 284.575824 -345.735423)
			(xy 284.534602 -345.771143) (xy 284.488716 -345.800632) (xy 284.4391 -345.823291) (xy 284.386764 -345.838658)
			(xy 284.332775 -345.846421) (xy 284.305502 -345.846908) (xy 283.441902 -345.846908) (xy 283.414634 -345.846353)
			(xy 283.360654 -345.838592) (xy 283.308327 -345.823228) (xy 283.25872 -345.800573) (xy 283.212841 -345.771089)
			(xy 283.171626 -345.735376) (xy 283.135912 -345.69416) (xy 283.106428 -345.648282) (xy 283.083773 -345.598675)
			(xy 283.068409 -345.546348) (xy 283.060647 -345.492368) (xy 281.577822 -345.492368) (xy 281.577822 -345.492371)
			(xy 281.57006 -345.546357) (xy 281.554695 -345.59869) (xy 281.532039 -345.648303) (xy 281.502554 -345.694187)
			(xy 281.466839 -345.735409) (xy 281.425621 -345.771128) (xy 281.37974 -345.800619) (xy 281.330129 -345.82328)
			(xy 281.277798 -345.838651) (xy 281.223813 -345.846419) (xy 281.196542 -345.846908) (xy 280.332942 -345.846908)
			(xy 280.305672 -345.846355) (xy 280.251687 -345.838599) (xy 280.199356 -345.823238) (xy 280.149743 -345.800586)
			(xy 280.10386 -345.771103) (xy 280.06264 -345.73539) (xy 280.026922 -345.694174) (xy 279.997434 -345.648293)
			(xy 279.974776 -345.598683) (xy 279.95941 -345.546354) (xy 279.951648 -345.49237) (xy 278.468944 -345.49237)
			(xy 278.468944 -345.492375) (xy 278.461181 -345.54637) (xy 278.445812 -345.59871) (xy 278.42315 -345.648331)
			(xy 278.393657 -345.694221) (xy 278.357934 -345.735446) (xy 278.316706 -345.771168) (xy 278.270815 -345.800659)
			(xy 278.221194 -345.823318) (xy 278.168852 -345.838685) (xy 278.114857 -345.846446) (xy 278.087582 -345.846908)
			(xy 277.223982 -345.846908) (xy 277.196717 -345.846328) (xy 277.142742 -345.838566) (xy 277.090421 -345.823201)
			(xy 277.040819 -345.800546) (xy 276.994945 -345.771063) (xy 276.953735 -345.735352) (xy 276.918026 -345.69414)
			(xy 276.888545 -345.648266) (xy 276.865893 -345.598663) (xy 276.850531 -345.546341) (xy 276.84277 -345.492365)
			(xy 275.359922 -345.492365) (xy 275.359922 -345.492372) (xy 275.352159 -345.54636) (xy 275.336793 -345.598694)
			(xy 275.314136 -345.648309) (xy 275.284649 -345.694194) (xy 275.248932 -345.735416) (xy 275.207712 -345.771136)
			(xy 275.161828 -345.800626) (xy 275.112215 -345.823286) (xy 275.059881 -345.838655) (xy 275.005894 -345.84642)
			(xy 274.978622 -345.846908) (xy 274.115022 -345.846908) (xy 274.087753 -345.846354) (xy 274.03377 -345.838595)
			(xy 273.981441 -345.823233) (xy 273.931832 -345.800579) (xy 273.885951 -345.771096) (xy 273.844733 -345.735383)
			(xy 273.809017 -345.694167) (xy 273.779531 -345.648288) (xy 273.756875 -345.598679) (xy 273.741509 -345.546351)
			(xy 273.733747 -345.492369) (xy 272.251044 -345.492369) (xy 272.251044 -345.492376) (xy 272.24328 -345.546373)
			(xy 272.22791 -345.598715) (xy 272.205247 -345.648336) (xy 272.175752 -345.694227) (xy 272.140027 -345.735453)
			(xy 272.098797 -345.771175) (xy 272.052903 -345.800665) (xy 272.003279 -345.823323) (xy 271.950936 -345.838688)
			(xy 271.896938 -345.846447) (xy 271.869662 -345.846908) (xy 271.006062 -345.846908) (xy 270.978798 -345.846327)
			(xy 270.924825 -345.838562) (xy 270.872506 -345.823195) (xy 270.822907 -345.80054) (xy 270.777036 -345.771056)
			(xy 270.735828 -345.735345) (xy 270.700121 -345.694134) (xy 270.670642 -345.64826) (xy 270.647992 -345.598658)
			(xy 270.63263 -345.546338) (xy 270.62487 -345.492364) (xy 269.142021 -345.492364) (xy 269.142021 -345.492373)
			(xy 269.134259 -345.546362) (xy 269.118892 -345.598698) (xy 269.096233 -345.648314) (xy 269.066744 -345.6942)
			(xy 269.031024 -345.735423) (xy 268.989802 -345.771143) (xy 268.943916 -345.800632) (xy 268.8943 -345.823291)
			(xy 268.841964 -345.838658) (xy 268.787975 -345.846421) (xy 268.760702 -345.846908) (xy 267.897102 -345.846908)
			(xy 267.869834 -345.846353) (xy 267.815854 -345.838592) (xy 267.763527 -345.823228) (xy 267.71392 -345.800573)
			(xy 267.668041 -345.771089) (xy 267.626826 -345.735376) (xy 267.591112 -345.69416) (xy 267.561628 -345.648282)
			(xy 267.538973 -345.598675) (xy 267.523609 -345.546348) (xy 267.515847 -345.492368) (xy 197.629644 -345.492368)
			(xy 197.629644 -345.492376) (xy 197.621881 -345.546371) (xy 197.606511 -345.598713) (xy 197.583849 -345.648334)
			(xy 197.554355 -345.694224) (xy 197.51863 -345.73545) (xy 197.477402 -345.771172) (xy 197.431509 -345.800662)
			(xy 197.381886 -345.823321) (xy 197.329544 -345.838686) (xy 197.275548 -345.846446) (xy 197.248272 -345.846908)
			(xy 196.384672 -345.846908) (xy 196.357407 -345.846328) (xy 196.303433 -345.838564) (xy 196.251113 -345.823198)
			(xy 196.201513 -345.800543) (xy 196.155641 -345.77106) (xy 196.114431 -345.735349) (xy 196.078723 -345.694137)
			(xy 196.049244 -345.648263) (xy 196.026592 -345.59866) (xy 196.01123 -345.546339) (xy 196.00347 -345.492365)
			(xy 194.520621 -345.492365) (xy 194.520621 -345.492372) (xy 194.512859 -345.546361) (xy 194.497493 -345.598696)
			(xy 194.474835 -345.648311) (xy 194.445346 -345.694197) (xy 194.409628 -345.735419) (xy 194.368407 -345.771139)
			(xy 194.322522 -345.800629) (xy 194.272907 -345.823288) (xy 194.220573 -345.838657) (xy 194.166584 -345.846421)
			(xy 194.139312 -345.846908) (xy 193.275712 -345.846908) (xy 193.248444 -345.846353) (xy 193.194462 -345.838594)
			(xy 193.142134 -345.82323) (xy 193.092526 -345.800576) (xy 193.046646 -345.771092) (xy 193.005429 -345.735379)
			(xy 192.969715 -345.694164) (xy 192.94023 -345.648285) (xy 192.917574 -345.598677) (xy 192.902209 -345.54635)
			(xy 192.894447 -345.492368) (xy 191.411744 -345.492368) (xy 191.411744 -345.492376) (xy 191.40398 -345.546374)
			(xy 191.388609 -345.598717) (xy 191.365946 -345.648339) (xy 191.33645 -345.694231) (xy 191.300723 -345.735457)
			(xy 191.259492 -345.771179) (xy 191.213597 -345.800669) (xy 191.163972 -345.823326) (xy 191.111627 -345.83869)
			(xy 191.057629 -345.846448) (xy 191.030352 -345.846908) (xy 190.166752 -345.846908) (xy 190.139488 -345.846326)
			(xy 190.085516 -345.83856) (xy 190.033199 -345.823192) (xy 189.983601 -345.800536) (xy 189.937731 -345.771053)
			(xy 189.896524 -345.735342) (xy 189.860819 -345.69413) (xy 189.831341 -345.648257) (xy 189.808691 -345.598656)
			(xy 189.79333 -345.546337) (xy 189.78557 -345.492364) (xy 188.302744 -345.492364) (xy 188.302744 -345.492375)
			(xy 188.294981 -345.546369) (xy 188.279613 -345.598708) (xy 188.256952 -345.648328) (xy 188.22746 -345.694218)
			(xy 188.191737 -345.735443) (xy 188.150511 -345.771165) (xy 188.104621 -345.800656) (xy 188.055001 -345.823315)
			(xy 188.002661 -345.838683) (xy 187.948667 -345.846445) (xy 187.921392 -345.846908) (xy 187.057792 -345.846908)
			(xy 187.030526 -345.846329) (xy 186.97655 -345.838567) (xy 186.924228 -345.823203) (xy 186.874625 -345.800549)
			(xy 186.82875 -345.771067) (xy 186.787538 -345.735356) (xy 186.751828 -345.694143) (xy 186.722347 -345.648268)
			(xy 186.699694 -345.598665) (xy 186.684331 -345.546342) (xy 186.67657 -345.492366) (xy 185.193722 -345.492366)
			(xy 185.193722 -345.492371) (xy 185.18596 -345.546358) (xy 185.170594 -345.598692) (xy 185.147938 -345.648306)
			(xy 185.118451 -345.694191) (xy 185.082735 -345.735412) (xy 185.041516 -345.771132) (xy 184.995634 -345.800622)
			(xy 184.946022 -345.823283) (xy 184.89369 -345.838653) (xy 184.839703 -345.846419) (xy 184.812432 -345.846908)
			(xy 183.948832 -345.846908) (xy 183.921563 -345.846355) (xy 183.867579 -345.838597) (xy 183.815249 -345.823236)
			(xy 183.765638 -345.800583) (xy 183.719755 -345.771099) (xy 183.678536 -345.735386) (xy 183.64282 -345.69417)
			(xy 183.613333 -345.648291) (xy 183.590676 -345.598681) (xy 183.57531 -345.546352) (xy 183.567547 -345.492369)
			(xy 182.084844 -345.492369) (xy 182.084844 -345.492376) (xy 182.077081 -345.546371) (xy 182.061711 -345.598713)
			(xy 182.039049 -345.648334) (xy 182.009555 -345.694224) (xy 181.97383 -345.73545) (xy 181.932602 -345.771172)
			(xy 181.886709 -345.800662) (xy 181.837086 -345.823321) (xy 181.784744 -345.838686) (xy 181.730748 -345.846446)
			(xy 181.703472 -345.846908) (xy 180.839872 -345.846908) (xy 180.812607 -345.846328) (xy 180.758633 -345.838564)
			(xy 180.706313 -345.823198) (xy 180.656713 -345.800543) (xy 180.610841 -345.77106) (xy 180.569631 -345.735349)
			(xy 180.533923 -345.694137) (xy 180.504444 -345.648263) (xy 180.481792 -345.59866) (xy 180.46643 -345.546339)
			(xy 180.45867 -345.492365) (xy 178.975821 -345.492365) (xy 178.975821 -345.492372) (xy 178.968059 -345.546361)
			(xy 178.952693 -345.598696) (xy 178.930035 -345.648311) (xy 178.900546 -345.694197) (xy 178.864828 -345.735419)
			(xy 178.823607 -345.771139) (xy 178.777722 -345.800629) (xy 178.728107 -345.823288) (xy 178.675773 -345.838657)
			(xy 178.621784 -345.846421) (xy 178.594512 -345.846908) (xy 177.730912 -345.846908) (xy 177.703644 -345.846353)
			(xy 177.649662 -345.838594) (xy 177.597334 -345.82323) (xy 177.547726 -345.800576) (xy 177.501846 -345.771092)
			(xy 177.460629 -345.735379) (xy 177.424915 -345.694164) (xy 177.39543 -345.648285) (xy 177.372774 -345.598677)
			(xy 177.357409 -345.54635) (xy 177.349647 -345.492368) (xy 175.866944 -345.492368) (xy 175.866944 -345.492376)
			(xy 175.85918 -345.546374) (xy 175.843809 -345.598717) (xy 175.821146 -345.648339) (xy 175.79165 -345.694231)
			(xy 175.755923 -345.735457) (xy 175.714692 -345.771179) (xy 175.668797 -345.800669) (xy 175.619172 -345.823326)
			(xy 175.566827 -345.83869) (xy 175.512829 -345.846448) (xy 175.485552 -345.846908) (xy 174.621952 -345.846908)
			(xy 174.594688 -345.846326) (xy 174.540716 -345.83856) (xy 174.488399 -345.823192) (xy 174.438801 -345.800536)
			(xy 174.392931 -345.771053) (xy 174.351724 -345.735342) (xy 174.316019 -345.69413) (xy 174.286541 -345.648257)
			(xy 174.263891 -345.598656) (xy 174.24853 -345.546337) (xy 174.24077 -345.492364) (xy 172.757944 -345.492364)
			(xy 172.757944 -345.492375) (xy 172.750181 -345.546369) (xy 172.734813 -345.598708) (xy 172.712152 -345.648328)
			(xy 172.68266 -345.694218) (xy 172.646937 -345.735443) (xy 172.605711 -345.771165) (xy 172.559821 -345.800656)
			(xy 172.510201 -345.823315) (xy 172.457861 -345.838683) (xy 172.403867 -345.846445) (xy 172.376592 -345.846908)
			(xy 171.512992 -345.846908) (xy 171.485726 -345.846329) (xy 171.43175 -345.838567) (xy 171.379428 -345.823203)
			(xy 171.329825 -345.800549) (xy 171.28395 -345.771067) (xy 171.242738 -345.735356) (xy 171.207028 -345.694143)
			(xy 171.177547 -345.648268) (xy 171.154894 -345.598665) (xy 171.139531 -345.546342) (xy 171.13177 -345.492366)
			(xy 169.648922 -345.492366) (xy 169.648922 -345.492371) (xy 169.64116 -345.546358) (xy 169.625794 -345.598692)
			(xy 169.603138 -345.648306) (xy 169.573651 -345.694191) (xy 169.537935 -345.735412) (xy 169.496716 -345.771132)
			(xy 169.450834 -345.800622) (xy 169.401222 -345.823283) (xy 169.34889 -345.838653) (xy 169.294903 -345.846419)
			(xy 169.267632 -345.846908) (xy 168.404032 -345.846908) (xy 168.376763 -345.846355) (xy 168.322779 -345.838597)
			(xy 168.270449 -345.823236) (xy 168.220838 -345.800583) (xy 168.174955 -345.771099) (xy 168.133736 -345.735386)
			(xy 168.09802 -345.69417) (xy 168.068533 -345.648291) (xy 168.045876 -345.598681) (xy 168.03051 -345.546352)
			(xy 168.022747 -345.492369) (xy 166.540044 -345.492369) (xy 166.540044 -345.492376) (xy 166.532281 -345.546371)
			(xy 166.516911 -345.598713) (xy 166.494249 -345.648334) (xy 166.464755 -345.694224) (xy 166.42903 -345.73545)
			(xy 166.387802 -345.771172) (xy 166.341909 -345.800662) (xy 166.292286 -345.823321) (xy 166.239944 -345.838686)
			(xy 166.185948 -345.846446) (xy 166.158672 -345.846908) (xy 165.295072 -345.846908) (xy 165.267807 -345.846328)
			(xy 165.213833 -345.838564) (xy 165.161513 -345.823198) (xy 165.111913 -345.800543) (xy 165.066041 -345.77106)
			(xy 165.024831 -345.735349) (xy 164.989123 -345.694137) (xy 164.959644 -345.648263) (xy 164.936992 -345.59866)
			(xy 164.92163 -345.546339) (xy 164.91387 -345.492365) (xy 144.196621 -345.492365) (xy 144.196621 -345.492372)
			(xy 144.188859 -345.546362) (xy 144.173492 -345.598697) (xy 144.150834 -345.648312) (xy 144.121345 -345.694199)
			(xy 144.085627 -345.735421) (xy 144.044405 -345.77114) (xy 143.99852 -345.80063) (xy 143.948904 -345.82329)
			(xy 143.89657 -345.838657) (xy 143.84258 -345.846421) (xy 143.815308 -345.846908) (xy 142.951708 -345.846908)
			(xy 142.92444 -345.846353) (xy 142.870459 -345.838593) (xy 142.818131 -345.823229) (xy 142.768523 -345.800575)
			(xy 142.722644 -345.771091) (xy 142.681428 -345.735378) (xy 142.645714 -345.694162) (xy 142.616229 -345.648284)
			(xy 142.593574 -345.598676) (xy 142.578209 -345.546349) (xy 142.570447 -345.492368) (xy 141.087622 -345.492368)
			(xy 141.087622 -345.49237) (xy 141.07986 -345.546356) (xy 141.064495 -345.598688) (xy 141.04184 -345.648301)
			(xy 141.012355 -345.694185) (xy 140.976641 -345.735407) (xy 140.935424 -345.771126) (xy 140.889543 -345.800617)
			(xy 140.839933 -345.823279) (xy 140.787603 -345.83865) (xy 140.733618 -345.846418) (xy 140.706348 -345.846908)
			(xy 139.842748 -345.846908) (xy 139.815478 -345.846356) (xy 139.761492 -345.8386) (xy 139.70916 -345.82324)
			(xy 139.659547 -345.800588) (xy 139.613663 -345.771105) (xy 139.572442 -345.735392) (xy 139.536724 -345.694176)
			(xy 139.507235 -345.648295) (xy 139.484577 -345.598685) (xy 139.46921 -345.546354) (xy 139.461448 -345.49237)
			(xy 137.978744 -345.49237) (xy 137.978744 -345.492375) (xy 137.970981 -345.546369) (xy 137.955612 -345.598709)
			(xy 137.932951 -345.648329) (xy 137.903459 -345.694219) (xy 137.867736 -345.735444) (xy 137.826509 -345.771166)
			(xy 137.780619 -345.800657) (xy 137.730998 -345.823316) (xy 137.678658 -345.838684) (xy 137.624663 -345.846445)
			(xy 137.597388 -345.846908) (xy 136.733788 -345.846908) (xy 136.706522 -345.846329) (xy 136.652547 -345.838567)
			(xy 136.600225 -345.823202) (xy 136.550622 -345.800548) (xy 136.504748 -345.771065) (xy 136.463537 -345.735354)
			(xy 136.427827 -345.694142) (xy 136.398346 -345.648267) (xy 136.375694 -345.598664) (xy 136.360331 -345.546342)
			(xy 136.35257 -345.492366) (xy 134.869722 -345.492366) (xy 134.869722 -345.492371) (xy 134.86196 -345.546359)
			(xy 134.846594 -345.598693) (xy 134.823937 -345.648307) (xy 134.79445 -345.694192) (xy 134.758734 -345.735414)
			(xy 134.717514 -345.771133) (xy 134.671632 -345.800624) (xy 134.622019 -345.823284) (xy 134.569686 -345.838654)
			(xy 134.515699 -345.84642) (xy 134.488428 -345.846908) (xy 133.624828 -345.846908) (xy 133.597559 -345.846355)
			(xy 133.543576 -345.838597) (xy 133.491246 -345.823235) (xy 133.441635 -345.800581) (xy 133.395753 -345.771098)
			(xy 133.354535 -345.735385) (xy 133.318819 -345.694169) (xy 133.289332 -345.648289) (xy 133.266675 -345.59868)
			(xy 133.251309 -345.546352) (xy 133.243547 -345.492369) (xy 131.760844 -345.492369) (xy 131.760844 -345.492376)
			(xy 131.75308 -345.546372) (xy 131.737711 -345.598713) (xy 131.715048 -345.648335) (xy 131.685554 -345.694225)
			(xy 131.649829 -345.735451) (xy 131.6086 -345.771173) (xy 131.562707 -345.800663) (xy 131.513083 -345.823322)
			(xy 131.460741 -345.838687) (xy 131.406744 -345.846447) (xy 131.379468 -345.846908) (xy 130.515868 -345.846908)
			(xy 130.488603 -345.846328) (xy 130.43463 -345.838563) (xy 130.38231 -345.823197) (xy 130.33271 -345.800542)
			(xy 130.286839 -345.771058) (xy 130.24563 -345.735347) (xy 130.209922 -345.694136) (xy 130.180443 -345.648262)
			(xy 130.157792 -345.59866) (xy 130.14243 -345.546339) (xy 130.13467 -345.492365) (xy 128.651821 -345.492365)
			(xy 128.651821 -345.492372) (xy 128.644059 -345.546362) (xy 128.628692 -345.598697) (xy 128.606034 -345.648312)
			(xy 128.576545 -345.694199) (xy 128.540827 -345.735421) (xy 128.499605 -345.77114) (xy 128.45372 -345.80063)
			(xy 128.404104 -345.82329) (xy 128.35177 -345.838657) (xy 128.29778 -345.846421) (xy 128.270508 -345.846908)
			(xy 127.406908 -345.846908) (xy 127.37964 -345.846353) (xy 127.325659 -345.838593) (xy 127.273331 -345.823229)
			(xy 127.223723 -345.800575) (xy 127.177844 -345.771091) (xy 127.136628 -345.735378) (xy 127.100914 -345.694162)
			(xy 127.071429 -345.648284) (xy 127.048774 -345.598676) (xy 127.033409 -345.546349) (xy 127.025647 -345.492368)
			(xy 125.542822 -345.492368) (xy 125.542822 -345.49237) (xy 125.53506 -345.546356) (xy 125.519695 -345.598688)
			(xy 125.49704 -345.648301) (xy 125.467555 -345.694185) (xy 125.431841 -345.735407) (xy 125.390624 -345.771126)
			(xy 125.344743 -345.800617) (xy 125.295133 -345.823279) (xy 125.242803 -345.83865) (xy 125.188818 -345.846418)
			(xy 125.161548 -345.846908) (xy 124.297948 -345.846908) (xy 124.270678 -345.846356) (xy 124.216692 -345.8386)
			(xy 124.16436 -345.82324) (xy 124.114747 -345.800588) (xy 124.068863 -345.771105) (xy 124.027642 -345.735392)
			(xy 123.991924 -345.694176) (xy 123.962435 -345.648295) (xy 123.939777 -345.598685) (xy 123.92441 -345.546354)
			(xy 123.916648 -345.49237) (xy 122.433944 -345.49237) (xy 122.433944 -345.492375) (xy 122.426181 -345.546369)
			(xy 122.410812 -345.598709) (xy 122.388151 -345.648329) (xy 122.358659 -345.694219) (xy 122.322936 -345.735444)
			(xy 122.281709 -345.771166) (xy 122.235819 -345.800657) (xy 122.186198 -345.823316) (xy 122.133858 -345.838684)
			(xy 122.079863 -345.846445) (xy 122.052588 -345.846908) (xy 121.188988 -345.846908) (xy 121.161722 -345.846329)
			(xy 121.107747 -345.838567) (xy 121.055425 -345.823202) (xy 121.005822 -345.800548) (xy 120.959948 -345.771065)
			(xy 120.918737 -345.735354) (xy 120.883027 -345.694142) (xy 120.853546 -345.648267) (xy 120.830894 -345.598664)
			(xy 120.815531 -345.546342) (xy 120.80777 -345.492366) (xy 119.324922 -345.492366) (xy 119.324922 -345.492371)
			(xy 119.31716 -345.546359) (xy 119.301794 -345.598693) (xy 119.279137 -345.648307) (xy 119.24965 -345.694192)
			(xy 119.213934 -345.735414) (xy 119.172714 -345.771133) (xy 119.126832 -345.800624) (xy 119.077219 -345.823284)
			(xy 119.024886 -345.838654) (xy 118.970899 -345.84642) (xy 118.943628 -345.846908) (xy 118.080028 -345.846908)
			(xy 118.052759 -345.846355) (xy 117.998776 -345.838597) (xy 117.946446 -345.823235) (xy 117.896835 -345.800581)
			(xy 117.850953 -345.771098) (xy 117.809735 -345.735385) (xy 117.774019 -345.694169) (xy 117.744532 -345.648289)
			(xy 117.721875 -345.59868) (xy 117.706509 -345.546352) (xy 117.698747 -345.492369) (xy 116.216044 -345.492369)
			(xy 116.216044 -345.492376) (xy 116.20828 -345.546372) (xy 116.192911 -345.598713) (xy 116.170248 -345.648335)
			(xy 116.140754 -345.694225) (xy 116.105029 -345.735451) (xy 116.0638 -345.771173) (xy 116.017907 -345.800663)
			(xy 115.968283 -345.823322) (xy 115.915941 -345.838687) (xy 115.861944 -345.846447) (xy 115.834668 -345.846908)
			(xy 114.971068 -345.846908) (xy 114.943803 -345.846328) (xy 114.88983 -345.838563) (xy 114.83751 -345.823197)
			(xy 114.78791 -345.800542) (xy 114.742039 -345.771058) (xy 114.70083 -345.735347) (xy 114.665122 -345.694136)
			(xy 114.635643 -345.648262) (xy 114.612992 -345.59866) (xy 114.59763 -345.546339) (xy 114.58987 -345.492365)
			(xy 113.107021 -345.492365) (xy 113.107021 -345.492372) (xy 113.099259 -345.546362) (xy 113.083892 -345.598697)
			(xy 113.061234 -345.648312) (xy 113.031745 -345.694199) (xy 112.996027 -345.735421) (xy 112.954805 -345.77114)
			(xy 112.90892 -345.80063) (xy 112.859304 -345.82329) (xy 112.80697 -345.838657) (xy 112.75298 -345.846421)
			(xy 112.725708 -345.846908) (xy 111.862108 -345.846908) (xy 111.83484 -345.846353) (xy 111.780859 -345.838593)
			(xy 111.728531 -345.823229) (xy 111.678923 -345.800575) (xy 111.633044 -345.771091) (xy 111.591828 -345.735378)
			(xy 111.556114 -345.694162) (xy 111.526629 -345.648284) (xy 111.503974 -345.598676) (xy 111.488609 -345.546349)
			(xy 111.480847 -345.492368) (xy 93.706722 -345.492368) (xy 93.706722 -345.492371) (xy 93.69896 -345.546357)
			(xy 93.683595 -345.59869) (xy 93.660939 -345.648303) (xy 93.631454 -345.694187) (xy 93.595739 -345.735409)
			(xy 93.554521 -345.771128) (xy 93.50864 -345.800619) (xy 93.459029 -345.82328) (xy 93.406698 -345.838651)
			(xy 93.352713 -345.846419) (xy 93.325442 -345.846908) (xy 92.461842 -345.846908) (xy 92.434572 -345.846355)
			(xy 92.380587 -345.838599) (xy 92.328256 -345.823238) (xy 92.278643 -345.800586) (xy 92.23276 -345.771103)
			(xy 92.19154 -345.73539) (xy 92.155822 -345.694174) (xy 92.126334 -345.648293) (xy 92.103676 -345.598683)
			(xy 92.08831 -345.546354) (xy 92.080548 -345.49237) (xy 90.597844 -345.49237) (xy 90.597844 -345.492375)
			(xy 90.590081 -345.54637) (xy 90.574712 -345.59871) (xy 90.55205 -345.648331) (xy 90.522557 -345.694221)
			(xy 90.486834 -345.735446) (xy 90.445606 -345.771168) (xy 90.399715 -345.800659) (xy 90.350094 -345.823318)
			(xy 90.297752 -345.838685) (xy 90.243757 -345.846446) (xy 90.216482 -345.846908) (xy 89.352882 -345.846908)
			(xy 89.325617 -345.846328) (xy 89.271642 -345.838566) (xy 89.219321 -345.823201) (xy 89.169719 -345.800546)
			(xy 89.123845 -345.771063) (xy 89.082635 -345.735352) (xy 89.046926 -345.69414) (xy 89.017445 -345.648266)
			(xy 88.994793 -345.598663) (xy 88.979431 -345.546341) (xy 88.97167 -345.492365) (xy 87.488822 -345.492365)
			(xy 87.488822 -345.492372) (xy 87.481059 -345.54636) (xy 87.465693 -345.598694) (xy 87.443036 -345.648309)
			(xy 87.413549 -345.694194) (xy 87.377832 -345.735416) (xy 87.336612 -345.771136) (xy 87.290728 -345.800626)
			(xy 87.241115 -345.823286) (xy 87.188781 -345.838655) (xy 87.134794 -345.84642) (xy 87.107522 -345.846908)
			(xy 86.243922 -345.846908) (xy 86.216653 -345.846354) (xy 86.16267 -345.838595) (xy 86.110341 -345.823233)
			(xy 86.060732 -345.800579) (xy 86.014851 -345.771096) (xy 85.973633 -345.735383) (xy 85.937917 -345.694167)
			(xy 85.908431 -345.648288) (xy 85.885775 -345.598679) (xy 85.870409 -345.546351) (xy 85.862647 -345.492369)
			(xy 84.379944 -345.492369) (xy 84.379944 -345.492376) (xy 84.37218 -345.546373) (xy 84.35681 -345.598715)
			(xy 84.334147 -345.648336) (xy 84.304652 -345.694227) (xy 84.268927 -345.735453) (xy 84.227697 -345.771175)
			(xy 84.181803 -345.800665) (xy 84.132179 -345.823323) (xy 84.079836 -345.838688) (xy 84.025838 -345.846447)
			(xy 83.998562 -345.846908) (xy 83.134962 -345.846908) (xy 83.107698 -345.846327) (xy 83.053725 -345.838562)
			(xy 83.001406 -345.823195) (xy 82.951807 -345.80054) (xy 82.905936 -345.771056) (xy 82.864728 -345.735345)
			(xy 82.829021 -345.694134) (xy 82.799542 -345.64826) (xy 82.776892 -345.598658) (xy 82.76153 -345.546338)
			(xy 82.75377 -345.492364) (xy 81.270921 -345.492364) (xy 81.270921 -345.492373) (xy 81.263159 -345.546362)
			(xy 81.247792 -345.598698) (xy 81.225133 -345.648314) (xy 81.195644 -345.6942) (xy 81.159924 -345.735423)
			(xy 81.118702 -345.771143) (xy 81.072816 -345.800632) (xy 81.0232 -345.823291) (xy 80.970864 -345.838658)
			(xy 80.916875 -345.846421) (xy 80.889602 -345.846908) (xy 80.026002 -345.846908) (xy 79.998734 -345.846353)
			(xy 79.944754 -345.838592) (xy 79.892427 -345.823228) (xy 79.84282 -345.800573) (xy 79.796941 -345.771089)
			(xy 79.755726 -345.735376) (xy 79.720012 -345.69416) (xy 79.690528 -345.648282) (xy 79.667873 -345.598675)
			(xy 79.652509 -345.546348) (xy 79.644747 -345.492368) (xy 78.161922 -345.492368) (xy 78.161922 -345.492371)
			(xy 78.15416 -345.546357) (xy 78.138795 -345.59869) (xy 78.116139 -345.648303) (xy 78.086654 -345.694187)
			(xy 78.050939 -345.735409) (xy 78.009721 -345.771128) (xy 77.96384 -345.800619) (xy 77.914229 -345.82328)
			(xy 77.861898 -345.838651) (xy 77.807913 -345.846419) (xy 77.780642 -345.846908) (xy 76.917042 -345.846908)
			(xy 76.889772 -345.846355) (xy 76.835787 -345.838599) (xy 76.783456 -345.823238) (xy 76.733843 -345.800586)
			(xy 76.68796 -345.771103) (xy 76.64674 -345.73539) (xy 76.611022 -345.694174) (xy 76.581534 -345.648293)
			(xy 76.558876 -345.598683) (xy 76.54351 -345.546354) (xy 76.535748 -345.49237) (xy 75.053044 -345.49237)
			(xy 75.053044 -345.492375) (xy 75.045281 -345.54637) (xy 75.029912 -345.59871) (xy 75.00725 -345.648331)
			(xy 74.977757 -345.694221) (xy 74.942034 -345.735446) (xy 74.900806 -345.771168) (xy 74.854915 -345.800659)
			(xy 74.805294 -345.823318) (xy 74.752952 -345.838685) (xy 74.698957 -345.846446) (xy 74.671682 -345.846908)
			(xy 73.808082 -345.846908) (xy 73.780817 -345.846328) (xy 73.726842 -345.838566) (xy 73.674521 -345.823201)
			(xy 73.624919 -345.800546) (xy 73.579045 -345.771063) (xy 73.537835 -345.735352) (xy 73.502126 -345.69414)
			(xy 73.472645 -345.648266) (xy 73.449993 -345.598663) (xy 73.434631 -345.546341) (xy 73.42687 -345.492365)
			(xy 71.944022 -345.492365) (xy 71.944022 -345.492372) (xy 71.936259 -345.54636) (xy 71.920893 -345.598694)
			(xy 71.898236 -345.648309) (xy 71.868749 -345.694194) (xy 71.833032 -345.735416) (xy 71.791812 -345.771136)
			(xy 71.745928 -345.800626) (xy 71.696315 -345.823286) (xy 71.643981 -345.838655) (xy 71.589994 -345.84642)
			(xy 71.562722 -345.846908) (xy 70.699122 -345.846908) (xy 70.671853 -345.846354) (xy 70.61787 -345.838595)
			(xy 70.565541 -345.823233) (xy 70.515932 -345.800579) (xy 70.470051 -345.771096) (xy 70.428833 -345.735383)
			(xy 70.393117 -345.694167) (xy 70.363631 -345.648288) (xy 70.340975 -345.598679) (xy 70.325609 -345.546351)
			(xy 70.317847 -345.492369) (xy 68.835144 -345.492369) (xy 68.835144 -345.492376) (xy 68.82738 -345.546373)
			(xy 68.81201 -345.598715) (xy 68.789347 -345.648336) (xy 68.759852 -345.694227) (xy 68.724127 -345.735453)
			(xy 68.682897 -345.771175) (xy 68.637003 -345.800665) (xy 68.587379 -345.823323) (xy 68.535036 -345.838688)
			(xy 68.481038 -345.846447) (xy 68.453762 -345.846908) (xy 67.590162 -345.846908) (xy 67.562898 -345.846327)
			(xy 67.508925 -345.838562) (xy 67.456606 -345.823195) (xy 67.407007 -345.80054) (xy 67.361136 -345.771056)
			(xy 67.319928 -345.735345) (xy 67.284221 -345.694134) (xy 67.254742 -345.64826) (xy 67.232092 -345.598658)
			(xy 67.21673 -345.546338) (xy 67.20897 -345.492364) (xy 65.726121 -345.492364) (xy 65.726121 -345.492373)
			(xy 65.718359 -345.546362) (xy 65.702992 -345.598698) (xy 65.680333 -345.648314) (xy 65.650844 -345.6942)
			(xy 65.615124 -345.735423) (xy 65.573902 -345.771143) (xy 65.528016 -345.800632) (xy 65.4784 -345.823291)
			(xy 65.426064 -345.838658) (xy 65.372075 -345.846421) (xy 65.344802 -345.846908) (xy 64.481202 -345.846908)
			(xy 64.453934 -345.846353) (xy 64.399954 -345.838592) (xy 64.347627 -345.823228) (xy 64.29802 -345.800573)
			(xy 64.252141 -345.771089) (xy 64.210926 -345.735376) (xy 64.175212 -345.69416) (xy 64.145728 -345.648282)
			(xy 64.123073 -345.598675) (xy 64.107709 -345.546348) (xy 64.099947 -345.492368) (xy 62.617122 -345.492368)
			(xy 62.617122 -345.492371) (xy 62.60936 -345.546357) (xy 62.593995 -345.59869) (xy 62.571339 -345.648303)
			(xy 62.541854 -345.694187) (xy 62.506139 -345.735409) (xy 62.464921 -345.771128) (xy 62.41904 -345.800619)
			(xy 62.369429 -345.82328) (xy 62.317098 -345.838651) (xy 62.263113 -345.846419) (xy 62.235842 -345.846908)
			(xy 61.372242 -345.846908) (xy 61.344972 -345.846355) (xy 61.290987 -345.838599) (xy 61.238656 -345.823238)
			(xy 61.189043 -345.800586) (xy 61.14316 -345.771103) (xy 61.10194 -345.73539) (xy 61.066222 -345.694174)
			(xy 61.036734 -345.648293) (xy 61.014076 -345.598683) (xy 60.99871 -345.546354) (xy 60.990948 -345.49237)
			(xy 51.666922 -345.49237) (xy 51.65916 -345.546356) (xy 51.643795 -345.598688) (xy 51.62114 -345.648301)
			(xy 51.591655 -345.694185) (xy 51.555941 -345.735407) (xy 51.514724 -345.771126) (xy 51.468843 -345.800617)
			(xy 51.419233 -345.823279) (xy 51.366903 -345.83865) (xy 51.312918 -345.846418) (xy 51.285648 -345.846908)
			(xy 50.422048 -345.846908) (xy 50.394778 -345.846356) (xy 50.340792 -345.8386) (xy 50.28846 -345.82324)
			(xy 50.238847 -345.800588) (xy 50.192963 -345.771105) (xy 50.151742 -345.735392) (xy 50.116024 -345.694176)
			(xy 50.086535 -345.648295) (xy 50.063877 -345.598685) (xy 50.04851 -345.546354) (xy 50.040748 -345.49237)
			(xy 48.558044 -345.49237) (xy 48.558044 -345.492375) (xy 48.550281 -345.546369) (xy 48.534912 -345.598709)
			(xy 48.512251 -345.648329) (xy 48.482759 -345.694219) (xy 48.447036 -345.735444) (xy 48.405809 -345.771166)
			(xy 48.359919 -345.800657) (xy 48.310298 -345.823316) (xy 48.257958 -345.838684) (xy 48.203963 -345.846445)
			(xy 48.176688 -345.846908) (xy 47.313088 -345.846908) (xy 47.285822 -345.846329) (xy 47.231847 -345.838567)
			(xy 47.179525 -345.823202) (xy 47.129922 -345.800548) (xy 47.084048 -345.771065) (xy 47.042837 -345.735354)
			(xy 47.007127 -345.694142) (xy 46.977646 -345.648267) (xy 46.954994 -345.598664) (xy 46.939631 -345.546342)
			(xy 46.93187 -345.492366) (xy 45.449022 -345.492366) (xy 45.449022 -345.492371) (xy 45.44126 -345.546359)
			(xy 45.425894 -345.598693) (xy 45.403237 -345.648307) (xy 45.37375 -345.694192) (xy 45.338034 -345.735414)
			(xy 45.296814 -345.771133) (xy 45.250932 -345.800624) (xy 45.201319 -345.823284) (xy 45.148986 -345.838654)
			(xy 45.094999 -345.84642) (xy 45.067728 -345.846908) (xy 44.204128 -345.846908) (xy 44.176859 -345.846355)
			(xy 44.122876 -345.838597) (xy 44.070546 -345.823235) (xy 44.020935 -345.800581) (xy 43.975053 -345.771098)
			(xy 43.933835 -345.735385) (xy 43.898119 -345.694169) (xy 43.868632 -345.648289) (xy 43.845975 -345.59868)
			(xy 43.830609 -345.546352) (xy 43.822847 -345.492369) (xy 42.340144 -345.492369) (xy 42.340144 -345.492376)
			(xy 42.33238 -345.546372) (xy 42.317011 -345.598713) (xy 42.294348 -345.648335) (xy 42.264854 -345.694225)
			(xy 42.229129 -345.735451) (xy 42.1879 -345.771173) (xy 42.142007 -345.800663) (xy 42.092383 -345.823322)
			(xy 42.040041 -345.838687) (xy 41.986044 -345.846447) (xy 41.958768 -345.846908) (xy 41.095168 -345.846908)
			(xy 41.067903 -345.846328) (xy 41.01393 -345.838563) (xy 40.96161 -345.823197) (xy 40.91201 -345.800542)
			(xy 40.866139 -345.771058) (xy 40.82493 -345.735347) (xy 40.789222 -345.694136) (xy 40.759743 -345.648262)
			(xy 40.737092 -345.59866) (xy 40.72173 -345.546339) (xy 40.71397 -345.492365) (xy 39.231121 -345.492365)
			(xy 39.231121 -345.492372) (xy 39.223359 -345.546362) (xy 39.207992 -345.598697) (xy 39.185334 -345.648312)
			(xy 39.155845 -345.694199) (xy 39.120127 -345.735421) (xy 39.078905 -345.77114) (xy 39.03302 -345.80063)
			(xy 38.983404 -345.82329) (xy 38.93107 -345.838657) (xy 38.87708 -345.846421) (xy 38.849808 -345.846908)
			(xy 37.986208 -345.846908) (xy 37.95894 -345.846353) (xy 37.904959 -345.838593) (xy 37.852631 -345.823229)
			(xy 37.803023 -345.800575) (xy 37.757144 -345.771091) (xy 37.715928 -345.735378) (xy 37.680214 -345.694162)
			(xy 37.650729 -345.648284) (xy 37.628074 -345.598676) (xy 37.612709 -345.546349) (xy 37.604947 -345.492368)
			(xy 36.122122 -345.492368) (xy 36.122122 -345.49237) (xy 36.11436 -345.546356) (xy 36.098995 -345.598688)
			(xy 36.07634 -345.648301) (xy 36.046855 -345.694185) (xy 36.011141 -345.735407) (xy 35.969924 -345.771126)
			(xy 35.924043 -345.800617) (xy 35.874433 -345.823279) (xy 35.822103 -345.83865) (xy 35.768118 -345.846418)
			(xy 35.740848 -345.846908) (xy 34.877248 -345.846908) (xy 34.849978 -345.846356) (xy 34.795992 -345.8386)
			(xy 34.74366 -345.82324) (xy 34.694047 -345.800588) (xy 34.648163 -345.771105) (xy 34.606942 -345.735392)
			(xy 34.571224 -345.694176) (xy 34.541735 -345.648295) (xy 34.519077 -345.598685) (xy 34.50371 -345.546354)
			(xy 34.495948 -345.49237) (xy 33.013244 -345.49237) (xy 33.013244 -345.492375) (xy 33.005481 -345.546369)
			(xy 32.990112 -345.598709) (xy 32.967451 -345.648329) (xy 32.937959 -345.694219) (xy 32.902236 -345.735444)
			(xy 32.861009 -345.771166) (xy 32.815119 -345.800657) (xy 32.765498 -345.823316) (xy 32.713158 -345.838684)
			(xy 32.659163 -345.846445) (xy 32.631888 -345.846908) (xy 31.768288 -345.846908) (xy 31.741022 -345.846329)
			(xy 31.687047 -345.838567) (xy 31.634725 -345.823202) (xy 31.585122 -345.800548) (xy 31.539248 -345.771065)
			(xy 31.498037 -345.735354) (xy 31.462327 -345.694142) (xy 31.432846 -345.648267) (xy 31.410194 -345.598664)
			(xy 31.394831 -345.546342) (xy 31.38707 -345.492366) (xy 29.904222 -345.492366) (xy 29.904222 -345.492371)
			(xy 29.89646 -345.546359) (xy 29.881094 -345.598693) (xy 29.858437 -345.648307) (xy 29.82895 -345.694192)
			(xy 29.793234 -345.735414) (xy 29.752014 -345.771133) (xy 29.706132 -345.800624) (xy 29.656519 -345.823284)
			(xy 29.604186 -345.838654) (xy 29.550199 -345.84642) (xy 29.522928 -345.846908) (xy 28.659328 -345.846908)
			(xy 28.632059 -345.846355) (xy 28.578076 -345.838597) (xy 28.525746 -345.823235) (xy 28.476135 -345.800581)
			(xy 28.430253 -345.771098) (xy 28.389035 -345.735385) (xy 28.353319 -345.694169) (xy 28.323832 -345.648289)
			(xy 28.301175 -345.59868) (xy 28.285809 -345.546352) (xy 28.278047 -345.492369) (xy 26.795344 -345.492369)
			(xy 26.795344 -345.492376) (xy 26.78758 -345.546372) (xy 26.772211 -345.598713) (xy 26.749548 -345.648335)
			(xy 26.720054 -345.694225) (xy 26.684329 -345.735451) (xy 26.6431 -345.771173) (xy 26.597207 -345.800663)
			(xy 26.547583 -345.823322) (xy 26.495241 -345.838687) (xy 26.441244 -345.846447) (xy 26.413968 -345.846908)
			(xy 25.550368 -345.846908) (xy 25.523103 -345.846328) (xy 25.46913 -345.838563) (xy 25.41681 -345.823197)
			(xy 25.36721 -345.800542) (xy 25.321339 -345.771058) (xy 25.28013 -345.735347) (xy 25.244422 -345.694136)
			(xy 25.214943 -345.648262) (xy 25.192292 -345.59866) (xy 25.17693 -345.546339) (xy 25.16917 -345.492365)
			(xy 23.686305 -345.492365) (xy 23.686305 -345.492421) (xy 23.678542 -345.546407) (xy 23.663176 -345.59874)
			(xy 23.640519 -345.648352) (xy 23.611031 -345.694236) (xy 23.575314 -345.735455) (xy 23.534094 -345.771172)
			(xy 23.488211 -345.80066) (xy 23.438598 -345.823317) (xy 23.386265 -345.838683) (xy 23.332279 -345.846445)
			(xy 23.305008 -345.846908) (xy 22.441408 -345.846908) (xy 22.414138 -345.846429) (xy 22.360154 -345.838667)
			(xy 22.307825 -345.823302) (xy 22.258214 -345.800645) (xy 22.212333 -345.771159) (xy 22.171115 -345.735443)
			(xy 22.1354 -345.694225) (xy 22.105914 -345.648344) (xy 22.083258 -345.598733) (xy 22.067892 -345.546404)
			(xy 22.06013 -345.49242) (xy 20.577345 -345.49242) (xy 20.577345 -345.492421) (xy 20.569582 -345.546407)
			(xy 20.554216 -345.59874) (xy 20.531559 -345.648352) (xy 20.502071 -345.694236) (xy 20.466354 -345.735455)
			(xy 20.425134 -345.771172) (xy 20.379251 -345.80066) (xy 20.329638 -345.823317) (xy 20.277305 -345.838683)
			(xy 20.223319 -345.846445) (xy 20.196048 -345.846908) (xy 19.332448 -345.846908) (xy 19.305178 -345.846429)
			(xy 19.251194 -345.838667) (xy 19.198865 -345.823302) (xy 19.149254 -345.800645) (xy 19.103373 -345.771159)
			(xy 19.062155 -345.735443) (xy 19.02644 -345.694225) (xy 18.996954 -345.648344) (xy 18.974298 -345.598733)
			(xy 18.958932 -345.546404) (xy 18.95117 -345.49242) (xy 0.508 -345.49242) (xy 0.508 -348.976496)
			(xy 4.708641 -348.976496) (xy 4.708641 -348.847356) (xy 4.716591 -348.718461) (xy 4.732461 -348.590301)
			(xy 4.75619 -348.46336) (xy 4.787689 -348.338121) (xy 4.826838 -348.215058) (xy 4.873489 -348.094639)
			(xy 4.927464 -347.97732) (xy 4.988559 -347.863546) (xy 5.056542 -347.753749) (xy 5.131156 -347.648346)
			(xy 5.212117 -347.547736) (xy 5.299117 -347.452301) (xy 5.391828 -347.362402) (xy 5.489898 -347.278381)
			(xy 5.592953 -347.200557) (xy 5.700604 -347.129225) (xy 5.812443 -347.064655) (xy 5.928044 -347.007093)
			(xy 6.046969 -346.956756) (xy 6.168768 -346.913836) (xy 6.292978 -346.878495) (xy 6.419127 -346.850868)
			(xy 6.546739 -346.831059) (xy 6.675328 -346.819143) (xy 6.804406 -346.815167) (xy 6.933484 -346.819143)
			(xy 7.062073 -346.831059) (xy 7.189685 -346.850868) (xy 7.315834 -346.878495) (xy 7.440044 -346.913836)
			(xy 7.451736 -346.917956) (xy 245.50903 -346.917956) (xy 245.50903 -346.83326) (xy 245.517081 -346.748946)
			(xy 245.53311 -346.66578) (xy 245.556971 -346.584513) (xy 245.58845 -346.505883) (xy 245.627261 -346.430602)
			(xy 245.673051 -346.35935) (xy 245.725407 -346.292774) (xy 245.783855 -346.231476) (xy 245.847865 -346.176011)
			(xy 245.916857 -346.126882) (xy 245.990207 -346.084533) (xy 246.06725 -346.049349) (xy 246.147289 -346.021647)
			(xy 246.229598 -346.001679) (xy 246.313433 -345.989626) (xy 246.398034 -345.985596) (xy 246.482635 -345.989626)
			(xy 246.56647 -346.001679) (xy 246.648779 -346.021647) (xy 246.728818 -346.049349) (xy 246.805861 -346.084533)
			(xy 246.879211 -346.126882) (xy 246.948203 -346.176011) (xy 247.012213 -346.231476) (xy 247.070661 -346.292774)
			(xy 247.123017 -346.35935) (xy 247.168807 -346.430602) (xy 247.207618 -346.505883) (xy 247.239097 -346.584513)
			(xy 247.262958 -346.66578) (xy 247.278987 -346.748946) (xy 247.287038 -346.83326) (xy 247.287542 -346.875608)
			(xy 247.287038 -346.917956) (xy 247.278987 -347.00227) (xy 247.262958 -347.085436) (xy 247.239097 -347.166703)
			(xy 247.207618 -347.245333) (xy 247.168807 -347.320614) (xy 247.123017 -347.391866) (xy 247.070661 -347.458442)
			(xy 247.012213 -347.51974) (xy 246.948203 -347.575205) (xy 246.879211 -347.624334) (xy 246.805861 -347.666683)
			(xy 246.728818 -347.701867) (xy 246.648779 -347.729569) (xy 246.56647 -347.749537) (xy 246.482635 -347.76159)
			(xy 246.398034 -347.765621) (xy 246.313433 -347.76159) (xy 246.229598 -347.749537) (xy 246.147289 -347.729569)
			(xy 246.06725 -347.701867) (xy 245.990207 -347.666683) (xy 245.916857 -347.624334) (xy 245.847865 -347.575205)
			(xy 245.783855 -347.51974) (xy 245.725407 -347.458442) (xy 245.673051 -347.391866) (xy 245.627261 -347.320614)
			(xy 245.58845 -347.245333) (xy 245.556971 -347.166703) (xy 245.53311 -347.085436) (xy 245.517081 -347.00227)
			(xy 245.50903 -346.917956) (xy 7.451736 -346.917956) (xy 7.561843 -346.956756) (xy 7.680768 -347.007093)
			(xy 7.796369 -347.064655) (xy 7.908208 -347.129225) (xy 8.015859 -347.200557) (xy 8.118914 -347.278381)
			(xy 8.216984 -347.362402) (xy 8.309695 -347.452301) (xy 8.396695 -347.547736) (xy 8.477656 -347.648346)
			(xy 8.55227 -347.753749) (xy 8.620253 -347.863546) (xy 8.681348 -347.97732) (xy 8.735323 -348.094639)
			(xy 8.781974 -348.215058) (xy 8.821123 -348.338121) (xy 8.852622 -348.46336) (xy 8.876351 -348.590301)
			(xy 8.879169 -348.613059) (xy 18.951174 -348.613059) (xy 18.951174 -348.558521) (xy 18.958936 -348.504537)
			(xy 18.974301 -348.452208) (xy 18.996957 -348.402598) (xy 19.026443 -348.356717) (xy 19.062158 -348.315499)
			(xy 19.103375 -348.279784) (xy 19.149256 -348.250298) (xy 19.198866 -348.227642) (xy 19.251195 -348.212276)
			(xy 19.305179 -348.204515) (xy 19.332448 -348.204028) (xy 20.196048 -348.204028) (xy 20.223319 -348.204491)
			(xy 20.277306 -348.212253) (xy 20.329639 -348.227619) (xy 20.379253 -348.250277) (xy 20.425136 -348.279764)
			(xy 20.466357 -348.315482) (xy 20.502074 -348.356702) (xy 20.531562 -348.402586) (xy 20.55422 -348.452199)
			(xy 20.569586 -348.504532) (xy 20.577349 -348.558519) (xy 20.577349 -348.613061) (xy 20.577347 -348.613072)
			(xy 22.060092 -348.613072) (xy 22.060092 -348.558528) (xy 22.067854 -348.504539) (xy 22.083221 -348.452204)
			(xy 22.10588 -348.402589) (xy 22.135369 -348.356704) (xy 22.171088 -348.315483) (xy 22.21231 -348.279764)
			(xy 22.258196 -348.250276) (xy 22.307812 -348.227618) (xy 22.360147 -348.212252) (xy 22.414136 -348.204491)
			(xy 22.441408 -348.204028) (xy 23.305008 -348.204028) (xy 23.332276 -348.204535) (xy 23.386258 -348.212297)
			(xy 23.438585 -348.227663) (xy 23.488193 -348.250319) (xy 23.534071 -348.279804) (xy 23.575287 -348.315519)
			(xy 23.611 -348.356735) (xy 23.640485 -348.402614) (xy 23.66314 -348.452223) (xy 23.678504 -348.50455)
			(xy 23.686266 -348.558532) (xy 23.686266 -348.613068) (xy 23.686266 -348.613069) (xy 25.169114 -348.613069)
			(xy 25.169114 -348.558531) (xy 25.176875 -348.504549) (xy 25.19224 -348.452221) (xy 25.214894 -348.402611)
			(xy 25.244378 -348.356731) (xy 25.28009 -348.315513) (xy 25.321305 -348.279797) (xy 25.367183 -348.250309)
			(xy 25.416791 -348.227651) (xy 25.469118 -348.212282) (xy 25.523099 -348.204517) (xy 25.550368 -348.204028)
			(xy 26.413968 -348.204028) (xy 26.44124 -348.204509) (xy 26.495229 -348.212268) (xy 26.547564 -348.227631)
			(xy 26.59718 -348.250286) (xy 26.643066 -348.279772) (xy 26.684289 -348.315488) (xy 26.720009 -348.356708)
			(xy 26.749499 -348.402592) (xy 26.772158 -348.452206) (xy 26.787526 -348.50454) (xy 26.795288 -348.558528)
			(xy 26.795288 -348.613072) (xy 26.795288 -348.613073) (xy 28.277992 -348.613073) (xy 28.277992 -348.558527)
			(xy 28.285755 -348.504536) (xy 28.301123 -348.4522) (xy 28.323783 -348.402584) (xy 28.353274 -348.356697)
			(xy 28.388995 -348.315476) (xy 28.43022 -348.279757) (xy 28.476108 -348.25027) (xy 28.525726 -348.227613)
			(xy 28.578064 -348.212249) (xy 28.632055 -348.20449) (xy 28.659328 -348.204028) (xy 29.522928 -348.204028)
			(xy 29.550195 -348.204536) (xy 29.604175 -348.212301) (xy 29.656499 -348.227668) (xy 29.706105 -348.250326)
			(xy 29.751981 -348.279811) (xy 29.793194 -348.315526) (xy 29.828905 -348.356742) (xy 29.858388 -348.40262)
			(xy 29.881041 -348.452227) (xy 29.896405 -348.504553) (xy 29.904166 -348.558533) (xy 29.904166 -348.613067)
			(xy 29.904166 -348.61307) (xy 31.387014 -348.61307) (xy 31.387014 -348.55853) (xy 31.394776 -348.504546)
			(xy 31.410141 -348.452217) (xy 31.432797 -348.402606) (xy 31.462283 -348.356724) (xy 31.497997 -348.315506)
			(xy 31.539215 -348.27979) (xy 31.585095 -348.250303) (xy 31.634705 -348.227645) (xy 31.687035 -348.212279)
			(xy 31.741018 -348.204515) (xy 31.768288 -348.204028) (xy 32.631888 -348.204028) (xy 32.659159 -348.204511)
			(xy 32.713146 -348.212271) (xy 32.765478 -348.227636) (xy 32.815092 -348.250292) (xy 32.860976 -348.279779)
			(xy 32.902196 -348.315495) (xy 32.937914 -348.356715) (xy 32.967402 -348.402598) (xy 32.99006 -348.45221)
			(xy 33.005426 -348.504543) (xy 33.013189 -348.558529) (xy 33.013189 -348.613071) (xy 33.013189 -348.613074)
			(xy 34.495892 -348.613074) (xy 34.495892 -348.558526) (xy 34.503655 -348.504534) (xy 34.519024 -348.452196)
			(xy 34.541686 -348.402578) (xy 34.571179 -348.356691) (xy 34.606902 -348.315468) (xy 34.648129 -348.27975)
			(xy 34.69402 -348.250263) (xy 34.743641 -348.227608) (xy 34.795981 -348.212245) (xy 34.849974 -348.204488)
			(xy 34.877248 -348.204028) (xy 35.740848 -348.204028) (xy 35.768114 -348.204538) (xy 35.822091 -348.212305)
			(xy 35.874414 -348.227674) (xy 35.924017 -348.250332) (xy 35.96989 -348.279819) (xy 36.011101 -348.315533)
			(xy 36.04681 -348.356748) (xy 36.076291 -348.402626) (xy 36.098943 -348.452231) (xy 36.114306 -348.504556)
			(xy 36.122066 -348.558534) (xy 36.122066 -348.613066) (xy 36.122065 -348.613072) (xy 37.604892 -348.613072)
			(xy 37.604892 -348.558528) (xy 37.612654 -348.504539) (xy 37.628021 -348.452204) (xy 37.65068 -348.402589)
			(xy 37.680169 -348.356704) (xy 37.715888 -348.315483) (xy 37.75711 -348.279764) (xy 37.802996 -348.250276)
			(xy 37.852612 -348.227618) (xy 37.904947 -348.212252) (xy 37.958936 -348.204491) (xy 37.986208 -348.204028)
			(xy 38.849808 -348.204028) (xy 38.877076 -348.204535) (xy 38.931058 -348.212297) (xy 38.983385 -348.227663)
			(xy 39.032993 -348.250319) (xy 39.078871 -348.279804) (xy 39.120087 -348.315519) (xy 39.1558 -348.356735)
			(xy 39.185285 -348.402614) (xy 39.20794 -348.452223) (xy 39.223304 -348.50455) (xy 39.231066 -348.558532)
			(xy 39.231066 -348.613068) (xy 39.231066 -348.613069) (xy 40.713914 -348.613069) (xy 40.713914 -348.558531)
			(xy 40.721675 -348.504549) (xy 40.73704 -348.452221) (xy 40.759694 -348.402611) (xy 40.789178 -348.356731)
			(xy 40.82489 -348.315513) (xy 40.866105 -348.279797) (xy 40.911983 -348.250309) (xy 40.961591 -348.227651)
			(xy 41.013918 -348.212282) (xy 41.067899 -348.204517) (xy 41.095168 -348.204028) (xy 41.958768 -348.204028)
			(xy 41.98604 -348.204509) (xy 42.040029 -348.212268) (xy 42.092364 -348.227631) (xy 42.14198 -348.250286)
			(xy 42.187866 -348.279772) (xy 42.229089 -348.315488) (xy 42.264809 -348.356708) (xy 42.294299 -348.402592)
			(xy 42.316958 -348.452206) (xy 42.332326 -348.50454) (xy 42.340088 -348.558528) (xy 42.340088 -348.613072)
			(xy 42.340088 -348.613073) (xy 43.822792 -348.613073) (xy 43.822792 -348.558527) (xy 43.830555 -348.504536)
			(xy 43.845923 -348.4522) (xy 43.868583 -348.402584) (xy 43.898074 -348.356697) (xy 43.933795 -348.315476)
			(xy 43.97502 -348.279757) (xy 44.020908 -348.25027) (xy 44.070526 -348.227613) (xy 44.122864 -348.212249)
			(xy 44.176855 -348.20449) (xy 44.204128 -348.204028) (xy 45.067728 -348.204028) (xy 45.094995 -348.204536)
			(xy 45.148975 -348.212301) (xy 45.201299 -348.227668) (xy 45.250905 -348.250326) (xy 45.296781 -348.279811)
			(xy 45.337994 -348.315526) (xy 45.373705 -348.356742) (xy 45.403188 -348.40262) (xy 45.425841 -348.452227)
			(xy 45.441205 -348.504553) (xy 45.448966 -348.558533) (xy 45.448966 -348.613067) (xy 45.448966 -348.61307)
			(xy 46.931814 -348.61307) (xy 46.931814 -348.55853) (xy 46.939576 -348.504546) (xy 46.954941 -348.452217)
			(xy 46.977597 -348.402606) (xy 47.007083 -348.356724) (xy 47.042797 -348.315506) (xy 47.084015 -348.27979)
			(xy 47.129895 -348.250303) (xy 47.179505 -348.227645) (xy 47.231835 -348.212279) (xy 47.285818 -348.204515)
			(xy 47.313088 -348.204028) (xy 48.176688 -348.204028) (xy 48.203959 -348.204511) (xy 48.257946 -348.212271)
			(xy 48.310278 -348.227636) (xy 48.359892 -348.250292) (xy 48.405776 -348.279779) (xy 48.446996 -348.315495)
			(xy 48.482714 -348.356715) (xy 48.512202 -348.402598) (xy 48.53486 -348.45221) (xy 48.550226 -348.504543)
			(xy 48.557989 -348.558529) (xy 48.557989 -348.613071) (xy 48.557989 -348.613074) (xy 50.040692 -348.613074)
			(xy 50.040692 -348.558526) (xy 50.048455 -348.504534) (xy 50.063824 -348.452196) (xy 50.086486 -348.402578)
			(xy 50.115979 -348.356691) (xy 50.151702 -348.315468) (xy 50.192929 -348.27975) (xy 50.23882 -348.250263)
			(xy 50.288441 -348.227608) (xy 50.340781 -348.212245) (xy 50.394774 -348.204488) (xy 50.422048 -348.204028)
			(xy 51.285648 -348.204028) (xy 51.312914 -348.204538) (xy 51.366891 -348.212305) (xy 51.419214 -348.227674)
			(xy 51.468817 -348.250332) (xy 51.51469 -348.279819) (xy 51.555901 -348.315533) (xy 51.59161 -348.356748)
			(xy 51.621091 -348.402626) (xy 51.643743 -348.452231) (xy 51.659106 -348.504556) (xy 51.666866 -348.558534)
			(xy 51.666866 -348.613066) (xy 51.666865 -348.613074) (xy 60.990892 -348.613074) (xy 60.990892 -348.558526)
			(xy 60.998655 -348.504534) (xy 61.014024 -348.452197) (xy 61.036685 -348.40258) (xy 61.066177 -348.356693)
			(xy 61.1019 -348.315471) (xy 61.143127 -348.279752) (xy 61.189017 -348.250265) (xy 61.238636 -348.227609)
			(xy 61.290976 -348.212246) (xy 61.344968 -348.204489) (xy 61.372242 -348.204028) (xy 62.235842 -348.204028)
			(xy 62.263109 -348.204537) (xy 62.317086 -348.212304) (xy 62.369409 -348.227672) (xy 62.419013 -348.25033)
			(xy 62.464887 -348.279816) (xy 62.506099 -348.315531) (xy 62.541809 -348.356746) (xy 62.57129 -348.402624)
			(xy 62.593943 -348.45223) (xy 62.609305 -348.504555) (xy 62.617066 -348.558533) (xy 62.617066 -348.613067)
			(xy 62.617065 -348.613072) (xy 64.099892 -348.613072) (xy 64.099892 -348.558528) (xy 64.107654 -348.50454)
			(xy 64.123021 -348.452206) (xy 64.145679 -348.402591) (xy 64.175168 -348.356706) (xy 64.210886 -348.315485)
			(xy 64.252108 -348.279766) (xy 64.297993 -348.250278) (xy 64.347607 -348.22762) (xy 64.399942 -348.212253)
			(xy 64.45393 -348.204491) (xy 64.481202 -348.204028) (xy 65.344802 -348.204028) (xy 65.372071 -348.204535)
			(xy 65.426053 -348.212296) (xy 65.47838 -348.227661) (xy 65.527989 -348.250317) (xy 65.573869 -348.279802)
			(xy 65.615085 -348.315517) (xy 65.650799 -348.356733) (xy 65.680284 -348.402613) (xy 65.702939 -348.452221)
			(xy 65.718304 -348.504549) (xy 65.726066 -348.558531) (xy 65.726066 -348.613068) (xy 67.208914 -348.613068)
			(xy 67.208914 -348.558532) (xy 67.216675 -348.50455) (xy 67.232039 -348.452222) (xy 67.254693 -348.402613)
			(xy 67.284176 -348.356733) (xy 67.319888 -348.315515) (xy 67.361102 -348.279799) (xy 67.40698 -348.250311)
			(xy 67.456586 -348.227652) (xy 67.508913 -348.212283) (xy 67.562894 -348.204517) (xy 67.590162 -348.204028)
			(xy 68.453762 -348.204028) (xy 68.481034 -348.204509) (xy 68.535024 -348.212266) (xy 68.58736 -348.227629)
			(xy 68.636976 -348.250284) (xy 68.682863 -348.27977) (xy 68.724087 -348.315486) (xy 68.759808 -348.356706)
			(xy 68.789298 -348.40259) (xy 68.811958 -348.452205) (xy 68.827326 -348.504539) (xy 68.835088 -348.558528)
			(xy 68.835088 -348.613072) (xy 68.835088 -348.613073) (xy 70.317792 -348.613073) (xy 70.317792 -348.558527)
			(xy 70.325554 -348.504537) (xy 70.340922 -348.452201) (xy 70.363582 -348.402585) (xy 70.393072 -348.356699)
			(xy 70.428793 -348.315478) (xy 70.470017 -348.279759) (xy 70.515905 -348.250271) (xy 70.565522 -348.227615)
			(xy 70.617859 -348.21225) (xy 70.671849 -348.20449) (xy 70.699122 -348.204028) (xy 71.562722 -348.204028)
			(xy 71.58999 -348.204536) (xy 71.643969 -348.2123) (xy 71.696295 -348.227667) (xy 71.745901 -348.250324)
			(xy 71.791778 -348.279809) (xy 71.832992 -348.315524) (xy 71.868704 -348.35674) (xy 71.898187 -348.402618)
			(xy 71.920841 -348.452226) (xy 71.936205 -348.504552) (xy 71.943966 -348.558532) (xy 71.943966 -348.613068)
			(xy 71.943966 -348.613069) (xy 73.426814 -348.613069) (xy 73.426814 -348.558531) (xy 73.434576 -348.504547)
			(xy 73.449941 -348.452218) (xy 73.472596 -348.402608) (xy 73.502081 -348.356726) (xy 73.537795 -348.315508)
			(xy 73.579012 -348.279792) (xy 73.624892 -348.250305) (xy 73.674501 -348.227647) (xy 73.72683 -348.21228)
			(xy 73.780813 -348.204516) (xy 73.808082 -348.204028) (xy 74.671682 -348.204028) (xy 74.698953 -348.20451)
			(xy 74.752941 -348.21227) (xy 74.805274 -348.227634) (xy 74.854888 -348.25029) (xy 74.900773 -348.279777)
			(xy 74.941994 -348.315493) (xy 74.977712 -348.356713) (xy 75.007201 -348.402596) (xy 75.029859 -348.452209)
			(xy 75.045226 -348.504542) (xy 75.052988 -348.558529) (xy 75.052988 -348.613071) (xy 75.052988 -348.613074)
			(xy 76.535692 -348.613074) (xy 76.535692 -348.558526) (xy 76.543455 -348.504534) (xy 76.558824 -348.452197)
			(xy 76.581485 -348.40258) (xy 76.610977 -348.356693) (xy 76.6467 -348.315471) (xy 76.687927 -348.279752)
			(xy 76.733817 -348.250265) (xy 76.783436 -348.227609) (xy 76.835776 -348.212246) (xy 76.889768 -348.204489)
			(xy 76.917042 -348.204028) (xy 77.780642 -348.204028) (xy 77.807909 -348.204537) (xy 77.861886 -348.212304)
			(xy 77.914209 -348.227672) (xy 77.963813 -348.25033) (xy 78.009687 -348.279816) (xy 78.050899 -348.315531)
			(xy 78.086609 -348.356746) (xy 78.11609 -348.402624) (xy 78.138743 -348.45223) (xy 78.154105 -348.504555)
			(xy 78.161866 -348.558533) (xy 78.161866 -348.613067) (xy 78.161865 -348.613072) (xy 79.644692 -348.613072)
			(xy 79.644692 -348.558528) (xy 79.652454 -348.50454) (xy 79.667821 -348.452206) (xy 79.690479 -348.402591)
			(xy 79.719968 -348.356706) (xy 79.755686 -348.315485) (xy 79.796908 -348.279766) (xy 79.842793 -348.250278)
			(xy 79.892407 -348.22762) (xy 79.944742 -348.212253) (xy 79.99873 -348.204491) (xy 80.026002 -348.204028)
			(xy 80.889602 -348.204028) (xy 80.916871 -348.204535) (xy 80.970853 -348.212296) (xy 81.02318 -348.227661)
			(xy 81.072789 -348.250317) (xy 81.118669 -348.279802) (xy 81.159885 -348.315517) (xy 81.195599 -348.356733)
			(xy 81.225084 -348.402613) (xy 81.247739 -348.452221) (xy 81.263104 -348.504549) (xy 81.270866 -348.558531)
			(xy 81.270866 -348.613068) (xy 82.753714 -348.613068) (xy 82.753714 -348.558532) (xy 82.761475 -348.50455)
			(xy 82.776839 -348.452222) (xy 82.799493 -348.402613) (xy 82.828976 -348.356733) (xy 82.864688 -348.315515)
			(xy 82.905902 -348.279799) (xy 82.95178 -348.250311) (xy 83.001386 -348.227652) (xy 83.053713 -348.212283)
			(xy 83.107694 -348.204517) (xy 83.134962 -348.204028) (xy 83.998562 -348.204028) (xy 84.025834 -348.204509)
			(xy 84.079824 -348.212266) (xy 84.13216 -348.227629) (xy 84.181776 -348.250284) (xy 84.227663 -348.27977)
			(xy 84.268887 -348.315486) (xy 84.304608 -348.356706) (xy 84.334098 -348.40259) (xy 84.356758 -348.452205)
			(xy 84.372126 -348.504539) (xy 84.379888 -348.558528) (xy 84.379888 -348.613072) (xy 84.379888 -348.613073)
			(xy 85.862592 -348.613073) (xy 85.862592 -348.558527) (xy 85.870354 -348.504537) (xy 85.885722 -348.452201)
			(xy 85.908382 -348.402585) (xy 85.937872 -348.356699) (xy 85.973593 -348.315478) (xy 86.014817 -348.279759)
			(xy 86.060705 -348.250271) (xy 86.110322 -348.227615) (xy 86.162659 -348.21225) (xy 86.216649 -348.20449)
			(xy 86.243922 -348.204028) (xy 87.107522 -348.204028) (xy 87.13479 -348.204536) (xy 87.188769 -348.2123)
			(xy 87.241095 -348.227667) (xy 87.290701 -348.250324) (xy 87.336578 -348.279809) (xy 87.377792 -348.315524)
			(xy 87.413504 -348.35674) (xy 87.442987 -348.402618) (xy 87.465641 -348.452226) (xy 87.481005 -348.504552)
			(xy 87.488766 -348.558532) (xy 87.488766 -348.613068) (xy 87.488766 -348.613069) (xy 88.971614 -348.613069)
			(xy 88.971614 -348.558531) (xy 88.979376 -348.504547) (xy 88.994741 -348.452218) (xy 89.017396 -348.402608)
			(xy 89.046881 -348.356726) (xy 89.082595 -348.315508) (xy 89.123812 -348.279792) (xy 89.169692 -348.250305)
			(xy 89.219301 -348.227647) (xy 89.27163 -348.21228) (xy 89.325613 -348.204516) (xy 89.352882 -348.204028)
			(xy 90.216482 -348.204028) (xy 90.243753 -348.20451) (xy 90.297741 -348.21227) (xy 90.350074 -348.227634)
			(xy 90.399688 -348.25029) (xy 90.445573 -348.279777) (xy 90.486794 -348.315493) (xy 90.522512 -348.356713)
			(xy 90.552001 -348.402596) (xy 90.574659 -348.452209) (xy 90.590026 -348.504542) (xy 90.597788 -348.558529)
			(xy 90.597788 -348.613071) (xy 90.597788 -348.613074) (xy 92.080492 -348.613074) (xy 92.080492 -348.558526)
			(xy 92.088255 -348.504534) (xy 92.103624 -348.452197) (xy 92.126285 -348.40258) (xy 92.155777 -348.356693)
			(xy 92.1915 -348.315471) (xy 92.232727 -348.279752) (xy 92.278617 -348.250265) (xy 92.328236 -348.227609)
			(xy 92.380576 -348.212246) (xy 92.434568 -348.204489) (xy 92.461842 -348.204028) (xy 93.325442 -348.204028)
			(xy 93.352709 -348.204537) (xy 93.406686 -348.212304) (xy 93.459009 -348.227672) (xy 93.508613 -348.25033)
			(xy 93.554487 -348.279816) (xy 93.595699 -348.315531) (xy 93.631409 -348.356746) (xy 93.66089 -348.402624)
			(xy 93.683543 -348.45223) (xy 93.698905 -348.504555) (xy 93.706666 -348.558533) (xy 93.706666 -348.613067)
			(xy 93.706665 -348.613072) (xy 111.480792 -348.613072) (xy 111.480792 -348.558528) (xy 111.488554 -348.504539)
			(xy 111.503921 -348.452204) (xy 111.52658 -348.402589) (xy 111.556069 -348.356704) (xy 111.591788 -348.315483)
			(xy 111.63301 -348.279764) (xy 111.678896 -348.250276) (xy 111.728512 -348.227618) (xy 111.780847 -348.212252)
			(xy 111.834836 -348.204491) (xy 111.862108 -348.204028) (xy 112.725708 -348.204028) (xy 112.752976 -348.204535)
			(xy 112.806958 -348.212297) (xy 112.859285 -348.227663) (xy 112.908893 -348.250319) (xy 112.954771 -348.279804)
			(xy 112.995987 -348.315519) (xy 113.0317 -348.356735) (xy 113.061185 -348.402614) (xy 113.08384 -348.452223)
			(xy 113.099204 -348.50455) (xy 113.106966 -348.558532) (xy 113.106966 -348.613068) (xy 113.106966 -348.613069)
			(xy 114.589814 -348.613069) (xy 114.589814 -348.558531) (xy 114.597575 -348.504549) (xy 114.61294 -348.452221)
			(xy 114.635594 -348.402611) (xy 114.665078 -348.356731) (xy 114.70079 -348.315513) (xy 114.742005 -348.279797)
			(xy 114.787883 -348.250309) (xy 114.837491 -348.227651) (xy 114.889818 -348.212282) (xy 114.943799 -348.204517)
			(xy 114.971068 -348.204028) (xy 115.834668 -348.204028) (xy 115.86194 -348.204509) (xy 115.915929 -348.212268)
			(xy 115.968264 -348.227631) (xy 116.01788 -348.250286) (xy 116.063766 -348.279772) (xy 116.104989 -348.315488)
			(xy 116.140709 -348.356708) (xy 116.170199 -348.402592) (xy 116.192858 -348.452206) (xy 116.208226 -348.50454)
			(xy 116.215988 -348.558528) (xy 116.215988 -348.613072) (xy 116.215988 -348.613073) (xy 117.698692 -348.613073)
			(xy 117.698692 -348.558527) (xy 117.706455 -348.504536) (xy 117.721823 -348.4522) (xy 117.744483 -348.402584)
			(xy 117.773974 -348.356697) (xy 117.809695 -348.315476) (xy 117.85092 -348.279757) (xy 117.896808 -348.25027)
			(xy 117.946426 -348.227613) (xy 117.998764 -348.212249) (xy 118.052755 -348.20449) (xy 118.080028 -348.204028)
			(xy 118.943628 -348.204028) (xy 118.970895 -348.204536) (xy 119.024875 -348.212301) (xy 119.077199 -348.227668)
			(xy 119.126805 -348.250326) (xy 119.172681 -348.279811) (xy 119.213894 -348.315526) (xy 119.249605 -348.356742)
			(xy 119.279088 -348.40262) (xy 119.301741 -348.452227) (xy 119.317105 -348.504553) (xy 119.324866 -348.558533)
			(xy 119.324866 -348.613067) (xy 119.324866 -348.61307) (xy 120.807714 -348.61307) (xy 120.807714 -348.55853)
			(xy 120.815476 -348.504546) (xy 120.830841 -348.452217) (xy 120.853497 -348.402606) (xy 120.882983 -348.356724)
			(xy 120.918697 -348.315506) (xy 120.959915 -348.27979) (xy 121.005795 -348.250303) (xy 121.055405 -348.227645)
			(xy 121.107735 -348.212279) (xy 121.161718 -348.204515) (xy 121.188988 -348.204028) (xy 122.052588 -348.204028)
			(xy 122.079859 -348.204511) (xy 122.133846 -348.212271) (xy 122.186178 -348.227636) (xy 122.235792 -348.250292)
			(xy 122.281676 -348.279779) (xy 122.322896 -348.315495) (xy 122.358614 -348.356715) (xy 122.388102 -348.402598)
			(xy 122.41076 -348.45221) (xy 122.426126 -348.504543) (xy 122.433889 -348.558529) (xy 122.433889 -348.613071)
			(xy 122.433889 -348.613074) (xy 123.916592 -348.613074) (xy 123.916592 -348.558526) (xy 123.924355 -348.504534)
			(xy 123.939724 -348.452196) (xy 123.962386 -348.402578) (xy 123.991879 -348.356691) (xy 124.027602 -348.315468)
			(xy 124.068829 -348.27975) (xy 124.11472 -348.250263) (xy 124.164341 -348.227608) (xy 124.216681 -348.212245)
			(xy 124.270674 -348.204488) (xy 124.297948 -348.204028) (xy 125.161548 -348.204028) (xy 125.188814 -348.204538)
			(xy 125.242791 -348.212305) (xy 125.295114 -348.227674) (xy 125.344717 -348.250332) (xy 125.39059 -348.279819)
			(xy 125.431801 -348.315533) (xy 125.46751 -348.356748) (xy 125.496991 -348.402626) (xy 125.519643 -348.452231)
			(xy 125.535006 -348.504556) (xy 125.542766 -348.558534) (xy 125.542766 -348.613066) (xy 125.542765 -348.613072)
			(xy 127.025592 -348.613072) (xy 127.025592 -348.558528) (xy 127.033354 -348.504539) (xy 127.048721 -348.452204)
			(xy 127.07138 -348.402589) (xy 127.100869 -348.356704) (xy 127.136588 -348.315483) (xy 127.17781 -348.279764)
			(xy 127.223696 -348.250276) (xy 127.273312 -348.227618) (xy 127.325647 -348.212252) (xy 127.379636 -348.204491)
			(xy 127.406908 -348.204028) (xy 128.270508 -348.204028) (xy 128.297776 -348.204535) (xy 128.351758 -348.212297)
			(xy 128.404085 -348.227663) (xy 128.453693 -348.250319) (xy 128.499571 -348.279804) (xy 128.540787 -348.315519)
			(xy 128.5765 -348.356735) (xy 128.605985 -348.402614) (xy 128.62864 -348.452223) (xy 128.644004 -348.50455)
			(xy 128.651766 -348.558532) (xy 128.651766 -348.613068) (xy 128.651766 -348.613069) (xy 130.134614 -348.613069)
			(xy 130.134614 -348.558531) (xy 130.142375 -348.504549) (xy 130.15774 -348.452221) (xy 130.180394 -348.402611)
			(xy 130.209878 -348.356731) (xy 130.24559 -348.315513) (xy 130.286805 -348.279797) (xy 130.332683 -348.250309)
			(xy 130.382291 -348.227651) (xy 130.434618 -348.212282) (xy 130.488599 -348.204517) (xy 130.515868 -348.204028)
			(xy 131.379468 -348.204028) (xy 131.40674 -348.204509) (xy 131.460729 -348.212268) (xy 131.513064 -348.227631)
			(xy 131.56268 -348.250286) (xy 131.608566 -348.279772) (xy 131.649789 -348.315488) (xy 131.685509 -348.356708)
			(xy 131.714999 -348.402592) (xy 131.737658 -348.452206) (xy 131.753026 -348.50454) (xy 131.760788 -348.558528)
			(xy 131.760788 -348.613072) (xy 131.760788 -348.613073) (xy 133.243492 -348.613073) (xy 133.243492 -348.558527)
			(xy 133.251255 -348.504536) (xy 133.266623 -348.4522) (xy 133.289283 -348.402584) (xy 133.318774 -348.356697)
			(xy 133.354495 -348.315476) (xy 133.39572 -348.279757) (xy 133.441608 -348.25027) (xy 133.491226 -348.227613)
			(xy 133.543564 -348.212249) (xy 133.597555 -348.20449) (xy 133.624828 -348.204028) (xy 134.488428 -348.204028)
			(xy 134.515695 -348.204536) (xy 134.569675 -348.212301) (xy 134.621999 -348.227668) (xy 134.671605 -348.250326)
			(xy 134.717481 -348.279811) (xy 134.758694 -348.315526) (xy 134.794405 -348.356742) (xy 134.823888 -348.40262)
			(xy 134.846541 -348.452227) (xy 134.861905 -348.504553) (xy 134.869666 -348.558533) (xy 134.869666 -348.613067)
			(xy 134.869666 -348.61307) (xy 136.352514 -348.61307) (xy 136.352514 -348.55853) (xy 136.360276 -348.504546)
			(xy 136.375641 -348.452217) (xy 136.398297 -348.402606) (xy 136.427783 -348.356724) (xy 136.463497 -348.315506)
			(xy 136.504715 -348.27979) (xy 136.550595 -348.250303) (xy 136.600205 -348.227645) (xy 136.652535 -348.212279)
			(xy 136.706518 -348.204515) (xy 136.733788 -348.204028) (xy 137.597388 -348.204028) (xy 137.624659 -348.204511)
			(xy 137.678646 -348.212271) (xy 137.730978 -348.227636) (xy 137.780592 -348.250292) (xy 137.826476 -348.279779)
			(xy 137.867696 -348.315495) (xy 137.903414 -348.356715) (xy 137.932902 -348.402598) (xy 137.95556 -348.45221)
			(xy 137.970926 -348.504543) (xy 137.978689 -348.558529) (xy 137.978689 -348.613071) (xy 137.978689 -348.613074)
			(xy 139.461392 -348.613074) (xy 139.461392 -348.558526) (xy 139.469155 -348.504534) (xy 139.484524 -348.452196)
			(xy 139.507186 -348.402578) (xy 139.536679 -348.356691) (xy 139.572402 -348.315468) (xy 139.613629 -348.27975)
			(xy 139.65952 -348.250263) (xy 139.709141 -348.227608) (xy 139.761481 -348.212245) (xy 139.815474 -348.204488)
			(xy 139.842748 -348.204028) (xy 140.706348 -348.204028) (xy 140.733614 -348.204538) (xy 140.787591 -348.212305)
			(xy 140.839914 -348.227674) (xy 140.889517 -348.250332) (xy 140.93539 -348.279819) (xy 140.976601 -348.315533)
			(xy 141.01231 -348.356748) (xy 141.041791 -348.402626) (xy 141.064443 -348.452231) (xy 141.079806 -348.504556)
			(xy 141.087566 -348.558534) (xy 141.087566 -348.613066) (xy 141.087565 -348.613072) (xy 142.570392 -348.613072)
			(xy 142.570392 -348.558528) (xy 142.578154 -348.504539) (xy 142.593521 -348.452204) (xy 142.61618 -348.402589)
			(xy 142.645669 -348.356704) (xy 142.681388 -348.315483) (xy 142.72261 -348.279764) (xy 142.768496 -348.250276)
			(xy 142.818112 -348.227618) (xy 142.870447 -348.212252) (xy 142.924436 -348.204491) (xy 142.951708 -348.204028)
			(xy 143.815308 -348.204028) (xy 143.842576 -348.204535) (xy 143.896558 -348.212297) (xy 143.948885 -348.227663)
			(xy 143.998493 -348.250319) (xy 144.044371 -348.279804) (xy 144.085587 -348.315519) (xy 144.1213 -348.356735)
			(xy 144.150785 -348.402614) (xy 144.17344 -348.452223) (xy 144.188804 -348.50455) (xy 144.196566 -348.558532)
			(xy 144.196566 -348.613068) (xy 144.196565 -348.613072) (xy 161.804792 -348.613072) (xy 161.804792 -348.558528)
			(xy 161.812554 -348.504538) (xy 161.827921 -348.452203) (xy 161.850581 -348.402588) (xy 161.88007 -348.356703)
			(xy 161.91579 -348.315481) (xy 161.957012 -348.279763) (xy 162.002899 -348.250275) (xy 162.052515 -348.227617)
			(xy 162.10485 -348.212252) (xy 162.15884 -348.204491) (xy 162.186112 -348.204028) (xy 163.049712 -348.204028)
			(xy 163.07698 -348.204535) (xy 163.130961 -348.212298) (xy 163.183288 -348.227664) (xy 163.232895 -348.25032)
			(xy 163.278773 -348.279806) (xy 163.319988 -348.31552) (xy 163.355701 -348.356736) (xy 163.385185 -348.402615)
			(xy 163.40784 -348.452224) (xy 163.423204 -348.504551) (xy 163.430966 -348.558532) (xy 163.430966 -348.613068)
			(xy 163.430966 -348.613069) (xy 164.913814 -348.613069) (xy 164.913814 -348.558531) (xy 164.921576 -348.504549)
			(xy 164.93694 -348.45222) (xy 164.959595 -348.40261) (xy 164.989079 -348.35673) (xy 165.024792 -348.315512)
			(xy 165.066007 -348.279795) (xy 165.111886 -348.250308) (xy 165.161494 -348.22765) (xy 165.213821 -348.212281)
			(xy 165.267803 -348.204516) (xy 165.295072 -348.204028) (xy 166.158672 -348.204028) (xy 166.185944 -348.20451)
			(xy 166.239932 -348.212268) (xy 166.292267 -348.227632) (xy 166.341882 -348.250287) (xy 166.387768 -348.279773)
			(xy 166.42899 -348.31549) (xy 166.46471 -348.356709) (xy 166.494199 -348.402593) (xy 166.516859 -348.452207)
			(xy 166.532226 -348.504541) (xy 166.539988 -348.558528) (xy 166.539988 -348.613072) (xy 166.539988 -348.613073)
			(xy 168.022692 -348.613073) (xy 168.022692 -348.558527) (xy 168.030455 -348.504536) (xy 168.045823 -348.452199)
			(xy 168.068484 -348.402583) (xy 168.097975 -348.356696) (xy 168.133697 -348.315474) (xy 168.174922 -348.279756)
			(xy 168.220811 -348.250268) (xy 168.270429 -348.227612) (xy 168.322767 -348.212248) (xy 168.376759 -348.204489)
			(xy 168.404032 -348.204028) (xy 169.267632 -348.204028) (xy 169.294899 -348.204537) (xy 169.348878 -348.212302)
			(xy 169.401202 -348.227669) (xy 169.450807 -348.250327) (xy 169.496683 -348.279813) (xy 169.537895 -348.315527)
			(xy 169.573606 -348.356743) (xy 169.603088 -348.402621) (xy 169.625742 -348.452228) (xy 169.641105 -348.504553)
			(xy 169.648866 -348.558533) (xy 169.648866 -348.613067) (xy 169.648866 -348.61307) (xy 171.131714 -348.61307)
			(xy 171.131714 -348.55853) (xy 171.139476 -348.504546) (xy 171.154841 -348.452216) (xy 171.177498 -348.402605)
			(xy 171.206984 -348.356723) (xy 171.242699 -348.315505) (xy 171.283917 -348.279788) (xy 171.329798 -348.250301)
			(xy 171.379408 -348.227644) (xy 171.431738 -348.212278) (xy 171.485722 -348.204515) (xy 171.512992 -348.204028)
			(xy 172.376592 -348.204028) (xy 172.403863 -348.204511) (xy 172.457849 -348.212272) (xy 172.510181 -348.227637)
			(xy 172.559794 -348.250294) (xy 172.605678 -348.27978) (xy 172.646898 -348.315497) (xy 172.682615 -348.356716)
			(xy 172.712103 -348.402599) (xy 172.73476 -348.452211) (xy 172.750126 -348.504543) (xy 172.757889 -348.558529)
			(xy 172.757889 -348.613068) (xy 174.240714 -348.613068) (xy 174.240714 -348.558532) (xy 174.248475 -348.504551)
			(xy 174.263838 -348.452224) (xy 174.286492 -348.402616) (xy 174.315974 -348.356736) (xy 174.351685 -348.315519)
			(xy 174.392898 -348.279803) (xy 174.438774 -348.250315) (xy 174.488379 -348.227655) (xy 174.540704 -348.212285)
			(xy 174.594684 -348.204518) (xy 174.621952 -348.204028) (xy 175.485552 -348.204028) (xy 175.512825 -348.204508)
			(xy 175.566815 -348.212265) (xy 175.619152 -348.227626) (xy 175.66877 -348.250281) (xy 175.714659 -348.279766)
			(xy 175.755883 -348.315483) (xy 175.791605 -348.356703) (xy 175.821096 -348.402588) (xy 175.843757 -348.452203)
			(xy 175.859125 -348.504538) (xy 175.866888 -348.558528) (xy 175.866888 -348.613072) (xy 177.349592 -348.613072)
			(xy 177.349592 -348.558528) (xy 177.357354 -348.504538) (xy 177.372721 -348.452203) (xy 177.395381 -348.402588)
			(xy 177.42487 -348.356703) (xy 177.46059 -348.315481) (xy 177.501812 -348.279763) (xy 177.547699 -348.250275)
			(xy 177.597315 -348.227617) (xy 177.64965 -348.212252) (xy 177.70364 -348.204491) (xy 177.730912 -348.204028)
			(xy 178.594512 -348.204028) (xy 178.62178 -348.204535) (xy 178.675761 -348.212298) (xy 178.728088 -348.227664)
			(xy 178.777695 -348.25032) (xy 178.823573 -348.279806) (xy 178.864788 -348.31552) (xy 178.900501 -348.356736)
			(xy 178.929985 -348.402615) (xy 178.95264 -348.452224) (xy 178.968004 -348.504551) (xy 178.975766 -348.558532)
			(xy 178.975766 -348.613068) (xy 178.975766 -348.613069) (xy 180.458614 -348.613069) (xy 180.458614 -348.558531)
			(xy 180.466376 -348.504549) (xy 180.48174 -348.45222) (xy 180.504395 -348.40261) (xy 180.533879 -348.35673)
			(xy 180.569592 -348.315512) (xy 180.610807 -348.279795) (xy 180.656686 -348.250308) (xy 180.706294 -348.22765)
			(xy 180.758621 -348.212281) (xy 180.812603 -348.204516) (xy 180.839872 -348.204028) (xy 181.703472 -348.204028)
			(xy 181.730744 -348.20451) (xy 181.784732 -348.212268) (xy 181.837067 -348.227632) (xy 181.886682 -348.250287)
			(xy 181.932568 -348.279773) (xy 181.97379 -348.31549) (xy 182.00951 -348.356709) (xy 182.038999 -348.402593)
			(xy 182.061659 -348.452207) (xy 182.077026 -348.504541) (xy 182.084788 -348.558528) (xy 182.084788 -348.613072)
			(xy 182.084788 -348.613073) (xy 183.567492 -348.613073) (xy 183.567492 -348.558527) (xy 183.575255 -348.504536)
			(xy 183.590623 -348.452199) (xy 183.613284 -348.402583) (xy 183.642775 -348.356696) (xy 183.678497 -348.315474)
			(xy 183.719722 -348.279756) (xy 183.765611 -348.250268) (xy 183.815229 -348.227612) (xy 183.867567 -348.212248)
			(xy 183.921559 -348.204489) (xy 183.948832 -348.204028) (xy 184.812432 -348.204028) (xy 184.839699 -348.204537)
			(xy 184.893678 -348.212302) (xy 184.946002 -348.227669) (xy 184.995607 -348.250327) (xy 185.041483 -348.279813)
			(xy 185.082695 -348.315527) (xy 185.118406 -348.356743) (xy 185.147888 -348.402621) (xy 185.170542 -348.452228)
			(xy 185.185905 -348.504553) (xy 185.193666 -348.558533) (xy 185.193666 -348.613067) (xy 185.193666 -348.61307)
			(xy 186.676514 -348.61307) (xy 186.676514 -348.55853) (xy 186.684276 -348.504546) (xy 186.699641 -348.452216)
			(xy 186.722298 -348.402605) (xy 186.751784 -348.356723) (xy 186.787499 -348.315505) (xy 186.828717 -348.279788)
			(xy 186.874598 -348.250301) (xy 186.924208 -348.227644) (xy 186.976538 -348.212278) (xy 187.030522 -348.204515)
			(xy 187.057792 -348.204028) (xy 187.921392 -348.204028) (xy 187.948663 -348.204511) (xy 188.002649 -348.212272)
			(xy 188.054981 -348.227637) (xy 188.104594 -348.250294) (xy 188.150478 -348.27978) (xy 188.191698 -348.315497)
			(xy 188.227415 -348.356716) (xy 188.256903 -348.402599) (xy 188.27956 -348.452211) (xy 188.294926 -348.504543)
			(xy 188.302689 -348.558529) (xy 188.302689 -348.613068) (xy 189.785514 -348.613068) (xy 189.785514 -348.558532)
			(xy 189.793275 -348.504551) (xy 189.808638 -348.452224) (xy 189.831292 -348.402616) (xy 189.860774 -348.356736)
			(xy 189.896485 -348.315519) (xy 189.937698 -348.279803) (xy 189.983574 -348.250315) (xy 190.033179 -348.227655)
			(xy 190.085504 -348.212285) (xy 190.139484 -348.204518) (xy 190.166752 -348.204028) (xy 191.030352 -348.204028)
			(xy 191.057625 -348.204508) (xy 191.111615 -348.212265) (xy 191.163952 -348.227626) (xy 191.21357 -348.250281)
			(xy 191.259459 -348.279766) (xy 191.300683 -348.315483) (xy 191.336405 -348.356703) (xy 191.365896 -348.402588)
			(xy 191.388557 -348.452203) (xy 191.403925 -348.504538) (xy 191.411688 -348.558528) (xy 191.411688 -348.613072)
			(xy 192.894392 -348.613072) (xy 192.894392 -348.558528) (xy 192.902154 -348.504538) (xy 192.917521 -348.452203)
			(xy 192.940181 -348.402588) (xy 192.96967 -348.356703) (xy 193.00539 -348.315481) (xy 193.046612 -348.279763)
			(xy 193.092499 -348.250275) (xy 193.142115 -348.227617) (xy 193.19445 -348.212252) (xy 193.24844 -348.204491)
			(xy 193.275712 -348.204028) (xy 194.139312 -348.204028) (xy 194.16658 -348.204535) (xy 194.220561 -348.212298)
			(xy 194.272888 -348.227664) (xy 194.322495 -348.25032) (xy 194.368373 -348.279806) (xy 194.409588 -348.31552)
			(xy 194.445301 -348.356736) (xy 194.474785 -348.402615) (xy 194.49744 -348.452224) (xy 194.512804 -348.504551)
			(xy 194.520566 -348.558532) (xy 194.520566 -348.613068) (xy 194.520565 -348.613072) (xy 267.515792 -348.613072)
			(xy 267.515792 -348.558528) (xy 267.523554 -348.50454) (xy 267.538921 -348.452206) (xy 267.561579 -348.402591)
			(xy 267.591068 -348.356706) (xy 267.626786 -348.315485) (xy 267.668008 -348.279766) (xy 267.713893 -348.250278)
			(xy 267.763507 -348.22762) (xy 267.815842 -348.212253) (xy 267.86983 -348.204491) (xy 267.897102 -348.204028)
			(xy 268.760702 -348.204028) (xy 268.787971 -348.204535) (xy 268.841953 -348.212296) (xy 268.89428 -348.227661)
			(xy 268.943889 -348.250317) (xy 268.989769 -348.279802) (xy 269.030985 -348.315517) (xy 269.066699 -348.356733)
			(xy 269.096184 -348.402613) (xy 269.118839 -348.452221) (xy 269.134204 -348.504549) (xy 269.141966 -348.558531)
			(xy 269.141966 -348.613068) (xy 270.624814 -348.613068) (xy 270.624814 -348.558532) (xy 270.632575 -348.50455)
			(xy 270.647939 -348.452222) (xy 270.670593 -348.402613) (xy 270.700076 -348.356733) (xy 270.735788 -348.315515)
			(xy 270.777002 -348.279799) (xy 270.82288 -348.250311) (xy 270.872486 -348.227652) (xy 270.924813 -348.212283)
			(xy 270.978794 -348.204517) (xy 271.006062 -348.204028) (xy 271.869662 -348.204028) (xy 271.896934 -348.204509)
			(xy 271.950924 -348.212266) (xy 272.00326 -348.227629) (xy 272.052876 -348.250284) (xy 272.098763 -348.27977)
			(xy 272.139987 -348.315486) (xy 272.175708 -348.356706) (xy 272.205198 -348.40259) (xy 272.227858 -348.452205)
			(xy 272.243226 -348.504539) (xy 272.250988 -348.558528) (xy 272.250988 -348.613072) (xy 272.250988 -348.613073)
			(xy 273.733692 -348.613073) (xy 273.733692 -348.558527) (xy 273.741454 -348.504537) (xy 273.756822 -348.452201)
			(xy 273.779482 -348.402585) (xy 273.808972 -348.356699) (xy 273.844693 -348.315478) (xy 273.885917 -348.279759)
			(xy 273.931805 -348.250271) (xy 273.981422 -348.227615) (xy 274.033759 -348.21225) (xy 274.087749 -348.20449)
			(xy 274.115022 -348.204028) (xy 274.978622 -348.204028) (xy 275.00589 -348.204536) (xy 275.059869 -348.2123)
			(xy 275.112195 -348.227667) (xy 275.161801 -348.250324) (xy 275.207678 -348.279809) (xy 275.248892 -348.315524)
			(xy 275.284604 -348.35674) (xy 275.314087 -348.402618) (xy 275.336741 -348.452226) (xy 275.352105 -348.504552)
			(xy 275.359866 -348.558532) (xy 275.359866 -348.613068) (xy 275.359866 -348.613069) (xy 276.842714 -348.613069)
			(xy 276.842714 -348.558531) (xy 276.850476 -348.504547) (xy 276.865841 -348.452218) (xy 276.888496 -348.402608)
			(xy 276.917981 -348.356726) (xy 276.953695 -348.315508) (xy 276.994912 -348.279792) (xy 277.040792 -348.250305)
			(xy 277.090401 -348.227647) (xy 277.14273 -348.21228) (xy 277.196713 -348.204516) (xy 277.223982 -348.204028)
			(xy 278.087582 -348.204028) (xy 278.114853 -348.20451) (xy 278.168841 -348.21227) (xy 278.221174 -348.227634)
			(xy 278.270788 -348.25029) (xy 278.316673 -348.279777) (xy 278.357894 -348.315493) (xy 278.393612 -348.356713)
			(xy 278.423101 -348.402596) (xy 278.445759 -348.452209) (xy 278.461126 -348.504542) (xy 278.468888 -348.558529)
			(xy 278.468888 -348.613071) (xy 278.468888 -348.613074) (xy 279.951592 -348.613074) (xy 279.951592 -348.558526)
			(xy 279.959355 -348.504534) (xy 279.974724 -348.452197) (xy 279.997385 -348.40258) (xy 280.026877 -348.356693)
			(xy 280.0626 -348.315471) (xy 280.103827 -348.279752) (xy 280.149717 -348.250265) (xy 280.199336 -348.227609)
			(xy 280.251676 -348.212246) (xy 280.305668 -348.204489) (xy 280.332942 -348.204028) (xy 281.196542 -348.204028)
			(xy 281.223809 -348.204537) (xy 281.277786 -348.212304) (xy 281.330109 -348.227672) (xy 281.379713 -348.25033)
			(xy 281.425587 -348.279816) (xy 281.466799 -348.315531) (xy 281.502509 -348.356746) (xy 281.53199 -348.402624)
			(xy 281.554643 -348.45223) (xy 281.570005 -348.504555) (xy 281.577766 -348.558533) (xy 281.577766 -348.613067)
			(xy 281.577765 -348.613072) (xy 283.060592 -348.613072) (xy 283.060592 -348.558528) (xy 283.068354 -348.50454)
			(xy 283.083721 -348.452206) (xy 283.106379 -348.402591) (xy 283.135868 -348.356706) (xy 283.171586 -348.315485)
			(xy 283.212808 -348.279766) (xy 283.258693 -348.250278) (xy 283.308307 -348.22762) (xy 283.360642 -348.212253)
			(xy 283.41463 -348.204491) (xy 283.441902 -348.204028) (xy 284.305502 -348.204028) (xy 284.332771 -348.204535)
			(xy 284.386753 -348.212296) (xy 284.43908 -348.227661) (xy 284.488689 -348.250317) (xy 284.534569 -348.279802)
			(xy 284.575785 -348.315517) (xy 284.611499 -348.356733) (xy 284.640984 -348.402613) (xy 284.663639 -348.452221)
			(xy 284.679004 -348.504549) (xy 284.686766 -348.558531) (xy 284.686766 -348.613068) (xy 286.169614 -348.613068)
			(xy 286.169614 -348.558532) (xy 286.177375 -348.50455) (xy 286.192739 -348.452222) (xy 286.215393 -348.402613)
			(xy 286.244876 -348.356733) (xy 286.280588 -348.315515) (xy 286.321802 -348.279799) (xy 286.36768 -348.250311)
			(xy 286.417286 -348.227652) (xy 286.469613 -348.212283) (xy 286.523594 -348.204517) (xy 286.550862 -348.204028)
			(xy 287.414462 -348.204028) (xy 287.441734 -348.204509) (xy 287.495724 -348.212266) (xy 287.54806 -348.227629)
			(xy 287.597676 -348.250284) (xy 287.643563 -348.27977) (xy 287.684787 -348.315486) (xy 287.720508 -348.356706)
			(xy 287.749998 -348.40259) (xy 287.772658 -348.452205) (xy 287.788026 -348.504539) (xy 287.795788 -348.558528)
			(xy 287.795788 -348.613072) (xy 287.795788 -348.613073) (xy 289.278492 -348.613073) (xy 289.278492 -348.558527)
			(xy 289.286254 -348.504537) (xy 289.301622 -348.452201) (xy 289.324282 -348.402585) (xy 289.353772 -348.356699)
			(xy 289.389493 -348.315478) (xy 289.430717 -348.279759) (xy 289.476605 -348.250271) (xy 289.526222 -348.227615)
			(xy 289.578559 -348.21225) (xy 289.632549 -348.20449) (xy 289.659822 -348.204028) (xy 290.523422 -348.204028)
			(xy 290.55069 -348.204536) (xy 290.604669 -348.2123) (xy 290.656995 -348.227667) (xy 290.706601 -348.250324)
			(xy 290.752478 -348.279809) (xy 290.793692 -348.315524) (xy 290.829404 -348.35674) (xy 290.858887 -348.402618)
			(xy 290.881541 -348.452226) (xy 290.896905 -348.504552) (xy 290.904666 -348.558532) (xy 290.904666 -348.613068)
			(xy 290.904666 -348.613069) (xy 292.387514 -348.613069) (xy 292.387514 -348.558531) (xy 292.395276 -348.504547)
			(xy 292.410641 -348.452218) (xy 292.433296 -348.402608) (xy 292.462781 -348.356726) (xy 292.498495 -348.315508)
			(xy 292.539712 -348.279792) (xy 292.585592 -348.250305) (xy 292.635201 -348.227647) (xy 292.68753 -348.21228)
			(xy 292.741513 -348.204516) (xy 292.768782 -348.204028) (xy 293.632382 -348.204028) (xy 293.659653 -348.20451)
			(xy 293.713641 -348.21227) (xy 293.765974 -348.227634) (xy 293.815588 -348.25029) (xy 293.861473 -348.279777)
			(xy 293.902694 -348.315493) (xy 293.938412 -348.356713) (xy 293.967901 -348.402596) (xy 293.990559 -348.452209)
			(xy 294.005926 -348.504542) (xy 294.013688 -348.558529) (xy 294.013688 -348.613071) (xy 294.013688 -348.613074)
			(xy 295.496392 -348.613074) (xy 295.496392 -348.558526) (xy 295.504155 -348.504534) (xy 295.519524 -348.452197)
			(xy 295.542185 -348.40258) (xy 295.571677 -348.356693) (xy 295.6074 -348.315471) (xy 295.648627 -348.279752)
			(xy 295.694517 -348.250265) (xy 295.744136 -348.227609) (xy 295.796476 -348.212246) (xy 295.850468 -348.204489)
			(xy 295.877742 -348.204028) (xy 296.741342 -348.204028) (xy 296.768609 -348.204537) (xy 296.822586 -348.212304)
			(xy 296.874909 -348.227672) (xy 296.924513 -348.25033) (xy 296.970387 -348.279816) (xy 297.011599 -348.315531)
			(xy 297.047309 -348.356746) (xy 297.07679 -348.402624) (xy 297.099443 -348.45223) (xy 297.114805 -348.504555)
			(xy 297.122566 -348.558533) (xy 297.122566 -348.613067) (xy 297.122565 -348.613072) (xy 298.605392 -348.613072)
			(xy 298.605392 -348.558528) (xy 298.613154 -348.50454) (xy 298.628521 -348.452206) (xy 298.651179 -348.402591)
			(xy 298.680668 -348.356706) (xy 298.716386 -348.315485) (xy 298.757608 -348.279766) (xy 298.803493 -348.250278)
			(xy 298.853107 -348.22762) (xy 298.905442 -348.212253) (xy 298.95943 -348.204491) (xy 298.986702 -348.204028)
			(xy 299.850302 -348.204028) (xy 299.877571 -348.204535) (xy 299.931553 -348.212296) (xy 299.98388 -348.227661)
			(xy 300.033489 -348.250317) (xy 300.079369 -348.279802) (xy 300.120585 -348.315517) (xy 300.156299 -348.356733)
			(xy 300.185784 -348.402613) (xy 300.208439 -348.452221) (xy 300.223804 -348.504549) (xy 300.231566 -348.558531)
			(xy 300.231566 -348.613069) (xy 300.231566 -348.613072) (xy 312.121492 -348.613072) (xy 312.121492 -348.558528)
			(xy 312.129254 -348.504539) (xy 312.144621 -348.452205) (xy 312.167279 -348.40259) (xy 312.196768 -348.356705)
			(xy 312.232487 -348.315484) (xy 312.273709 -348.279766) (xy 312.319594 -348.250277) (xy 312.369209 -348.227619)
			(xy 312.421543 -348.212253) (xy 312.475532 -348.204491) (xy 312.502804 -348.204028) (xy 313.366404 -348.204028)
			(xy 313.393672 -348.204535) (xy 313.447654 -348.212297) (xy 313.499982 -348.227662) (xy 313.54959 -348.250318)
			(xy 313.595469 -348.279803) (xy 313.636686 -348.315517) (xy 313.672399 -348.356734) (xy 313.701884 -348.402613)
			(xy 313.72454 -348.452222) (xy 313.739904 -348.50455) (xy 313.747666 -348.558532) (xy 313.747666 -348.613068)
			(xy 315.230514 -348.613068) (xy 315.230514 -348.558532) (xy 315.238275 -348.50455) (xy 315.253639 -348.452222)
			(xy 315.276293 -348.402613) (xy 315.305777 -348.356732) (xy 315.341489 -348.315514) (xy 315.382703 -348.279798)
			(xy 315.428581 -348.250311) (xy 315.478188 -348.227652) (xy 315.530514 -348.212283) (xy 315.584496 -348.204517)
			(xy 315.611764 -348.204028) (xy 316.475364 -348.204028) (xy 316.502636 -348.204509) (xy 316.556625 -348.212267)
			(xy 316.608961 -348.22763) (xy 316.658577 -348.250284) (xy 316.704464 -348.27977) (xy 316.745688 -348.315487)
			(xy 316.781408 -348.356707) (xy 316.810898 -348.402591) (xy 316.833558 -348.452205) (xy 316.848926 -348.504539)
			(xy 316.856688 -348.558528) (xy 316.856688 -348.613072) (xy 316.856688 -348.613073) (xy 318.339392 -348.613073)
			(xy 318.339392 -348.558527) (xy 318.347155 -348.504537) (xy 318.362522 -348.452201) (xy 318.385182 -348.402585)
			(xy 318.414673 -348.356699) (xy 318.450394 -348.315477) (xy 318.491618 -348.279759) (xy 318.537506 -348.250271)
			(xy 318.587123 -348.227614) (xy 318.63946 -348.212249) (xy 318.693451 -348.20449) (xy 318.720724 -348.204028)
			(xy 319.584324 -348.204028) (xy 319.611592 -348.204536) (xy 319.665571 -348.2123) (xy 319.717896 -348.227667)
			(xy 319.767502 -348.250324) (xy 319.813379 -348.27981) (xy 319.854593 -348.315524) (xy 319.890304 -348.35674)
			(xy 319.919787 -348.402619) (xy 319.942441 -348.452226) (xy 319.957805 -348.504552) (xy 319.965566 -348.558532)
			(xy 319.965566 -348.613068) (xy 319.965566 -348.613069) (xy 321.448414 -348.613069) (xy 321.448414 -348.558531)
			(xy 321.456176 -348.504547) (xy 321.471541 -348.452217) (xy 321.494196 -348.402607) (xy 321.523682 -348.356726)
			(xy 321.559396 -348.315507) (xy 321.600613 -348.279791) (xy 321.646493 -348.250304) (xy 321.696102 -348.227646)
			(xy 321.748431 -348.212279) (xy 321.802415 -348.204516) (xy 321.829684 -348.204028) (xy 322.693284 -348.204028)
			(xy 322.720555 -348.20451) (xy 322.774542 -348.21227) (xy 322.826875 -348.227635) (xy 322.876489 -348.250291)
			(xy 322.922374 -348.279777) (xy 322.963595 -348.315494) (xy 322.999313 -348.356713) (xy 323.028801 -348.402597)
			(xy 323.051459 -348.45221) (xy 323.066826 -348.504542) (xy 323.074588 -348.558529) (xy 323.074588 -348.613071)
			(xy 323.074588 -348.613074) (xy 324.557292 -348.613074) (xy 324.557292 -348.558526) (xy 324.565055 -348.504534)
			(xy 324.580424 -348.452197) (xy 324.603085 -348.402579) (xy 324.632578 -348.356692) (xy 324.668301 -348.31547)
			(xy 324.709527 -348.279751) (xy 324.755418 -348.250264) (xy 324.805038 -348.227609) (xy 324.857377 -348.212246)
			(xy 324.91137 -348.204489) (xy 324.938644 -348.204028) (xy 325.802244 -348.204028) (xy 325.829511 -348.204537)
			(xy 325.883488 -348.212304) (xy 325.935811 -348.227673) (xy 325.985414 -348.250331) (xy 326.031288 -348.279817)
			(xy 326.0725 -348.315531) (xy 326.108209 -348.356747) (xy 326.13769 -348.402624) (xy 326.160343 -348.45223)
			(xy 326.175705 -348.504555) (xy 326.183466 -348.558533) (xy 326.183466 -348.613067) (xy 326.183465 -348.613072)
			(xy 327.666292 -348.613072) (xy 327.666292 -348.558528) (xy 327.674054 -348.504539) (xy 327.689421 -348.452205)
			(xy 327.712079 -348.40259) (xy 327.741568 -348.356705) (xy 327.777287 -348.315484) (xy 327.818509 -348.279766)
			(xy 327.864394 -348.250277) (xy 327.914009 -348.227619) (xy 327.966343 -348.212253) (xy 328.020332 -348.204491)
			(xy 328.047604 -348.204028) (xy 328.911204 -348.204028) (xy 328.938472 -348.204535) (xy 328.992454 -348.212297)
			(xy 329.044782 -348.227662) (xy 329.09439 -348.250318) (xy 329.140269 -348.279803) (xy 329.181486 -348.315517)
			(xy 329.217199 -348.356734) (xy 329.246684 -348.402613) (xy 329.26934 -348.452222) (xy 329.284704 -348.50455)
			(xy 329.292466 -348.558532) (xy 329.292466 -348.613068) (xy 330.775314 -348.613068) (xy 330.775314 -348.558532)
			(xy 330.783075 -348.50455) (xy 330.798439 -348.452222) (xy 330.821093 -348.402613) (xy 330.850577 -348.356732)
			(xy 330.886289 -348.315514) (xy 330.927503 -348.279798) (xy 330.973381 -348.250311) (xy 331.022988 -348.227652)
			(xy 331.075314 -348.212283) (xy 331.129296 -348.204517) (xy 331.156564 -348.204028) (xy 332.020164 -348.204028)
			(xy 332.047436 -348.204509) (xy 332.101425 -348.212267) (xy 332.153761 -348.22763) (xy 332.203377 -348.250284)
			(xy 332.249264 -348.27977) (xy 332.290488 -348.315487) (xy 332.326208 -348.356707) (xy 332.355698 -348.402591)
			(xy 332.378358 -348.452205) (xy 332.393726 -348.504539) (xy 332.401488 -348.558528) (xy 332.401488 -348.613072)
			(xy 332.401488 -348.613073) (xy 333.884192 -348.613073) (xy 333.884192 -348.558527) (xy 333.891955 -348.504537)
			(xy 333.907322 -348.452201) (xy 333.929982 -348.402585) (xy 333.959473 -348.356699) (xy 333.995194 -348.315477)
			(xy 334.036418 -348.279759) (xy 334.082306 -348.250271) (xy 334.131923 -348.227614) (xy 334.18426 -348.212249)
			(xy 334.238251 -348.20449) (xy 334.265524 -348.204028) (xy 335.129124 -348.204028) (xy 335.156392 -348.204536)
			(xy 335.210371 -348.2123) (xy 335.262696 -348.227667) (xy 335.312302 -348.250324) (xy 335.358179 -348.27981)
			(xy 335.399393 -348.315524) (xy 335.435104 -348.35674) (xy 335.464587 -348.402619) (xy 335.487241 -348.452226)
			(xy 335.502605 -348.504552) (xy 335.510366 -348.558532) (xy 335.510366 -348.613068) (xy 335.510366 -348.613069)
			(xy 336.993214 -348.613069) (xy 336.993214 -348.558531) (xy 337.000976 -348.504547) (xy 337.016341 -348.452217)
			(xy 337.038996 -348.402607) (xy 337.068482 -348.356726) (xy 337.104196 -348.315507) (xy 337.145413 -348.279791)
			(xy 337.191293 -348.250304) (xy 337.240902 -348.227646) (xy 337.293231 -348.212279) (xy 337.347215 -348.204516)
			(xy 337.374484 -348.204028) (xy 338.238084 -348.204028) (xy 338.265355 -348.20451) (xy 338.319342 -348.21227)
			(xy 338.371675 -348.227635) (xy 338.421289 -348.250291) (xy 338.467174 -348.279777) (xy 338.508395 -348.315494)
			(xy 338.544113 -348.356713) (xy 338.573601 -348.402597) (xy 338.596259 -348.45221) (xy 338.611626 -348.504542)
			(xy 338.619388 -348.558529) (xy 338.619388 -348.613071) (xy 338.619388 -348.613074) (xy 340.102092 -348.613074)
			(xy 340.102092 -348.558526) (xy 340.109855 -348.504534) (xy 340.125224 -348.452197) (xy 340.147885 -348.402579)
			(xy 340.177378 -348.356692) (xy 340.213101 -348.31547) (xy 340.254327 -348.279751) (xy 340.300218 -348.250264)
			(xy 340.349838 -348.227609) (xy 340.402177 -348.212246) (xy 340.45617 -348.204489) (xy 340.483444 -348.204028)
			(xy 341.347044 -348.204028) (xy 341.374311 -348.204537) (xy 341.428288 -348.212304) (xy 341.480611 -348.227673)
			(xy 341.530214 -348.250331) (xy 341.576088 -348.279817) (xy 341.6173 -348.315531) (xy 341.653009 -348.356747)
			(xy 341.68249 -348.402624) (xy 341.705143 -348.45223) (xy 341.720505 -348.504555) (xy 341.728266 -348.558533)
			(xy 341.728266 -348.613067) (xy 341.728265 -348.613072) (xy 343.211092 -348.613072) (xy 343.211092 -348.558528)
			(xy 343.218854 -348.504539) (xy 343.234221 -348.452205) (xy 343.256879 -348.40259) (xy 343.286368 -348.356705)
			(xy 343.322087 -348.315484) (xy 343.363309 -348.279766) (xy 343.409194 -348.250277) (xy 343.458809 -348.227619)
			(xy 343.511143 -348.212253) (xy 343.565132 -348.204491) (xy 343.592404 -348.204028) (xy 344.456004 -348.204028)
			(xy 344.483272 -348.204535) (xy 344.537254 -348.212297) (xy 344.589582 -348.227662) (xy 344.63919 -348.250318)
			(xy 344.685069 -348.279803) (xy 344.726286 -348.315517) (xy 344.761999 -348.356734) (xy 344.791484 -348.402613)
			(xy 344.81414 -348.452222) (xy 344.829504 -348.50455) (xy 344.837266 -348.558532) (xy 344.837266 -348.613068)
			(xy 344.837266 -348.613069) (xy 370.806714 -348.613069) (xy 370.806714 -348.558531) (xy 370.814476 -348.504548)
			(xy 370.82984 -348.452218) (xy 370.852496 -348.402608) (xy 370.881981 -348.356727) (xy 370.917695 -348.315509)
			(xy 370.958911 -348.279793) (xy 371.004791 -348.250305) (xy 371.054399 -348.227647) (xy 371.106728 -348.21228)
			(xy 371.160711 -348.204516) (xy 371.18798 -348.204028) (xy 372.05158 -348.204028) (xy 372.078851 -348.20451)
			(xy 372.132839 -348.21227) (xy 372.185173 -348.227634) (xy 372.234787 -348.25029) (xy 372.280672 -348.279776)
			(xy 372.321893 -348.315493) (xy 372.357612 -348.356712) (xy 372.387101 -348.402595) (xy 372.409759 -348.452209)
			(xy 372.425126 -348.504542) (xy 372.432888 -348.558529) (xy 372.432888 -348.613071) (xy 372.432888 -348.613074)
			(xy 373.915592 -348.613074) (xy 373.915592 -348.558526) (xy 373.923355 -348.504535) (xy 373.938724 -348.452197)
			(xy 373.961385 -348.40258) (xy 373.990877 -348.356694) (xy 374.0266 -348.315471) (xy 374.067826 -348.279753)
			(xy 374.113715 -348.250266) (xy 374.163335 -348.22761) (xy 374.215674 -348.212246) (xy 374.269666 -348.204489)
			(xy 374.29694 -348.204028) (xy 375.16054 -348.204028) (xy 375.187807 -348.204537) (xy 375.241785 -348.212303)
			(xy 375.294108 -348.227672) (xy 375.343712 -348.25033) (xy 375.389587 -348.279816) (xy 375.430798 -348.31553)
			(xy 375.466508 -348.356746) (xy 375.49599 -348.402623) (xy 375.518642 -348.45223) (xy 375.534005 -348.504554)
			(xy 375.541766 -348.558533) (xy 375.541766 -348.613067) (xy 375.541766 -348.61307) (xy 377.024614 -348.61307)
			(xy 377.024614 -348.55853) (xy 377.032376 -348.504545) (xy 377.047742 -348.452214) (xy 377.070399 -348.402603)
			(xy 377.099886 -348.35672) (xy 377.135602 -348.315502) (xy 377.17682 -348.279786) (xy 377.222703 -348.250299)
			(xy 377.272314 -348.227642) (xy 377.324645 -348.212276) (xy 377.37863 -348.204514) (xy 377.4059 -348.204028)
			(xy 378.2695 -348.204028) (xy 378.296769 -348.204534) (xy 378.350751 -348.212296) (xy 378.403079 -348.227661)
			(xy 378.452688 -348.250316) (xy 378.498568 -348.279802) (xy 378.539784 -348.315516) (xy 378.575498 -348.356732)
			(xy 378.604984 -348.402612) (xy 378.627639 -348.452221) (xy 378.643004 -348.504549) (xy 378.650766 -348.558531)
			(xy 378.650766 -348.613068) (xy 380.133614 -348.613068) (xy 380.133614 -348.558532) (xy 380.141375 -348.50455)
			(xy 380.156739 -348.452223) (xy 380.179393 -348.402614) (xy 380.208876 -348.356734) (xy 380.244588 -348.315516)
			(xy 380.285801 -348.2798) (xy 380.331679 -348.250312) (xy 380.381285 -348.227653) (xy 380.433611 -348.212284)
			(xy 380.487592 -348.204517) (xy 380.51486 -348.204028) (xy 381.37846 -348.204028) (xy 381.405732 -348.204509)
			(xy 381.459722 -348.212266) (xy 381.512058 -348.227628) (xy 381.561675 -348.250283) (xy 381.607562 -348.279769)
			(xy 381.648786 -348.315485) (xy 381.684507 -348.356706) (xy 381.713998 -348.40259) (xy 381.736658 -348.452204)
			(xy 381.752025 -348.504539) (xy 381.759788 -348.558528) (xy 381.759788 -348.613072) (xy 381.759788 -348.613073)
			(xy 383.242492 -348.613073) (xy 383.242492 -348.558527) (xy 383.250254 -348.504537) (xy 383.265622 -348.452202)
			(xy 383.288282 -348.402586) (xy 383.317772 -348.3567) (xy 383.353493 -348.315478) (xy 383.394716 -348.27976)
			(xy 383.440603 -348.250272) (xy 383.49022 -348.227615) (xy 383.542557 -348.21225) (xy 383.596547 -348.20449)
			(xy 383.62382 -348.204028) (xy 384.48742 -348.204028) (xy 384.514688 -348.204536) (xy 384.568668 -348.2123)
			(xy 384.620994 -348.227666) (xy 384.6706 -348.250323) (xy 384.716477 -348.279809) (xy 384.757691 -348.315523)
			(xy 384.793403 -348.356739) (xy 384.822887 -348.402618) (xy 384.845541 -348.452225) (xy 384.860905 -348.504552)
			(xy 384.868666 -348.558532) (xy 384.868666 -348.613068) (xy 384.868666 -348.613069) (xy 386.351514 -348.613069)
			(xy 386.351514 -348.558531) (xy 386.359276 -348.504548) (xy 386.37464 -348.452218) (xy 386.397296 -348.402608)
			(xy 386.426781 -348.356727) (xy 386.462495 -348.315509) (xy 386.503711 -348.279793) (xy 386.549591 -348.250305)
			(xy 386.599199 -348.227647) (xy 386.651528 -348.21228) (xy 386.705511 -348.204516) (xy 386.73278 -348.204028)
			(xy 387.59638 -348.204028) (xy 387.623651 -348.20451) (xy 387.677639 -348.21227) (xy 387.729973 -348.227634)
			(xy 387.779587 -348.25029) (xy 387.825472 -348.279776) (xy 387.866693 -348.315493) (xy 387.902412 -348.356712)
			(xy 387.931901 -348.402595) (xy 387.954559 -348.452209) (xy 387.969926 -348.504542) (xy 387.977688 -348.558529)
			(xy 387.977688 -348.613071) (xy 387.977688 -348.613074) (xy 389.460392 -348.613074) (xy 389.460392 -348.558526)
			(xy 389.468155 -348.504535) (xy 389.483524 -348.452197) (xy 389.506185 -348.40258) (xy 389.535677 -348.356694)
			(xy 389.5714 -348.315471) (xy 389.612626 -348.279753) (xy 389.658515 -348.250266) (xy 389.708135 -348.22761)
			(xy 389.760474 -348.212246) (xy 389.814466 -348.204489) (xy 389.84174 -348.204028) (xy 390.70534 -348.204028)
			(xy 390.732607 -348.204537) (xy 390.786585 -348.212303) (xy 390.838908 -348.227672) (xy 390.888512 -348.25033)
			(xy 390.934387 -348.279816) (xy 390.975598 -348.31553) (xy 391.011308 -348.356746) (xy 391.04079 -348.402623)
			(xy 391.063442 -348.45223) (xy 391.078805 -348.504554) (xy 391.086566 -348.558533) (xy 391.086566 -348.613067)
			(xy 391.086566 -348.61307) (xy 392.569414 -348.61307) (xy 392.569414 -348.55853) (xy 392.577176 -348.504545)
			(xy 392.592542 -348.452214) (xy 392.615199 -348.402603) (xy 392.644686 -348.35672) (xy 392.680402 -348.315502)
			(xy 392.72162 -348.279786) (xy 392.767503 -348.250299) (xy 392.817114 -348.227642) (xy 392.869445 -348.212276)
			(xy 392.92343 -348.204514) (xy 392.9507 -348.204028) (xy 393.8143 -348.204028) (xy 393.841569 -348.204534)
			(xy 393.895551 -348.212296) (xy 393.947879 -348.227661) (xy 393.997488 -348.250316) (xy 394.043368 -348.279802)
			(xy 394.084584 -348.315516) (xy 394.120298 -348.356732) (xy 394.149784 -348.402612) (xy 394.172439 -348.452221)
			(xy 394.187804 -348.504549) (xy 394.195566 -348.558531) (xy 394.195566 -348.613068) (xy 395.678414 -348.613068)
			(xy 395.678414 -348.558532) (xy 395.686175 -348.50455) (xy 395.701539 -348.452223) (xy 395.724193 -348.402614)
			(xy 395.753676 -348.356734) (xy 395.789388 -348.315516) (xy 395.830601 -348.2798) (xy 395.876479 -348.250312)
			(xy 395.926085 -348.227653) (xy 395.978411 -348.212284) (xy 396.032392 -348.204517) (xy 396.05966 -348.204028)
			(xy 396.92326 -348.204028) (xy 396.950532 -348.204509) (xy 397.004522 -348.212266) (xy 397.056858 -348.227628)
			(xy 397.106475 -348.250283) (xy 397.152362 -348.279769) (xy 397.193586 -348.315485) (xy 397.229307 -348.356706)
			(xy 397.258798 -348.40259) (xy 397.281458 -348.452204) (xy 397.296825 -348.504539) (xy 397.304588 -348.558528)
			(xy 397.304588 -348.613072) (xy 397.304588 -348.613073) (xy 398.787292 -348.613073) (xy 398.787292 -348.558527)
			(xy 398.795054 -348.504537) (xy 398.810422 -348.452202) (xy 398.833082 -348.402586) (xy 398.862572 -348.3567)
			(xy 398.898293 -348.315478) (xy 398.939516 -348.27976) (xy 398.985403 -348.250272) (xy 399.03502 -348.227615)
			(xy 399.087357 -348.21225) (xy 399.141347 -348.20449) (xy 399.16862 -348.204028) (xy 400.03222 -348.204028)
			(xy 400.059488 -348.204536) (xy 400.113468 -348.2123) (xy 400.165794 -348.227666) (xy 400.2154 -348.250323)
			(xy 400.261277 -348.279809) (xy 400.302491 -348.315523) (xy 400.338203 -348.356739) (xy 400.367687 -348.402618)
			(xy 400.390341 -348.452225) (xy 400.405705 -348.504552) (xy 400.413466 -348.558532) (xy 400.413466 -348.613068)
			(xy 400.413466 -348.613069) (xy 401.896314 -348.613069) (xy 401.896314 -348.558531) (xy 401.904076 -348.504548)
			(xy 401.91944 -348.452218) (xy 401.942096 -348.402608) (xy 401.971581 -348.356727) (xy 402.007295 -348.315509)
			(xy 402.048511 -348.279793) (xy 402.094391 -348.250305) (xy 402.143999 -348.227647) (xy 402.196328 -348.21228)
			(xy 402.250311 -348.204516) (xy 402.27758 -348.204028) (xy 403.14118 -348.204028) (xy 403.168451 -348.20451)
			(xy 403.222439 -348.21227) (xy 403.274773 -348.227634) (xy 403.324387 -348.25029) (xy 403.370272 -348.279776)
			(xy 403.411493 -348.315493) (xy 403.447212 -348.356712) (xy 403.476701 -348.402595) (xy 403.499359 -348.452209)
			(xy 403.514726 -348.504542) (xy 403.522488 -348.558529) (xy 403.522488 -348.61307) (xy 408.913814 -348.61307)
			(xy 408.913814 -348.55853) (xy 408.921576 -348.504546) (xy 408.936941 -348.452216) (xy 408.959598 -348.402605)
			(xy 408.989084 -348.356723) (xy 409.024799 -348.315505) (xy 409.066017 -348.279788) (xy 409.111898 -348.250301)
			(xy 409.161508 -348.227644) (xy 409.213838 -348.212278) (xy 409.267822 -348.204515) (xy 409.295092 -348.204028)
			(xy 410.158692 -348.204028) (xy 410.185963 -348.204511) (xy 410.239949 -348.212272) (xy 410.292281 -348.227637)
			(xy 410.341894 -348.250294) (xy 410.387778 -348.27978) (xy 410.428998 -348.315497) (xy 410.464715 -348.356716)
			(xy 410.494203 -348.402599) (xy 410.51686 -348.452211) (xy 410.532226 -348.504543) (xy 410.539989 -348.558529)
			(xy 410.539989 -348.613068) (xy 412.022814 -348.613068) (xy 412.022814 -348.558532) (xy 412.030575 -348.504551)
			(xy 412.045938 -348.452224) (xy 412.068592 -348.402616) (xy 412.098074 -348.356736) (xy 412.133785 -348.315519)
			(xy 412.174998 -348.279803) (xy 412.220874 -348.250315) (xy 412.270479 -348.227655) (xy 412.322804 -348.212285)
			(xy 412.376784 -348.204518) (xy 412.404052 -348.204028) (xy 413.267652 -348.204028) (xy 413.294925 -348.204508)
			(xy 413.348915 -348.212265) (xy 413.401252 -348.227626) (xy 413.45087 -348.250281) (xy 413.496759 -348.279766)
			(xy 413.537983 -348.315483) (xy 413.573705 -348.356703) (xy 413.603196 -348.402588) (xy 413.625857 -348.452203)
			(xy 413.641225 -348.504538) (xy 413.648988 -348.558528) (xy 413.648988 -348.613072) (xy 415.131692 -348.613072)
			(xy 415.131692 -348.558528) (xy 415.139454 -348.504538) (xy 415.154821 -348.452203) (xy 415.177481 -348.402588)
			(xy 415.20697 -348.356703) (xy 415.24269 -348.315481) (xy 415.283912 -348.279763) (xy 415.329799 -348.250275)
			(xy 415.379415 -348.227617) (xy 415.43175 -348.212252) (xy 415.48574 -348.204491) (xy 415.513012 -348.204028)
			(xy 416.376612 -348.204028) (xy 416.40388 -348.204535) (xy 416.457861 -348.212298) (xy 416.510188 -348.227664)
			(xy 416.559795 -348.25032) (xy 416.605673 -348.279806) (xy 416.646888 -348.31552) (xy 416.682601 -348.356736)
			(xy 416.712085 -348.402615) (xy 416.73474 -348.452224) (xy 416.750104 -348.504551) (xy 416.757866 -348.558532)
			(xy 416.757866 -348.613068) (xy 416.757866 -348.613069) (xy 418.240714 -348.613069) (xy 418.240714 -348.558531)
			(xy 418.248476 -348.504549) (xy 418.26384 -348.45222) (xy 418.286495 -348.40261) (xy 418.315979 -348.35673)
			(xy 418.351692 -348.315512) (xy 418.392907 -348.279795) (xy 418.438786 -348.250308) (xy 418.488394 -348.22765)
			(xy 418.540721 -348.212281) (xy 418.594703 -348.204516) (xy 418.621972 -348.204028) (xy 419.485572 -348.204028)
			(xy 419.512844 -348.20451) (xy 419.566832 -348.212268) (xy 419.619167 -348.227632) (xy 419.668782 -348.250287)
			(xy 419.714668 -348.279773) (xy 419.75589 -348.31549) (xy 419.79161 -348.356709) (xy 419.821099 -348.402593)
			(xy 419.843759 -348.452207) (xy 419.859126 -348.504541) (xy 419.866888 -348.558528) (xy 419.866888 -348.613072)
			(xy 419.866888 -348.613073) (xy 421.349592 -348.613073) (xy 421.349592 -348.558527) (xy 421.357355 -348.504536)
			(xy 421.372723 -348.452199) (xy 421.395384 -348.402583) (xy 421.424875 -348.356696) (xy 421.460597 -348.315474)
			(xy 421.501822 -348.279756) (xy 421.547711 -348.250268) (xy 421.597329 -348.227612) (xy 421.649667 -348.212248)
			(xy 421.703659 -348.204489) (xy 421.730932 -348.204028) (xy 422.594532 -348.204028) (xy 422.621799 -348.204537)
			(xy 422.675778 -348.212302) (xy 422.728102 -348.227669) (xy 422.777707 -348.250327) (xy 422.823583 -348.279813)
			(xy 422.864795 -348.315527) (xy 422.900506 -348.356743) (xy 422.929988 -348.402621) (xy 422.952642 -348.452228)
			(xy 422.968005 -348.504553) (xy 422.975766 -348.558533) (xy 422.975766 -348.613067) (xy 422.975766 -348.61307)
			(xy 424.458614 -348.61307) (xy 424.458614 -348.55853) (xy 424.466376 -348.504546) (xy 424.481741 -348.452216)
			(xy 424.504398 -348.402605) (xy 424.533884 -348.356723) (xy 424.569599 -348.315505) (xy 424.610817 -348.279788)
			(xy 424.656698 -348.250301) (xy 424.706308 -348.227644) (xy 424.758638 -348.212278) (xy 424.812622 -348.204515)
			(xy 424.839892 -348.204028) (xy 425.703492 -348.204028) (xy 425.730763 -348.204511) (xy 425.784749 -348.212272)
			(xy 425.837081 -348.227637) (xy 425.886694 -348.250294) (xy 425.932578 -348.27978) (xy 425.973798 -348.315497)
			(xy 426.009515 -348.356716) (xy 426.039003 -348.402599) (xy 426.06166 -348.452211) (xy 426.077026 -348.504543)
			(xy 426.084789 -348.558529) (xy 426.084789 -348.613068) (xy 427.567614 -348.613068) (xy 427.567614 -348.558532)
			(xy 427.575375 -348.504551) (xy 427.590738 -348.452224) (xy 427.613392 -348.402616) (xy 427.642874 -348.356736)
			(xy 427.678585 -348.315519) (xy 427.719798 -348.279803) (xy 427.765674 -348.250315) (xy 427.815279 -348.227655)
			(xy 427.867604 -348.212285) (xy 427.921584 -348.204518) (xy 427.948852 -348.204028) (xy 428.812452 -348.204028)
			(xy 428.839725 -348.204508) (xy 428.893715 -348.212265) (xy 428.946052 -348.227626) (xy 428.99567 -348.250281)
			(xy 429.041559 -348.279766) (xy 429.082783 -348.315483) (xy 429.118505 -348.356703) (xy 429.147996 -348.402588)
			(xy 429.170657 -348.452203) (xy 429.186025 -348.504538) (xy 429.193788 -348.558528) (xy 429.193788 -348.613072)
			(xy 430.676492 -348.613072) (xy 430.676492 -348.558528) (xy 430.684254 -348.504538) (xy 430.699621 -348.452203)
			(xy 430.722281 -348.402588) (xy 430.75177 -348.356703) (xy 430.78749 -348.315481) (xy 430.828712 -348.279763)
			(xy 430.874599 -348.250275) (xy 430.924215 -348.227617) (xy 430.97655 -348.212252) (xy 431.03054 -348.204491)
			(xy 431.057812 -348.204028) (xy 431.921412 -348.204028) (xy 431.94868 -348.204535) (xy 432.002661 -348.212298)
			(xy 432.054988 -348.227664) (xy 432.104595 -348.25032) (xy 432.150473 -348.279806) (xy 432.191688 -348.31552)
			(xy 432.227401 -348.356736) (xy 432.256885 -348.402615) (xy 432.27954 -348.452224) (xy 432.294904 -348.504551)
			(xy 432.302666 -348.558532) (xy 432.302666 -348.613068) (xy 432.302666 -348.613069) (xy 433.785514 -348.613069)
			(xy 433.785514 -348.558531) (xy 433.793276 -348.504549) (xy 433.80864 -348.45222) (xy 433.831295 -348.40261)
			(xy 433.860779 -348.35673) (xy 433.896492 -348.315512) (xy 433.937707 -348.279795) (xy 433.983586 -348.250308)
			(xy 434.033194 -348.22765) (xy 434.085521 -348.212281) (xy 434.139503 -348.204516) (xy 434.166772 -348.204028)
			(xy 435.030372 -348.204028) (xy 435.057644 -348.20451) (xy 435.111632 -348.212268) (xy 435.163967 -348.227632)
			(xy 435.213582 -348.250287) (xy 435.259468 -348.279773) (xy 435.30069 -348.31549) (xy 435.33641 -348.356709)
			(xy 435.365899 -348.402593) (xy 435.388559 -348.452207) (xy 435.403926 -348.504541) (xy 435.411688 -348.558528)
			(xy 435.411688 -348.613072) (xy 435.411688 -348.613073) (xy 436.894392 -348.613073) (xy 436.894392 -348.558527)
			(xy 436.902155 -348.504536) (xy 436.917523 -348.452199) (xy 436.940184 -348.402583) (xy 436.969675 -348.356696)
			(xy 437.005397 -348.315474) (xy 437.046622 -348.279756) (xy 437.092511 -348.250268) (xy 437.142129 -348.227612)
			(xy 437.194467 -348.212248) (xy 437.248459 -348.204489) (xy 437.275732 -348.204028) (xy 438.139332 -348.204028)
			(xy 438.166599 -348.204537) (xy 438.220578 -348.212302) (xy 438.272902 -348.227669) (xy 438.322507 -348.250327)
			(xy 438.368383 -348.279813) (xy 438.409595 -348.315527) (xy 438.445306 -348.356743) (xy 438.474788 -348.402621)
			(xy 438.497442 -348.452228) (xy 438.512805 -348.504553) (xy 438.520566 -348.558533) (xy 438.520566 -348.613067)
			(xy 438.520566 -348.61307) (xy 440.003414 -348.61307) (xy 440.003414 -348.55853) (xy 440.011176 -348.504546)
			(xy 440.026541 -348.452216) (xy 440.049198 -348.402605) (xy 440.078684 -348.356723) (xy 440.114399 -348.315505)
			(xy 440.155617 -348.279788) (xy 440.201498 -348.250301) (xy 440.251108 -348.227644) (xy 440.303438 -348.212278)
			(xy 440.357422 -348.204515) (xy 440.384692 -348.204028) (xy 441.248292 -348.204028) (xy 441.275563 -348.204511)
			(xy 441.329549 -348.212272) (xy 441.381881 -348.227637) (xy 441.431494 -348.250294) (xy 441.477378 -348.27978)
			(xy 441.518598 -348.315497) (xy 441.554315 -348.356716) (xy 441.583803 -348.402599) (xy 441.60646 -348.452211)
			(xy 441.621826 -348.504543) (xy 441.629589 -348.558529) (xy 441.629589 -348.613071) (xy 441.621826 -348.667057)
			(xy 441.60646 -348.719389) (xy 441.583803 -348.769001) (xy 441.554315 -348.814884) (xy 441.518598 -348.856103)
			(xy 441.477378 -348.89182) (xy 441.431494 -348.921306) (xy 441.381881 -348.943963) (xy 441.329549 -348.959328)
			(xy 441.275563 -348.967089) (xy 441.248292 -348.967552) (xy 440.384692 -348.967552) (xy 440.357422 -348.967085)
			(xy 440.303438 -348.959322) (xy 440.251108 -348.943956) (xy 440.201498 -348.921299) (xy 440.155617 -348.891812)
			(xy 440.114399 -348.856095) (xy 440.078684 -348.814877) (xy 440.049198 -348.768995) (xy 440.026541 -348.719384)
			(xy 440.011176 -348.667054) (xy 440.003414 -348.61307) (xy 438.520566 -348.61307) (xy 438.512805 -348.667047)
			(xy 438.497442 -348.719372) (xy 438.474788 -348.768979) (xy 438.445306 -348.814857) (xy 438.409595 -348.856073)
			(xy 438.368383 -348.891787) (xy 438.322507 -348.921273) (xy 438.272902 -348.943931) (xy 438.220578 -348.959298)
			(xy 438.166599 -348.967063) (xy 438.139332 -348.967552) (xy 437.275732 -348.967552) (xy 437.248459 -348.967111)
			(xy 437.194467 -348.959352) (xy 437.142129 -348.943988) (xy 437.092511 -348.921332) (xy 437.046622 -348.891844)
			(xy 437.005397 -348.856126) (xy 436.969675 -348.814904) (xy 436.940184 -348.769017) (xy 436.917523 -348.719401)
			(xy 436.902155 -348.667064) (xy 436.894392 -348.613073) (xy 435.411688 -348.613073) (xy 435.403926 -348.667059)
			(xy 435.388559 -348.719393) (xy 435.365899 -348.769007) (xy 435.33641 -348.814891) (xy 435.30069 -348.85611)
			(xy 435.259468 -348.891827) (xy 435.213582 -348.921313) (xy 435.163967 -348.943968) (xy 435.111632 -348.959332)
			(xy 435.057644 -348.96709) (xy 435.030372 -348.967552) (xy 434.166772 -348.967552) (xy 434.139503 -348.967084)
			(xy 434.085521 -348.959319) (xy 434.033194 -348.94395) (xy 433.983586 -348.921292) (xy 433.937707 -348.891805)
			(xy 433.896492 -348.856088) (xy 433.860779 -348.81487) (xy 433.831295 -348.76899) (xy 433.80864 -348.71938)
			(xy 433.793276 -348.667051) (xy 433.785514 -348.613069) (xy 432.302666 -348.613069) (xy 432.294904 -348.667049)
			(xy 432.27954 -348.719376) (xy 432.256885 -348.768985) (xy 432.227401 -348.814864) (xy 432.191688 -348.85608)
			(xy 432.150473 -348.891794) (xy 432.104595 -348.92128) (xy 432.054988 -348.943936) (xy 432.002661 -348.959302)
			(xy 431.94868 -348.967065) (xy 431.921412 -348.967552) (xy 431.057812 -348.967552) (xy 431.03054 -348.967109)
			(xy 430.97655 -348.959348) (xy 430.924215 -348.943983) (xy 430.874599 -348.921325) (xy 430.828712 -348.891837)
			(xy 430.78749 -348.856119) (xy 430.75177 -348.814897) (xy 430.722281 -348.769012) (xy 430.699621 -348.719397)
			(xy 430.684254 -348.667062) (xy 430.676492 -348.613072) (xy 429.193788 -348.613072) (xy 429.186025 -348.667062)
			(xy 429.170657 -348.719397) (xy 429.147996 -348.769012) (xy 429.118505 -348.814897) (xy 429.082783 -348.856117)
			(xy 429.041559 -348.891834) (xy 428.99567 -348.921319) (xy 428.946052 -348.943974) (xy 428.893715 -348.959335)
			(xy 428.839725 -348.967092) (xy 428.812452 -348.967552) (xy 427.948852 -348.967552) (xy 427.921584 -348.967082)
			(xy 427.867604 -348.959315) (xy 427.815279 -348.943945) (xy 427.765674 -348.921285) (xy 427.719798 -348.891797)
			(xy 427.678585 -348.856081) (xy 427.642874 -348.814864) (xy 427.613392 -348.768984) (xy 427.590738 -348.719376)
			(xy 427.575375 -348.667049) (xy 427.567614 -348.613068) (xy 426.084789 -348.613068) (xy 426.084789 -348.613071)
			(xy 426.077026 -348.667057) (xy 426.06166 -348.719389) (xy 426.039003 -348.769001) (xy 426.009515 -348.814884)
			(xy 425.973798 -348.856103) (xy 425.932578 -348.89182) (xy 425.886694 -348.921306) (xy 425.837081 -348.943963)
			(xy 425.784749 -348.959328) (xy 425.730763 -348.967089) (xy 425.703492 -348.967552) (xy 424.839892 -348.967552)
			(xy 424.812622 -348.967085) (xy 424.758638 -348.959322) (xy 424.706308 -348.943956) (xy 424.656698 -348.921299)
			(xy 424.610817 -348.891812) (xy 424.569599 -348.856095) (xy 424.533884 -348.814877) (xy 424.504398 -348.768995)
			(xy 424.481741 -348.719384) (xy 424.466376 -348.667054) (xy 424.458614 -348.61307) (xy 422.975766 -348.61307)
			(xy 422.968005 -348.667047) (xy 422.952642 -348.719372) (xy 422.929988 -348.768979) (xy 422.900506 -348.814857)
			(xy 422.864795 -348.856073) (xy 422.823583 -348.891787) (xy 422.777707 -348.921273) (xy 422.728102 -348.943931)
			(xy 422.675778 -348.959298) (xy 422.621799 -348.967063) (xy 422.594532 -348.967552) (xy 421.730932 -348.967552)
			(xy 421.703659 -348.967111) (xy 421.649667 -348.959352) (xy 421.597329 -348.943988) (xy 421.547711 -348.921332)
			(xy 421.501822 -348.891844) (xy 421.460597 -348.856126) (xy 421.424875 -348.814904) (xy 421.395384 -348.769017)
			(xy 421.372723 -348.719401) (xy 421.357355 -348.667064) (xy 421.349592 -348.613073) (xy 419.866888 -348.613073)
			(xy 419.859126 -348.667059) (xy 419.843759 -348.719393) (xy 419.821099 -348.769007) (xy 419.79161 -348.814891)
			(xy 419.75589 -348.85611) (xy 419.714668 -348.891827) (xy 419.668782 -348.921313) (xy 419.619167 -348.943968)
			(xy 419.566832 -348.959332) (xy 419.512844 -348.96709) (xy 419.485572 -348.967552) (xy 418.621972 -348.967552)
			(xy 418.594703 -348.967084) (xy 418.540721 -348.959319) (xy 418.488394 -348.94395) (xy 418.438786 -348.921292)
			(xy 418.392907 -348.891805) (xy 418.351692 -348.856088) (xy 418.315979 -348.81487) (xy 418.286495 -348.76899)
			(xy 418.26384 -348.71938) (xy 418.248476 -348.667051) (xy 418.240714 -348.613069) (xy 416.757866 -348.613069)
			(xy 416.750104 -348.667049) (xy 416.73474 -348.719376) (xy 416.712085 -348.768985) (xy 416.682601 -348.814864)
			(xy 416.646888 -348.85608) (xy 416.605673 -348.891794) (xy 416.559795 -348.92128) (xy 416.510188 -348.943936)
			(xy 416.457861 -348.959302) (xy 416.40388 -348.967065) (xy 416.376612 -348.967552) (xy 415.513012 -348.967552)
			(xy 415.48574 -348.967109) (xy 415.43175 -348.959348) (xy 415.379415 -348.943983) (xy 415.329799 -348.921325)
			(xy 415.283912 -348.891837) (xy 415.24269 -348.856119) (xy 415.20697 -348.814897) (xy 415.177481 -348.769012)
			(xy 415.154821 -348.719397) (xy 415.139454 -348.667062) (xy 415.131692 -348.613072) (xy 413.648988 -348.613072)
			(xy 413.641225 -348.667062) (xy 413.625857 -348.719397) (xy 413.603196 -348.769012) (xy 413.573705 -348.814897)
			(xy 413.537983 -348.856117) (xy 413.496759 -348.891834) (xy 413.45087 -348.921319) (xy 413.401252 -348.943974)
			(xy 413.348915 -348.959335) (xy 413.294925 -348.967092) (xy 413.267652 -348.967552) (xy 412.404052 -348.967552)
			(xy 412.376784 -348.967082) (xy 412.322804 -348.959315) (xy 412.270479 -348.943945) (xy 412.220874 -348.921285)
			(xy 412.174998 -348.891797) (xy 412.133785 -348.856081) (xy 412.098074 -348.814864) (xy 412.068592 -348.768984)
			(xy 412.045938 -348.719376) (xy 412.030575 -348.667049) (xy 412.022814 -348.613068) (xy 410.539989 -348.613068)
			(xy 410.539989 -348.613071) (xy 410.532226 -348.667057) (xy 410.51686 -348.719389) (xy 410.494203 -348.769001)
			(xy 410.464715 -348.814884) (xy 410.428998 -348.856103) (xy 410.387778 -348.89182) (xy 410.341894 -348.921306)
			(xy 410.292281 -348.943963) (xy 410.239949 -348.959328) (xy 410.185963 -348.967089) (xy 410.158692 -348.967552)
			(xy 409.295092 -348.967552) (xy 409.267822 -348.967085) (xy 409.213838 -348.959322) (xy 409.161508 -348.943956)
			(xy 409.111898 -348.921299) (xy 409.066017 -348.891812) (xy 409.024799 -348.856095) (xy 408.989084 -348.814877)
			(xy 408.959598 -348.768995) (xy 408.936941 -348.719384) (xy 408.921576 -348.667054) (xy 408.913814 -348.61307)
			(xy 403.522488 -348.61307) (xy 403.522488 -348.613071) (xy 403.514726 -348.667058) (xy 403.499359 -348.719391)
			(xy 403.476701 -348.769005) (xy 403.447212 -348.814888) (xy 403.411493 -348.856107) (xy 403.370272 -348.891824)
			(xy 403.324387 -348.92131) (xy 403.274773 -348.943966) (xy 403.222439 -348.95933) (xy 403.168451 -348.96709)
			(xy 403.14118 -348.967552) (xy 402.27758 -348.967552) (xy 402.250311 -348.967084) (xy 402.196328 -348.95932)
			(xy 402.143999 -348.943953) (xy 402.094391 -348.921295) (xy 402.048511 -348.891807) (xy 402.007295 -348.856091)
			(xy 401.971581 -348.814873) (xy 401.942096 -348.768992) (xy 401.91944 -348.719382) (xy 401.904076 -348.667052)
			(xy 401.896314 -348.613069) (xy 400.413466 -348.613069) (xy 400.405705 -348.667048) (xy 400.390341 -348.719375)
			(xy 400.367687 -348.768982) (xy 400.338203 -348.814861) (xy 400.302491 -348.856077) (xy 400.261277 -348.891791)
			(xy 400.2154 -348.921277) (xy 400.165794 -348.943934) (xy 400.113468 -348.9593) (xy 400.059488 -348.967064)
			(xy 400.03222 -348.967552) (xy 399.16862 -348.967552) (xy 399.141347 -348.96711) (xy 399.087357 -348.95935)
			(xy 399.03502 -348.943985) (xy 398.985403 -348.921328) (xy 398.939516 -348.89184) (xy 398.898293 -348.856122)
			(xy 398.862572 -348.8149) (xy 398.833082 -348.769014) (xy 398.810422 -348.719398) (xy 398.795054 -348.667063)
			(xy 398.787292 -348.613073) (xy 397.304588 -348.613073) (xy 397.296825 -348.667061) (xy 397.281458 -348.719396)
			(xy 397.258798 -348.76901) (xy 397.229307 -348.814894) (xy 397.193586 -348.856115) (xy 397.152362 -348.891831)
			(xy 397.106475 -348.921317) (xy 397.056858 -348.943972) (xy 397.004522 -348.959334) (xy 396.950532 -348.967091)
			(xy 396.92326 -348.967552) (xy 396.05966 -348.967552) (xy 396.032392 -348.967083) (xy 395.978411 -348.959316)
			(xy 395.926085 -348.943947) (xy 395.876479 -348.921288) (xy 395.830601 -348.8918) (xy 395.789388 -348.856084)
			(xy 395.753676 -348.814866) (xy 395.724193 -348.768986) (xy 395.701539 -348.719377) (xy 395.686175 -348.66705)
			(xy 395.678414 -348.613068) (xy 394.195566 -348.613068) (xy 394.195566 -348.613069) (xy 394.187804 -348.667051)
			(xy 394.172439 -348.719379) (xy 394.149784 -348.768988) (xy 394.120298 -348.814868) (xy 394.084584 -348.856084)
			(xy 394.043368 -348.891798) (xy 393.997488 -348.921284) (xy 393.947879 -348.943939) (xy 393.895551 -348.959304)
			(xy 393.841569 -348.967066) (xy 393.8143 -348.967552) (xy 392.9507 -348.967552) (xy 392.92343 -348.967086)
			(xy 392.869445 -348.959324) (xy 392.817114 -348.943958) (xy 392.767503 -348.921301) (xy 392.72162 -348.891814)
			(xy 392.680402 -348.856098) (xy 392.644686 -348.81488) (xy 392.615199 -348.768997) (xy 392.592542 -348.719386)
			(xy 392.577176 -348.667055) (xy 392.569414 -348.61307) (xy 391.086566 -348.61307) (xy 391.078805 -348.667046)
			(xy 391.063442 -348.71937) (xy 391.04079 -348.768977) (xy 391.011308 -348.814854) (xy 390.975598 -348.85607)
			(xy 390.934387 -348.891784) (xy 390.888512 -348.92127) (xy 390.838908 -348.943928) (xy 390.786585 -348.959297)
			(xy 390.732607 -348.967063) (xy 390.70534 -348.967552) (xy 389.84174 -348.967552) (xy 389.814466 -348.967111)
			(xy 389.760474 -348.959354) (xy 389.708135 -348.94399) (xy 389.658515 -348.921334) (xy 389.612626 -348.891847)
			(xy 389.5714 -348.856129) (xy 389.535677 -348.814906) (xy 389.506185 -348.76902) (xy 389.483524 -348.719403)
			(xy 389.468155 -348.667065) (xy 389.460392 -348.613074) (xy 387.977688 -348.613074) (xy 387.969926 -348.667058)
			(xy 387.954559 -348.719391) (xy 387.931901 -348.769005) (xy 387.902412 -348.814888) (xy 387.866693 -348.856107)
			(xy 387.825472 -348.891824) (xy 387.779587 -348.92131) (xy 387.729973 -348.943966) (xy 387.677639 -348.95933)
			(xy 387.623651 -348.96709) (xy 387.59638 -348.967552) (xy 386.73278 -348.967552) (xy 386.705511 -348.967084)
			(xy 386.651528 -348.95932) (xy 386.599199 -348.943953) (xy 386.549591 -348.921295) (xy 386.503711 -348.891807)
			(xy 386.462495 -348.856091) (xy 386.426781 -348.814873) (xy 386.397296 -348.768992) (xy 386.37464 -348.719382)
			(xy 386.359276 -348.667052) (xy 386.351514 -348.613069) (xy 384.868666 -348.613069) (xy 384.860905 -348.667048)
			(xy 384.845541 -348.719375) (xy 384.822887 -348.768982) (xy 384.793403 -348.814861) (xy 384.757691 -348.856077)
			(xy 384.716477 -348.891791) (xy 384.6706 -348.921277) (xy 384.620994 -348.943934) (xy 384.568668 -348.9593)
			(xy 384.514688 -348.967064) (xy 384.48742 -348.967552) (xy 383.62382 -348.967552) (xy 383.596547 -348.96711)
			(xy 383.542557 -348.95935) (xy 383.49022 -348.943985) (xy 383.440603 -348.921328) (xy 383.394716 -348.89184)
			(xy 383.353493 -348.856122) (xy 383.317772 -348.8149) (xy 383.288282 -348.769014) (xy 383.265622 -348.719398)
			(xy 383.250254 -348.667063) (xy 383.242492 -348.613073) (xy 381.759788 -348.613073) (xy 381.752025 -348.667061)
			(xy 381.736658 -348.719396) (xy 381.713998 -348.76901) (xy 381.684507 -348.814894) (xy 381.648786 -348.856115)
			(xy 381.607562 -348.891831) (xy 381.561675 -348.921317) (xy 381.512058 -348.943972) (xy 381.459722 -348.959334)
			(xy 381.405732 -348.967091) (xy 381.37846 -348.967552) (xy 380.51486 -348.967552) (xy 380.487592 -348.967083)
			(xy 380.433611 -348.959316) (xy 380.381285 -348.943947) (xy 380.331679 -348.921288) (xy 380.285801 -348.8918)
			(xy 380.244588 -348.856084) (xy 380.208876 -348.814866) (xy 380.179393 -348.768986) (xy 380.156739 -348.719377)
			(xy 380.141375 -348.66705) (xy 380.133614 -348.613068) (xy 378.650766 -348.613068) (xy 378.650766 -348.613069)
			(xy 378.643004 -348.667051) (xy 378.627639 -348.719379) (xy 378.604984 -348.768988) (xy 378.575498 -348.814868)
			(xy 378.539784 -348.856084) (xy 378.498568 -348.891798) (xy 378.452688 -348.921284) (xy 378.403079 -348.943939)
			(xy 378.350751 -348.959304) (xy 378.296769 -348.967066) (xy 378.2695 -348.967552) (xy 377.4059 -348.967552)
			(xy 377.37863 -348.967086) (xy 377.324645 -348.959324) (xy 377.272314 -348.943958) (xy 377.222703 -348.921301)
			(xy 377.17682 -348.891814) (xy 377.135602 -348.856098) (xy 377.099886 -348.81488) (xy 377.070399 -348.768997)
			(xy 377.047742 -348.719386) (xy 377.032376 -348.667055) (xy 377.024614 -348.61307) (xy 375.541766 -348.61307)
			(xy 375.534005 -348.667046) (xy 375.518642 -348.71937) (xy 375.49599 -348.768977) (xy 375.466508 -348.814854)
			(xy 375.430798 -348.85607) (xy 375.389587 -348.891784) (xy 375.343712 -348.92127) (xy 375.294108 -348.943928)
			(xy 375.241785 -348.959297) (xy 375.187807 -348.967063) (xy 375.16054 -348.967552) (xy 374.29694 -348.967552)
			(xy 374.269666 -348.967111) (xy 374.215674 -348.959354) (xy 374.163335 -348.94399) (xy 374.113715 -348.921334)
			(xy 374.067826 -348.891847) (xy 374.0266 -348.856129) (xy 373.990877 -348.814906) (xy 373.961385 -348.76902)
			(xy 373.938724 -348.719403) (xy 373.923355 -348.667065) (xy 373.915592 -348.613074) (xy 372.432888 -348.613074)
			(xy 372.425126 -348.667058) (xy 372.409759 -348.719391) (xy 372.387101 -348.769005) (xy 372.357612 -348.814888)
			(xy 372.321893 -348.856107) (xy 372.280672 -348.891824) (xy 372.234787 -348.92131) (xy 372.185173 -348.943966)
			(xy 372.132839 -348.95933) (xy 372.078851 -348.96709) (xy 372.05158 -348.967552) (xy 371.18798 -348.967552)
			(xy 371.160711 -348.967084) (xy 371.106728 -348.95932) (xy 371.054399 -348.943953) (xy 371.004791 -348.921295)
			(xy 370.958911 -348.891807) (xy 370.917695 -348.856091) (xy 370.881981 -348.814873) (xy 370.852496 -348.768992)
			(xy 370.82984 -348.719382) (xy 370.814476 -348.667052) (xy 370.806714 -348.613069) (xy 344.837266 -348.613069)
			(xy 344.829504 -348.66705) (xy 344.81414 -348.719378) (xy 344.791484 -348.768987) (xy 344.761999 -348.814866)
			(xy 344.726286 -348.856083) (xy 344.685069 -348.891797) (xy 344.63919 -348.921282) (xy 344.589582 -348.943938)
			(xy 344.537254 -348.959303) (xy 344.483272 -348.967065) (xy 344.456004 -348.967552) (xy 343.592404 -348.967552)
			(xy 343.565132 -348.967109) (xy 343.511143 -348.959347) (xy 343.458809 -348.943981) (xy 343.409194 -348.921323)
			(xy 343.363309 -348.891834) (xy 343.322087 -348.856116) (xy 343.286368 -348.814895) (xy 343.256879 -348.76901)
			(xy 343.234221 -348.719395) (xy 343.218854 -348.667061) (xy 343.211092 -348.613072) (xy 341.728265 -348.613072)
			(xy 341.720505 -348.667045) (xy 341.705143 -348.71937) (xy 341.68249 -348.768976) (xy 341.653009 -348.814853)
			(xy 341.6173 -348.856069) (xy 341.576088 -348.891783) (xy 341.530214 -348.921269) (xy 341.480611 -348.943927)
			(xy 341.428288 -348.959296) (xy 341.374311 -348.967063) (xy 341.347044 -348.967552) (xy 340.483444 -348.967552)
			(xy 340.45617 -348.967111) (xy 340.402177 -348.959354) (xy 340.349838 -348.943991) (xy 340.300218 -348.921336)
			(xy 340.254327 -348.891849) (xy 340.213101 -348.85613) (xy 340.177378 -348.814908) (xy 340.147885 -348.769021)
			(xy 340.125224 -348.719403) (xy 340.109855 -348.667066) (xy 340.102092 -348.613074) (xy 338.619388 -348.613074)
			(xy 338.611626 -348.667058) (xy 338.596259 -348.71939) (xy 338.573601 -348.769003) (xy 338.544113 -348.814887)
			(xy 338.508395 -348.856106) (xy 338.467174 -348.891823) (xy 338.421289 -348.921309) (xy 338.371675 -348.943965)
			(xy 338.319342 -348.95933) (xy 338.265355 -348.96709) (xy 338.238084 -348.967552) (xy 337.374484 -348.967552)
			(xy 337.347215 -348.967084) (xy 337.293231 -348.959321) (xy 337.240902 -348.943954) (xy 337.191293 -348.921296)
			(xy 337.145413 -348.891809) (xy 337.104196 -348.856093) (xy 337.068482 -348.814874) (xy 337.038996 -348.768993)
			(xy 337.016341 -348.719383) (xy 337.000976 -348.667053) (xy 336.993214 -348.613069) (xy 335.510366 -348.613069)
			(xy 335.502605 -348.667048) (xy 335.487241 -348.719374) (xy 335.464587 -348.768981) (xy 335.435104 -348.81486)
			(xy 335.399393 -348.856076) (xy 335.358179 -348.89179) (xy 335.312302 -348.921276) (xy 335.262696 -348.943933)
			(xy 335.210371 -348.9593) (xy 335.156392 -348.967064) (xy 335.129124 -348.967552) (xy 334.265524 -348.967552)
			(xy 334.238251 -348.96711) (xy 334.18426 -348.959351) (xy 334.131923 -348.943986) (xy 334.082306 -348.921329)
			(xy 334.036418 -348.891841) (xy 333.995194 -348.856123) (xy 333.959473 -348.814901) (xy 333.929982 -348.769015)
			(xy 333.907322 -348.719399) (xy 333.891955 -348.667063) (xy 333.884192 -348.613073) (xy 332.401488 -348.613073)
			(xy 332.393726 -348.667061) (xy 332.378358 -348.719395) (xy 332.355698 -348.769009) (xy 332.326208 -348.814893)
			(xy 332.290488 -348.856113) (xy 332.249264 -348.89183) (xy 332.203377 -348.921316) (xy 332.153761 -348.94397)
			(xy 332.101425 -348.959333) (xy 332.047436 -348.967091) (xy 332.020164 -348.967552) (xy 331.156564 -348.967552)
			(xy 331.129296 -348.967083) (xy 331.075314 -348.959317) (xy 331.022988 -348.943948) (xy 330.973381 -348.921289)
			(xy 330.927503 -348.891802) (xy 330.886289 -348.856086) (xy 330.850577 -348.814868) (xy 330.821093 -348.768987)
			(xy 330.798439 -348.719378) (xy 330.783075 -348.66705) (xy 330.775314 -348.613068) (xy 329.292466 -348.613068)
			(xy 329.284704 -348.66705) (xy 329.26934 -348.719378) (xy 329.246684 -348.768987) (xy 329.217199 -348.814866)
			(xy 329.181486 -348.856083) (xy 329.140269 -348.891797) (xy 329.09439 -348.921282) (xy 329.044782 -348.943938)
			(xy 328.992454 -348.959303) (xy 328.938472 -348.967065) (xy 328.911204 -348.967552) (xy 328.047604 -348.967552)
			(xy 328.020332 -348.967109) (xy 327.966343 -348.959347) (xy 327.914009 -348.943981) (xy 327.864394 -348.921323)
			(xy 327.818509 -348.891834) (xy 327.777287 -348.856116) (xy 327.741568 -348.814895) (xy 327.712079 -348.76901)
			(xy 327.689421 -348.719395) (xy 327.674054 -348.667061) (xy 327.666292 -348.613072) (xy 326.183465 -348.613072)
			(xy 326.175705 -348.667045) (xy 326.160343 -348.71937) (xy 326.13769 -348.768976) (xy 326.108209 -348.814853)
			(xy 326.0725 -348.856069) (xy 326.031288 -348.891783) (xy 325.985414 -348.921269) (xy 325.935811 -348.943927)
			(xy 325.883488 -348.959296) (xy 325.829511 -348.967063) (xy 325.802244 -348.967552) (xy 324.938644 -348.967552)
			(xy 324.91137 -348.967111) (xy 324.857377 -348.959354) (xy 324.805038 -348.943991) (xy 324.755418 -348.921336)
			(xy 324.709527 -348.891849) (xy 324.668301 -348.85613) (xy 324.632578 -348.814908) (xy 324.603085 -348.769021)
			(xy 324.580424 -348.719403) (xy 324.565055 -348.667066) (xy 324.557292 -348.613074) (xy 323.074588 -348.613074)
			(xy 323.066826 -348.667058) (xy 323.051459 -348.71939) (xy 323.028801 -348.769003) (xy 322.999313 -348.814887)
			(xy 322.963595 -348.856106) (xy 322.922374 -348.891823) (xy 322.876489 -348.921309) (xy 322.826875 -348.943965)
			(xy 322.774542 -348.95933) (xy 322.720555 -348.96709) (xy 322.693284 -348.967552) (xy 321.829684 -348.967552)
			(xy 321.802415 -348.967084) (xy 321.748431 -348.959321) (xy 321.696102 -348.943954) (xy 321.646493 -348.921296)
			(xy 321.600613 -348.891809) (xy 321.559396 -348.856093) (xy 321.523682 -348.814874) (xy 321.494196 -348.768993)
			(xy 321.471541 -348.719383) (xy 321.456176 -348.667053) (xy 321.448414 -348.613069) (xy 319.965566 -348.613069)
			(xy 319.957805 -348.667048) (xy 319.942441 -348.719374) (xy 319.919787 -348.768981) (xy 319.890304 -348.81486)
			(xy 319.854593 -348.856076) (xy 319.813379 -348.89179) (xy 319.767502 -348.921276) (xy 319.717896 -348.943933)
			(xy 319.665571 -348.9593) (xy 319.611592 -348.967064) (xy 319.584324 -348.967552) (xy 318.720724 -348.967552)
			(xy 318.693451 -348.96711) (xy 318.63946 -348.959351) (xy 318.587123 -348.943986) (xy 318.537506 -348.921329)
			(xy 318.491618 -348.891841) (xy 318.450394 -348.856123) (xy 318.414673 -348.814901) (xy 318.385182 -348.769015)
			(xy 318.362522 -348.719399) (xy 318.347155 -348.667063) (xy 318.339392 -348.613073) (xy 316.856688 -348.613073)
			(xy 316.848926 -348.667061) (xy 316.833558 -348.719395) (xy 316.810898 -348.769009) (xy 316.781408 -348.814893)
			(xy 316.745688 -348.856113) (xy 316.704464 -348.89183) (xy 316.658577 -348.921316) (xy 316.608961 -348.94397)
			(xy 316.556625 -348.959333) (xy 316.502636 -348.967091) (xy 316.475364 -348.967552) (xy 315.611764 -348.967552)
			(xy 315.584496 -348.967083) (xy 315.530514 -348.959317) (xy 315.478188 -348.943948) (xy 315.428581 -348.921289)
			(xy 315.382703 -348.891802) (xy 315.341489 -348.856086) (xy 315.305777 -348.814868) (xy 315.276293 -348.768987)
			(xy 315.253639 -348.719378) (xy 315.238275 -348.66705) (xy 315.230514 -348.613068) (xy 313.747666 -348.613068)
			(xy 313.739904 -348.66705) (xy 313.72454 -348.719378) (xy 313.701884 -348.768987) (xy 313.672399 -348.814866)
			(xy 313.636686 -348.856083) (xy 313.595469 -348.891797) (xy 313.54959 -348.921282) (xy 313.499982 -348.943938)
			(xy 313.447654 -348.959303) (xy 313.393672 -348.967065) (xy 313.366404 -348.967552) (xy 312.502804 -348.967552)
			(xy 312.475532 -348.967109) (xy 312.421543 -348.959347) (xy 312.369209 -348.943981) (xy 312.319594 -348.921323)
			(xy 312.273709 -348.891834) (xy 312.232487 -348.856116) (xy 312.196768 -348.814895) (xy 312.167279 -348.76901)
			(xy 312.144621 -348.719395) (xy 312.129254 -348.667061) (xy 312.121492 -348.613072) (xy 300.231566 -348.613072)
			(xy 300.223804 -348.667051) (xy 300.208439 -348.719379) (xy 300.185784 -348.768987) (xy 300.156299 -348.814867)
			(xy 300.120585 -348.856083) (xy 300.079369 -348.891798) (xy 300.033489 -348.921283) (xy 299.98388 -348.943939)
			(xy 299.931553 -348.959304) (xy 299.877571 -348.967065) (xy 299.850302 -348.967552) (xy 298.986702 -348.967552)
			(xy 298.95943 -348.967109) (xy 298.905442 -348.959347) (xy 298.853107 -348.94398) (xy 298.803493 -348.921322)
			(xy 298.757608 -348.891834) (xy 298.716386 -348.856115) (xy 298.680668 -348.814894) (xy 298.651179 -348.769009)
			(xy 298.628521 -348.719394) (xy 298.613154 -348.66706) (xy 298.605392 -348.613072) (xy 297.122565 -348.613072)
			(xy 297.114805 -348.667045) (xy 297.099443 -348.71937) (xy 297.07679 -348.768976) (xy 297.047309 -348.814854)
			(xy 297.011599 -348.856069) (xy 296.970387 -348.891784) (xy 296.924513 -348.92127) (xy 296.874909 -348.943928)
			(xy 296.822586 -348.959296) (xy 296.768609 -348.967063) (xy 296.741342 -348.967552) (xy 295.877742 -348.967552)
			(xy 295.850468 -348.967111) (xy 295.796476 -348.959354) (xy 295.744136 -348.943991) (xy 295.694517 -348.921335)
			(xy 295.648627 -348.891848) (xy 295.6074 -348.856129) (xy 295.571677 -348.814907) (xy 295.542185 -348.76902)
			(xy 295.519524 -348.719403) (xy 295.504155 -348.667066) (xy 295.496392 -348.613074) (xy 294.013688 -348.613074)
			(xy 294.005926 -348.667058) (xy 293.990559 -348.719391) (xy 293.967901 -348.769004) (xy 293.938412 -348.814887)
			(xy 293.902694 -348.856107) (xy 293.861473 -348.891823) (xy 293.815588 -348.92131) (xy 293.765974 -348.943966)
			(xy 293.713641 -348.95933) (xy 293.659653 -348.96709) (xy 293.632382 -348.967552) (xy 292.768782 -348.967552)
			(xy 292.741513 -348.967084) (xy 292.68753 -348.95932) (xy 292.635201 -348.943953) (xy 292.585592 -348.921295)
			(xy 292.539712 -348.891808) (xy 292.498495 -348.856092) (xy 292.462781 -348.814874) (xy 292.433296 -348.768992)
			(xy 292.410641 -348.719382) (xy 292.395276 -348.667053) (xy 292.387514 -348.613069) (xy 290.904666 -348.613069)
			(xy 290.896905 -348.667048) (xy 290.881541 -348.719374) (xy 290.858887 -348.768982) (xy 290.829404 -348.81486)
			(xy 290.793692 -348.856076) (xy 290.752478 -348.891791) (xy 290.706601 -348.921276) (xy 290.656995 -348.943933)
			(xy 290.604669 -348.9593) (xy 290.55069 -348.967064) (xy 290.523422 -348.967552) (xy 289.659822 -348.967552)
			(xy 289.632549 -348.96711) (xy 289.578559 -348.95935) (xy 289.526222 -348.943985) (xy 289.476605 -348.921329)
			(xy 289.430717 -348.891841) (xy 289.389493 -348.856122) (xy 289.353772 -348.814901) (xy 289.324282 -348.769015)
			(xy 289.301622 -348.719399) (xy 289.286254 -348.667063) (xy 289.278492 -348.613073) (xy 287.795788 -348.613073)
			(xy 287.788026 -348.667061) (xy 287.772658 -348.719395) (xy 287.749998 -348.76901) (xy 287.720508 -348.814894)
			(xy 287.684787 -348.856114) (xy 287.643563 -348.89183) (xy 287.597676 -348.921316) (xy 287.54806 -348.943971)
			(xy 287.495724 -348.959334) (xy 287.441734 -348.967091) (xy 287.414462 -348.967552) (xy 286.550862 -348.967552)
			(xy 286.523594 -348.967083) (xy 286.469613 -348.959317) (xy 286.417286 -348.943948) (xy 286.36768 -348.921289)
			(xy 286.321802 -348.891801) (xy 286.280588 -348.856085) (xy 286.244876 -348.814867) (xy 286.215393 -348.768987)
			(xy 286.192739 -348.719378) (xy 286.177375 -348.66705) (xy 286.169614 -348.613068) (xy 284.686766 -348.613068)
			(xy 284.686766 -348.613069) (xy 284.679004 -348.667051) (xy 284.663639 -348.719379) (xy 284.640984 -348.768987)
			(xy 284.611499 -348.814867) (xy 284.575785 -348.856083) (xy 284.534569 -348.891798) (xy 284.488689 -348.921283)
			(xy 284.43908 -348.943939) (xy 284.386753 -348.959304) (xy 284.332771 -348.967065) (xy 284.305502 -348.967552)
			(xy 283.441902 -348.967552) (xy 283.41463 -348.967109) (xy 283.360642 -348.959347) (xy 283.308307 -348.94398)
			(xy 283.258693 -348.921322) (xy 283.212808 -348.891834) (xy 283.171586 -348.856115) (xy 283.135868 -348.814894)
			(xy 283.106379 -348.769009) (xy 283.083721 -348.719394) (xy 283.068354 -348.66706) (xy 283.060592 -348.613072)
			(xy 281.577765 -348.613072) (xy 281.570005 -348.667045) (xy 281.554643 -348.71937) (xy 281.53199 -348.768976)
			(xy 281.502509 -348.814854) (xy 281.466799 -348.856069) (xy 281.425587 -348.891784) (xy 281.379713 -348.92127)
			(xy 281.330109 -348.943928) (xy 281.277786 -348.959296) (xy 281.223809 -348.967063) (xy 281.196542 -348.967552)
			(xy 280.332942 -348.967552) (xy 280.305668 -348.967111) (xy 280.251676 -348.959354) (xy 280.199336 -348.943991)
			(xy 280.149717 -348.921335) (xy 280.103827 -348.891848) (xy 280.0626 -348.856129) (xy 280.026877 -348.814907)
			(xy 279.997385 -348.76902) (xy 279.974724 -348.719403) (xy 279.959355 -348.667066) (xy 279.951592 -348.613074)
			(xy 278.468888 -348.613074) (xy 278.461126 -348.667058) (xy 278.445759 -348.719391) (xy 278.423101 -348.769004)
			(xy 278.393612 -348.814887) (xy 278.357894 -348.856107) (xy 278.316673 -348.891823) (xy 278.270788 -348.92131)
			(xy 278.221174 -348.943966) (xy 278.168841 -348.95933) (xy 278.114853 -348.96709) (xy 278.087582 -348.967552)
			(xy 277.223982 -348.967552) (xy 277.196713 -348.967084) (xy 277.14273 -348.95932) (xy 277.090401 -348.943953)
			(xy 277.040792 -348.921295) (xy 276.994912 -348.891808) (xy 276.953695 -348.856092) (xy 276.917981 -348.814874)
			(xy 276.888496 -348.768992) (xy 276.865841 -348.719382) (xy 276.850476 -348.667053) (xy 276.842714 -348.613069)
			(xy 275.359866 -348.613069) (xy 275.352105 -348.667048) (xy 275.336741 -348.719374) (xy 275.314087 -348.768982)
			(xy 275.284604 -348.81486) (xy 275.248892 -348.856076) (xy 275.207678 -348.891791) (xy 275.161801 -348.921276)
			(xy 275.112195 -348.943933) (xy 275.059869 -348.9593) (xy 275.00589 -348.967064) (xy 274.978622 -348.967552)
			(xy 274.115022 -348.967552) (xy 274.087749 -348.96711) (xy 274.033759 -348.95935) (xy 273.981422 -348.943985)
			(xy 273.931805 -348.921329) (xy 273.885917 -348.891841) (xy 273.844693 -348.856122) (xy 273.808972 -348.814901)
			(xy 273.779482 -348.769015) (xy 273.756822 -348.719399) (xy 273.741454 -348.667063) (xy 273.733692 -348.613073)
			(xy 272.250988 -348.613073) (xy 272.243226 -348.667061) (xy 272.227858 -348.719395) (xy 272.205198 -348.76901)
			(xy 272.175708 -348.814894) (xy 272.139987 -348.856114) (xy 272.098763 -348.89183) (xy 272.052876 -348.921316)
			(xy 272.00326 -348.943971) (xy 271.950924 -348.959334) (xy 271.896934 -348.967091) (xy 271.869662 -348.967552)
			(xy 271.006062 -348.967552) (xy 270.978794 -348.967083) (xy 270.924813 -348.959317) (xy 270.872486 -348.943948)
			(xy 270.82288 -348.921289) (xy 270.777002 -348.891801) (xy 270.735788 -348.856085) (xy 270.700076 -348.814867)
			(xy 270.670593 -348.768987) (xy 270.647939 -348.719378) (xy 270.632575 -348.66705) (xy 270.624814 -348.613068)
			(xy 269.141966 -348.613068) (xy 269.141966 -348.613069) (xy 269.134204 -348.667051) (xy 269.118839 -348.719379)
			(xy 269.096184 -348.768987) (xy 269.066699 -348.814867) (xy 269.030985 -348.856083) (xy 268.989769 -348.891798)
			(xy 268.943889 -348.921283) (xy 268.89428 -348.943939) (xy 268.841953 -348.959304) (xy 268.787971 -348.967065)
			(xy 268.760702 -348.967552) (xy 267.897102 -348.967552) (xy 267.86983 -348.967109) (xy 267.815842 -348.959347)
			(xy 267.763507 -348.94398) (xy 267.713893 -348.921322) (xy 267.668008 -348.891834) (xy 267.626786 -348.856115)
			(xy 267.591068 -348.814894) (xy 267.561579 -348.769009) (xy 267.538921 -348.719394) (xy 267.523554 -348.66706)
			(xy 267.515792 -348.613072) (xy 194.520565 -348.613072) (xy 194.512804 -348.667049) (xy 194.49744 -348.719376)
			(xy 194.474785 -348.768985) (xy 194.445301 -348.814864) (xy 194.409588 -348.85608) (xy 194.368373 -348.891794)
			(xy 194.322495 -348.92128) (xy 194.272888 -348.943936) (xy 194.220561 -348.959302) (xy 194.16658 -348.967065)
			(xy 194.139312 -348.967552) (xy 193.275712 -348.967552) (xy 193.24844 -348.967109) (xy 193.19445 -348.959348)
			(xy 193.142115 -348.943983) (xy 193.092499 -348.921325) (xy 193.046612 -348.891837) (xy 193.00539 -348.856119)
			(xy 192.96967 -348.814897) (xy 192.940181 -348.769012) (xy 192.917521 -348.719397) (xy 192.902154 -348.667062)
			(xy 192.894392 -348.613072) (xy 191.411688 -348.613072) (xy 191.403925 -348.667062) (xy 191.388557 -348.719397)
			(xy 191.365896 -348.769012) (xy 191.336405 -348.814897) (xy 191.300683 -348.856117) (xy 191.259459 -348.891834)
			(xy 191.21357 -348.921319) (xy 191.163952 -348.943974) (xy 191.111615 -348.959335) (xy 191.057625 -348.967092)
			(xy 191.030352 -348.967552) (xy 190.166752 -348.967552) (xy 190.139484 -348.967082) (xy 190.085504 -348.959315)
			(xy 190.033179 -348.943945) (xy 189.983574 -348.921285) (xy 189.937698 -348.891797) (xy 189.896485 -348.856081)
			(xy 189.860774 -348.814864) (xy 189.831292 -348.768984) (xy 189.808638 -348.719376) (xy 189.793275 -348.667049)
			(xy 189.785514 -348.613068) (xy 188.302689 -348.613068) (xy 188.302689 -348.613071) (xy 188.294926 -348.667057)
			(xy 188.27956 -348.719389) (xy 188.256903 -348.769001) (xy 188.227415 -348.814884) (xy 188.191698 -348.856103)
			(xy 188.150478 -348.89182) (xy 188.104594 -348.921306) (xy 188.054981 -348.943963) (xy 188.002649 -348.959328)
			(xy 187.948663 -348.967089) (xy 187.921392 -348.967552) (xy 187.057792 -348.967552) (xy 187.030522 -348.967085)
			(xy 186.976538 -348.959322) (xy 186.924208 -348.943956) (xy 186.874598 -348.921299) (xy 186.828717 -348.891812)
			(xy 186.787499 -348.856095) (xy 186.751784 -348.814877) (xy 186.722298 -348.768995) (xy 186.699641 -348.719384)
			(xy 186.684276 -348.667054) (xy 186.676514 -348.61307) (xy 185.193666 -348.61307) (xy 185.185905 -348.667047)
			(xy 185.170542 -348.719372) (xy 185.147888 -348.768979) (xy 185.118406 -348.814857) (xy 185.082695 -348.856073)
			(xy 185.041483 -348.891787) (xy 184.995607 -348.921273) (xy 184.946002 -348.943931) (xy 184.893678 -348.959298)
			(xy 184.839699 -348.967063) (xy 184.812432 -348.967552) (xy 183.948832 -348.967552) (xy 183.921559 -348.967111)
			(xy 183.867567 -348.959352) (xy 183.815229 -348.943988) (xy 183.765611 -348.921332) (xy 183.719722 -348.891844)
			(xy 183.678497 -348.856126) (xy 183.642775 -348.814904) (xy 183.613284 -348.769017) (xy 183.590623 -348.719401)
			(xy 183.575255 -348.667064) (xy 183.567492 -348.613073) (xy 182.084788 -348.613073) (xy 182.077026 -348.667059)
			(xy 182.061659 -348.719393) (xy 182.038999 -348.769007) (xy 182.00951 -348.814891) (xy 181.97379 -348.85611)
			(xy 181.932568 -348.891827) (xy 181.886682 -348.921313) (xy 181.837067 -348.943968) (xy 181.784732 -348.959332)
			(xy 181.730744 -348.96709) (xy 181.703472 -348.967552) (xy 180.839872 -348.967552) (xy 180.812603 -348.967084)
			(xy 180.758621 -348.959319) (xy 180.706294 -348.94395) (xy 180.656686 -348.921292) (xy 180.610807 -348.891805)
			(xy 180.569592 -348.856088) (xy 180.533879 -348.81487) (xy 180.504395 -348.76899) (xy 180.48174 -348.71938)
			(xy 180.466376 -348.667051) (xy 180.458614 -348.613069) (xy 178.975766 -348.613069) (xy 178.968004 -348.667049)
			(xy 178.95264 -348.719376) (xy 178.929985 -348.768985) (xy 178.900501 -348.814864) (xy 178.864788 -348.85608)
			(xy 178.823573 -348.891794) (xy 178.777695 -348.92128) (xy 178.728088 -348.943936) (xy 178.675761 -348.959302)
			(xy 178.62178 -348.967065) (xy 178.594512 -348.967552) (xy 177.730912 -348.967552) (xy 177.70364 -348.967109)
			(xy 177.64965 -348.959348) (xy 177.597315 -348.943983) (xy 177.547699 -348.921325) (xy 177.501812 -348.891837)
			(xy 177.46059 -348.856119) (xy 177.42487 -348.814897) (xy 177.395381 -348.769012) (xy 177.372721 -348.719397)
			(xy 177.357354 -348.667062) (xy 177.349592 -348.613072) (xy 175.866888 -348.613072) (xy 175.859125 -348.667062)
			(xy 175.843757 -348.719397) (xy 175.821096 -348.769012) (xy 175.791605 -348.814897) (xy 175.755883 -348.856117)
			(xy 175.714659 -348.891834) (xy 175.66877 -348.921319) (xy 175.619152 -348.943974) (xy 175.566815 -348.959335)
			(xy 175.512825 -348.967092) (xy 175.485552 -348.967552) (xy 174.621952 -348.967552) (xy 174.594684 -348.967082)
			(xy 174.540704 -348.959315) (xy 174.488379 -348.943945) (xy 174.438774 -348.921285) (xy 174.392898 -348.891797)
			(xy 174.351685 -348.856081) (xy 174.315974 -348.814864) (xy 174.286492 -348.768984) (xy 174.263838 -348.719376)
			(xy 174.248475 -348.667049) (xy 174.240714 -348.613068) (xy 172.757889 -348.613068) (xy 172.757889 -348.613071)
			(xy 172.750126 -348.667057) (xy 172.73476 -348.719389) (xy 172.712103 -348.769001) (xy 172.682615 -348.814884)
			(xy 172.646898 -348.856103) (xy 172.605678 -348.89182) (xy 172.559794 -348.921306) (xy 172.510181 -348.943963)
			(xy 172.457849 -348.959328) (xy 172.403863 -348.967089) (xy 172.376592 -348.967552) (xy 171.512992 -348.967552)
			(xy 171.485722 -348.967085) (xy 171.431738 -348.959322) (xy 171.379408 -348.943956) (xy 171.329798 -348.921299)
			(xy 171.283917 -348.891812) (xy 171.242699 -348.856095) (xy 171.206984 -348.814877) (xy 171.177498 -348.768995)
			(xy 171.154841 -348.719384) (xy 171.139476 -348.667054) (xy 171.131714 -348.61307) (xy 169.648866 -348.61307)
			(xy 169.641105 -348.667047) (xy 169.625742 -348.719372) (xy 169.603088 -348.768979) (xy 169.573606 -348.814857)
			(xy 169.537895 -348.856073) (xy 169.496683 -348.891787) (xy 169.450807 -348.921273) (xy 169.401202 -348.943931)
			(xy 169.348878 -348.959298) (xy 169.294899 -348.967063) (xy 169.267632 -348.967552) (xy 168.404032 -348.967552)
			(xy 168.376759 -348.967111) (xy 168.322767 -348.959352) (xy 168.270429 -348.943988) (xy 168.220811 -348.921332)
			(xy 168.174922 -348.891844) (xy 168.133697 -348.856126) (xy 168.097975 -348.814904) (xy 168.068484 -348.769017)
			(xy 168.045823 -348.719401) (xy 168.030455 -348.667064) (xy 168.022692 -348.613073) (xy 166.539988 -348.613073)
			(xy 166.532226 -348.667059) (xy 166.516859 -348.719393) (xy 166.494199 -348.769007) (xy 166.46471 -348.814891)
			(xy 166.42899 -348.85611) (xy 166.387768 -348.891827) (xy 166.341882 -348.921313) (xy 166.292267 -348.943968)
			(xy 166.239932 -348.959332) (xy 166.185944 -348.96709) (xy 166.158672 -348.967552) (xy 165.295072 -348.967552)
			(xy 165.267803 -348.967084) (xy 165.213821 -348.959319) (xy 165.161494 -348.94395) (xy 165.111886 -348.921292)
			(xy 165.066007 -348.891805) (xy 165.024792 -348.856088) (xy 164.989079 -348.81487) (xy 164.959595 -348.76899)
			(xy 164.93694 -348.71938) (xy 164.921576 -348.667051) (xy 164.913814 -348.613069) (xy 163.430966 -348.613069)
			(xy 163.423204 -348.667049) (xy 163.40784 -348.719376) (xy 163.385185 -348.768985) (xy 163.355701 -348.814864)
			(xy 163.319988 -348.85608) (xy 163.278773 -348.891794) (xy 163.232895 -348.92128) (xy 163.183288 -348.943936)
			(xy 163.130961 -348.959302) (xy 163.07698 -348.967065) (xy 163.049712 -348.967552) (xy 162.186112 -348.967552)
			(xy 162.15884 -348.967109) (xy 162.10485 -348.959348) (xy 162.052515 -348.943983) (xy 162.002899 -348.921325)
			(xy 161.957012 -348.891837) (xy 161.91579 -348.856119) (xy 161.88007 -348.814897) (xy 161.850581 -348.769012)
			(xy 161.827921 -348.719397) (xy 161.812554 -348.667062) (xy 161.804792 -348.613072) (xy 144.196565 -348.613072)
			(xy 144.188804 -348.66705) (xy 144.17344 -348.719377) (xy 144.150785 -348.768986) (xy 144.1213 -348.814865)
			(xy 144.085587 -348.856081) (xy 144.044371 -348.891796) (xy 143.998493 -348.921281) (xy 143.948885 -348.943937)
			(xy 143.896558 -348.959303) (xy 143.842576 -348.967065) (xy 143.815308 -348.967552) (xy 142.951708 -348.967552)
			(xy 142.924436 -348.967109) (xy 142.870447 -348.959348) (xy 142.818112 -348.943982) (xy 142.768496 -348.921324)
			(xy 142.72261 -348.891836) (xy 142.681388 -348.856117) (xy 142.645669 -348.814896) (xy 142.61618 -348.769011)
			(xy 142.593521 -348.719396) (xy 142.578154 -348.667061) (xy 142.570392 -348.613072) (xy 141.087565 -348.613072)
			(xy 141.079806 -348.667044) (xy 141.064443 -348.719369) (xy 141.041791 -348.768974) (xy 141.01231 -348.814852)
			(xy 140.976601 -348.856067) (xy 140.93539 -348.891781) (xy 140.889517 -348.921268) (xy 140.839914 -348.943926)
			(xy 140.787591 -348.959295) (xy 140.733614 -348.967062) (xy 140.706348 -348.967552) (xy 139.842748 -348.967552)
			(xy 139.815474 -348.967112) (xy 139.761481 -348.959355) (xy 139.709141 -348.943992) (xy 139.65952 -348.921337)
			(xy 139.613629 -348.89185) (xy 139.572402 -348.856132) (xy 139.536679 -348.814909) (xy 139.507186 -348.769022)
			(xy 139.484524 -348.719404) (xy 139.469155 -348.667066) (xy 139.461392 -348.613074) (xy 137.978689 -348.613074)
			(xy 137.970926 -348.667057) (xy 137.95556 -348.71939) (xy 137.932902 -348.769002) (xy 137.903414 -348.814885)
			(xy 137.867696 -348.856105) (xy 137.826476 -348.891821) (xy 137.780592 -348.921308) (xy 137.730978 -348.943964)
			(xy 137.678646 -348.959329) (xy 137.624659 -348.967089) (xy 137.597388 -348.967552) (xy 136.733788 -348.967552)
			(xy 136.706518 -348.967085) (xy 136.652535 -348.959321) (xy 136.600205 -348.943955) (xy 136.550595 -348.921297)
			(xy 136.504715 -348.89181) (xy 136.463497 -348.856094) (xy 136.427783 -348.814876) (xy 136.398297 -348.768994)
			(xy 136.375641 -348.719383) (xy 136.360276 -348.667053) (xy 136.352514 -348.61307) (xy 134.869666 -348.61307)
			(xy 134.861905 -348.667047) (xy 134.846541 -348.719373) (xy 134.823888 -348.76898) (xy 134.794405 -348.814858)
			(xy 134.758694 -348.856074) (xy 134.717481 -348.891789) (xy 134.671605 -348.921274) (xy 134.621999 -348.943932)
			(xy 134.569675 -348.959299) (xy 134.515695 -348.967064) (xy 134.488428 -348.967552) (xy 133.624828 -348.967552)
			(xy 133.597555 -348.96711) (xy 133.543564 -348.959351) (xy 133.491226 -348.943987) (xy 133.441608 -348.92133)
			(xy 133.39572 -348.891843) (xy 133.354495 -348.856124) (xy 133.318774 -348.814903) (xy 133.289283 -348.769016)
			(xy 133.266623 -348.7194) (xy 133.251255 -348.667064) (xy 133.243492 -348.613073) (xy 131.760788 -348.613073)
			(xy 131.753026 -348.66706) (xy 131.737658 -348.719394) (xy 131.714999 -348.769008) (xy 131.685509 -348.814892)
			(xy 131.649789 -348.856112) (xy 131.608566 -348.891828) (xy 131.56268 -348.921314) (xy 131.513064 -348.943969)
			(xy 131.460729 -348.959332) (xy 131.40674 -348.967091) (xy 131.379468 -348.967552) (xy 130.515868 -348.967552)
			(xy 130.488599 -348.967083) (xy 130.434618 -348.959318) (xy 130.382291 -348.943949) (xy 130.332683 -348.921291)
			(xy 130.286805 -348.891803) (xy 130.24559 -348.856087) (xy 130.209878 -348.814869) (xy 130.180394 -348.768989)
			(xy 130.15774 -348.719379) (xy 130.142375 -348.667051) (xy 130.134614 -348.613069) (xy 128.651766 -348.613069)
			(xy 128.644004 -348.66705) (xy 128.62864 -348.719377) (xy 128.605985 -348.768986) (xy 128.5765 -348.814865)
			(xy 128.540787 -348.856081) (xy 128.499571 -348.891796) (xy 128.453693 -348.921281) (xy 128.404085 -348.943937)
			(xy 128.351758 -348.959303) (xy 128.297776 -348.967065) (xy 128.270508 -348.967552) (xy 127.406908 -348.967552)
			(xy 127.379636 -348.967109) (xy 127.325647 -348.959348) (xy 127.273312 -348.943982) (xy 127.223696 -348.921324)
			(xy 127.17781 -348.891836) (xy 127.136588 -348.856117) (xy 127.100869 -348.814896) (xy 127.07138 -348.769011)
			(xy 127.048721 -348.719396) (xy 127.033354 -348.667061) (xy 127.025592 -348.613072) (xy 125.542765 -348.613072)
			(xy 125.535006 -348.667044) (xy 125.519643 -348.719369) (xy 125.496991 -348.768974) (xy 125.46751 -348.814852)
			(xy 125.431801 -348.856067) (xy 125.39059 -348.891781) (xy 125.344717 -348.921268) (xy 125.295114 -348.943926)
			(xy 125.242791 -348.959295) (xy 125.188814 -348.967062) (xy 125.161548 -348.967552) (xy 124.297948 -348.967552)
			(xy 124.270674 -348.967112) (xy 124.216681 -348.959355) (xy 124.164341 -348.943992) (xy 124.11472 -348.921337)
			(xy 124.068829 -348.89185) (xy 124.027602 -348.856132) (xy 123.991879 -348.814909) (xy 123.962386 -348.769022)
			(xy 123.939724 -348.719404) (xy 123.924355 -348.667066) (xy 123.916592 -348.613074) (xy 122.433889 -348.613074)
			(xy 122.426126 -348.667057) (xy 122.41076 -348.71939) (xy 122.388102 -348.769002) (xy 122.358614 -348.814885)
			(xy 122.322896 -348.856105) (xy 122.281676 -348.891821) (xy 122.235792 -348.921308) (xy 122.186178 -348.943964)
			(xy 122.133846 -348.959329) (xy 122.079859 -348.967089) (xy 122.052588 -348.967552) (xy 121.188988 -348.967552)
			(xy 121.161718 -348.967085) (xy 121.107735 -348.959321) (xy 121.055405 -348.943955) (xy 121.005795 -348.921297)
			(xy 120.959915 -348.89181) (xy 120.918697 -348.856094) (xy 120.882983 -348.814876) (xy 120.853497 -348.768994)
			(xy 120.830841 -348.719383) (xy 120.815476 -348.667053) (xy 120.807714 -348.61307) (xy 119.324866 -348.61307)
			(xy 119.317105 -348.667047) (xy 119.301741 -348.719373) (xy 119.279088 -348.76898) (xy 119.249605 -348.814858)
			(xy 119.213894 -348.856074) (xy 119.172681 -348.891789) (xy 119.126805 -348.921274) (xy 119.077199 -348.943932)
			(xy 119.024875 -348.959299) (xy 118.970895 -348.967064) (xy 118.943628 -348.967552) (xy 118.080028 -348.967552)
			(xy 118.052755 -348.96711) (xy 117.998764 -348.959351) (xy 117.946426 -348.943987) (xy 117.896808 -348.92133)
			(xy 117.85092 -348.891843) (xy 117.809695 -348.856124) (xy 117.773974 -348.814903) (xy 117.744483 -348.769016)
			(xy 117.721823 -348.7194) (xy 117.706455 -348.667064) (xy 117.698692 -348.613073) (xy 116.215988 -348.613073)
			(xy 116.208226 -348.66706) (xy 116.192858 -348.719394) (xy 116.170199 -348.769008) (xy 116.140709 -348.814892)
			(xy 116.104989 -348.856112) (xy 116.063766 -348.891828) (xy 116.01788 -348.921314) (xy 115.968264 -348.943969)
			(xy 115.915929 -348.959332) (xy 115.86194 -348.967091) (xy 115.834668 -348.967552) (xy 114.971068 -348.967552)
			(xy 114.943799 -348.967083) (xy 114.889818 -348.959318) (xy 114.837491 -348.943949) (xy 114.787883 -348.921291)
			(xy 114.742005 -348.891803) (xy 114.70079 -348.856087) (xy 114.665078 -348.814869) (xy 114.635594 -348.768989)
			(xy 114.61294 -348.719379) (xy 114.597575 -348.667051) (xy 114.589814 -348.613069) (xy 113.106966 -348.613069)
			(xy 113.099204 -348.66705) (xy 113.08384 -348.719377) (xy 113.061185 -348.768986) (xy 113.0317 -348.814865)
			(xy 112.995987 -348.856081) (xy 112.954771 -348.891796) (xy 112.908893 -348.921281) (xy 112.859285 -348.943937)
			(xy 112.806958 -348.959303) (xy 112.752976 -348.967065) (xy 112.725708 -348.967552) (xy 111.862108 -348.967552)
			(xy 111.834836 -348.967109) (xy 111.780847 -348.959348) (xy 111.728512 -348.943982) (xy 111.678896 -348.921324)
			(xy 111.63301 -348.891836) (xy 111.591788 -348.856117) (xy 111.556069 -348.814896) (xy 111.52658 -348.769011)
			(xy 111.503921 -348.719396) (xy 111.488554 -348.667061) (xy 111.480792 -348.613072) (xy 93.706665 -348.613072)
			(xy 93.698905 -348.667045) (xy 93.683543 -348.71937) (xy 93.66089 -348.768976) (xy 93.631409 -348.814854)
			(xy 93.595699 -348.856069) (xy 93.554487 -348.891784) (xy 93.508613 -348.92127) (xy 93.459009 -348.943928)
			(xy 93.406686 -348.959296) (xy 93.352709 -348.967063) (xy 93.325442 -348.967552) (xy 92.461842 -348.967552)
			(xy 92.434568 -348.967111) (xy 92.380576 -348.959354) (xy 92.328236 -348.943991) (xy 92.278617 -348.921335)
			(xy 92.232727 -348.891848) (xy 92.1915 -348.856129) (xy 92.155777 -348.814907) (xy 92.126285 -348.76902)
			(xy 92.103624 -348.719403) (xy 92.088255 -348.667066) (xy 92.080492 -348.613074) (xy 90.597788 -348.613074)
			(xy 90.590026 -348.667058) (xy 90.574659 -348.719391) (xy 90.552001 -348.769004) (xy 90.522512 -348.814887)
			(xy 90.486794 -348.856107) (xy 90.445573 -348.891823) (xy 90.399688 -348.92131) (xy 90.350074 -348.943966)
			(xy 90.297741 -348.95933) (xy 90.243753 -348.96709) (xy 90.216482 -348.967552) (xy 89.352882 -348.967552)
			(xy 89.325613 -348.967084) (xy 89.27163 -348.95932) (xy 89.219301 -348.943953) (xy 89.169692 -348.921295)
			(xy 89.123812 -348.891808) (xy 89.082595 -348.856092) (xy 89.046881 -348.814874) (xy 89.017396 -348.768992)
			(xy 88.994741 -348.719382) (xy 88.979376 -348.667053) (xy 88.971614 -348.613069) (xy 87.488766 -348.613069)
			(xy 87.481005 -348.667048) (xy 87.465641 -348.719374) (xy 87.442987 -348.768982) (xy 87.413504 -348.81486)
			(xy 87.377792 -348.856076) (xy 87.336578 -348.891791) (xy 87.290701 -348.921276) (xy 87.241095 -348.943933)
			(xy 87.188769 -348.9593) (xy 87.13479 -348.967064) (xy 87.107522 -348.967552) (xy 86.243922 -348.967552)
			(xy 86.216649 -348.96711) (xy 86.162659 -348.95935) (xy 86.110322 -348.943985) (xy 86.060705 -348.921329)
			(xy 86.014817 -348.891841) (xy 85.973593 -348.856122) (xy 85.937872 -348.814901) (xy 85.908382 -348.769015)
			(xy 85.885722 -348.719399) (xy 85.870354 -348.667063) (xy 85.862592 -348.613073) (xy 84.379888 -348.613073)
			(xy 84.372126 -348.667061) (xy 84.356758 -348.719395) (xy 84.334098 -348.76901) (xy 84.304608 -348.814894)
			(xy 84.268887 -348.856114) (xy 84.227663 -348.89183) (xy 84.181776 -348.921316) (xy 84.13216 -348.943971)
			(xy 84.079824 -348.959334) (xy 84.025834 -348.967091) (xy 83.998562 -348.967552) (xy 83.134962 -348.967552)
			(xy 83.107694 -348.967083) (xy 83.053713 -348.959317) (xy 83.001386 -348.943948) (xy 82.95178 -348.921289)
			(xy 82.905902 -348.891801) (xy 82.864688 -348.856085) (xy 82.828976 -348.814867) (xy 82.799493 -348.768987)
			(xy 82.776839 -348.719378) (xy 82.761475 -348.66705) (xy 82.753714 -348.613068) (xy 81.270866 -348.613068)
			(xy 81.270866 -348.613069) (xy 81.263104 -348.667051) (xy 81.247739 -348.719379) (xy 81.225084 -348.768987)
			(xy 81.195599 -348.814867) (xy 81.159885 -348.856083) (xy 81.118669 -348.891798) (xy 81.072789 -348.921283)
			(xy 81.02318 -348.943939) (xy 80.970853 -348.959304) (xy 80.916871 -348.967065) (xy 80.889602 -348.967552)
			(xy 80.026002 -348.967552) (xy 79.99873 -348.967109) (xy 79.944742 -348.959347) (xy 79.892407 -348.94398)
			(xy 79.842793 -348.921322) (xy 79.796908 -348.891834) (xy 79.755686 -348.856115) (xy 79.719968 -348.814894)
			(xy 79.690479 -348.769009) (xy 79.667821 -348.719394) (xy 79.652454 -348.66706) (xy 79.644692 -348.613072)
			(xy 78.161865 -348.613072) (xy 78.154105 -348.667045) (xy 78.138743 -348.71937) (xy 78.11609 -348.768976)
			(xy 78.086609 -348.814854) (xy 78.050899 -348.856069) (xy 78.009687 -348.891784) (xy 77.963813 -348.92127)
			(xy 77.914209 -348.943928) (xy 77.861886 -348.959296) (xy 77.807909 -348.967063) (xy 77.780642 -348.967552)
			(xy 76.917042 -348.967552) (xy 76.889768 -348.967111) (xy 76.835776 -348.959354) (xy 76.783436 -348.943991)
			(xy 76.733817 -348.921335) (xy 76.687927 -348.891848) (xy 76.6467 -348.856129) (xy 76.610977 -348.814907)
			(xy 76.581485 -348.76902) (xy 76.558824 -348.719403) (xy 76.543455 -348.667066) (xy 76.535692 -348.613074)
			(xy 75.052988 -348.613074) (xy 75.045226 -348.667058) (xy 75.029859 -348.719391) (xy 75.007201 -348.769004)
			(xy 74.977712 -348.814887) (xy 74.941994 -348.856107) (xy 74.900773 -348.891823) (xy 74.854888 -348.92131)
			(xy 74.805274 -348.943966) (xy 74.752941 -348.95933) (xy 74.698953 -348.96709) (xy 74.671682 -348.967552)
			(xy 73.808082 -348.967552) (xy 73.780813 -348.967084) (xy 73.72683 -348.95932) (xy 73.674501 -348.943953)
			(xy 73.624892 -348.921295) (xy 73.579012 -348.891808) (xy 73.537795 -348.856092) (xy 73.502081 -348.814874)
			(xy 73.472596 -348.768992) (xy 73.449941 -348.719382) (xy 73.434576 -348.667053) (xy 73.426814 -348.613069)
			(xy 71.943966 -348.613069) (xy 71.936205 -348.667048) (xy 71.920841 -348.719374) (xy 71.898187 -348.768982)
			(xy 71.868704 -348.81486) (xy 71.832992 -348.856076) (xy 71.791778 -348.891791) (xy 71.745901 -348.921276)
			(xy 71.696295 -348.943933) (xy 71.643969 -348.9593) (xy 71.58999 -348.967064) (xy 71.562722 -348.967552)
			(xy 70.699122 -348.967552) (xy 70.671849 -348.96711) (xy 70.617859 -348.95935) (xy 70.565522 -348.943985)
			(xy 70.515905 -348.921329) (xy 70.470017 -348.891841) (xy 70.428793 -348.856122) (xy 70.393072 -348.814901)
			(xy 70.363582 -348.769015) (xy 70.340922 -348.719399) (xy 70.325554 -348.667063) (xy 70.317792 -348.613073)
			(xy 68.835088 -348.613073) (xy 68.827326 -348.667061) (xy 68.811958 -348.719395) (xy 68.789298 -348.76901)
			(xy 68.759808 -348.814894) (xy 68.724087 -348.856114) (xy 68.682863 -348.89183) (xy 68.636976 -348.921316)
			(xy 68.58736 -348.943971) (xy 68.535024 -348.959334) (xy 68.481034 -348.967091) (xy 68.453762 -348.967552)
			(xy 67.590162 -348.967552) (xy 67.562894 -348.967083) (xy 67.508913 -348.959317) (xy 67.456586 -348.943948)
			(xy 67.40698 -348.921289) (xy 67.361102 -348.891801) (xy 67.319888 -348.856085) (xy 67.284176 -348.814867)
			(xy 67.254693 -348.768987) (xy 67.232039 -348.719378) (xy 67.216675 -348.66705) (xy 67.208914 -348.613068)
			(xy 65.726066 -348.613068) (xy 65.726066 -348.613069) (xy 65.718304 -348.667051) (xy 65.702939 -348.719379)
			(xy 65.680284 -348.768987) (xy 65.650799 -348.814867) (xy 65.615085 -348.856083) (xy 65.573869 -348.891798)
			(xy 65.527989 -348.921283) (xy 65.47838 -348.943939) (xy 65.426053 -348.959304) (xy 65.372071 -348.967065)
			(xy 65.344802 -348.967552) (xy 64.481202 -348.967552) (xy 64.45393 -348.967109) (xy 64.399942 -348.959347)
			(xy 64.347607 -348.94398) (xy 64.297993 -348.921322) (xy 64.252108 -348.891834) (xy 64.210886 -348.856115)
			(xy 64.175168 -348.814894) (xy 64.145679 -348.769009) (xy 64.123021 -348.719394) (xy 64.107654 -348.66706)
			(xy 64.099892 -348.613072) (xy 62.617065 -348.613072) (xy 62.609305 -348.667045) (xy 62.593943 -348.71937)
			(xy 62.57129 -348.768976) (xy 62.541809 -348.814854) (xy 62.506099 -348.856069) (xy 62.464887 -348.891784)
			(xy 62.419013 -348.92127) (xy 62.369409 -348.943928) (xy 62.317086 -348.959296) (xy 62.263109 -348.967063)
			(xy 62.235842 -348.967552) (xy 61.372242 -348.967552) (xy 61.344968 -348.967111) (xy 61.290976 -348.959354)
			(xy 61.238636 -348.943991) (xy 61.189017 -348.921335) (xy 61.143127 -348.891848) (xy 61.1019 -348.856129)
			(xy 61.066177 -348.814907) (xy 61.036685 -348.76902) (xy 61.014024 -348.719403) (xy 60.998655 -348.667066)
			(xy 60.990892 -348.613074) (xy 51.666865 -348.613074) (xy 51.659106 -348.667044) (xy 51.643743 -348.719369)
			(xy 51.621091 -348.768974) (xy 51.59161 -348.814852) (xy 51.555901 -348.856067) (xy 51.51469 -348.891781)
			(xy 51.468817 -348.921268) (xy 51.419214 -348.943926) (xy 51.366891 -348.959295) (xy 51.312914 -348.967062)
			(xy 51.285648 -348.967552) (xy 50.422048 -348.967552) (xy 50.394774 -348.967112) (xy 50.340781 -348.959355)
			(xy 50.288441 -348.943992) (xy 50.23882 -348.921337) (xy 50.192929 -348.89185) (xy 50.151702 -348.856132)
			(xy 50.115979 -348.814909) (xy 50.086486 -348.769022) (xy 50.063824 -348.719404) (xy 50.048455 -348.667066)
			(xy 50.040692 -348.613074) (xy 48.557989 -348.613074) (xy 48.550226 -348.667057) (xy 48.53486 -348.71939)
			(xy 48.512202 -348.769002) (xy 48.482714 -348.814885) (xy 48.446996 -348.856105) (xy 48.405776 -348.891821)
			(xy 48.359892 -348.921308) (xy 48.310278 -348.943964) (xy 48.257946 -348.959329) (xy 48.203959 -348.967089)
			(xy 48.176688 -348.967552) (xy 47.313088 -348.967552) (xy 47.285818 -348.967085) (xy 47.231835 -348.959321)
			(xy 47.179505 -348.943955) (xy 47.129895 -348.921297) (xy 47.084015 -348.89181) (xy 47.042797 -348.856094)
			(xy 47.007083 -348.814876) (xy 46.977597 -348.768994) (xy 46.954941 -348.719383) (xy 46.939576 -348.667053)
			(xy 46.931814 -348.61307) (xy 45.448966 -348.61307) (xy 45.441205 -348.667047) (xy 45.425841 -348.719373)
			(xy 45.403188 -348.76898) (xy 45.373705 -348.814858) (xy 45.337994 -348.856074) (xy 45.296781 -348.891789)
			(xy 45.250905 -348.921274) (xy 45.201299 -348.943932) (xy 45.148975 -348.959299) (xy 45.094995 -348.967064)
			(xy 45.067728 -348.967552) (xy 44.204128 -348.967552) (xy 44.176855 -348.96711) (xy 44.122864 -348.959351)
			(xy 44.070526 -348.943987) (xy 44.020908 -348.92133) (xy 43.97502 -348.891843) (xy 43.933795 -348.856124)
			(xy 43.898074 -348.814903) (xy 43.868583 -348.769016) (xy 43.845923 -348.7194) (xy 43.830555 -348.667064)
			(xy 43.822792 -348.613073) (xy 42.340088 -348.613073) (xy 42.332326 -348.66706) (xy 42.316958 -348.719394)
			(xy 42.294299 -348.769008) (xy 42.264809 -348.814892) (xy 42.229089 -348.856112) (xy 42.187866 -348.891828)
			(xy 42.14198 -348.921314) (xy 42.092364 -348.943969) (xy 42.040029 -348.959332) (xy 41.98604 -348.967091)
			(xy 41.958768 -348.967552) (xy 41.095168 -348.967552) (xy 41.067899 -348.967083) (xy 41.013918 -348.959318)
			(xy 40.961591 -348.943949) (xy 40.911983 -348.921291) (xy 40.866105 -348.891803) (xy 40.82489 -348.856087)
			(xy 40.789178 -348.814869) (xy 40.759694 -348.768989) (xy 40.73704 -348.719379) (xy 40.721675 -348.667051)
			(xy 40.713914 -348.613069) (xy 39.231066 -348.613069) (xy 39.223304 -348.66705) (xy 39.20794 -348.719377)
			(xy 39.185285 -348.768986) (xy 39.1558 -348.814865) (xy 39.120087 -348.856081) (xy 39.078871 -348.891796)
			(xy 39.032993 -348.921281) (xy 38.983385 -348.943937) (xy 38.931058 -348.959303) (xy 38.877076 -348.967065)
			(xy 38.849808 -348.967552) (xy 37.986208 -348.967552) (xy 37.958936 -348.967109) (xy 37.904947 -348.959348)
			(xy 37.852612 -348.943982) (xy 37.802996 -348.921324) (xy 37.75711 -348.891836) (xy 37.715888 -348.856117)
			(xy 37.680169 -348.814896) (xy 37.65068 -348.769011) (xy 37.628021 -348.719396) (xy 37.612654 -348.667061)
			(xy 37.604892 -348.613072) (xy 36.122065 -348.613072) (xy 36.114306 -348.667044) (xy 36.098943 -348.719369)
			(xy 36.076291 -348.768974) (xy 36.04681 -348.814852) (xy 36.011101 -348.856067) (xy 35.96989 -348.891781)
			(xy 35.924017 -348.921268) (xy 35.874414 -348.943926) (xy 35.822091 -348.959295) (xy 35.768114 -348.967062)
			(xy 35.740848 -348.967552) (xy 34.877248 -348.967552) (xy 34.849974 -348.967112) (xy 34.795981 -348.959355)
			(xy 34.743641 -348.943992) (xy 34.69402 -348.921337) (xy 34.648129 -348.89185) (xy 34.606902 -348.856132)
			(xy 34.571179 -348.814909) (xy 34.541686 -348.769022) (xy 34.519024 -348.719404) (xy 34.503655 -348.667066)
			(xy 34.495892 -348.613074) (xy 33.013189 -348.613074) (xy 33.005426 -348.667057) (xy 32.99006 -348.71939)
			(xy 32.967402 -348.769002) (xy 32.937914 -348.814885) (xy 32.902196 -348.856105) (xy 32.860976 -348.891821)
			(xy 32.815092 -348.921308) (xy 32.765478 -348.943964) (xy 32.713146 -348.959329) (xy 32.659159 -348.967089)
			(xy 32.631888 -348.967552) (xy 31.768288 -348.967552) (xy 31.741018 -348.967085) (xy 31.687035 -348.959321)
			(xy 31.634705 -348.943955) (xy 31.585095 -348.921297) (xy 31.539215 -348.89181) (xy 31.497997 -348.856094)
			(xy 31.462283 -348.814876) (xy 31.432797 -348.768994) (xy 31.410141 -348.719383) (xy 31.394776 -348.667053)
			(xy 31.387014 -348.61307) (xy 29.904166 -348.61307) (xy 29.896405 -348.667047) (xy 29.881041 -348.719373)
			(xy 29.858388 -348.76898) (xy 29.828905 -348.814858) (xy 29.793194 -348.856074) (xy 29.751981 -348.891789)
			(xy 29.706105 -348.921274) (xy 29.656499 -348.943932) (xy 29.604175 -348.959299) (xy 29.550195 -348.967064)
			(xy 29.522928 -348.967552) (xy 28.659328 -348.967552) (xy 28.632055 -348.96711) (xy 28.578064 -348.959351)
			(xy 28.525726 -348.943987) (xy 28.476108 -348.92133) (xy 28.43022 -348.891843) (xy 28.388995 -348.856124)
			(xy 28.353274 -348.814903) (xy 28.323783 -348.769016) (xy 28.301123 -348.7194) (xy 28.285755 -348.667064)
			(xy 28.277992 -348.613073) (xy 26.795288 -348.613073) (xy 26.787526 -348.66706) (xy 26.772158 -348.719394)
			(xy 26.749499 -348.769008) (xy 26.720009 -348.814892) (xy 26.684289 -348.856112) (xy 26.643066 -348.891828)
			(xy 26.59718 -348.921314) (xy 26.547564 -348.943969) (xy 26.495229 -348.959332) (xy 26.44124 -348.967091)
			(xy 26.413968 -348.967552) (xy 25.550368 -348.967552) (xy 25.523099 -348.967083) (xy 25.469118 -348.959318)
			(xy 25.416791 -348.943949) (xy 25.367183 -348.921291) (xy 25.321305 -348.891803) (xy 25.28009 -348.856087)
			(xy 25.244378 -348.814869) (xy 25.214894 -348.768989) (xy 25.19224 -348.719379) (xy 25.176875 -348.667051)
			(xy 25.169114 -348.613069) (xy 23.686266 -348.613069) (xy 23.678504 -348.66705) (xy 23.66314 -348.719377)
			(xy 23.640485 -348.768986) (xy 23.611 -348.814865) (xy 23.575287 -348.856081) (xy 23.534071 -348.891796)
			(xy 23.488193 -348.921281) (xy 23.438585 -348.943937) (xy 23.386258 -348.959303) (xy 23.332276 -348.967065)
			(xy 23.305008 -348.967552) (xy 22.441408 -348.967552) (xy 22.414136 -348.967109) (xy 22.360147 -348.959348)
			(xy 22.307812 -348.943982) (xy 22.258196 -348.921324) (xy 22.21231 -348.891836) (xy 22.171088 -348.856117)
			(xy 22.135369 -348.814896) (xy 22.10588 -348.769011) (xy 22.083221 -348.719396) (xy 22.067854 -348.667061)
			(xy 22.060092 -348.613072) (xy 20.577347 -348.613072) (xy 20.569586 -348.667048) (xy 20.55422 -348.719381)
			(xy 20.531562 -348.768994) (xy 20.502074 -348.814878) (xy 20.466357 -348.856098) (xy 20.425136 -348.891816)
			(xy 20.379253 -348.921303) (xy 20.329639 -348.943961) (xy 20.277306 -348.959327) (xy 20.223319 -348.967089)
			(xy 20.196048 -348.967552) (xy 19.332448 -348.967552) (xy 19.305179 -348.967065) (xy 19.251195 -348.959304)
			(xy 19.198866 -348.943938) (xy 19.149256 -348.921282) (xy 19.103375 -348.891796) (xy 19.062158 -348.856081)
			(xy 19.026443 -348.814863) (xy 18.996957 -348.768982) (xy 18.974301 -348.719372) (xy 18.958936 -348.667043)
			(xy 18.951174 -348.613059) (xy 8.879169 -348.613059) (xy 8.892221 -348.718461) (xy 8.900171 -348.847356)
			(xy 8.900668 -348.911926) (xy 8.900171 -348.976496) (xy 8.892221 -349.105391) (xy 8.876351 -349.233551)
			(xy 8.852622 -349.360492) (xy 8.821123 -349.485731) (xy 8.781974 -349.608794) (xy 8.735323 -349.729213)
			(xy 8.681348 -349.846532) (xy 8.620253 -349.960306) (xy 8.55227 -350.070103) (xy 8.477656 -350.175506)
			(xy 8.396695 -350.276116) (xy 8.309695 -350.371551) (xy 8.216984 -350.46145) (xy 8.118914 -350.545471)
			(xy 8.015859 -350.623295) (xy 7.908208 -350.694627) (xy 7.796369 -350.759197) (xy 7.680768 -350.816759)
			(xy 7.561843 -350.867096) (xy 7.440044 -350.910016) (xy 7.315834 -350.945357) (xy 7.189685 -350.972984)
			(xy 7.062073 -350.992793) (xy 6.933484 -351.004709) (xy 6.804406 -351.008686) (xy 6.675328 -351.004709)
			(xy 6.546739 -350.992793) (xy 6.419127 -350.972984) (xy 6.292978 -350.945357) (xy 6.168768 -350.910016)
			(xy 6.046969 -350.867096) (xy 5.928044 -350.816759) (xy 5.812443 -350.759197) (xy 5.700604 -350.694627)
			(xy 5.592953 -350.623295) (xy 5.489898 -350.545471) (xy 5.391828 -350.46145) (xy 5.299117 -350.371551)
			(xy 5.212117 -350.276116) (xy 5.131156 -350.175506) (xy 5.056542 -350.070103) (xy 4.988559 -349.960306)
			(xy 4.927464 -349.846532) (xy 4.873489 -349.729213) (xy 4.826838 -349.608794) (xy 4.787689 -349.485731)
			(xy 4.75619 -349.360492) (xy 4.732461 -349.233551) (xy 4.716591 -349.105391) (xy 4.708641 -348.976496)
			(xy 0.508 -348.976496) (xy 0.508 -351.638709) (xy 18.951172 -351.638709) (xy 18.951172 -351.584171)
			(xy 18.958934 -351.530187) (xy 18.974299 -351.477857) (xy 18.996956 -351.428247) (xy 19.026441 -351.382366)
			(xy 19.062157 -351.341148) (xy 19.103374 -351.305433) (xy 19.149255 -351.275947) (xy 19.198865 -351.25329)
			(xy 19.251195 -351.237925) (xy 19.305179 -351.230163) (xy 19.332448 -351.229676) (xy 20.196048 -351.229676)
			(xy 20.223319 -351.230143) (xy 20.277306 -351.237905) (xy 20.329638 -351.253271) (xy 20.379252 -351.275929)
			(xy 20.425135 -351.305416) (xy 20.466355 -351.341133) (xy 20.502073 -351.382353) (xy 20.53156 -351.428237)
			(xy 20.554218 -351.47785) (xy 20.569584 -351.530182) (xy 20.577347 -351.584169) (xy 20.577347 -351.638669)
			(xy 22.060139 -351.638669) (xy 22.060139 -351.584131) (xy 22.067901 -351.530149) (xy 22.083266 -351.477821)
			(xy 22.105922 -351.428212) (xy 22.135407 -351.382333) (xy 22.171122 -351.341117) (xy 22.212339 -351.305403)
			(xy 22.258219 -351.275918) (xy 22.307829 -351.253263) (xy 22.360157 -351.237899) (xy 22.414139 -351.230139)
			(xy 22.441408 -351.229676) (xy 23.305008 -351.229676) (xy 23.33228 -351.230087) (xy 23.386268 -351.23785)
			(xy 23.438602 -351.253218) (xy 23.488216 -351.275877) (xy 23.5341 -351.305366) (xy 23.575321 -351.341085)
			(xy 23.611039 -351.382306) (xy 23.640527 -351.428191) (xy 23.663185 -351.477806) (xy 23.678551 -351.53014)
			(xy 23.686314 -351.584128) (xy 23.686314 -351.638665) (xy 25.169162 -351.638665) (xy 25.169162 -351.584135)
			(xy 25.176922 -351.530159) (xy 25.192284 -351.477838) (xy 25.214936 -351.428234) (xy 25.244416 -351.38236)
			(xy 25.280124 -351.341147) (xy 25.321334 -351.305435) (xy 25.367206 -351.275951) (xy 25.416808 -351.253296)
			(xy 25.469128 -351.237929) (xy 25.523103 -351.230165) (xy 25.550368 -351.229676) (xy 26.413968 -351.229676)
			(xy 26.441243 -351.230061) (xy 26.495239 -351.237821) (xy 26.547581 -351.253186) (xy 26.597203 -351.275844)
			(xy 26.643095 -351.305333) (xy 26.684323 -351.341054) (xy 26.720047 -351.382279) (xy 26.749541 -351.428169)
			(xy 26.772203 -351.477789) (xy 26.787573 -351.53013) (xy 26.795336 -351.584125) (xy 26.795336 -351.63867)
			(xy 28.278039 -351.63867) (xy 28.278039 -351.58413) (xy 28.285802 -351.530146) (xy 28.301168 -351.477817)
			(xy 28.323825 -351.428207) (xy 28.353312 -351.382326) (xy 28.389029 -351.341109) (xy 28.430249 -351.305396)
			(xy 28.476131 -351.275912) (xy 28.525743 -351.253258) (xy 28.578074 -351.237896) (xy 28.632058 -351.230137)
			(xy 28.659328 -351.229676) (xy 29.522928 -351.229676) (xy 29.550199 -351.230088) (xy 29.604185 -351.237854)
			(xy 29.656516 -351.253223) (xy 29.706128 -351.275883) (xy 29.75201 -351.305373) (xy 29.793228 -351.341092)
			(xy 29.828944 -351.382313) (xy 29.85843 -351.428197) (xy 29.881086 -351.47781) (xy 29.896452 -351.530143)
			(xy 29.904214 -351.584129) (xy 29.904214 -351.638666) (xy 31.387062 -351.638666) (xy 31.387062 -351.584134)
			(xy 31.394823 -351.530157) (xy 31.410186 -351.477833) (xy 31.432839 -351.428229) (xy 31.462321 -351.382353)
			(xy 31.498031 -351.34114) (xy 31.539243 -351.305428) (xy 31.585118 -351.275945) (xy 31.634722 -351.25329)
			(xy 31.687045 -351.237925) (xy 31.741022 -351.230163) (xy 31.768288 -351.229676) (xy 32.631888 -351.229676)
			(xy 32.659162 -351.230063) (xy 32.713156 -351.237824) (xy 32.765495 -351.253191) (xy 32.815115 -351.27585)
			(xy 32.861004 -351.30534) (xy 32.90223 -351.341061) (xy 32.937952 -351.382286) (xy 32.967444 -351.428175)
			(xy 32.990105 -351.477794) (xy 33.005473 -351.530132) (xy 33.013236 -351.584126) (xy 33.013236 -351.63867)
			(xy 34.49594 -351.63867) (xy 34.49594 -351.58413) (xy 34.503702 -351.530144) (xy 34.519069 -351.477812)
			(xy 34.541728 -351.428201) (xy 34.571217 -351.38232) (xy 34.606936 -351.341102) (xy 34.648158 -351.305388)
			(xy 34.694043 -351.275905) (xy 34.743658 -351.253253) (xy 34.795991 -351.237892) (xy 34.849977 -351.230136)
			(xy 34.877248 -351.229676) (xy 35.740848 -351.229676) (xy 35.768118 -351.23009) (xy 35.822102 -351.237858)
			(xy 35.874431 -351.253229) (xy 35.92404 -351.27589) (xy 35.969919 -351.30538) (xy 36.011135 -351.341099)
			(xy 36.046849 -351.382319) (xy 36.076333 -351.428203) (xy 36.098988 -351.477814) (xy 36.114352 -351.530145)
			(xy 36.122114 -351.58413) (xy 36.122114 -351.638669) (xy 37.604939 -351.638669) (xy 37.604939 -351.584131)
			(xy 37.612701 -351.530149) (xy 37.628066 -351.477821) (xy 37.650722 -351.428212) (xy 37.680207 -351.382333)
			(xy 37.715922 -351.341117) (xy 37.757139 -351.305403) (xy 37.803019 -351.275918) (xy 37.852629 -351.253263)
			(xy 37.904957 -351.237899) (xy 37.958939 -351.230139) (xy 37.986208 -351.229676) (xy 38.849808 -351.229676)
			(xy 38.87708 -351.230087) (xy 38.931068 -351.23785) (xy 38.983402 -351.253218) (xy 39.033016 -351.275877)
			(xy 39.0789 -351.305366) (xy 39.120121 -351.341085) (xy 39.155839 -351.382306) (xy 39.185327 -351.428191)
			(xy 39.207985 -351.477806) (xy 39.223351 -351.53014) (xy 39.231114 -351.584128) (xy 39.231114 -351.638665)
			(xy 40.713962 -351.638665) (xy 40.713962 -351.584135) (xy 40.721722 -351.530159) (xy 40.737084 -351.477838)
			(xy 40.759736 -351.428234) (xy 40.789216 -351.38236) (xy 40.824924 -351.341147) (xy 40.866134 -351.305435)
			(xy 40.912006 -351.275951) (xy 40.961608 -351.253296) (xy 41.013928 -351.237929) (xy 41.067903 -351.230165)
			(xy 41.095168 -351.229676) (xy 41.958768 -351.229676) (xy 41.986043 -351.230061) (xy 42.040039 -351.237821)
			(xy 42.092381 -351.253186) (xy 42.142003 -351.275844) (xy 42.187895 -351.305333) (xy 42.229123 -351.341054)
			(xy 42.264847 -351.382279) (xy 42.294341 -351.428169) (xy 42.317003 -351.477789) (xy 42.332373 -351.53013)
			(xy 42.340136 -351.584125) (xy 42.340136 -351.63867) (xy 43.822839 -351.63867) (xy 43.822839 -351.58413)
			(xy 43.830602 -351.530146) (xy 43.845968 -351.477817) (xy 43.868625 -351.428207) (xy 43.898112 -351.382326)
			(xy 43.933829 -351.341109) (xy 43.975049 -351.305396) (xy 44.020931 -351.275912) (xy 44.070543 -351.253258)
			(xy 44.122874 -351.237896) (xy 44.176858 -351.230137) (xy 44.204128 -351.229676) (xy 45.067728 -351.229676)
			(xy 45.094999 -351.230088) (xy 45.148985 -351.237854) (xy 45.201316 -351.253223) (xy 45.250928 -351.275883)
			(xy 45.29681 -351.305373) (xy 45.338028 -351.341092) (xy 45.373744 -351.382313) (xy 45.40323 -351.428197)
			(xy 45.425886 -351.47781) (xy 45.441252 -351.530143) (xy 45.449014 -351.584129) (xy 45.449014 -351.638666)
			(xy 46.931862 -351.638666) (xy 46.931862 -351.584134) (xy 46.939623 -351.530157) (xy 46.954986 -351.477833)
			(xy 46.977639 -351.428229) (xy 47.007121 -351.382353) (xy 47.042831 -351.34114) (xy 47.084043 -351.305428)
			(xy 47.129918 -351.275945) (xy 47.179522 -351.25329) (xy 47.231845 -351.237925) (xy 47.285822 -351.230163)
			(xy 47.313088 -351.229676) (xy 48.176688 -351.229676) (xy 48.203962 -351.230063) (xy 48.257956 -351.237824)
			(xy 48.310295 -351.253191) (xy 48.359915 -351.27585) (xy 48.405804 -351.30534) (xy 48.44703 -351.341061)
			(xy 48.482752 -351.382286) (xy 48.512244 -351.428175) (xy 48.534905 -351.477794) (xy 48.550273 -351.530132)
			(xy 48.558036 -351.584126) (xy 48.558036 -351.63867) (xy 50.04074 -351.63867) (xy 50.04074 -351.58413)
			(xy 50.048502 -351.530144) (xy 50.063869 -351.477812) (xy 50.086528 -351.428201) (xy 50.116017 -351.38232)
			(xy 50.151736 -351.341102) (xy 50.192958 -351.305388) (xy 50.238843 -351.275905) (xy 50.288458 -351.253253)
			(xy 50.340791 -351.237892) (xy 50.394777 -351.230136) (xy 50.422048 -351.229676) (xy 51.285648 -351.229676)
			(xy 51.312918 -351.23009) (xy 51.366902 -351.237858) (xy 51.419231 -351.253229) (xy 51.46884 -351.27589)
			(xy 51.514719 -351.30538) (xy 51.555935 -351.341099) (xy 51.591649 -351.382319) (xy 51.621133 -351.428203)
			(xy 51.643788 -351.477814) (xy 51.659152 -351.530145) (xy 51.666914 -351.58413) (xy 51.666914 -351.63867)
			(xy 60.99094 -351.63867) (xy 60.99094 -351.58413) (xy 60.998702 -351.530145) (xy 61.014069 -351.477814)
			(xy 61.036727 -351.428203) (xy 61.066216 -351.382322) (xy 61.101934 -351.341105) (xy 61.143155 -351.305391)
			(xy 61.18904 -351.275907) (xy 61.238653 -351.253254) (xy 61.290986 -351.237893) (xy 61.344972 -351.230137)
			(xy 61.372242 -351.229676) (xy 62.235842 -351.229676) (xy 62.263112 -351.230089) (xy 62.317097 -351.237857)
			(xy 62.369426 -351.253227) (xy 62.419036 -351.275888) (xy 62.464916 -351.305378) (xy 62.506133 -351.341097)
			(xy 62.541847 -351.382317) (xy 62.571332 -351.428201) (xy 62.593988 -351.477813) (xy 62.609352 -351.530145)
			(xy 62.617114 -351.58413) (xy 62.617114 -351.638668) (xy 64.099939 -351.638668) (xy 64.099939 -351.584132)
			(xy 64.107701 -351.53015) (xy 64.123066 -351.477822) (xy 64.145721 -351.428214) (xy 64.175206 -351.382335)
			(xy 64.21092 -351.341119) (xy 64.252136 -351.305405) (xy 64.298016 -351.27592) (xy 64.347624 -351.253265)
			(xy 64.399952 -351.2379) (xy 64.453934 -351.230139) (xy 64.481202 -351.229676) (xy 65.344802 -351.229676)
			(xy 65.372074 -351.230087) (xy 65.426063 -351.237849) (xy 65.478397 -351.253216) (xy 65.528012 -351.275875)
			(xy 65.573897 -351.305364) (xy 65.615119 -351.341083) (xy 65.650837 -351.382304) (xy 65.680326 -351.42819)
			(xy 65.702984 -351.477805) (xy 65.718351 -351.530139) (xy 65.726113 -351.584128) (xy 65.726113 -351.638665)
			(xy 67.208962 -351.638665) (xy 67.208962 -351.584135) (xy 67.216722 -351.53016) (xy 67.232084 -351.477839)
			(xy 67.254735 -351.428236) (xy 67.284215 -351.382362) (xy 67.319922 -351.341149) (xy 67.361131 -351.305437)
			(xy 67.407003 -351.275953) (xy 67.456603 -351.253297) (xy 67.508923 -351.23793) (xy 67.562897 -351.230165)
			(xy 67.590162 -351.229676) (xy 68.453762 -351.229676) (xy 68.481037 -351.230061) (xy 68.535034 -351.23782)
			(xy 68.587376 -351.253184) (xy 68.636999 -351.275842) (xy 68.682892 -351.305331) (xy 68.724121 -351.341052)
			(xy 68.759846 -351.382277) (xy 68.78934 -351.428167) (xy 68.812003 -351.477788) (xy 68.827372 -351.530129)
			(xy 68.835136 -351.584125) (xy 68.835136 -351.638669) (xy 70.317839 -351.638669) (xy 70.317839 -351.584131)
			(xy 70.325601 -351.530147) (xy 70.340967 -351.477818) (xy 70.363624 -351.428208) (xy 70.393111 -351.382328)
			(xy 70.428827 -351.341112) (xy 70.470046 -351.305398) (xy 70.515928 -351.275914) (xy 70.565539 -351.25326)
			(xy 70.617869 -351.237897) (xy 70.671853 -351.230138) (xy 70.699122 -351.229676) (xy 71.562722 -351.229676)
			(xy 71.589993 -351.230088) (xy 71.64398 -351.237853) (xy 71.696312 -351.253222) (xy 71.745924 -351.275881)
			(xy 71.791807 -351.305371) (xy 71.833026 -351.34109) (xy 71.868742 -351.382311) (xy 71.898229 -351.428195)
			(xy 71.920886 -351.477809) (xy 71.936252 -351.530142) (xy 71.944014 -351.584129) (xy 71.944014 -351.638666)
			(xy 73.426862 -351.638666) (xy 73.426862 -351.584134) (xy 73.434623 -351.530158) (xy 73.449986 -351.477835)
			(xy 73.472638 -351.428231) (xy 73.50212 -351.382355) (xy 73.537829 -351.341142) (xy 73.579041 -351.30543)
			(xy 73.624915 -351.275947) (xy 73.674518 -351.253292) (xy 73.72684 -351.237927) (xy 73.780816 -351.230164)
			(xy 73.808082 -351.229676) (xy 74.671682 -351.229676) (xy 74.698957 -351.230062) (xy 74.752951 -351.237823)
			(xy 74.805291 -351.253189) (xy 74.854911 -351.275848) (xy 74.900802 -351.305338) (xy 74.942028 -351.341059)
			(xy 74.977751 -351.382284) (xy 75.007243 -351.428173) (xy 75.029904 -351.477792) (xy 75.045273 -351.530132)
			(xy 75.053036 -351.584125) (xy 75.053036 -351.63867) (xy 76.53574 -351.63867) (xy 76.53574 -351.58413)
			(xy 76.543502 -351.530145) (xy 76.558869 -351.477814) (xy 76.581527 -351.428203) (xy 76.611016 -351.382322)
			(xy 76.646734 -351.341105) (xy 76.687955 -351.305391) (xy 76.73384 -351.275907) (xy 76.783453 -351.253254)
			(xy 76.835786 -351.237893) (xy 76.889772 -351.230137) (xy 76.917042 -351.229676) (xy 77.780642 -351.229676)
			(xy 77.807912 -351.230089) (xy 77.861897 -351.237857) (xy 77.914226 -351.253227) (xy 77.963836 -351.275888)
			(xy 78.009716 -351.305378) (xy 78.050933 -351.341097) (xy 78.086647 -351.382317) (xy 78.116132 -351.428201)
			(xy 78.138788 -351.477813) (xy 78.154152 -351.530145) (xy 78.161914 -351.58413) (xy 78.161914 -351.638668)
			(xy 79.644739 -351.638668) (xy 79.644739 -351.584132) (xy 79.652501 -351.53015) (xy 79.667866 -351.477822)
			(xy 79.690521 -351.428214) (xy 79.720006 -351.382335) (xy 79.75572 -351.341119) (xy 79.796936 -351.305405)
			(xy 79.842816 -351.27592) (xy 79.892424 -351.253265) (xy 79.944752 -351.2379) (xy 79.998734 -351.230139)
			(xy 80.026002 -351.229676) (xy 80.889602 -351.229676) (xy 80.916874 -351.230087) (xy 80.970863 -351.237849)
			(xy 81.023197 -351.253216) (xy 81.072812 -351.275875) (xy 81.118697 -351.305364) (xy 81.159919 -351.341083)
			(xy 81.195637 -351.382304) (xy 81.225126 -351.42819) (xy 81.247784 -351.477805) (xy 81.263151 -351.530139)
			(xy 81.270913 -351.584128) (xy 81.270913 -351.638665) (xy 82.753762 -351.638665) (xy 82.753762 -351.584135)
			(xy 82.761522 -351.53016) (xy 82.776884 -351.477839) (xy 82.799535 -351.428236) (xy 82.829015 -351.382362)
			(xy 82.864722 -351.341149) (xy 82.905931 -351.305437) (xy 82.951803 -351.275953) (xy 83.001403 -351.253297)
			(xy 83.053723 -351.23793) (xy 83.107697 -351.230165) (xy 83.134962 -351.229676) (xy 83.998562 -351.229676)
			(xy 84.025837 -351.230061) (xy 84.079834 -351.23782) (xy 84.132176 -351.253184) (xy 84.181799 -351.275842)
			(xy 84.227692 -351.305331) (xy 84.268921 -351.341052) (xy 84.304646 -351.382277) (xy 84.33414 -351.428167)
			(xy 84.356803 -351.477788) (xy 84.372172 -351.530129) (xy 84.379936 -351.584125) (xy 84.379936 -351.638669)
			(xy 85.862639 -351.638669) (xy 85.862639 -351.584131) (xy 85.870401 -351.530147) (xy 85.885767 -351.477818)
			(xy 85.908424 -351.428208) (xy 85.937911 -351.382328) (xy 85.973627 -351.341112) (xy 86.014846 -351.305398)
			(xy 86.060728 -351.275914) (xy 86.110339 -351.25326) (xy 86.162669 -351.237897) (xy 86.216653 -351.230138)
			(xy 86.243922 -351.229676) (xy 87.107522 -351.229676) (xy 87.134793 -351.230088) (xy 87.18878 -351.237853)
			(xy 87.241112 -351.253222) (xy 87.290724 -351.275881) (xy 87.336607 -351.305371) (xy 87.377826 -351.34109)
			(xy 87.413542 -351.382311) (xy 87.443029 -351.428195) (xy 87.465686 -351.477809) (xy 87.481052 -351.530142)
			(xy 87.488814 -351.584129) (xy 87.488814 -351.638666) (xy 88.971662 -351.638666) (xy 88.971662 -351.584134)
			(xy 88.979423 -351.530158) (xy 88.994786 -351.477835) (xy 89.017438 -351.428231) (xy 89.04692 -351.382355)
			(xy 89.082629 -351.341142) (xy 89.123841 -351.30543) (xy 89.169715 -351.275947) (xy 89.219318 -351.253292)
			(xy 89.27164 -351.237927) (xy 89.325616 -351.230164) (xy 89.352882 -351.229676) (xy 90.216482 -351.229676)
			(xy 90.243757 -351.230062) (xy 90.297751 -351.237823) (xy 90.350091 -351.253189) (xy 90.399711 -351.275848)
			(xy 90.445602 -351.305338) (xy 90.486828 -351.341059) (xy 90.522551 -351.382284) (xy 90.552043 -351.428173)
			(xy 90.574704 -351.477792) (xy 90.590073 -351.530132) (xy 90.597836 -351.584125) (xy 90.597836 -351.63867)
			(xy 92.08054 -351.63867) (xy 92.08054 -351.58413) (xy 92.088302 -351.530145) (xy 92.103669 -351.477814)
			(xy 92.126327 -351.428203) (xy 92.155816 -351.382322) (xy 92.191534 -351.341105) (xy 92.232755 -351.305391)
			(xy 92.27864 -351.275907) (xy 92.328253 -351.253254) (xy 92.380586 -351.237893) (xy 92.434572 -351.230137)
			(xy 92.461842 -351.229676) (xy 93.325442 -351.229676) (xy 93.352712 -351.230089) (xy 93.406697 -351.237857)
			(xy 93.459026 -351.253227) (xy 93.508636 -351.275888) (xy 93.554516 -351.305378) (xy 93.595733 -351.341097)
			(xy 93.631447 -351.382317) (xy 93.660932 -351.428201) (xy 93.683588 -351.477813) (xy 93.698952 -351.530145)
			(xy 93.706714 -351.58413) (xy 93.706714 -351.638669) (xy 111.480839 -351.638669) (xy 111.480839 -351.584131)
			(xy 111.488601 -351.530149) (xy 111.503966 -351.477821) (xy 111.526622 -351.428212) (xy 111.556107 -351.382333)
			(xy 111.591822 -351.341117) (xy 111.633039 -351.305403) (xy 111.678919 -351.275918) (xy 111.728529 -351.253263)
			(xy 111.780857 -351.237899) (xy 111.834839 -351.230139) (xy 111.862108 -351.229676) (xy 112.725708 -351.229676)
			(xy 112.75298 -351.230087) (xy 112.806968 -351.23785) (xy 112.859302 -351.253218) (xy 112.908916 -351.275877)
			(xy 112.9548 -351.305366) (xy 112.996021 -351.341085) (xy 113.031739 -351.382306) (xy 113.061227 -351.428191)
			(xy 113.083885 -351.477806) (xy 113.099251 -351.53014) (xy 113.107014 -351.584128) (xy 113.107014 -351.638665)
			(xy 114.589862 -351.638665) (xy 114.589862 -351.584135) (xy 114.597622 -351.530159) (xy 114.612984 -351.477838)
			(xy 114.635636 -351.428234) (xy 114.665116 -351.38236) (xy 114.700824 -351.341147) (xy 114.742034 -351.305435)
			(xy 114.787906 -351.275951) (xy 114.837508 -351.253296) (xy 114.889828 -351.237929) (xy 114.943803 -351.230165)
			(xy 114.971068 -351.229676) (xy 115.834668 -351.229676) (xy 115.861943 -351.230061) (xy 115.915939 -351.237821)
			(xy 115.968281 -351.253186) (xy 116.017903 -351.275844) (xy 116.063795 -351.305333) (xy 116.105023 -351.341054)
			(xy 116.140747 -351.382279) (xy 116.170241 -351.428169) (xy 116.192903 -351.477789) (xy 116.208273 -351.53013)
			(xy 116.216036 -351.584125) (xy 116.216036 -351.63867) (xy 117.698739 -351.63867) (xy 117.698739 -351.58413)
			(xy 117.706502 -351.530146) (xy 117.721868 -351.477817) (xy 117.744525 -351.428207) (xy 117.774012 -351.382326)
			(xy 117.809729 -351.341109) (xy 117.850949 -351.305396) (xy 117.896831 -351.275912) (xy 117.946443 -351.253258)
			(xy 117.998774 -351.237896) (xy 118.052758 -351.230137) (xy 118.080028 -351.229676) (xy 118.943628 -351.229676)
			(xy 118.970899 -351.230088) (xy 119.024885 -351.237854) (xy 119.077216 -351.253223) (xy 119.126828 -351.275883)
			(xy 119.17271 -351.305373) (xy 119.213928 -351.341092) (xy 119.249644 -351.382313) (xy 119.27913 -351.428197)
			(xy 119.301786 -351.47781) (xy 119.317152 -351.530143) (xy 119.324914 -351.584129) (xy 119.324914 -351.638666)
			(xy 120.807762 -351.638666) (xy 120.807762 -351.584134) (xy 120.815523 -351.530157) (xy 120.830886 -351.477833)
			(xy 120.853539 -351.428229) (xy 120.883021 -351.382353) (xy 120.918731 -351.34114) (xy 120.959943 -351.305428)
			(xy 121.005818 -351.275945) (xy 121.055422 -351.25329) (xy 121.107745 -351.237925) (xy 121.161722 -351.230163)
			(xy 121.188988 -351.229676) (xy 122.052588 -351.229676) (xy 122.079862 -351.230063) (xy 122.133856 -351.237824)
			(xy 122.186195 -351.253191) (xy 122.235815 -351.27585) (xy 122.281704 -351.30534) (xy 122.32293 -351.341061)
			(xy 122.358652 -351.382286) (xy 122.388144 -351.428175) (xy 122.410805 -351.477794) (xy 122.426173 -351.530132)
			(xy 122.433936 -351.584126) (xy 122.433936 -351.63867) (xy 123.91664 -351.63867) (xy 123.91664 -351.58413)
			(xy 123.924402 -351.530144) (xy 123.939769 -351.477812) (xy 123.962428 -351.428201) (xy 123.991917 -351.38232)
			(xy 124.027636 -351.341102) (xy 124.068858 -351.305388) (xy 124.114743 -351.275905) (xy 124.164358 -351.253253)
			(xy 124.216691 -351.237892) (xy 124.270677 -351.230136) (xy 124.297948 -351.229676) (xy 125.161548 -351.229676)
			(xy 125.188818 -351.23009) (xy 125.242802 -351.237858) (xy 125.295131 -351.253229) (xy 125.34474 -351.27589)
			(xy 125.390619 -351.30538) (xy 125.431835 -351.341099) (xy 125.467549 -351.382319) (xy 125.497033 -351.428203)
			(xy 125.519688 -351.477814) (xy 125.535052 -351.530145) (xy 125.542814 -351.58413) (xy 125.542814 -351.638669)
			(xy 127.025639 -351.638669) (xy 127.025639 -351.584131) (xy 127.033401 -351.530149) (xy 127.048766 -351.477821)
			(xy 127.071422 -351.428212) (xy 127.100907 -351.382333) (xy 127.136622 -351.341117) (xy 127.177839 -351.305403)
			(xy 127.223719 -351.275918) (xy 127.273329 -351.253263) (xy 127.325657 -351.237899) (xy 127.379639 -351.230139)
			(xy 127.406908 -351.229676) (xy 128.270508 -351.229676) (xy 128.29778 -351.230087) (xy 128.351768 -351.23785)
			(xy 128.404102 -351.253218) (xy 128.453716 -351.275877) (xy 128.4996 -351.305366) (xy 128.540821 -351.341085)
			(xy 128.576539 -351.382306) (xy 128.606027 -351.428191) (xy 128.628685 -351.477806) (xy 128.644051 -351.53014)
			(xy 128.651814 -351.584128) (xy 128.651814 -351.638665) (xy 130.134662 -351.638665) (xy 130.134662 -351.584135)
			(xy 130.142422 -351.530159) (xy 130.157784 -351.477838) (xy 130.180436 -351.428234) (xy 130.209916 -351.38236)
			(xy 130.245624 -351.341147) (xy 130.286834 -351.305435) (xy 130.332706 -351.275951) (xy 130.382308 -351.253296)
			(xy 130.434628 -351.237929) (xy 130.488603 -351.230165) (xy 130.515868 -351.229676) (xy 131.379468 -351.229676)
			(xy 131.406743 -351.230061) (xy 131.460739 -351.237821) (xy 131.513081 -351.253186) (xy 131.562703 -351.275844)
			(xy 131.608595 -351.305333) (xy 131.649823 -351.341054) (xy 131.685547 -351.382279) (xy 131.715041 -351.428169)
			(xy 131.737703 -351.477789) (xy 131.753073 -351.53013) (xy 131.760836 -351.584125) (xy 131.760836 -351.63867)
			(xy 133.243539 -351.63867) (xy 133.243539 -351.58413) (xy 133.251302 -351.530146) (xy 133.266668 -351.477817)
			(xy 133.289325 -351.428207) (xy 133.318812 -351.382326) (xy 133.354529 -351.341109) (xy 133.395749 -351.305396)
			(xy 133.441631 -351.275912) (xy 133.491243 -351.253258) (xy 133.543574 -351.237896) (xy 133.597558 -351.230137)
			(xy 133.624828 -351.229676) (xy 134.488428 -351.229676) (xy 134.515699 -351.230088) (xy 134.569685 -351.237854)
			(xy 134.622016 -351.253223) (xy 134.671628 -351.275883) (xy 134.71751 -351.305373) (xy 134.758728 -351.341092)
			(xy 134.794444 -351.382313) (xy 134.82393 -351.428197) (xy 134.846586 -351.47781) (xy 134.861952 -351.530143)
			(xy 134.869714 -351.584129) (xy 134.869714 -351.638666) (xy 136.352562 -351.638666) (xy 136.352562 -351.584134)
			(xy 136.360323 -351.530157) (xy 136.375686 -351.477833) (xy 136.398339 -351.428229) (xy 136.427821 -351.382353)
			(xy 136.463531 -351.34114) (xy 136.504743 -351.305428) (xy 136.550618 -351.275945) (xy 136.600222 -351.25329)
			(xy 136.652545 -351.237925) (xy 136.706522 -351.230163) (xy 136.733788 -351.229676) (xy 137.597388 -351.229676)
			(xy 137.624662 -351.230063) (xy 137.678656 -351.237824) (xy 137.730995 -351.253191) (xy 137.780615 -351.27585)
			(xy 137.826504 -351.30534) (xy 137.86773 -351.341061) (xy 137.903452 -351.382286) (xy 137.932944 -351.428175)
			(xy 137.955605 -351.477794) (xy 137.970973 -351.530132) (xy 137.978736 -351.584126) (xy 137.978736 -351.63867)
			(xy 139.46144 -351.63867) (xy 139.46144 -351.58413) (xy 139.469202 -351.530144) (xy 139.484569 -351.477812)
			(xy 139.507228 -351.428201) (xy 139.536717 -351.38232) (xy 139.572436 -351.341102) (xy 139.613658 -351.305388)
			(xy 139.659543 -351.275905) (xy 139.709158 -351.253253) (xy 139.761491 -351.237892) (xy 139.815477 -351.230136)
			(xy 139.842748 -351.229676) (xy 140.706348 -351.229676) (xy 140.733618 -351.23009) (xy 140.787602 -351.237858)
			(xy 140.839931 -351.253229) (xy 140.88954 -351.27589) (xy 140.935419 -351.30538) (xy 140.976635 -351.341099)
			(xy 141.012349 -351.382319) (xy 141.041833 -351.428203) (xy 141.064488 -351.477814) (xy 141.079852 -351.530145)
			(xy 141.087614 -351.58413) (xy 141.087614 -351.638669) (xy 142.570439 -351.638669) (xy 142.570439 -351.584131)
			(xy 142.578201 -351.530149) (xy 142.593566 -351.477821) (xy 142.616222 -351.428212) (xy 142.645707 -351.382333)
			(xy 142.681422 -351.341117) (xy 142.722639 -351.305403) (xy 142.768519 -351.275918) (xy 142.818129 -351.253263)
			(xy 142.870457 -351.237899) (xy 142.924439 -351.230139) (xy 142.951708 -351.229676) (xy 143.815308 -351.229676)
			(xy 143.84258 -351.230087) (xy 143.896568 -351.23785) (xy 143.948902 -351.253218) (xy 143.998516 -351.275877)
			(xy 144.0444 -351.305366) (xy 144.085621 -351.341085) (xy 144.121339 -351.382306) (xy 144.150827 -351.428191)
			(xy 144.173485 -351.477806) (xy 144.188851 -351.53014) (xy 144.196614 -351.584128) (xy 144.196614 -351.638669)
			(xy 161.804839 -351.638669) (xy 161.804839 -351.584131) (xy 161.812601 -351.530149) (xy 161.827966 -351.47782)
			(xy 161.850623 -351.428211) (xy 161.880108 -351.382331) (xy 161.915824 -351.341115) (xy 161.957041 -351.305401)
			(xy 162.002922 -351.275917) (xy 162.052531 -351.253262) (xy 162.10486 -351.237899) (xy 162.158843 -351.230139)
			(xy 162.186112 -351.229676) (xy 163.049712 -351.229676) (xy 163.076984 -351.230087) (xy 163.130971 -351.237851)
			(xy 163.183304 -351.253219) (xy 163.232918 -351.275878) (xy 163.278802 -351.305367) (xy 163.320022 -351.341086)
			(xy 163.35574 -351.382308) (xy 163.385228 -351.428192) (xy 163.407885 -351.477807) (xy 163.423251 -351.530141)
			(xy 163.431014 -351.584128) (xy 163.431014 -351.638665) (xy 164.913862 -351.638665) (xy 164.913862 -351.584135)
			(xy 164.921622 -351.530159) (xy 164.936985 -351.477837) (xy 164.959637 -351.428233) (xy 164.989117 -351.382358)
			(xy 165.024826 -351.341146) (xy 165.066036 -351.305434) (xy 165.111909 -351.27595) (xy 165.16151 -351.253295)
			(xy 165.213831 -351.237928) (xy 165.267807 -351.230164) (xy 165.295072 -351.229676) (xy 166.158672 -351.229676)
			(xy 166.185947 -351.230062) (xy 166.239942 -351.237821) (xy 166.292284 -351.253187) (xy 166.341905 -351.275845)
			(xy 166.387797 -351.305335) (xy 166.429024 -351.341056) (xy 166.464748 -351.382281) (xy 166.494242 -351.42817)
			(xy 166.516903 -351.47779) (xy 166.532273 -351.53013) (xy 166.540036 -351.584125) (xy 166.540036 -351.63867)
			(xy 168.022739 -351.63867) (xy 168.022739 -351.58413) (xy 168.030502 -351.530146) (xy 168.045868 -351.477816)
			(xy 168.068526 -351.428206) (xy 168.098013 -351.382325) (xy 168.133731 -351.341108) (xy 168.174951 -351.305394)
			(xy 168.220834 -351.27591) (xy 168.270446 -351.253257) (xy 168.322777 -351.237895) (xy 168.376762 -351.230137)
			(xy 168.404032 -351.229676) (xy 169.267632 -351.229676) (xy 169.294903 -351.230089) (xy 169.348888 -351.237855)
			(xy 169.401219 -351.253224) (xy 169.45083 -351.275885) (xy 169.496712 -351.305374) (xy 169.537929 -351.341093)
			(xy 169.573645 -351.382314) (xy 169.603131 -351.428198) (xy 169.625787 -351.477811) (xy 169.641152 -351.530143)
			(xy 169.648914 -351.584129) (xy 169.648914 -351.638666) (xy 171.131762 -351.638666) (xy 171.131762 -351.584134)
			(xy 171.139523 -351.530156) (xy 171.154886 -351.477832) (xy 171.17754 -351.428228) (xy 171.207022 -351.382352)
			(xy 171.242733 -351.341138) (xy 171.283945 -351.305427) (xy 171.329821 -351.275944) (xy 171.379425 -351.253289)
			(xy 171.431748 -351.237925) (xy 171.485726 -351.230163) (xy 171.512992 -351.229676) (xy 172.376592 -351.229676)
			(xy 172.403866 -351.230063) (xy 172.457859 -351.237825) (xy 172.510198 -351.253192) (xy 172.559817 -351.275851)
			(xy 172.605706 -351.305342) (xy 172.646932 -351.341063) (xy 172.682653 -351.382287) (xy 172.712145 -351.428176)
			(xy 172.734805 -351.477794) (xy 172.750173 -351.530133) (xy 172.757936 -351.584126) (xy 172.757936 -351.638664)
			(xy 174.240762 -351.638664) (xy 174.240762 -351.584136) (xy 174.248522 -351.530162) (xy 174.263883 -351.477841)
			(xy 174.286534 -351.428239) (xy 174.316012 -351.382365) (xy 174.351719 -351.341153) (xy 174.392926 -351.305441)
			(xy 174.438797 -351.275957) (xy 174.488396 -351.2533) (xy 174.540715 -351.237932) (xy 174.594688 -351.230166)
			(xy 174.621952 -351.229676) (xy 175.485552 -351.229676) (xy 175.512828 -351.23006) (xy 175.566825 -351.237818)
			(xy 175.619169 -351.253181) (xy 175.668793 -351.275838) (xy 175.714687 -351.305328) (xy 175.755917 -351.341049)
			(xy 175.791644 -351.382274) (xy 175.821139 -351.428165) (xy 175.843802 -351.477786) (xy 175.859172 -351.530128)
			(xy 175.866936 -351.584124) (xy 175.866936 -351.638669) (xy 177.349639 -351.638669) (xy 177.349639 -351.584131)
			(xy 177.357401 -351.530149) (xy 177.372766 -351.47782) (xy 177.395423 -351.428211) (xy 177.424908 -351.382331)
			(xy 177.460624 -351.341115) (xy 177.501841 -351.305401) (xy 177.547722 -351.275917) (xy 177.597331 -351.253262)
			(xy 177.64966 -351.237899) (xy 177.703643 -351.230139) (xy 177.730912 -351.229676) (xy 178.594512 -351.229676)
			(xy 178.621784 -351.230087) (xy 178.675771 -351.237851) (xy 178.728104 -351.253219) (xy 178.777718 -351.275878)
			(xy 178.823602 -351.305367) (xy 178.864822 -351.341086) (xy 178.90054 -351.382308) (xy 178.930028 -351.428192)
			(xy 178.952685 -351.477807) (xy 178.968051 -351.530141) (xy 178.975814 -351.584128) (xy 178.975814 -351.638665)
			(xy 180.458662 -351.638665) (xy 180.458662 -351.584135) (xy 180.466422 -351.530159) (xy 180.481785 -351.477837)
			(xy 180.504437 -351.428233) (xy 180.533917 -351.382358) (xy 180.569626 -351.341146) (xy 180.610836 -351.305434)
			(xy 180.656709 -351.27595) (xy 180.70631 -351.253295) (xy 180.758631 -351.237928) (xy 180.812607 -351.230164)
			(xy 180.839872 -351.229676) (xy 181.703472 -351.229676) (xy 181.730747 -351.230062) (xy 181.784742 -351.237821)
			(xy 181.837084 -351.253187) (xy 181.886705 -351.275845) (xy 181.932597 -351.305335) (xy 181.973824 -351.341056)
			(xy 182.009548 -351.382281) (xy 182.039042 -351.42817) (xy 182.061703 -351.47779) (xy 182.077073 -351.53013)
			(xy 182.084836 -351.584125) (xy 182.084836 -351.63867) (xy 183.567539 -351.63867) (xy 183.567539 -351.58413)
			(xy 183.575302 -351.530146) (xy 183.590668 -351.477816) (xy 183.613326 -351.428206) (xy 183.642813 -351.382325)
			(xy 183.678531 -351.341108) (xy 183.719751 -351.305394) (xy 183.765634 -351.27591) (xy 183.815246 -351.253257)
			(xy 183.867577 -351.237895) (xy 183.921562 -351.230137) (xy 183.948832 -351.229676) (xy 184.812432 -351.229676)
			(xy 184.839703 -351.230089) (xy 184.893688 -351.237855) (xy 184.946019 -351.253224) (xy 184.99563 -351.275885)
			(xy 185.041512 -351.305374) (xy 185.082729 -351.341093) (xy 185.118445 -351.382314) (xy 185.147931 -351.428198)
			(xy 185.170587 -351.477811) (xy 185.185952 -351.530143) (xy 185.193714 -351.584129) (xy 185.193714 -351.638666)
			(xy 186.676562 -351.638666) (xy 186.676562 -351.584134) (xy 186.684323 -351.530156) (xy 186.699686 -351.477832)
			(xy 186.72234 -351.428228) (xy 186.751822 -351.382352) (xy 186.787533 -351.341138) (xy 186.828745 -351.305427)
			(xy 186.874621 -351.275944) (xy 186.924225 -351.253289) (xy 186.976548 -351.237925) (xy 187.030526 -351.230163)
			(xy 187.057792 -351.229676) (xy 187.921392 -351.229676) (xy 187.948666 -351.230063) (xy 188.002659 -351.237825)
			(xy 188.054998 -351.253192) (xy 188.104617 -351.275851) (xy 188.150506 -351.305342) (xy 188.191732 -351.341063)
			(xy 188.227453 -351.382287) (xy 188.256945 -351.428176) (xy 188.279605 -351.477794) (xy 188.294973 -351.530133)
			(xy 188.302736 -351.584126) (xy 188.302736 -351.638664) (xy 189.785562 -351.638664) (xy 189.785562 -351.584136)
			(xy 189.793322 -351.530162) (xy 189.808683 -351.477841) (xy 189.831334 -351.428239) (xy 189.860812 -351.382365)
			(xy 189.896519 -351.341153) (xy 189.937726 -351.305441) (xy 189.983597 -351.275957) (xy 190.033196 -351.2533)
			(xy 190.085515 -351.237932) (xy 190.139488 -351.230166) (xy 190.166752 -351.229676) (xy 191.030352 -351.229676)
			(xy 191.057628 -351.23006) (xy 191.111625 -351.237818) (xy 191.163969 -351.253181) (xy 191.213593 -351.275838)
			(xy 191.259487 -351.305328) (xy 191.300717 -351.341049) (xy 191.336444 -351.382274) (xy 191.365939 -351.428165)
			(xy 191.388602 -351.477786) (xy 191.403972 -351.530128) (xy 191.411736 -351.584124) (xy 191.411736 -351.638669)
			(xy 192.894439 -351.638669) (xy 192.894439 -351.584131) (xy 192.902201 -351.530149) (xy 192.917566 -351.47782)
			(xy 192.940223 -351.428211) (xy 192.969708 -351.382331) (xy 193.005424 -351.341115) (xy 193.046641 -351.305401)
			(xy 193.092522 -351.275917) (xy 193.142131 -351.253262) (xy 193.19446 -351.237899) (xy 193.248443 -351.230139)
			(xy 193.275712 -351.229676) (xy 194.139312 -351.229676) (xy 194.166584 -351.230087) (xy 194.220571 -351.237851)
			(xy 194.272904 -351.253219) (xy 194.322518 -351.275878) (xy 194.368402 -351.305367) (xy 194.409622 -351.341086)
			(xy 194.44534 -351.382308) (xy 194.474828 -351.428192) (xy 194.497485 -351.477807) (xy 194.512851 -351.530141)
			(xy 194.520614 -351.584128) (xy 194.520614 -351.638668) (xy 267.515839 -351.638668) (xy 267.515839 -351.584132)
			(xy 267.523601 -351.53015) (xy 267.538966 -351.477822) (xy 267.561621 -351.428214) (xy 267.591106 -351.382335)
			(xy 267.62682 -351.341119) (xy 267.668036 -351.305405) (xy 267.713916 -351.27592) (xy 267.763524 -351.253265)
			(xy 267.815852 -351.2379) (xy 267.869834 -351.230139) (xy 267.897102 -351.229676) (xy 268.760702 -351.229676)
			(xy 268.787974 -351.230087) (xy 268.841963 -351.237849) (xy 268.894297 -351.253216) (xy 268.943912 -351.275875)
			(xy 268.989797 -351.305364) (xy 269.031019 -351.341083) (xy 269.066737 -351.382304) (xy 269.096226 -351.42819)
			(xy 269.118884 -351.477805) (xy 269.134251 -351.530139) (xy 269.142013 -351.584128) (xy 269.142013 -351.638665)
			(xy 270.624862 -351.638665) (xy 270.624862 -351.584135) (xy 270.632622 -351.53016) (xy 270.647984 -351.477839)
			(xy 270.670635 -351.428236) (xy 270.700115 -351.382362) (xy 270.735822 -351.341149) (xy 270.777031 -351.305437)
			(xy 270.822903 -351.275953) (xy 270.872503 -351.253297) (xy 270.924823 -351.23793) (xy 270.978797 -351.230165)
			(xy 271.006062 -351.229676) (xy 271.869662 -351.229676) (xy 271.896937 -351.230061) (xy 271.950934 -351.23782)
			(xy 272.003276 -351.253184) (xy 272.052899 -351.275842) (xy 272.098792 -351.305331) (xy 272.140021 -351.341052)
			(xy 272.175746 -351.382277) (xy 272.20524 -351.428167) (xy 272.227903 -351.477788) (xy 272.243272 -351.530129)
			(xy 272.251036 -351.584125) (xy 272.251036 -351.638669) (xy 273.733739 -351.638669) (xy 273.733739 -351.584131)
			(xy 273.741501 -351.530147) (xy 273.756867 -351.477818) (xy 273.779524 -351.428208) (xy 273.809011 -351.382328)
			(xy 273.844727 -351.341112) (xy 273.885946 -351.305398) (xy 273.931828 -351.275914) (xy 273.981439 -351.25326)
			(xy 274.033769 -351.237897) (xy 274.087753 -351.230138) (xy 274.115022 -351.229676) (xy 274.978622 -351.229676)
			(xy 275.005893 -351.230088) (xy 275.05988 -351.237853) (xy 275.112212 -351.253222) (xy 275.161824 -351.275881)
			(xy 275.207707 -351.305371) (xy 275.248926 -351.34109) (xy 275.284642 -351.382311) (xy 275.314129 -351.428195)
			(xy 275.336786 -351.477809) (xy 275.352152 -351.530142) (xy 275.359914 -351.584129) (xy 275.359914 -351.638666)
			(xy 276.842762 -351.638666) (xy 276.842762 -351.584134) (xy 276.850523 -351.530158) (xy 276.865886 -351.477835)
			(xy 276.888538 -351.428231) (xy 276.91802 -351.382355) (xy 276.953729 -351.341142) (xy 276.994941 -351.30543)
			(xy 277.040815 -351.275947) (xy 277.090418 -351.253292) (xy 277.14274 -351.237927) (xy 277.196716 -351.230164)
			(xy 277.223982 -351.229676) (xy 278.087582 -351.229676) (xy 278.114857 -351.230062) (xy 278.168851 -351.237823)
			(xy 278.221191 -351.253189) (xy 278.270811 -351.275848) (xy 278.316702 -351.305338) (xy 278.357928 -351.341059)
			(xy 278.393651 -351.382284) (xy 278.423143 -351.428173) (xy 278.445804 -351.477792) (xy 278.461173 -351.530132)
			(xy 278.468936 -351.584125) (xy 278.468936 -351.63867) (xy 279.95164 -351.63867) (xy 279.95164 -351.58413)
			(xy 279.959402 -351.530145) (xy 279.974769 -351.477814) (xy 279.997427 -351.428203) (xy 280.026916 -351.382322)
			(xy 280.062634 -351.341105) (xy 280.103855 -351.305391) (xy 280.14974 -351.275907) (xy 280.199353 -351.253254)
			(xy 280.251686 -351.237893) (xy 280.305672 -351.230137) (xy 280.332942 -351.229676) (xy 281.196542 -351.229676)
			(xy 281.223812 -351.230089) (xy 281.277797 -351.237857) (xy 281.330126 -351.253227) (xy 281.379736 -351.275888)
			(xy 281.425616 -351.305378) (xy 281.466833 -351.341097) (xy 281.502547 -351.382317) (xy 281.532032 -351.428201)
			(xy 281.554688 -351.477813) (xy 281.570052 -351.530145) (xy 281.577814 -351.58413) (xy 281.577814 -351.638668)
			(xy 283.060639 -351.638668) (xy 283.060639 -351.584132) (xy 283.068401 -351.53015) (xy 283.083766 -351.477822)
			(xy 283.106421 -351.428214) (xy 283.135906 -351.382335) (xy 283.17162 -351.341119) (xy 283.212836 -351.305405)
			(xy 283.258716 -351.27592) (xy 283.308324 -351.253265) (xy 283.360652 -351.2379) (xy 283.414634 -351.230139)
			(xy 283.441902 -351.229676) (xy 284.305502 -351.229676) (xy 284.332774 -351.230087) (xy 284.386763 -351.237849)
			(xy 284.439097 -351.253216) (xy 284.488712 -351.275875) (xy 284.534597 -351.305364) (xy 284.575819 -351.341083)
			(xy 284.611537 -351.382304) (xy 284.641026 -351.42819) (xy 284.663684 -351.477805) (xy 284.679051 -351.530139)
			(xy 284.686813 -351.584128) (xy 284.686813 -351.638665) (xy 286.169662 -351.638665) (xy 286.169662 -351.584135)
			(xy 286.177422 -351.53016) (xy 286.192784 -351.477839) (xy 286.215435 -351.428236) (xy 286.244915 -351.382362)
			(xy 286.280622 -351.341149) (xy 286.321831 -351.305437) (xy 286.367703 -351.275953) (xy 286.417303 -351.253297)
			(xy 286.469623 -351.23793) (xy 286.523597 -351.230165) (xy 286.550862 -351.229676) (xy 287.414462 -351.229676)
			(xy 287.441737 -351.230061) (xy 287.495734 -351.23782) (xy 287.548076 -351.253184) (xy 287.597699 -351.275842)
			(xy 287.643592 -351.305331) (xy 287.684821 -351.341052) (xy 287.720546 -351.382277) (xy 287.75004 -351.428167)
			(xy 287.772703 -351.477788) (xy 287.788072 -351.530129) (xy 287.795836 -351.584125) (xy 287.795836 -351.638669)
			(xy 289.278539 -351.638669) (xy 289.278539 -351.584131) (xy 289.286301 -351.530147) (xy 289.301667 -351.477818)
			(xy 289.324324 -351.428208) (xy 289.353811 -351.382328) (xy 289.389527 -351.341112) (xy 289.430746 -351.305398)
			(xy 289.476628 -351.275914) (xy 289.526239 -351.25326) (xy 289.578569 -351.237897) (xy 289.632553 -351.230138)
			(xy 289.659822 -351.229676) (xy 290.523422 -351.229676) (xy 290.550693 -351.230088) (xy 290.60468 -351.237853)
			(xy 290.657012 -351.253222) (xy 290.706624 -351.275881) (xy 290.752507 -351.305371) (xy 290.793726 -351.34109)
			(xy 290.829442 -351.382311) (xy 290.858929 -351.428195) (xy 290.881586 -351.477809) (xy 290.896952 -351.530142)
			(xy 290.904714 -351.584129) (xy 290.904714 -351.638666) (xy 292.387562 -351.638666) (xy 292.387562 -351.584134)
			(xy 292.395323 -351.530158) (xy 292.410686 -351.477835) (xy 292.433338 -351.428231) (xy 292.46282 -351.382355)
			(xy 292.498529 -351.341142) (xy 292.539741 -351.30543) (xy 292.585615 -351.275947) (xy 292.635218 -351.253292)
			(xy 292.68754 -351.237927) (xy 292.741516 -351.230164) (xy 292.768782 -351.229676) (xy 293.632382 -351.229676)
			(xy 293.659657 -351.230062) (xy 293.713651 -351.237823) (xy 293.765991 -351.253189) (xy 293.815611 -351.275848)
			(xy 293.861502 -351.305338) (xy 293.902728 -351.341059) (xy 293.938451 -351.382284) (xy 293.967943 -351.428173)
			(xy 293.990604 -351.477792) (xy 294.005973 -351.530132) (xy 294.013736 -351.584125) (xy 294.013736 -351.63867)
			(xy 295.49644 -351.63867) (xy 295.49644 -351.58413) (xy 295.504202 -351.530145) (xy 295.519569 -351.477814)
			(xy 295.542227 -351.428203) (xy 295.571716 -351.382322) (xy 295.607434 -351.341105) (xy 295.648655 -351.305391)
			(xy 295.69454 -351.275907) (xy 295.744153 -351.253254) (xy 295.796486 -351.237893) (xy 295.850472 -351.230137)
			(xy 295.877742 -351.229676) (xy 296.741342 -351.229676) (xy 296.768612 -351.230089) (xy 296.822597 -351.237857)
			(xy 296.874926 -351.253227) (xy 296.924536 -351.275888) (xy 296.970416 -351.305378) (xy 297.011633 -351.341097)
			(xy 297.047347 -351.382317) (xy 297.076832 -351.428201) (xy 297.099488 -351.477813) (xy 297.114852 -351.530145)
			(xy 297.122614 -351.58413) (xy 297.122614 -351.638668) (xy 298.605439 -351.638668) (xy 298.605439 -351.584132)
			(xy 298.613201 -351.53015) (xy 298.628566 -351.477822) (xy 298.651221 -351.428214) (xy 298.680706 -351.382335)
			(xy 298.71642 -351.341119) (xy 298.757636 -351.305405) (xy 298.803516 -351.27592) (xy 298.853124 -351.253265)
			(xy 298.905452 -351.2379) (xy 298.959434 -351.230139) (xy 298.986702 -351.229676) (xy 299.850302 -351.229676)
			(xy 299.877574 -351.230087) (xy 299.931563 -351.237849) (xy 299.983897 -351.253216) (xy 300.033512 -351.275875)
			(xy 300.079397 -351.305364) (xy 300.120619 -351.341083) (xy 300.156337 -351.382304) (xy 300.185826 -351.42819)
			(xy 300.208484 -351.477805) (xy 300.223851 -351.530139) (xy 300.231613 -351.584128) (xy 300.231613 -351.638668)
			(xy 312.121539 -351.638668) (xy 312.121539 -351.584132) (xy 312.129301 -351.53015) (xy 312.144666 -351.477822)
			(xy 312.167321 -351.428213) (xy 312.196807 -351.382334) (xy 312.232521 -351.341118) (xy 312.273737 -351.305404)
			(xy 312.319617 -351.27592) (xy 312.369226 -351.253264) (xy 312.421554 -351.2379) (xy 312.475536 -351.230139)
			(xy 312.502804 -351.229676) (xy 313.366404 -351.229676) (xy 313.393676 -351.230087) (xy 313.447664 -351.23785)
			(xy 313.499999 -351.253217) (xy 313.549613 -351.275876) (xy 313.595498 -351.305365) (xy 313.63672 -351.341083)
			(xy 313.672438 -351.382305) (xy 313.701926 -351.42819) (xy 313.724584 -351.477805) (xy 313.739951 -351.530139)
			(xy 313.747713 -351.584128) (xy 313.747713 -351.638665) (xy 315.230562 -351.638665) (xy 315.230562 -351.584135)
			(xy 315.238322 -351.53016) (xy 315.253684 -351.477838) (xy 315.276335 -351.428236) (xy 315.305815 -351.382361)
			(xy 315.341523 -351.341148) (xy 315.382732 -351.305437) (xy 315.428604 -351.275953) (xy 315.478205 -351.253297)
			(xy 315.530525 -351.23793) (xy 315.584499 -351.230165) (xy 315.611764 -351.229676) (xy 316.475364 -351.229676)
			(xy 316.502639 -351.230061) (xy 316.556636 -351.23782) (xy 316.608978 -351.253185) (xy 316.6586 -351.275842)
			(xy 316.704493 -351.305332) (xy 316.745722 -351.341053) (xy 316.781446 -351.382278) (xy 316.81094 -351.428168)
			(xy 316.833603 -351.477788) (xy 316.848972 -351.530129) (xy 316.856736 -351.584125) (xy 316.856736 -351.638669)
			(xy 318.339439 -351.638669) (xy 318.339439 -351.584131) (xy 318.347201 -351.530147) (xy 318.362567 -351.477818)
			(xy 318.385224 -351.428208) (xy 318.414711 -351.382328) (xy 318.450428 -351.341111) (xy 318.491647 -351.305397)
			(xy 318.537529 -351.275913) (xy 318.58714 -351.253259) (xy 318.63947 -351.237896) (xy 318.693455 -351.230138)
			(xy 318.720724 -351.229676) (xy 319.584324 -351.229676) (xy 319.611595 -351.230088) (xy 319.665581 -351.237853)
			(xy 319.717913 -351.253222) (xy 319.767525 -351.275882) (xy 319.813408 -351.305372) (xy 319.854627 -351.34109)
			(xy 319.890343 -351.382312) (xy 319.919829 -351.428196) (xy 319.942486 -351.477809) (xy 319.957852 -351.530142)
			(xy 319.965614 -351.584129) (xy 319.965614 -351.638666) (xy 321.448462 -351.638666) (xy 321.448462 -351.584134)
			(xy 321.456223 -351.530157) (xy 321.471586 -351.477834) (xy 321.494239 -351.42823) (xy 321.52372 -351.382354)
			(xy 321.55943 -351.341141) (xy 321.600642 -351.30543) (xy 321.646516 -351.275946) (xy 321.696119 -351.253291)
			(xy 321.748442 -351.237926) (xy 321.802418 -351.230163) (xy 321.829684 -351.229676) (xy 322.693284 -351.229676)
			(xy 322.720558 -351.230062) (xy 322.774552 -351.237824) (xy 322.826892 -351.25319) (xy 322.876512 -351.275849)
			(xy 322.922403 -351.305339) (xy 322.963629 -351.34106) (xy 322.999351 -351.382285) (xy 323.028843 -351.428174)
			(xy 323.051504 -351.477793) (xy 323.066873 -351.530132) (xy 323.074636 -351.584126) (xy 323.074636 -351.63867)
			(xy 324.55734 -351.63867) (xy 324.55734 -351.58413) (xy 324.565102 -351.530144) (xy 324.580469 -351.477813)
			(xy 324.603128 -351.428202) (xy 324.632616 -351.382321) (xy 324.668335 -351.341104) (xy 324.709556 -351.30539)
			(xy 324.755441 -351.275906) (xy 324.805055 -351.253254) (xy 324.857387 -351.237893) (xy 324.911374 -351.230136)
			(xy 324.938644 -351.229676) (xy 325.802244 -351.229676) (xy 325.829514 -351.23009) (xy 325.883498 -351.237857)
			(xy 325.935828 -351.253228) (xy 325.985437 -351.275889) (xy 326.031317 -351.305379) (xy 326.072534 -351.341097)
			(xy 326.108248 -351.382318) (xy 326.137732 -351.428201) (xy 326.160388 -351.477814) (xy 326.175752 -351.530145)
			(xy 326.183514 -351.58413) (xy 326.183514 -351.638668) (xy 327.666339 -351.638668) (xy 327.666339 -351.584132)
			(xy 327.674101 -351.53015) (xy 327.689466 -351.477822) (xy 327.712121 -351.428213) (xy 327.741607 -351.382334)
			(xy 327.777321 -351.341118) (xy 327.818537 -351.305404) (xy 327.864417 -351.27592) (xy 327.914026 -351.253264)
			(xy 327.966354 -351.2379) (xy 328.020336 -351.230139) (xy 328.047604 -351.229676) (xy 328.911204 -351.229676)
			(xy 328.938476 -351.230087) (xy 328.992464 -351.23785) (xy 329.044799 -351.253217) (xy 329.094413 -351.275876)
			(xy 329.140298 -351.305365) (xy 329.18152 -351.341083) (xy 329.217238 -351.382305) (xy 329.246726 -351.42819)
			(xy 329.269384 -351.477805) (xy 329.284751 -351.530139) (xy 329.292513 -351.584128) (xy 329.292513 -351.638665)
			(xy 330.775362 -351.638665) (xy 330.775362 -351.584135) (xy 330.783122 -351.53016) (xy 330.798484 -351.477838)
			(xy 330.821135 -351.428236) (xy 330.850615 -351.382361) (xy 330.886323 -351.341148) (xy 330.927532 -351.305437)
			(xy 330.973404 -351.275953) (xy 331.023005 -351.253297) (xy 331.075325 -351.23793) (xy 331.129299 -351.230165)
			(xy 331.156564 -351.229676) (xy 332.020164 -351.229676) (xy 332.047439 -351.230061) (xy 332.101436 -351.23782)
			(xy 332.153778 -351.253185) (xy 332.2034 -351.275842) (xy 332.249293 -351.305332) (xy 332.290522 -351.341053)
			(xy 332.326246 -351.382278) (xy 332.35574 -351.428168) (xy 332.378403 -351.477788) (xy 332.393772 -351.530129)
			(xy 332.401536 -351.584125) (xy 332.401536 -351.638669) (xy 333.884239 -351.638669) (xy 333.884239 -351.584131)
			(xy 333.892001 -351.530147) (xy 333.907367 -351.477818) (xy 333.930024 -351.428208) (xy 333.959511 -351.382328)
			(xy 333.995228 -351.341111) (xy 334.036447 -351.305397) (xy 334.082329 -351.275913) (xy 334.13194 -351.253259)
			(xy 334.18427 -351.237896) (xy 334.238255 -351.230138) (xy 334.265524 -351.229676) (xy 335.129124 -351.229676)
			(xy 335.156395 -351.230088) (xy 335.210381 -351.237853) (xy 335.262713 -351.253222) (xy 335.312325 -351.275882)
			(xy 335.358208 -351.305372) (xy 335.399427 -351.34109) (xy 335.435143 -351.382312) (xy 335.464629 -351.428196)
			(xy 335.487286 -351.477809) (xy 335.502652 -351.530142) (xy 335.510414 -351.584129) (xy 335.510414 -351.638666)
			(xy 336.993262 -351.638666) (xy 336.993262 -351.584134) (xy 337.001023 -351.530157) (xy 337.016386 -351.477834)
			(xy 337.039039 -351.42823) (xy 337.06852 -351.382354) (xy 337.10423 -351.341141) (xy 337.145442 -351.30543)
			(xy 337.191316 -351.275946) (xy 337.240919 -351.253291) (xy 337.293242 -351.237926) (xy 337.347218 -351.230163)
			(xy 337.374484 -351.229676) (xy 338.238084 -351.229676) (xy 338.265358 -351.230062) (xy 338.319352 -351.237824)
			(xy 338.371692 -351.25319) (xy 338.421312 -351.275849) (xy 338.467203 -351.305339) (xy 338.508429 -351.34106)
			(xy 338.544151 -351.382285) (xy 338.573643 -351.428174) (xy 338.596304 -351.477793) (xy 338.611673 -351.530132)
			(xy 338.619436 -351.584126) (xy 338.619436 -351.63867) (xy 340.10214 -351.63867) (xy 340.10214 -351.58413)
			(xy 340.109902 -351.530144) (xy 340.125269 -351.477813) (xy 340.147928 -351.428202) (xy 340.177416 -351.382321)
			(xy 340.213135 -351.341104) (xy 340.254356 -351.30539) (xy 340.300241 -351.275906) (xy 340.349855 -351.253254)
			(xy 340.402187 -351.237893) (xy 340.456174 -351.230136) (xy 340.483444 -351.229676) (xy 341.347044 -351.229676)
			(xy 341.374314 -351.23009) (xy 341.428298 -351.237857) (xy 341.480628 -351.253228) (xy 341.530237 -351.275889)
			(xy 341.576117 -351.305379) (xy 341.617334 -351.341097) (xy 341.653048 -351.382318) (xy 341.682532 -351.428201)
			(xy 341.705188 -351.477814) (xy 341.720552 -351.530145) (xy 341.728314 -351.58413) (xy 341.728314 -351.638668)
			(xy 343.211139 -351.638668) (xy 343.211139 -351.584132) (xy 343.218901 -351.53015) (xy 343.234266 -351.477822)
			(xy 343.256921 -351.428213) (xy 343.286407 -351.382334) (xy 343.322121 -351.341118) (xy 343.363337 -351.305404)
			(xy 343.409217 -351.27592) (xy 343.458826 -351.253264) (xy 343.511154 -351.2379) (xy 343.565136 -351.230139)
			(xy 343.592404 -351.229676) (xy 344.456004 -351.229676) (xy 344.483276 -351.230087) (xy 344.537264 -351.23785)
			(xy 344.589599 -351.253217) (xy 344.639213 -351.275876) (xy 344.685098 -351.305365) (xy 344.72632 -351.341083)
			(xy 344.762038 -351.382305) (xy 344.791526 -351.42819) (xy 344.814184 -351.477805) (xy 344.829551 -351.530139)
			(xy 344.837313 -351.584128) (xy 344.837313 -351.638666) (xy 370.806762 -351.638666) (xy 370.806762 -351.584134)
			(xy 370.814523 -351.530158) (xy 370.829885 -351.477835) (xy 370.852538 -351.428231) (xy 370.882019 -351.382356)
			(xy 370.917729 -351.341143) (xy 370.95894 -351.305431) (xy 371.004814 -351.275948) (xy 371.054416 -351.253292)
			(xy 371.106738 -351.237927) (xy 371.160714 -351.230164) (xy 371.18798 -351.229676) (xy 372.05158 -351.229676)
			(xy 372.078855 -351.230062) (xy 372.132849 -351.237823) (xy 372.185189 -351.253189) (xy 372.23481 -351.275848)
			(xy 372.280701 -351.305338) (xy 372.321927 -351.341059) (xy 372.35765 -351.382283) (xy 372.387143 -351.428172)
			(xy 372.409804 -351.477792) (xy 372.425173 -351.530131) (xy 372.432936 -351.584125) (xy 372.432936 -351.63867)
			(xy 373.91564 -351.63867) (xy 373.91564 -351.58413) (xy 373.923402 -351.530145) (xy 373.938769 -351.477814)
			(xy 373.961427 -351.428203) (xy 373.990915 -351.382322) (xy 374.026634 -351.341105) (xy 374.067854 -351.305391)
			(xy 374.113738 -351.275908) (xy 374.163352 -351.253255) (xy 374.215684 -351.237893) (xy 374.26967 -351.230137)
			(xy 374.29694 -351.229676) (xy 375.16054 -351.229676) (xy 375.18781 -351.230089) (xy 375.241795 -351.237856)
			(xy 375.294125 -351.253227) (xy 375.343735 -351.275887) (xy 375.389615 -351.305377) (xy 375.430832 -351.341096)
			(xy 375.466547 -351.382317) (xy 375.496032 -351.4282) (xy 375.518687 -351.477813) (xy 375.534052 -351.530144)
			(xy 375.541814 -351.58413) (xy 375.541814 -351.638667) (xy 377.024662 -351.638667) (xy 377.024662 -351.584133)
			(xy 377.032423 -351.530155) (xy 377.047787 -351.477831) (xy 377.070441 -351.428226) (xy 377.099924 -351.382349)
			(xy 377.135636 -351.341136) (xy 377.176849 -351.305424) (xy 377.222726 -351.275941) (xy 377.272331 -351.253287)
			(xy 377.324655 -351.237923) (xy 377.378633 -351.230162) (xy 377.4059 -351.229676) (xy 378.2695 -351.229676)
			(xy 378.296772 -351.230087) (xy 378.350761 -351.237849) (xy 378.403096 -351.253216) (xy 378.452711 -351.275874)
			(xy 378.498596 -351.305363) (xy 378.539818 -351.341082) (xy 378.575537 -351.382304) (xy 378.605026 -351.428189)
			(xy 378.627684 -351.477804) (xy 378.643051 -351.530139) (xy 378.650813 -351.584128) (xy 378.650813 -351.638665)
			(xy 380.133662 -351.638665) (xy 380.133662 -351.584135) (xy 380.141422 -351.53016) (xy 380.156784 -351.477839)
			(xy 380.179435 -351.428237) (xy 380.208914 -351.382362) (xy 380.244621 -351.34115) (xy 380.28583 -351.305438)
			(xy 380.331702 -351.275954) (xy 380.381302 -351.253298) (xy 380.433621 -351.237931) (xy 380.487595 -351.230165)
			(xy 380.51486 -351.229676) (xy 381.37846 -351.229676) (xy 381.405736 -351.230061) (xy 381.459732 -351.237819)
			(xy 381.512075 -351.253183) (xy 381.561698 -351.275841) (xy 381.607591 -351.30533) (xy 381.64882 -351.341051)
			(xy 381.684546 -351.382277) (xy 381.71404 -351.428167) (xy 381.736703 -351.477788) (xy 381.752072 -351.530129)
			(xy 381.759836 -351.584124) (xy 381.759836 -351.638669) (xy 383.242539 -351.638669) (xy 383.242539 -351.584131)
			(xy 383.250301 -351.530148) (xy 383.265667 -351.477818) (xy 383.288324 -351.428209) (xy 383.31781 -351.382329)
			(xy 383.353526 -351.341112) (xy 383.394745 -351.305398) (xy 383.440626 -351.275914) (xy 383.490237 -351.25326)
			(xy 383.542567 -351.237897) (xy 383.596551 -351.230138) (xy 383.62382 -351.229676) (xy 384.48742 -351.229676)
			(xy 384.514691 -351.230088) (xy 384.568678 -351.237853) (xy 384.62101 -351.253221) (xy 384.670623 -351.275881)
			(xy 384.716506 -351.30537) (xy 384.757725 -351.341089) (xy 384.793442 -351.38231) (xy 384.822929 -351.428195)
			(xy 384.845586 -351.477808) (xy 384.860952 -351.530142) (xy 384.868714 -351.584129) (xy 384.868714 -351.638666)
			(xy 386.351562 -351.638666) (xy 386.351562 -351.584134) (xy 386.359323 -351.530158) (xy 386.374685 -351.477835)
			(xy 386.397338 -351.428231) (xy 386.426819 -351.382356) (xy 386.462529 -351.341143) (xy 386.50374 -351.305431)
			(xy 386.549614 -351.275948) (xy 386.599216 -351.253292) (xy 386.651538 -351.237927) (xy 386.705514 -351.230164)
			(xy 386.73278 -351.229676) (xy 387.59638 -351.229676) (xy 387.623655 -351.230062) (xy 387.677649 -351.237823)
			(xy 387.729989 -351.253189) (xy 387.77961 -351.275848) (xy 387.825501 -351.305338) (xy 387.866727 -351.341059)
			(xy 387.90245 -351.382283) (xy 387.931943 -351.428172) (xy 387.954604 -351.477792) (xy 387.969973 -351.530131)
			(xy 387.977736 -351.584125) (xy 387.977736 -351.63867) (xy 389.46044 -351.63867) (xy 389.46044 -351.58413)
			(xy 389.468202 -351.530145) (xy 389.483569 -351.477814) (xy 389.506227 -351.428203) (xy 389.535715 -351.382322)
			(xy 389.571434 -351.341105) (xy 389.612654 -351.305391) (xy 389.658538 -351.275908) (xy 389.708152 -351.253255)
			(xy 389.760484 -351.237893) (xy 389.81447 -351.230137) (xy 389.84174 -351.229676) (xy 390.70534 -351.229676)
			(xy 390.73261 -351.230089) (xy 390.786595 -351.237856) (xy 390.838925 -351.253227) (xy 390.888535 -351.275887)
			(xy 390.934415 -351.305377) (xy 390.975632 -351.341096) (xy 391.011347 -351.382317) (xy 391.040832 -351.4282)
			(xy 391.063487 -351.477813) (xy 391.078852 -351.530144) (xy 391.086614 -351.58413) (xy 391.086614 -351.638667)
			(xy 392.569462 -351.638667) (xy 392.569462 -351.584133) (xy 392.577223 -351.530155) (xy 392.592587 -351.477831)
			(xy 392.615241 -351.428226) (xy 392.644724 -351.382349) (xy 392.680436 -351.341136) (xy 392.721649 -351.305424)
			(xy 392.767526 -351.275941) (xy 392.817131 -351.253287) (xy 392.869455 -351.237923) (xy 392.923433 -351.230162)
			(xy 392.9507 -351.229676) (xy 393.8143 -351.229676) (xy 393.841572 -351.230087) (xy 393.895561 -351.237849)
			(xy 393.947896 -351.253216) (xy 393.997511 -351.275874) (xy 394.043396 -351.305363) (xy 394.084618 -351.341082)
			(xy 394.120337 -351.382304) (xy 394.149826 -351.428189) (xy 394.172484 -351.477804) (xy 394.187851 -351.530139)
			(xy 394.195613 -351.584128) (xy 394.195613 -351.638665) (xy 395.678462 -351.638665) (xy 395.678462 -351.584135)
			(xy 395.686222 -351.53016) (xy 395.701584 -351.477839) (xy 395.724235 -351.428237) (xy 395.753714 -351.382362)
			(xy 395.789421 -351.34115) (xy 395.83063 -351.305438) (xy 395.876502 -351.275954) (xy 395.926102 -351.253298)
			(xy 395.978421 -351.237931) (xy 396.032395 -351.230165) (xy 396.05966 -351.229676) (xy 396.92326 -351.229676)
			(xy 396.950536 -351.230061) (xy 397.004532 -351.237819) (xy 397.056875 -351.253183) (xy 397.106498 -351.275841)
			(xy 397.152391 -351.30533) (xy 397.19362 -351.341051) (xy 397.229346 -351.382277) (xy 397.25884 -351.428167)
			(xy 397.281503 -351.477788) (xy 397.296872 -351.530129) (xy 397.304636 -351.584124) (xy 397.304636 -351.638669)
			(xy 398.787339 -351.638669) (xy 398.787339 -351.584131) (xy 398.795101 -351.530148) (xy 398.810467 -351.477818)
			(xy 398.833124 -351.428209) (xy 398.86261 -351.382329) (xy 398.898326 -351.341112) (xy 398.939545 -351.305398)
			(xy 398.985426 -351.275914) (xy 399.035037 -351.25326) (xy 399.087367 -351.237897) (xy 399.141351 -351.230138)
			(xy 399.16862 -351.229676) (xy 400.03222 -351.229676) (xy 400.059491 -351.230088) (xy 400.113478 -351.237853)
			(xy 400.16581 -351.253221) (xy 400.215423 -351.275881) (xy 400.261306 -351.30537) (xy 400.302525 -351.341089)
			(xy 400.338242 -351.38231) (xy 400.367729 -351.428195) (xy 400.390386 -351.477808) (xy 400.405752 -351.530142)
			(xy 400.413514 -351.584129) (xy 400.413514 -351.638666) (xy 401.896362 -351.638666) (xy 401.896362 -351.584134)
			(xy 401.904123 -351.530158) (xy 401.919485 -351.477835) (xy 401.942138 -351.428231) (xy 401.971619 -351.382356)
			(xy 402.007329 -351.341143) (xy 402.04854 -351.305431) (xy 402.094414 -351.275948) (xy 402.144016 -351.253292)
			(xy 402.196338 -351.237927) (xy 402.250314 -351.230164) (xy 402.27758 -351.229676) (xy 403.14118 -351.229676)
			(xy 403.168455 -351.230062) (xy 403.222449 -351.237823) (xy 403.274789 -351.253189) (xy 403.32441 -351.275848)
			(xy 403.370301 -351.305338) (xy 403.411527 -351.341059) (xy 403.44725 -351.382283) (xy 403.476743 -351.428172)
			(xy 403.499404 -351.477792) (xy 403.514773 -351.530131) (xy 403.522536 -351.584125) (xy 403.522536 -351.638666)
			(xy 408.913862 -351.638666) (xy 408.913862 -351.584134) (xy 408.921623 -351.530156) (xy 408.936986 -351.477832)
			(xy 408.95964 -351.428228) (xy 408.989122 -351.382352) (xy 409.024833 -351.341138) (xy 409.066045 -351.305427)
			(xy 409.111921 -351.275944) (xy 409.161525 -351.253289) (xy 409.213848 -351.237925) (xy 409.267826 -351.230163)
			(xy 409.295092 -351.229676) (xy 410.158692 -351.229676) (xy 410.185966 -351.230063) (xy 410.239959 -351.237825)
			(xy 410.292298 -351.253192) (xy 410.341917 -351.275851) (xy 410.387806 -351.305342) (xy 410.429032 -351.341063)
			(xy 410.464753 -351.382287) (xy 410.494245 -351.428176) (xy 410.516905 -351.477794) (xy 410.532273 -351.530133)
			(xy 410.540036 -351.584126) (xy 410.540036 -351.638664) (xy 412.022862 -351.638664) (xy 412.022862 -351.584136)
			(xy 412.030622 -351.530162) (xy 412.045983 -351.477841) (xy 412.068634 -351.428239) (xy 412.098112 -351.382365)
			(xy 412.133819 -351.341153) (xy 412.175026 -351.305441) (xy 412.220897 -351.275957) (xy 412.270496 -351.2533)
			(xy 412.322815 -351.237932) (xy 412.376788 -351.230166) (xy 412.404052 -351.229676) (xy 413.267652 -351.229676)
			(xy 413.294928 -351.23006) (xy 413.348925 -351.237818) (xy 413.401269 -351.253181) (xy 413.450893 -351.275838)
			(xy 413.496787 -351.305328) (xy 413.538017 -351.341049) (xy 413.573744 -351.382274) (xy 413.603239 -351.428165)
			(xy 413.625902 -351.477786) (xy 413.641272 -351.530128) (xy 413.649036 -351.584124) (xy 413.649036 -351.638669)
			(xy 415.131739 -351.638669) (xy 415.131739 -351.584131) (xy 415.139501 -351.530149) (xy 415.154866 -351.47782)
			(xy 415.177523 -351.428211) (xy 415.207008 -351.382331) (xy 415.242724 -351.341115) (xy 415.283941 -351.305401)
			(xy 415.329822 -351.275917) (xy 415.379431 -351.253262) (xy 415.43176 -351.237899) (xy 415.485743 -351.230139)
			(xy 415.513012 -351.229676) (xy 416.376612 -351.229676) (xy 416.403884 -351.230087) (xy 416.457871 -351.237851)
			(xy 416.510204 -351.253219) (xy 416.559818 -351.275878) (xy 416.605702 -351.305367) (xy 416.646922 -351.341086)
			(xy 416.68264 -351.382308) (xy 416.712128 -351.428192) (xy 416.734785 -351.477807) (xy 416.750151 -351.530141)
			(xy 416.757914 -351.584128) (xy 416.757914 -351.638665) (xy 418.240762 -351.638665) (xy 418.240762 -351.584135)
			(xy 418.248522 -351.530159) (xy 418.263885 -351.477837) (xy 418.286537 -351.428233) (xy 418.316017 -351.382358)
			(xy 418.351726 -351.341146) (xy 418.392936 -351.305434) (xy 418.438809 -351.27595) (xy 418.48841 -351.253295)
			(xy 418.540731 -351.237928) (xy 418.594707 -351.230164) (xy 418.621972 -351.229676) (xy 419.485572 -351.229676)
			(xy 419.512847 -351.230062) (xy 419.566842 -351.237821) (xy 419.619184 -351.253187) (xy 419.668805 -351.275845)
			(xy 419.714697 -351.305335) (xy 419.755924 -351.341056) (xy 419.791648 -351.382281) (xy 419.821142 -351.42817)
			(xy 419.843803 -351.47779) (xy 419.859173 -351.53013) (xy 419.866936 -351.584125) (xy 419.866936 -351.63867)
			(xy 421.349639 -351.63867) (xy 421.349639 -351.58413) (xy 421.357402 -351.530146) (xy 421.372768 -351.477816)
			(xy 421.395426 -351.428206) (xy 421.424913 -351.382325) (xy 421.460631 -351.341108) (xy 421.501851 -351.305394)
			(xy 421.547734 -351.27591) (xy 421.597346 -351.253257) (xy 421.649677 -351.237895) (xy 421.703662 -351.230137)
			(xy 421.730932 -351.229676) (xy 422.594532 -351.229676) (xy 422.621803 -351.230089) (xy 422.675788 -351.237855)
			(xy 422.728119 -351.253224) (xy 422.77773 -351.275885) (xy 422.823612 -351.305374) (xy 422.864829 -351.341093)
			(xy 422.900545 -351.382314) (xy 422.930031 -351.428198) (xy 422.952687 -351.477811) (xy 422.968052 -351.530143)
			(xy 422.975814 -351.584129) (xy 422.975814 -351.638666) (xy 424.458662 -351.638666) (xy 424.458662 -351.584134)
			(xy 424.466423 -351.530156) (xy 424.481786 -351.477832) (xy 424.50444 -351.428228) (xy 424.533922 -351.382352)
			(xy 424.569633 -351.341138) (xy 424.610845 -351.305427) (xy 424.656721 -351.275944) (xy 424.706325 -351.253289)
			(xy 424.758648 -351.237925) (xy 424.812626 -351.230163) (xy 424.839892 -351.229676) (xy 425.703492 -351.229676)
			(xy 425.730766 -351.230063) (xy 425.784759 -351.237825) (xy 425.837098 -351.253192) (xy 425.886717 -351.275851)
			(xy 425.932606 -351.305342) (xy 425.973832 -351.341063) (xy 426.009553 -351.382287) (xy 426.039045 -351.428176)
			(xy 426.061705 -351.477794) (xy 426.077073 -351.530133) (xy 426.084836 -351.584126) (xy 426.084836 -351.638664)
			(xy 427.567662 -351.638664) (xy 427.567662 -351.584136) (xy 427.575422 -351.530162) (xy 427.590783 -351.477841)
			(xy 427.613434 -351.428239) (xy 427.642912 -351.382365) (xy 427.678619 -351.341153) (xy 427.719826 -351.305441)
			(xy 427.765697 -351.275957) (xy 427.815296 -351.2533) (xy 427.867615 -351.237932) (xy 427.921588 -351.230166)
			(xy 427.948852 -351.229676) (xy 428.812452 -351.229676) (xy 428.839728 -351.23006) (xy 428.893725 -351.237818)
			(xy 428.946069 -351.253181) (xy 428.995693 -351.275838) (xy 429.041587 -351.305328) (xy 429.082817 -351.341049)
			(xy 429.118544 -351.382274) (xy 429.148039 -351.428165) (xy 429.170702 -351.477786) (xy 429.186072 -351.530128)
			(xy 429.193836 -351.584124) (xy 429.193836 -351.638669) (xy 430.676539 -351.638669) (xy 430.676539 -351.584131)
			(xy 430.684301 -351.530149) (xy 430.699666 -351.47782) (xy 430.722323 -351.428211) (xy 430.751808 -351.382331)
			(xy 430.787524 -351.341115) (xy 430.828741 -351.305401) (xy 430.874622 -351.275917) (xy 430.924231 -351.253262)
			(xy 430.97656 -351.237899) (xy 431.030543 -351.230139) (xy 431.057812 -351.229676) (xy 431.921412 -351.229676)
			(xy 431.948684 -351.230087) (xy 432.002671 -351.237851) (xy 432.055004 -351.253219) (xy 432.104618 -351.275878)
			(xy 432.150502 -351.305367) (xy 432.191722 -351.341086) (xy 432.22744 -351.382308) (xy 432.256928 -351.428192)
			(xy 432.279585 -351.477807) (xy 432.294951 -351.530141) (xy 432.302714 -351.584128) (xy 432.302714 -351.638665)
			(xy 433.785562 -351.638665) (xy 433.785562 -351.584135) (xy 433.793322 -351.530159) (xy 433.808685 -351.477837)
			(xy 433.831337 -351.428233) (xy 433.860817 -351.382358) (xy 433.896526 -351.341146) (xy 433.937736 -351.305434)
			(xy 433.983609 -351.27595) (xy 434.03321 -351.253295) (xy 434.085531 -351.237928) (xy 434.139507 -351.230164)
			(xy 434.166772 -351.229676) (xy 435.030372 -351.229676) (xy 435.057647 -351.230062) (xy 435.111642 -351.237821)
			(xy 435.163984 -351.253187) (xy 435.213605 -351.275845) (xy 435.259497 -351.305335) (xy 435.300724 -351.341056)
			(xy 435.336448 -351.382281) (xy 435.365942 -351.42817) (xy 435.388603 -351.47779) (xy 435.403973 -351.53013)
			(xy 435.411736 -351.584125) (xy 435.411736 -351.63867) (xy 436.894439 -351.63867) (xy 436.894439 -351.58413)
			(xy 436.902202 -351.530146) (xy 436.917568 -351.477816) (xy 436.940226 -351.428206) (xy 436.969713 -351.382325)
			(xy 437.005431 -351.341108) (xy 437.046651 -351.305394) (xy 437.092534 -351.27591) (xy 437.142146 -351.253257)
			(xy 437.194477 -351.237895) (xy 437.248462 -351.230137) (xy 437.275732 -351.229676) (xy 438.139332 -351.229676)
			(xy 438.166603 -351.230089) (xy 438.220588 -351.237855) (xy 438.272919 -351.253224) (xy 438.32253 -351.275885)
			(xy 438.368412 -351.305374) (xy 438.409629 -351.341093) (xy 438.445345 -351.382314) (xy 438.474831 -351.428198)
			(xy 438.497487 -351.477811) (xy 438.512852 -351.530143) (xy 438.520614 -351.584129) (xy 438.520614 -351.638666)
			(xy 440.003462 -351.638666) (xy 440.003462 -351.584134) (xy 440.011223 -351.530156) (xy 440.026586 -351.477832)
			(xy 440.04924 -351.428228) (xy 440.078722 -351.382352) (xy 440.114433 -351.341138) (xy 440.155645 -351.305427)
			(xy 440.201521 -351.275944) (xy 440.251125 -351.253289) (xy 440.303448 -351.237925) (xy 440.357426 -351.230163)
			(xy 440.384692 -351.229676) (xy 441.248292 -351.229676) (xy 441.275566 -351.230063) (xy 441.329559 -351.237825)
			(xy 441.381898 -351.253192) (xy 441.431517 -351.275851) (xy 441.477406 -351.305342) (xy 441.518632 -351.341063)
			(xy 441.554353 -351.382287) (xy 441.583845 -351.428176) (xy 441.606505 -351.477794) (xy 441.621873 -351.530133)
			(xy 441.629636 -351.584126) (xy 441.629636 -351.638674) (xy 441.621873 -351.692667) (xy 441.606505 -351.745006)
			(xy 441.583845 -351.794624) (xy 441.554353 -351.840513) (xy 441.518632 -351.881737) (xy 441.477406 -351.917458)
			(xy 441.431517 -351.946949) (xy 441.381898 -351.969608) (xy 441.329559 -351.984975) (xy 441.275566 -351.992737)
			(xy 441.248292 -351.9932) (xy 440.384692 -351.9932) (xy 440.357426 -351.992637) (xy 440.303448 -351.984875)
			(xy 440.251125 -351.969511) (xy 440.201521 -351.946856) (xy 440.155645 -351.917373) (xy 440.114433 -351.881662)
			(xy 440.078722 -351.840448) (xy 440.04924 -351.794572) (xy 440.026586 -351.744968) (xy 440.011223 -351.692644)
			(xy 440.003462 -351.638666) (xy 438.520614 -351.638666) (xy 438.520614 -351.638671) (xy 438.512852 -351.692657)
			(xy 438.497487 -351.744989) (xy 438.474831 -351.794602) (xy 438.445345 -351.840486) (xy 438.409629 -351.881707)
			(xy 438.368412 -351.917426) (xy 438.32253 -351.946915) (xy 438.272919 -351.969576) (xy 438.220588 -351.984945)
			(xy 438.166603 -351.992711) (xy 438.139332 -351.9932) (xy 437.275732 -351.9932) (xy 437.248462 -351.992663)
			(xy 437.194477 -351.984905) (xy 437.142146 -351.969543) (xy 437.092534 -351.94689) (xy 437.046651 -351.917406)
			(xy 437.005431 -351.881692) (xy 436.969713 -351.840475) (xy 436.940226 -351.794594) (xy 436.917568 -351.744984)
			(xy 436.902202 -351.692654) (xy 436.894439 -351.63867) (xy 435.411736 -351.63867) (xy 435.411736 -351.638675)
			(xy 435.403973 -351.69267) (xy 435.388603 -351.74501) (xy 435.365942 -351.79463) (xy 435.336448 -351.840519)
			(xy 435.300724 -351.881744) (xy 435.259497 -351.917465) (xy 435.213605 -351.946955) (xy 435.163984 -351.969613)
			(xy 435.111642 -351.984979) (xy 435.057647 -351.992738) (xy 435.030372 -351.9932) (xy 434.166772 -351.9932)
			(xy 434.139507 -351.992636) (xy 434.085531 -351.984872) (xy 434.03321 -351.969505) (xy 433.983609 -351.94685)
			(xy 433.937736 -351.917366) (xy 433.896526 -351.881654) (xy 433.860817 -351.840442) (xy 433.831337 -351.794567)
			(xy 433.808685 -351.744963) (xy 433.793322 -351.692641) (xy 433.785562 -351.638665) (xy 432.302714 -351.638665)
			(xy 432.302714 -351.638672) (xy 432.294951 -351.692659) (xy 432.279585 -351.744993) (xy 432.256928 -351.794608)
			(xy 432.22744 -351.840492) (xy 432.191722 -351.881714) (xy 432.150502 -351.917433) (xy 432.104618 -351.946922)
			(xy 432.055004 -351.969581) (xy 432.002671 -351.984949) (xy 431.948684 -351.992713) (xy 431.921412 -351.9932)
			(xy 431.057812 -351.9932) (xy 431.030543 -351.992661) (xy 430.97656 -351.984901) (xy 430.924231 -351.969538)
			(xy 430.874622 -351.946883) (xy 430.828741 -351.917399) (xy 430.787524 -351.881685) (xy 430.751808 -351.840469)
			(xy 430.722323 -351.794589) (xy 430.699666 -351.74498) (xy 430.684301 -351.692651) (xy 430.676539 -351.638669)
			(xy 429.193836 -351.638669) (xy 429.193836 -351.638676) (xy 429.186072 -351.692672) (xy 429.170702 -351.745014)
			(xy 429.148039 -351.794635) (xy 429.118544 -351.840526) (xy 429.082817 -351.881751) (xy 429.041587 -351.917472)
			(xy 428.995693 -351.946962) (xy 428.946069 -351.969619) (xy 428.893725 -351.984982) (xy 428.839728 -351.99274)
			(xy 428.812452 -351.9932) (xy 427.948852 -351.9932) (xy 427.921588 -351.992634) (xy 427.867615 -351.984868)
			(xy 427.815296 -351.9695) (xy 427.765697 -351.946843) (xy 427.719826 -351.917359) (xy 427.678619 -351.881647)
			(xy 427.642912 -351.840435) (xy 427.613434 -351.794561) (xy 427.590783 -351.744959) (xy 427.575422 -351.692639)
			(xy 427.567662 -351.638664) (xy 426.084836 -351.638664) (xy 426.084836 -351.638674) (xy 426.077073 -351.692667)
			(xy 426.061705 -351.745006) (xy 426.039045 -351.794624) (xy 426.009553 -351.840513) (xy 425.973832 -351.881737)
			(xy 425.932606 -351.917458) (xy 425.886717 -351.946949) (xy 425.837098 -351.969608) (xy 425.784759 -351.984975)
			(xy 425.730766 -351.992737) (xy 425.703492 -351.9932) (xy 424.839892 -351.9932) (xy 424.812626 -351.992637)
			(xy 424.758648 -351.984875) (xy 424.706325 -351.969511) (xy 424.656721 -351.946856) (xy 424.610845 -351.917373)
			(xy 424.569633 -351.881662) (xy 424.533922 -351.840448) (xy 424.50444 -351.794572) (xy 424.481786 -351.744968)
			(xy 424.466423 -351.692644) (xy 424.458662 -351.638666) (xy 422.975814 -351.638666) (xy 422.975814 -351.638671)
			(xy 422.968052 -351.692657) (xy 422.952687 -351.744989) (xy 422.930031 -351.794602) (xy 422.900545 -351.840486)
			(xy 422.864829 -351.881707) (xy 422.823612 -351.917426) (xy 422.77773 -351.946915) (xy 422.728119 -351.969576)
			(xy 422.675788 -351.984945) (xy 422.621803 -351.992711) (xy 422.594532 -351.9932) (xy 421.730932 -351.9932)
			(xy 421.703662 -351.992663) (xy 421.649677 -351.984905) (xy 421.597346 -351.969543) (xy 421.547734 -351.94689)
			(xy 421.501851 -351.917406) (xy 421.460631 -351.881692) (xy 421.424913 -351.840475) (xy 421.395426 -351.794594)
			(xy 421.372768 -351.744984) (xy 421.357402 -351.692654) (xy 421.349639 -351.63867) (xy 419.866936 -351.63867)
			(xy 419.866936 -351.638675) (xy 419.859173 -351.69267) (xy 419.843803 -351.74501) (xy 419.821142 -351.79463)
			(xy 419.791648 -351.840519) (xy 419.755924 -351.881744) (xy 419.714697 -351.917465) (xy 419.668805 -351.946955)
			(xy 419.619184 -351.969613) (xy 419.566842 -351.984979) (xy 419.512847 -351.992738) (xy 419.485572 -351.9932)
			(xy 418.621972 -351.9932) (xy 418.594707 -351.992636) (xy 418.540731 -351.984872) (xy 418.48841 -351.969505)
			(xy 418.438809 -351.94685) (xy 418.392936 -351.917366) (xy 418.351726 -351.881654) (xy 418.316017 -351.840442)
			(xy 418.286537 -351.794567) (xy 418.263885 -351.744963) (xy 418.248522 -351.692641) (xy 418.240762 -351.638665)
			(xy 416.757914 -351.638665) (xy 416.757914 -351.638672) (xy 416.750151 -351.692659) (xy 416.734785 -351.744993)
			(xy 416.712128 -351.794608) (xy 416.68264 -351.840492) (xy 416.646922 -351.881714) (xy 416.605702 -351.917433)
			(xy 416.559818 -351.946922) (xy 416.510204 -351.969581) (xy 416.457871 -351.984949) (xy 416.403884 -351.992713)
			(xy 416.376612 -351.9932) (xy 415.513012 -351.9932) (xy 415.485743 -351.992661) (xy 415.43176 -351.984901)
			(xy 415.379431 -351.969538) (xy 415.329822 -351.946883) (xy 415.283941 -351.917399) (xy 415.242724 -351.881685)
			(xy 415.207008 -351.840469) (xy 415.177523 -351.794589) (xy 415.154866 -351.74498) (xy 415.139501 -351.692651)
			(xy 415.131739 -351.638669) (xy 413.649036 -351.638669) (xy 413.649036 -351.638676) (xy 413.641272 -351.692672)
			(xy 413.625902 -351.745014) (xy 413.603239 -351.794635) (xy 413.573744 -351.840526) (xy 413.538017 -351.881751)
			(xy 413.496787 -351.917472) (xy 413.450893 -351.946962) (xy 413.401269 -351.969619) (xy 413.348925 -351.984982)
			(xy 413.294928 -351.99274) (xy 413.267652 -351.9932) (xy 412.404052 -351.9932) (xy 412.376788 -351.992634)
			(xy 412.322815 -351.984868) (xy 412.270496 -351.9695) (xy 412.220897 -351.946843) (xy 412.175026 -351.917359)
			(xy 412.133819 -351.881647) (xy 412.098112 -351.840435) (xy 412.068634 -351.794561) (xy 412.045983 -351.744959)
			(xy 412.030622 -351.692639) (xy 412.022862 -351.638664) (xy 410.540036 -351.638664) (xy 410.540036 -351.638674)
			(xy 410.532273 -351.692667) (xy 410.516905 -351.745006) (xy 410.494245 -351.794624) (xy 410.464753 -351.840513)
			(xy 410.429032 -351.881737) (xy 410.387806 -351.917458) (xy 410.341917 -351.946949) (xy 410.292298 -351.969608)
			(xy 410.239959 -351.984975) (xy 410.185966 -351.992737) (xy 410.158692 -351.9932) (xy 409.295092 -351.9932)
			(xy 409.267826 -351.992637) (xy 409.213848 -351.984875) (xy 409.161525 -351.969511) (xy 409.111921 -351.946856)
			(xy 409.066045 -351.917373) (xy 409.024833 -351.881662) (xy 408.989122 -351.840448) (xy 408.95964 -351.794572)
			(xy 408.936986 -351.744968) (xy 408.921623 -351.692644) (xy 408.913862 -351.638666) (xy 403.522536 -351.638666)
			(xy 403.522536 -351.638675) (xy 403.514773 -351.692669) (xy 403.499404 -351.745008) (xy 403.476743 -351.794628)
			(xy 403.44725 -351.840517) (xy 403.411527 -351.881741) (xy 403.370301 -351.917462) (xy 403.32441 -351.946952)
			(xy 403.274789 -351.969611) (xy 403.222449 -351.984977) (xy 403.168455 -351.992738) (xy 403.14118 -351.9932)
			(xy 402.27758 -351.9932) (xy 402.250314 -351.992636) (xy 402.196338 -351.984873) (xy 402.144016 -351.969508)
			(xy 402.094414 -351.946852) (xy 402.04854 -351.917369) (xy 402.007329 -351.881657) (xy 401.971619 -351.840444)
			(xy 401.942138 -351.794569) (xy 401.919485 -351.744965) (xy 401.904123 -351.692642) (xy 401.896362 -351.638666)
			(xy 400.413514 -351.638666) (xy 400.413514 -351.638671) (xy 400.405752 -351.692658) (xy 400.390386 -351.744992)
			(xy 400.367729 -351.794605) (xy 400.338242 -351.84049) (xy 400.302525 -351.881711) (xy 400.261306 -351.91743)
			(xy 400.215423 -351.946919) (xy 400.16581 -351.969579) (xy 400.113478 -351.984947) (xy 400.059491 -351.992712)
			(xy 400.03222 -351.9932) (xy 399.16862 -351.9932) (xy 399.141351 -351.992662) (xy 399.087367 -351.984903)
			(xy 399.035037 -351.96954) (xy 398.985426 -351.946886) (xy 398.939545 -351.917402) (xy 398.898326 -351.881688)
			(xy 398.86261 -351.840471) (xy 398.833124 -351.794591) (xy 398.810467 -351.744982) (xy 398.795101 -351.692652)
			(xy 398.787339 -351.638669) (xy 397.304636 -351.638669) (xy 397.304636 -351.638676) (xy 397.296872 -351.692671)
			(xy 397.281503 -351.745012) (xy 397.25884 -351.794633) (xy 397.229346 -351.840523) (xy 397.19362 -351.881749)
			(xy 397.152391 -351.91747) (xy 397.106498 -351.946959) (xy 397.056875 -351.969617) (xy 397.004532 -351.984981)
			(xy 396.950536 -351.992739) (xy 396.92326 -351.9932) (xy 396.05966 -351.9932) (xy 396.032395 -351.992635)
			(xy 395.978421 -351.984869) (xy 395.926102 -351.969502) (xy 395.876502 -351.946846) (xy 395.83063 -351.917362)
			(xy 395.789421 -351.88165) (xy 395.753714 -351.840438) (xy 395.724235 -351.794563) (xy 395.701584 -351.744961)
			(xy 395.686222 -351.69264) (xy 395.678462 -351.638665) (xy 394.195613 -351.638665) (xy 394.195613 -351.638672)
			(xy 394.187851 -351.692661) (xy 394.172484 -351.744996) (xy 394.149826 -351.794611) (xy 394.120337 -351.840496)
			(xy 394.084618 -351.881718) (xy 394.043396 -351.917437) (xy 393.997511 -351.946926) (xy 393.947896 -351.969584)
			(xy 393.895561 -351.984951) (xy 393.841572 -351.992713) (xy 393.8143 -351.9932) (xy 392.9507 -351.9932)
			(xy 392.923433 -351.992638) (xy 392.869455 -351.984877) (xy 392.817131 -351.969513) (xy 392.767526 -351.946859)
			(xy 392.721649 -351.917376) (xy 392.680436 -351.881664) (xy 392.644724 -351.840451) (xy 392.615241 -351.794574)
			(xy 392.592587 -351.744969) (xy 392.577223 -351.692645) (xy 392.569462 -351.638667) (xy 391.086614 -351.638667)
			(xy 391.086614 -351.63867) (xy 391.078852 -351.692656) (xy 391.063487 -351.744987) (xy 391.040832 -351.7946)
			(xy 391.011347 -351.840483) (xy 390.975632 -351.881704) (xy 390.934415 -351.917423) (xy 390.888535 -351.946913)
			(xy 390.838925 -351.969573) (xy 390.786595 -351.984944) (xy 390.73261 -351.992711) (xy 390.70534 -351.9932)
			(xy 389.84174 -351.9932) (xy 389.81447 -351.992663) (xy 389.760484 -351.984907) (xy 389.708152 -351.969545)
			(xy 389.658538 -351.946892) (xy 389.612654 -351.917409) (xy 389.571434 -351.881695) (xy 389.535715 -351.840478)
			(xy 389.506227 -351.794597) (xy 389.483569 -351.744986) (xy 389.468202 -351.692655) (xy 389.46044 -351.63867)
			(xy 387.977736 -351.63867) (xy 387.977736 -351.638675) (xy 387.969973 -351.692669) (xy 387.954604 -351.745008)
			(xy 387.931943 -351.794628) (xy 387.90245 -351.840517) (xy 387.866727 -351.881741) (xy 387.825501 -351.917462)
			(xy 387.77961 -351.946952) (xy 387.729989 -351.969611) (xy 387.677649 -351.984977) (xy 387.623655 -351.992738)
			(xy 387.59638 -351.9932) (xy 386.73278 -351.9932) (xy 386.705514 -351.992636) (xy 386.651538 -351.984873)
			(xy 386.599216 -351.969508) (xy 386.549614 -351.946852) (xy 386.50374 -351.917369) (xy 386.462529 -351.881657)
			(xy 386.426819 -351.840444) (xy 386.397338 -351.794569) (xy 386.374685 -351.744965) (xy 386.359323 -351.692642)
			(xy 386.351562 -351.638666) (xy 384.868714 -351.638666) (xy 384.868714 -351.638671) (xy 384.860952 -351.692658)
			(xy 384.845586 -351.744992) (xy 384.822929 -351.794605) (xy 384.793442 -351.84049) (xy 384.757725 -351.881711)
			(xy 384.716506 -351.91743) (xy 384.670623 -351.946919) (xy 384.62101 -351.969579) (xy 384.568678 -351.984947)
			(xy 384.514691 -351.992712) (xy 384.48742 -351.9932) (xy 383.62382 -351.9932) (xy 383.596551 -351.992662)
			(xy 383.542567 -351.984903) (xy 383.490237 -351.96954) (xy 383.440626 -351.946886) (xy 383.394745 -351.917402)
			(xy 383.353526 -351.881688) (xy 383.31781 -351.840471) (xy 383.288324 -351.794591) (xy 383.265667 -351.744982)
			(xy 383.250301 -351.692652) (xy 383.242539 -351.638669) (xy 381.759836 -351.638669) (xy 381.759836 -351.638676)
			(xy 381.752072 -351.692671) (xy 381.736703 -351.745012) (xy 381.71404 -351.794633) (xy 381.684546 -351.840523)
			(xy 381.64882 -351.881749) (xy 381.607591 -351.91747) (xy 381.561698 -351.946959) (xy 381.512075 -351.969617)
			(xy 381.459732 -351.984981) (xy 381.405736 -351.992739) (xy 381.37846 -351.9932) (xy 380.51486 -351.9932)
			(xy 380.487595 -351.992635) (xy 380.433621 -351.984869) (xy 380.381302 -351.969502) (xy 380.331702 -351.946846)
			(xy 380.28583 -351.917362) (xy 380.244621 -351.88165) (xy 380.208914 -351.840438) (xy 380.179435 -351.794563)
			(xy 380.156784 -351.744961) (xy 380.141422 -351.69264) (xy 380.133662 -351.638665) (xy 378.650813 -351.638665)
			(xy 378.650813 -351.638672) (xy 378.643051 -351.692661) (xy 378.627684 -351.744996) (xy 378.605026 -351.794611)
			(xy 378.575537 -351.840496) (xy 378.539818 -351.881718) (xy 378.498596 -351.917437) (xy 378.452711 -351.946926)
			(xy 378.403096 -351.969584) (xy 378.350761 -351.984951) (xy 378.296772 -351.992713) (xy 378.2695 -351.9932)
			(xy 377.4059 -351.9932) (xy 377.378633 -351.992638) (xy 377.324655 -351.984877) (xy 377.272331 -351.969513)
			(xy 377.222726 -351.946859) (xy 377.176849 -351.917376) (xy 377.135636 -351.881664) (xy 377.099924 -351.840451)
			(xy 377.070441 -351.794574) (xy 377.047787 -351.744969) (xy 377.032423 -351.692645) (xy 377.024662 -351.638667)
			(xy 375.541814 -351.638667) (xy 375.541814 -351.63867) (xy 375.534052 -351.692656) (xy 375.518687 -351.744987)
			(xy 375.496032 -351.7946) (xy 375.466547 -351.840483) (xy 375.430832 -351.881704) (xy 375.389615 -351.917423)
			(xy 375.343735 -351.946913) (xy 375.294125 -351.969573) (xy 375.241795 -351.984944) (xy 375.18781 -351.992711)
			(xy 375.16054 -351.9932) (xy 374.29694 -351.9932) (xy 374.26967 -351.992663) (xy 374.215684 -351.984907)
			(xy 374.163352 -351.969545) (xy 374.113738 -351.946892) (xy 374.067854 -351.917409) (xy 374.026634 -351.881695)
			(xy 373.990915 -351.840478) (xy 373.961427 -351.794597) (xy 373.938769 -351.744986) (xy 373.923402 -351.692655)
			(xy 373.91564 -351.63867) (xy 372.432936 -351.63867) (xy 372.432936 -351.638675) (xy 372.425173 -351.692669)
			(xy 372.409804 -351.745008) (xy 372.387143 -351.794628) (xy 372.35765 -351.840517) (xy 372.321927 -351.881741)
			(xy 372.280701 -351.917462) (xy 372.23481 -351.946952) (xy 372.185189 -351.969611) (xy 372.132849 -351.984977)
			(xy 372.078855 -351.992738) (xy 372.05158 -351.9932) (xy 371.18798 -351.9932) (xy 371.160714 -351.992636)
			(xy 371.106738 -351.984873) (xy 371.054416 -351.969508) (xy 371.004814 -351.946852) (xy 370.95894 -351.917369)
			(xy 370.917729 -351.881657) (xy 370.882019 -351.840444) (xy 370.852538 -351.794569) (xy 370.829885 -351.744965)
			(xy 370.814523 -351.692642) (xy 370.806762 -351.638666) (xy 344.837313 -351.638666) (xy 344.837313 -351.638672)
			(xy 344.829551 -351.692661) (xy 344.814184 -351.744995) (xy 344.791526 -351.79461) (xy 344.762038 -351.840495)
			(xy 344.726319 -351.881717) (xy 344.685098 -351.917435) (xy 344.639213 -351.946924) (xy 344.589599 -351.969583)
			(xy 344.537264 -351.98495) (xy 344.483276 -351.992713) (xy 344.456004 -351.9932) (xy 343.592404 -351.9932)
			(xy 343.565136 -351.992661) (xy 343.511154 -351.9849) (xy 343.458826 -351.969536) (xy 343.409217 -351.94688)
			(xy 343.363337 -351.917396) (xy 343.322121 -351.881682) (xy 343.286407 -351.840466) (xy 343.256921 -351.794587)
			(xy 343.234266 -351.744978) (xy 343.218901 -351.69265) (xy 343.211139 -351.638668) (xy 341.728314 -351.638668)
			(xy 341.728314 -351.63867) (xy 341.720552 -351.692655) (xy 341.705188 -351.744986) (xy 341.682532 -351.794599)
			(xy 341.653048 -351.840482) (xy 341.617334 -351.881703) (xy 341.576117 -351.917421) (xy 341.530237 -351.946911)
			(xy 341.480628 -351.969572) (xy 341.428298 -351.984943) (xy 341.374314 -351.99271) (xy 341.347044 -351.9932)
			(xy 340.483444 -351.9932) (xy 340.456174 -351.992664) (xy 340.402187 -351.984907) (xy 340.349855 -351.969546)
			(xy 340.300241 -351.946894) (xy 340.254356 -351.91741) (xy 340.213135 -351.881696) (xy 340.177416 -351.840479)
			(xy 340.147928 -351.794598) (xy 340.125269 -351.744987) (xy 340.109902 -351.692656) (xy 340.10214 -351.63867)
			(xy 338.619436 -351.63867) (xy 338.619436 -351.638674) (xy 338.611673 -351.692668) (xy 338.596304 -351.745007)
			(xy 338.573643 -351.794626) (xy 338.544151 -351.840515) (xy 338.508429 -351.88174) (xy 338.467203 -351.917461)
			(xy 338.421312 -351.946951) (xy 338.371692 -351.96961) (xy 338.319352 -351.984976) (xy 338.265358 -351.992738)
			(xy 338.238084 -351.9932) (xy 337.374484 -351.9932) (xy 337.347218 -351.992637) (xy 337.293242 -351.984874)
			(xy 337.240919 -351.969509) (xy 337.191316 -351.946854) (xy 337.145442 -351.91737) (xy 337.10423 -351.881659)
			(xy 337.06852 -351.840446) (xy 337.039039 -351.79457) (xy 337.016386 -351.744966) (xy 337.001023 -351.692643)
			(xy 336.993262 -351.638666) (xy 335.510414 -351.638666) (xy 335.510414 -351.638671) (xy 335.502652 -351.692658)
			(xy 335.487286 -351.744991) (xy 335.464629 -351.794604) (xy 335.435143 -351.840488) (xy 335.399427 -351.88171)
			(xy 335.358208 -351.917428) (xy 335.312325 -351.946918) (xy 335.262713 -351.969578) (xy 335.210381 -351.984947)
			(xy 335.156395 -351.992712) (xy 335.129124 -351.9932) (xy 334.265524 -351.9932) (xy 334.238255 -351.992662)
			(xy 334.18427 -351.984904) (xy 334.13194 -351.969541) (xy 334.082329 -351.946887) (xy 334.036447 -351.917403)
			(xy 333.995228 -351.881689) (xy 333.959511 -351.840472) (xy 333.930024 -351.794592) (xy 333.907367 -351.744982)
			(xy 333.892001 -351.692653) (xy 333.884239 -351.638669) (xy 332.401536 -351.638669) (xy 332.401536 -351.638675)
			(xy 332.393772 -351.692671) (xy 332.378403 -351.745011) (xy 332.35574 -351.794632) (xy 332.326246 -351.840522)
			(xy 332.290522 -351.881747) (xy 332.249293 -351.917468) (xy 332.2034 -351.946958) (xy 332.153778 -351.969615)
			(xy 332.101436 -351.98498) (xy 332.047439 -351.992739) (xy 332.020164 -351.9932) (xy 331.156564 -351.9932)
			(xy 331.129299 -351.992635) (xy 331.075325 -351.98487) (xy 331.023005 -351.969503) (xy 330.973404 -351.946847)
			(xy 330.927532 -351.917363) (xy 330.886323 -351.881652) (xy 330.850615 -351.840439) (xy 330.821136 -351.794564)
			(xy 330.798484 -351.744962) (xy 330.783122 -351.69264) (xy 330.775362 -351.638665) (xy 329.292513 -351.638665)
			(xy 329.292513 -351.638672) (xy 329.284751 -351.692661) (xy 329.269384 -351.744995) (xy 329.246726 -351.79461)
			(xy 329.217238 -351.840495) (xy 329.181519 -351.881717) (xy 329.140298 -351.917435) (xy 329.094413 -351.946924)
			(xy 329.044799 -351.969583) (xy 328.992464 -351.98495) (xy 328.938476 -351.992713) (xy 328.911204 -351.9932)
			(xy 328.047604 -351.9932) (xy 328.020336 -351.992661) (xy 327.966354 -351.9849) (xy 327.914026 -351.969536)
			(xy 327.864417 -351.94688) (xy 327.818537 -351.917396) (xy 327.777321 -351.881682) (xy 327.741607 -351.840466)
			(xy 327.712121 -351.794587) (xy 327.689466 -351.744978) (xy 327.674101 -351.69265) (xy 327.666339 -351.638668)
			(xy 326.183514 -351.638668) (xy 326.183514 -351.63867) (xy 326.175752 -351.692655) (xy 326.160388 -351.744986)
			(xy 326.137732 -351.794599) (xy 326.108248 -351.840482) (xy 326.072534 -351.881703) (xy 326.031317 -351.917421)
			(xy 325.985437 -351.946911) (xy 325.935828 -351.969572) (xy 325.883498 -351.984943) (xy 325.829514 -351.99271)
			(xy 325.802244 -351.9932) (xy 324.938644 -351.9932) (xy 324.911374 -351.992664) (xy 324.857387 -351.984907)
			(xy 324.805055 -351.969546) (xy 324.755441 -351.946894) (xy 324.709556 -351.91741) (xy 324.668335 -351.881696)
			(xy 324.632616 -351.840479) (xy 324.603128 -351.794598) (xy 324.580469 -351.744987) (xy 324.565102 -351.692656)
			(xy 324.55734 -351.63867) (xy 323.074636 -351.63867) (xy 323.074636 -351.638674) (xy 323.066873 -351.692668)
			(xy 323.051504 -351.745007) (xy 323.028843 -351.794626) (xy 322.999351 -351.840515) (xy 322.963629 -351.88174)
			(xy 322.922403 -351.917461) (xy 322.876512 -351.946951) (xy 322.826892 -351.96961) (xy 322.774552 -351.984976)
			(xy 322.720558 -351.992738) (xy 322.693284 -351.9932) (xy 321.829684 -351.9932) (xy 321.802418 -351.992637)
			(xy 321.748442 -351.984874) (xy 321.696119 -351.969509) (xy 321.646516 -351.946854) (xy 321.600642 -351.91737)
			(xy 321.55943 -351.881659) (xy 321.52372 -351.840446) (xy 321.494239 -351.79457) (xy 321.471586 -351.744966)
			(xy 321.456223 -351.692643) (xy 321.448462 -351.638666) (xy 319.965614 -351.638666) (xy 319.965614 -351.638671)
			(xy 319.957852 -351.692658) (xy 319.942486 -351.744991) (xy 319.919829 -351.794604) (xy 319.890343 -351.840488)
			(xy 319.854627 -351.88171) (xy 319.813408 -351.917428) (xy 319.767525 -351.946918) (xy 319.717913 -351.969578)
			(xy 319.665581 -351.984947) (xy 319.611595 -351.992712) (xy 319.584324 -351.9932) (xy 318.720724 -351.9932)
			(xy 318.693455 -351.992662) (xy 318.63947 -351.984904) (xy 318.58714 -351.969541) (xy 318.537529 -351.946887)
			(xy 318.491647 -351.917403) (xy 318.450428 -351.881689) (xy 318.414711 -351.840472) (xy 318.385224 -351.794592)
			(xy 318.362567 -351.744982) (xy 318.347201 -351.692653) (xy 318.339439 -351.638669) (xy 316.856736 -351.638669)
			(xy 316.856736 -351.638675) (xy 316.848972 -351.692671) (xy 316.833603 -351.745011) (xy 316.81094 -351.794632)
			(xy 316.781446 -351.840522) (xy 316.745722 -351.881747) (xy 316.704493 -351.917468) (xy 316.6586 -351.946958)
			(xy 316.608978 -351.969615) (xy 316.556636 -351.98498) (xy 316.502639 -351.992739) (xy 316.475364 -351.9932)
			(xy 315.611764 -351.9932) (xy 315.584499 -351.992635) (xy 315.530525 -351.98487) (xy 315.478205 -351.969503)
			(xy 315.428604 -351.946847) (xy 315.382732 -351.917363) (xy 315.341523 -351.881652) (xy 315.305815 -351.840439)
			(xy 315.276336 -351.794564) (xy 315.253684 -351.744962) (xy 315.238322 -351.69264) (xy 315.230562 -351.638665)
			(xy 313.747713 -351.638665) (xy 313.747713 -351.638672) (xy 313.739951 -351.692661) (xy 313.724584 -351.744995)
			(xy 313.701926 -351.79461) (xy 313.672438 -351.840495) (xy 313.636719 -351.881717) (xy 313.595498 -351.917435)
			(xy 313.549613 -351.946924) (xy 313.499999 -351.969583) (xy 313.447664 -351.98495) (xy 313.393676 -351.992713)
			(xy 313.366404 -351.9932) (xy 312.502804 -351.9932) (xy 312.475536 -351.992661) (xy 312.421554 -351.9849)
			(xy 312.369226 -351.969536) (xy 312.319617 -351.94688) (xy 312.273737 -351.917396) (xy 312.232521 -351.881682)
			(xy 312.196807 -351.840466) (xy 312.167321 -351.794587) (xy 312.144666 -351.744978) (xy 312.129301 -351.69265)
			(xy 312.121539 -351.638668) (xy 300.231613 -351.638668) (xy 300.231613 -351.638672) (xy 300.223851 -351.692661)
			(xy 300.208484 -351.744995) (xy 300.185826 -351.79461) (xy 300.156337 -351.840496) (xy 300.120619 -351.881717)
			(xy 300.079397 -351.917436) (xy 300.033512 -351.946925) (xy 299.983897 -351.969584) (xy 299.931563 -351.984951)
			(xy 299.877574 -351.992713) (xy 299.850302 -351.9932) (xy 298.986702 -351.9932) (xy 298.959434 -351.992661)
			(xy 298.905452 -351.9849) (xy 298.853124 -351.969535) (xy 298.803516 -351.94688) (xy 298.757636 -351.917395)
			(xy 298.71642 -351.881681) (xy 298.680706 -351.840465) (xy 298.651221 -351.794586) (xy 298.628566 -351.744978)
			(xy 298.613201 -351.69265) (xy 298.605439 -351.638668) (xy 297.122614 -351.638668) (xy 297.122614 -351.63867)
			(xy 297.114852 -351.692655) (xy 297.099488 -351.744987) (xy 297.076832 -351.794599) (xy 297.047347 -351.840483)
			(xy 297.011633 -351.881703) (xy 296.970416 -351.917422) (xy 296.924536 -351.946912) (xy 296.874926 -351.969573)
			(xy 296.822597 -351.984943) (xy 296.768612 -351.992711) (xy 296.741342 -351.9932) (xy 295.877742 -351.9932)
			(xy 295.850472 -351.992663) (xy 295.796486 -351.984907) (xy 295.744153 -351.969546) (xy 295.69454 -351.946893)
			(xy 295.648655 -351.917409) (xy 295.607434 -351.881695) (xy 295.571716 -351.840478) (xy 295.542227 -351.794597)
			(xy 295.519569 -351.744986) (xy 295.504202 -351.692655) (xy 295.49644 -351.63867) (xy 294.013736 -351.63867)
			(xy 294.013736 -351.638675) (xy 294.005973 -351.692668) (xy 293.990604 -351.745008) (xy 293.967943 -351.794627)
			(xy 293.938451 -351.840516) (xy 293.902728 -351.881741) (xy 293.861502 -351.917462) (xy 293.815611 -351.946952)
			(xy 293.765991 -351.969611) (xy 293.713651 -351.984977) (xy 293.659657 -351.992738) (xy 293.632382 -351.9932)
			(xy 292.768782 -351.9932) (xy 292.741516 -351.992636) (xy 292.68754 -351.984873) (xy 292.635218 -351.969508)
			(xy 292.585615 -351.946853) (xy 292.539741 -351.91737) (xy 292.498529 -351.881658) (xy 292.46282 -351.840445)
			(xy 292.433338 -351.794569) (xy 292.410686 -351.744965) (xy 292.395323 -351.692642) (xy 292.387562 -351.638666)
			(xy 290.904714 -351.638666) (xy 290.904714 -351.638671) (xy 290.896952 -351.692658) (xy 290.881586 -351.744991)
			(xy 290.858929 -351.794605) (xy 290.829442 -351.840489) (xy 290.793726 -351.88171) (xy 290.752507 -351.917429)
			(xy 290.706624 -351.946919) (xy 290.657012 -351.969578) (xy 290.60468 -351.984947) (xy 290.550693 -351.992712)
			(xy 290.523422 -351.9932) (xy 289.659822 -351.9932) (xy 289.632553 -351.992662) (xy 289.578569 -351.984903)
			(xy 289.526239 -351.96954) (xy 289.476628 -351.946886) (xy 289.430746 -351.917402) (xy 289.389527 -351.881688)
			(xy 289.353811 -351.840472) (xy 289.324324 -351.794592) (xy 289.301667 -351.744982) (xy 289.286301 -351.692653)
			(xy 289.278539 -351.638669) (xy 287.795836 -351.638669) (xy 287.795836 -351.638675) (xy 287.788072 -351.692671)
			(xy 287.772703 -351.745012) (xy 287.75004 -351.794633) (xy 287.720546 -351.840523) (xy 287.684821 -351.881748)
			(xy 287.643592 -351.917469) (xy 287.597699 -351.946958) (xy 287.548076 -351.969616) (xy 287.495734 -351.98498)
			(xy 287.441737 -351.992739) (xy 287.414462 -351.9932) (xy 286.550862 -351.9932) (xy 286.523597 -351.992635)
			(xy 286.469623 -351.98487) (xy 286.417303 -351.969503) (xy 286.367703 -351.946847) (xy 286.321831 -351.917363)
			(xy 286.280622 -351.881651) (xy 286.244915 -351.840438) (xy 286.215435 -351.794564) (xy 286.192784 -351.744961)
			(xy 286.177422 -351.69264) (xy 286.169662 -351.638665) (xy 284.686813 -351.638665) (xy 284.686813 -351.638672)
			(xy 284.679051 -351.692661) (xy 284.663684 -351.744995) (xy 284.641026 -351.79461) (xy 284.611537 -351.840496)
			(xy 284.575819 -351.881717) (xy 284.534597 -351.917436) (xy 284.488712 -351.946925) (xy 284.439097 -351.969584)
			(xy 284.386763 -351.984951) (xy 284.332774 -351.992713) (xy 284.305502 -351.9932) (xy 283.441902 -351.9932)
			(xy 283.414634 -351.992661) (xy 283.360652 -351.9849) (xy 283.308324 -351.969535) (xy 283.258716 -351.94688)
			(xy 283.212836 -351.917395) (xy 283.17162 -351.881681) (xy 283.135906 -351.840465) (xy 283.106421 -351.794586)
			(xy 283.083766 -351.744978) (xy 283.068401 -351.69265) (xy 283.060639 -351.638668) (xy 281.577814 -351.638668)
			(xy 281.577814 -351.63867) (xy 281.570052 -351.692655) (xy 281.554688 -351.744987) (xy 281.532032 -351.794599)
			(xy 281.502547 -351.840483) (xy 281.466833 -351.881703) (xy 281.425616 -351.917422) (xy 281.379736 -351.946912)
			(xy 281.330126 -351.969573) (xy 281.277797 -351.984943) (xy 281.223812 -351.992711) (xy 281.196542 -351.9932)
			(xy 280.332942 -351.9932) (xy 280.305672 -351.992663) (xy 280.251686 -351.984907) (xy 280.199353 -351.969546)
			(xy 280.14974 -351.946893) (xy 280.103855 -351.917409) (xy 280.062634 -351.881695) (xy 280.026916 -351.840478)
			(xy 279.997427 -351.794597) (xy 279.974769 -351.744986) (xy 279.959402 -351.692655) (xy 279.95164 -351.63867)
			(xy 278.468936 -351.63867) (xy 278.468936 -351.638675) (xy 278.461173 -351.692668) (xy 278.445804 -351.745008)
			(xy 278.423143 -351.794627) (xy 278.393651 -351.840516) (xy 278.357928 -351.881741) (xy 278.316702 -351.917462)
			(xy 278.270811 -351.946952) (xy 278.221191 -351.969611) (xy 278.168851 -351.984977) (xy 278.114857 -351.992738)
			(xy 278.087582 -351.9932) (xy 277.223982 -351.9932) (xy 277.196716 -351.992636) (xy 277.14274 -351.984873)
			(xy 277.090418 -351.969508) (xy 277.040815 -351.946853) (xy 276.994941 -351.91737) (xy 276.953729 -351.881658)
			(xy 276.91802 -351.840445) (xy 276.888538 -351.794569) (xy 276.865886 -351.744965) (xy 276.850523 -351.692642)
			(xy 276.842762 -351.638666) (xy 275.359914 -351.638666) (xy 275.359914 -351.638671) (xy 275.352152 -351.692658)
			(xy 275.336786 -351.744991) (xy 275.314129 -351.794605) (xy 275.284642 -351.840489) (xy 275.248926 -351.88171)
			(xy 275.207707 -351.917429) (xy 275.161824 -351.946919) (xy 275.112212 -351.969578) (xy 275.05988 -351.984947)
			(xy 275.005893 -351.992712) (xy 274.978622 -351.9932) (xy 274.115022 -351.9932) (xy 274.087753 -351.992662)
			(xy 274.033769 -351.984903) (xy 273.981439 -351.96954) (xy 273.931828 -351.946886) (xy 273.885946 -351.917402)
			(xy 273.844727 -351.881688) (xy 273.809011 -351.840472) (xy 273.779524 -351.794592) (xy 273.756867 -351.744982)
			(xy 273.741501 -351.692653) (xy 273.733739 -351.638669) (xy 272.251036 -351.638669) (xy 272.251036 -351.638675)
			(xy 272.243272 -351.692671) (xy 272.227903 -351.745012) (xy 272.20524 -351.794633) (xy 272.175746 -351.840523)
			(xy 272.140021 -351.881748) (xy 272.098792 -351.917469) (xy 272.052899 -351.946958) (xy 272.003276 -351.969616)
			(xy 271.950934 -351.98498) (xy 271.896937 -351.992739) (xy 271.869662 -351.9932) (xy 271.006062 -351.9932)
			(xy 270.978797 -351.992635) (xy 270.924823 -351.98487) (xy 270.872503 -351.969503) (xy 270.822903 -351.946847)
			(xy 270.777031 -351.917363) (xy 270.735822 -351.881651) (xy 270.700115 -351.840438) (xy 270.670635 -351.794564)
			(xy 270.647984 -351.744961) (xy 270.632622 -351.69264) (xy 270.624862 -351.638665) (xy 269.142013 -351.638665)
			(xy 269.142013 -351.638672) (xy 269.134251 -351.692661) (xy 269.118884 -351.744995) (xy 269.096226 -351.79461)
			(xy 269.066737 -351.840496) (xy 269.031019 -351.881717) (xy 268.989797 -351.917436) (xy 268.943912 -351.946925)
			(xy 268.894297 -351.969584) (xy 268.841963 -351.984951) (xy 268.787974 -351.992713) (xy 268.760702 -351.9932)
			(xy 267.897102 -351.9932) (xy 267.869834 -351.992661) (xy 267.815852 -351.9849) (xy 267.763524 -351.969535)
			(xy 267.713916 -351.94688) (xy 267.668036 -351.917395) (xy 267.62682 -351.881681) (xy 267.591106 -351.840465)
			(xy 267.561621 -351.794586) (xy 267.538966 -351.744978) (xy 267.523601 -351.69265) (xy 267.515839 -351.638668)
			(xy 194.520614 -351.638668) (xy 194.520614 -351.638672) (xy 194.512851 -351.692659) (xy 194.497485 -351.744993)
			(xy 194.474828 -351.794608) (xy 194.44534 -351.840492) (xy 194.409622 -351.881714) (xy 194.368402 -351.917433)
			(xy 194.322518 -351.946922) (xy 194.272904 -351.969581) (xy 194.220571 -351.984949) (xy 194.166584 -351.992713)
			(xy 194.139312 -351.9932) (xy 193.275712 -351.9932) (xy 193.248443 -351.992661) (xy 193.19446 -351.984901)
			(xy 193.142131 -351.969538) (xy 193.092522 -351.946883) (xy 193.046641 -351.917399) (xy 193.005424 -351.881685)
			(xy 192.969708 -351.840469) (xy 192.940223 -351.794589) (xy 192.917566 -351.74498) (xy 192.902201 -351.692651)
			(xy 192.894439 -351.638669) (xy 191.411736 -351.638669) (xy 191.411736 -351.638676) (xy 191.403972 -351.692672)
			(xy 191.388602 -351.745014) (xy 191.365939 -351.794635) (xy 191.336444 -351.840526) (xy 191.300717 -351.881751)
			(xy 191.259487 -351.917472) (xy 191.213593 -351.946962) (xy 191.163969 -351.969619) (xy 191.111625 -351.984982)
			(xy 191.057628 -351.99274) (xy 191.030352 -351.9932) (xy 190.166752 -351.9932) (xy 190.139488 -351.992634)
			(xy 190.085515 -351.984868) (xy 190.033196 -351.9695) (xy 189.983597 -351.946843) (xy 189.937726 -351.917359)
			(xy 189.896519 -351.881647) (xy 189.860812 -351.840435) (xy 189.831334 -351.794561) (xy 189.808683 -351.744959)
			(xy 189.793322 -351.692639) (xy 189.785562 -351.638664) (xy 188.302736 -351.638664) (xy 188.302736 -351.638674)
			(xy 188.294973 -351.692667) (xy 188.279605 -351.745006) (xy 188.256945 -351.794624) (xy 188.227453 -351.840513)
			(xy 188.191732 -351.881737) (xy 188.150506 -351.917458) (xy 188.104617 -351.946949) (xy 188.054998 -351.969608)
			(xy 188.002659 -351.984975) (xy 187.948666 -351.992737) (xy 187.921392 -351.9932) (xy 187.057792 -351.9932)
			(xy 187.030526 -351.992637) (xy 186.976548 -351.984875) (xy 186.924225 -351.969511) (xy 186.874621 -351.946856)
			(xy 186.828745 -351.917373) (xy 186.787533 -351.881662) (xy 186.751822 -351.840448) (xy 186.72234 -351.794572)
			(xy 186.699686 -351.744968) (xy 186.684323 -351.692644) (xy 186.676562 -351.638666) (xy 185.193714 -351.638666)
			(xy 185.193714 -351.638671) (xy 185.185952 -351.692657) (xy 185.170587 -351.744989) (xy 185.147931 -351.794602)
			(xy 185.118445 -351.840486) (xy 185.082729 -351.881707) (xy 185.041512 -351.917426) (xy 184.99563 -351.946915)
			(xy 184.946019 -351.969576) (xy 184.893688 -351.984945) (xy 184.839703 -351.992711) (xy 184.812432 -351.9932)
			(xy 183.948832 -351.9932) (xy 183.921562 -351.992663) (xy 183.867577 -351.984905) (xy 183.815246 -351.969543)
			(xy 183.765634 -351.94689) (xy 183.719751 -351.917406) (xy 183.678531 -351.881692) (xy 183.642813 -351.840475)
			(xy 183.613326 -351.794594) (xy 183.590668 -351.744984) (xy 183.575302 -351.692654) (xy 183.567539 -351.63867)
			(xy 182.084836 -351.63867) (xy 182.084836 -351.638675) (xy 182.077073 -351.69267) (xy 182.061703 -351.74501)
			(xy 182.039042 -351.79463) (xy 182.009548 -351.840519) (xy 181.973824 -351.881744) (xy 181.932597 -351.917465)
			(xy 181.886705 -351.946955) (xy 181.837084 -351.969613) (xy 181.784742 -351.984979) (xy 181.730747 -351.992738)
			(xy 181.703472 -351.9932) (xy 180.839872 -351.9932) (xy 180.812607 -351.992636) (xy 180.758631 -351.984872)
			(xy 180.70631 -351.969505) (xy 180.656709 -351.94685) (xy 180.610836 -351.917366) (xy 180.569626 -351.881654)
			(xy 180.533917 -351.840442) (xy 180.504437 -351.794567) (xy 180.481785 -351.744963) (xy 180.466422 -351.692641)
			(xy 180.458662 -351.638665) (xy 178.975814 -351.638665) (xy 178.975814 -351.638672) (xy 178.968051 -351.692659)
			(xy 178.952685 -351.744993) (xy 178.930028 -351.794608) (xy 178.90054 -351.840492) (xy 178.864822 -351.881714)
			(xy 178.823602 -351.917433) (xy 178.777718 -351.946922) (xy 178.728104 -351.969581) (xy 178.675771 -351.984949)
			(xy 178.621784 -351.992713) (xy 178.594512 -351.9932) (xy 177.730912 -351.9932) (xy 177.703643 -351.992661)
			(xy 177.64966 -351.984901) (xy 177.597331 -351.969538) (xy 177.547722 -351.946883) (xy 177.501841 -351.917399)
			(xy 177.460624 -351.881685) (xy 177.424908 -351.840469) (xy 177.395423 -351.794589) (xy 177.372766 -351.74498)
			(xy 177.357401 -351.692651) (xy 177.349639 -351.638669) (xy 175.866936 -351.638669) (xy 175.866936 -351.638676)
			(xy 175.859172 -351.692672) (xy 175.843802 -351.745014) (xy 175.821139 -351.794635) (xy 175.791644 -351.840526)
			(xy 175.755917 -351.881751) (xy 175.714687 -351.917472) (xy 175.668793 -351.946962) (xy 175.619169 -351.969619)
			(xy 175.566825 -351.984982) (xy 175.512828 -351.99274) (xy 175.485552 -351.9932) (xy 174.621952 -351.9932)
			(xy 174.594688 -351.992634) (xy 174.540715 -351.984868) (xy 174.488396 -351.9695) (xy 174.438797 -351.946843)
			(xy 174.392926 -351.917359) (xy 174.351719 -351.881647) (xy 174.316012 -351.840435) (xy 174.286534 -351.794561)
			(xy 174.263883 -351.744959) (xy 174.248522 -351.692639) (xy 174.240762 -351.638664) (xy 172.757936 -351.638664)
			(xy 172.757936 -351.638674) (xy 172.750173 -351.692667) (xy 172.734805 -351.745006) (xy 172.712145 -351.794624)
			(xy 172.682653 -351.840513) (xy 172.646932 -351.881737) (xy 172.605706 -351.917458) (xy 172.559817 -351.946949)
			(xy 172.510198 -351.969608) (xy 172.457859 -351.984975) (xy 172.403866 -351.992737) (xy 172.376592 -351.9932)
			(xy 171.512992 -351.9932) (xy 171.485726 -351.992637) (xy 171.431748 -351.984875) (xy 171.379425 -351.969511)
			(xy 171.329821 -351.946856) (xy 171.283945 -351.917373) (xy 171.242733 -351.881662) (xy 171.207022 -351.840448)
			(xy 171.17754 -351.794572) (xy 171.154886 -351.744968) (xy 171.139523 -351.692644) (xy 171.131762 -351.638666)
			(xy 169.648914 -351.638666) (xy 169.648914 -351.638671) (xy 169.641152 -351.692657) (xy 169.625787 -351.744989)
			(xy 169.603131 -351.794602) (xy 169.573645 -351.840486) (xy 169.537929 -351.881707) (xy 169.496712 -351.917426)
			(xy 169.45083 -351.946915) (xy 169.401219 -351.969576) (xy 169.348888 -351.984945) (xy 169.294903 -351.992711)
			(xy 169.267632 -351.9932) (xy 168.404032 -351.9932) (xy 168.376762 -351.992663) (xy 168.322777 -351.984905)
			(xy 168.270446 -351.969543) (xy 168.220834 -351.94689) (xy 168.174951 -351.917406) (xy 168.133731 -351.881692)
			(xy 168.098013 -351.840475) (xy 168.068526 -351.794594) (xy 168.045868 -351.744984) (xy 168.030502 -351.692654)
			(xy 168.022739 -351.63867) (xy 166.540036 -351.63867) (xy 166.540036 -351.638675) (xy 166.532273 -351.69267)
			(xy 166.516903 -351.74501) (xy 166.494242 -351.79463) (xy 166.464748 -351.840519) (xy 166.429024 -351.881744)
			(xy 166.387797 -351.917465) (xy 166.341905 -351.946955) (xy 166.292284 -351.969613) (xy 166.239942 -351.984979)
			(xy 166.185947 -351.992738) (xy 166.158672 -351.9932) (xy 165.295072 -351.9932) (xy 165.267807 -351.992636)
			(xy 165.213831 -351.984872) (xy 165.16151 -351.969505) (xy 165.111909 -351.94685) (xy 165.066036 -351.917366)
			(xy 165.024826 -351.881654) (xy 164.989117 -351.840442) (xy 164.959637 -351.794567) (xy 164.936985 -351.744963)
			(xy 164.921622 -351.692641) (xy 164.913862 -351.638665) (xy 163.431014 -351.638665) (xy 163.431014 -351.638672)
			(xy 163.423251 -351.692659) (xy 163.407885 -351.744993) (xy 163.385228 -351.794608) (xy 163.35574 -351.840492)
			(xy 163.320022 -351.881714) (xy 163.278802 -351.917433) (xy 163.232918 -351.946922) (xy 163.183304 -351.969581)
			(xy 163.130971 -351.984949) (xy 163.076984 -351.992713) (xy 163.049712 -351.9932) (xy 162.186112 -351.9932)
			(xy 162.158843 -351.992661) (xy 162.10486 -351.984901) (xy 162.052531 -351.969538) (xy 162.002922 -351.946883)
			(xy 161.957041 -351.917399) (xy 161.915824 -351.881685) (xy 161.880108 -351.840469) (xy 161.850623 -351.794589)
			(xy 161.827966 -351.74498) (xy 161.812601 -351.692651) (xy 161.804839 -351.638669) (xy 144.196614 -351.638669)
			(xy 144.196614 -351.638672) (xy 144.188851 -351.69266) (xy 144.173485 -351.744994) (xy 144.150827 -351.794609)
			(xy 144.121339 -351.840494) (xy 144.085621 -351.881715) (xy 144.0444 -351.917434) (xy 143.998516 -351.946923)
			(xy 143.948902 -351.969582) (xy 143.896568 -351.98495) (xy 143.84258 -351.992713) (xy 143.815308 -351.9932)
			(xy 142.951708 -351.9932) (xy 142.924439 -351.992661) (xy 142.870457 -351.984901) (xy 142.818129 -351.969537)
			(xy 142.768519 -351.946882) (xy 142.722639 -351.917397) (xy 142.681422 -351.881683) (xy 142.645707 -351.840467)
			(xy 142.616222 -351.794588) (xy 142.593566 -351.744979) (xy 142.578201 -351.692651) (xy 142.570439 -351.638669)
			(xy 141.087614 -351.638669) (xy 141.087614 -351.63867) (xy 141.079852 -351.692655) (xy 141.064488 -351.744986)
			(xy 141.041833 -351.794597) (xy 141.012349 -351.840481) (xy 140.976635 -351.881701) (xy 140.935419 -351.91742)
			(xy 140.88954 -351.94691) (xy 140.839931 -351.969571) (xy 140.787602 -351.984942) (xy 140.733618 -351.99271)
			(xy 140.706348 -351.9932) (xy 139.842748 -351.9932) (xy 139.815477 -351.992664) (xy 139.761491 -351.984908)
			(xy 139.709158 -351.969547) (xy 139.659543 -351.946895) (xy 139.613658 -351.917411) (xy 139.572436 -351.881698)
			(xy 139.536717 -351.84048) (xy 139.507228 -351.794599) (xy 139.484569 -351.744987) (xy 139.469202 -351.692656)
			(xy 139.46144 -351.63867) (xy 137.978736 -351.63867) (xy 137.978736 -351.638674) (xy 137.970973 -351.692668)
			(xy 137.955605 -351.745006) (xy 137.932944 -351.794625) (xy 137.903452 -351.840514) (xy 137.86773 -351.881739)
			(xy 137.826504 -351.91746) (xy 137.780615 -351.94695) (xy 137.730995 -351.969609) (xy 137.678656 -351.984976)
			(xy 137.624662 -351.992737) (xy 137.597388 -351.9932) (xy 136.733788 -351.9932) (xy 136.706522 -351.992637)
			(xy 136.652545 -351.984875) (xy 136.600222 -351.96951) (xy 136.550618 -351.946855) (xy 136.504744 -351.917372)
			(xy 136.463531 -351.88166) (xy 136.427821 -351.840447) (xy 136.398339 -351.794571) (xy 136.375686 -351.744967)
			(xy 136.360323 -351.692643) (xy 136.352562 -351.638666) (xy 134.869714 -351.638666) (xy 134.869714 -351.638671)
			(xy 134.861952 -351.692657) (xy 134.846586 -351.74499) (xy 134.82393 -351.794603) (xy 134.794444 -351.840487)
			(xy 134.758728 -351.881708) (xy 134.71751 -351.917427) (xy 134.671628 -351.946917) (xy 134.622016 -351.969577)
			(xy 134.569685 -351.984946) (xy 134.515699 -351.992712) (xy 134.488428 -351.9932) (xy 133.624828 -351.9932)
			(xy 133.597558 -351.992663) (xy 133.543574 -351.984904) (xy 133.491243 -351.969542) (xy 133.441631 -351.946888)
			(xy 133.395749 -351.917404) (xy 133.354529 -351.881691) (xy 133.318812 -351.840474) (xy 133.289325 -351.794593)
			(xy 133.266668 -351.744983) (xy 133.251302 -351.692654) (xy 133.243539 -351.63867) (xy 131.760836 -351.63867)
			(xy 131.760836 -351.638675) (xy 131.753073 -351.69267) (xy 131.737703 -351.745011) (xy 131.715041 -351.794631)
			(xy 131.685547 -351.840521) (xy 131.649823 -351.881746) (xy 131.608595 -351.917467) (xy 131.562703 -351.946956)
			(xy 131.513081 -351.969614) (xy 131.460739 -351.984979) (xy 131.406743 -351.992739) (xy 131.379468 -351.9932)
			(xy 130.515868 -351.9932) (xy 130.488603 -351.992635) (xy 130.434628 -351.984871) (xy 130.382308 -351.969504)
			(xy 130.332706 -351.946849) (xy 130.286834 -351.917365) (xy 130.245624 -351.881653) (xy 130.209916 -351.84044)
			(xy 130.180436 -351.794566) (xy 130.157784 -351.744962) (xy 130.142422 -351.692641) (xy 130.134662 -351.638665)
			(xy 128.651814 -351.638665) (xy 128.651814 -351.638672) (xy 128.644051 -351.69266) (xy 128.628685 -351.744994)
			(xy 128.606027 -351.794609) (xy 128.576539 -351.840494) (xy 128.540821 -351.881715) (xy 128.4996 -351.917434)
			(xy 128.453716 -351.946923) (xy 128.404102 -351.969582) (xy 128.351768 -351.98495) (xy 128.29778 -351.992713)
			(xy 128.270508 -351.9932) (xy 127.406908 -351.9932) (xy 127.379639 -351.992661) (xy 127.325657 -351.984901)
			(xy 127.273329 -351.969537) (xy 127.223719 -351.946882) (xy 127.177839 -351.917397) (xy 127.136622 -351.881683)
			(xy 127.100907 -351.840467) (xy 127.071422 -351.794588) (xy 127.048766 -351.744979) (xy 127.033401 -351.692651)
			(xy 127.025639 -351.638669) (xy 125.542814 -351.638669) (xy 125.542814 -351.63867) (xy 125.535052 -351.692655)
			(xy 125.519688 -351.744986) (xy 125.497033 -351.794597) (xy 125.467549 -351.840481) (xy 125.431835 -351.881701)
			(xy 125.390619 -351.91742) (xy 125.34474 -351.94691) (xy 125.295131 -351.969571) (xy 125.242802 -351.984942)
			(xy 125.188818 -351.99271) (xy 125.161548 -351.9932) (xy 124.297948 -351.9932) (xy 124.270677 -351.992664)
			(xy 124.216691 -351.984908) (xy 124.164358 -351.969547) (xy 124.114743 -351.946895) (xy 124.068858 -351.917411)
			(xy 124.027636 -351.881698) (xy 123.991917 -351.84048) (xy 123.962428 -351.794599) (xy 123.939769 -351.744987)
			(xy 123.924402 -351.692656) (xy 123.91664 -351.63867) (xy 122.433936 -351.63867) (xy 122.433936 -351.638674)
			(xy 122.426173 -351.692668) (xy 122.410805 -351.745006) (xy 122.388144 -351.794625) (xy 122.358652 -351.840514)
			(xy 122.32293 -351.881739) (xy 122.281704 -351.91746) (xy 122.235815 -351.94695) (xy 122.186195 -351.969609)
			(xy 122.133856 -351.984976) (xy 122.079862 -351.992737) (xy 122.052588 -351.9932) (xy 121.188988 -351.9932)
			(xy 121.161722 -351.992637) (xy 121.107745 -351.984875) (xy 121.055422 -351.96951) (xy 121.005818 -351.946855)
			(xy 120.959944 -351.917372) (xy 120.918731 -351.88166) (xy 120.883021 -351.840447) (xy 120.853539 -351.794571)
			(xy 120.830886 -351.744967) (xy 120.815523 -351.692643) (xy 120.807762 -351.638666) (xy 119.324914 -351.638666)
			(xy 119.324914 -351.638671) (xy 119.317152 -351.692657) (xy 119.301786 -351.74499) (xy 119.27913 -351.794603)
			(xy 119.249644 -351.840487) (xy 119.213928 -351.881708) (xy 119.17271 -351.917427) (xy 119.126828 -351.946917)
			(xy 119.077216 -351.969577) (xy 119.024885 -351.984946) (xy 118.970899 -351.992712) (xy 118.943628 -351.9932)
			(xy 118.080028 -351.9932) (xy 118.052758 -351.992663) (xy 117.998774 -351.984904) (xy 117.946443 -351.969542)
			(xy 117.896831 -351.946888) (xy 117.850949 -351.917404) (xy 117.809729 -351.881691) (xy 117.774012 -351.840474)
			(xy 117.744525 -351.794593) (xy 117.721868 -351.744983) (xy 117.706502 -351.692654) (xy 117.698739 -351.63867)
			(xy 116.216036 -351.63867) (xy 116.216036 -351.638675) (xy 116.208273 -351.69267) (xy 116.192903 -351.745011)
			(xy 116.170241 -351.794631) (xy 116.140747 -351.840521) (xy 116.105023 -351.881746) (xy 116.063795 -351.917467)
			(xy 116.017903 -351.946956) (xy 115.968281 -351.969614) (xy 115.915939 -351.984979) (xy 115.861943 -351.992739)
			(xy 115.834668 -351.9932) (xy 114.971068 -351.9932) (xy 114.943803 -351.992635) (xy 114.889828 -351.984871)
			(xy 114.837508 -351.969504) (xy 114.787906 -351.946849) (xy 114.742034 -351.917365) (xy 114.700824 -351.881653)
			(xy 114.665116 -351.84044) (xy 114.635636 -351.794566) (xy 114.612984 -351.744962) (xy 114.597622 -351.692641)
			(xy 114.589862 -351.638665) (xy 113.107014 -351.638665) (xy 113.107014 -351.638672) (xy 113.099251 -351.69266)
			(xy 113.083885 -351.744994) (xy 113.061227 -351.794609) (xy 113.031739 -351.840494) (xy 112.996021 -351.881715)
			(xy 112.9548 -351.917434) (xy 112.908916 -351.946923) (xy 112.859302 -351.969582) (xy 112.806968 -351.98495)
			(xy 112.75298 -351.992713) (xy 112.725708 -351.9932) (xy 111.862108 -351.9932) (xy 111.834839 -351.992661)
			(xy 111.780857 -351.984901) (xy 111.728529 -351.969537) (xy 111.678919 -351.946882) (xy 111.633039 -351.917397)
			(xy 111.591822 -351.881683) (xy 111.556107 -351.840467) (xy 111.526622 -351.794588) (xy 111.503966 -351.744979)
			(xy 111.488601 -351.692651) (xy 111.480839 -351.638669) (xy 93.706714 -351.638669) (xy 93.706714 -351.63867)
			(xy 93.698952 -351.692655) (xy 93.683588 -351.744987) (xy 93.660932 -351.794599) (xy 93.631447 -351.840483)
			(xy 93.595733 -351.881703) (xy 93.554516 -351.917422) (xy 93.508636 -351.946912) (xy 93.459026 -351.969573)
			(xy 93.406697 -351.984943) (xy 93.352712 -351.992711) (xy 93.325442 -351.9932) (xy 92.461842 -351.9932)
			(xy 92.434572 -351.992663) (xy 92.380586 -351.984907) (xy 92.328253 -351.969546) (xy 92.27864 -351.946893)
			(xy 92.232755 -351.917409) (xy 92.191534 -351.881695) (xy 92.155816 -351.840478) (xy 92.126327 -351.794597)
			(xy 92.103669 -351.744986) (xy 92.088302 -351.692655) (xy 92.08054 -351.63867) (xy 90.597836 -351.63867)
			(xy 90.597836 -351.638675) (xy 90.590073 -351.692668) (xy 90.574704 -351.745008) (xy 90.552043 -351.794627)
			(xy 90.522551 -351.840516) (xy 90.486828 -351.881741) (xy 90.445602 -351.917462) (xy 90.399711 -351.946952)
			(xy 90.350091 -351.969611) (xy 90.297751 -351.984977) (xy 90.243757 -351.992738) (xy 90.216482 -351.9932)
			(xy 89.352882 -351.9932) (xy 89.325616 -351.992636) (xy 89.27164 -351.984873) (xy 89.219318 -351.969508)
			(xy 89.169715 -351.946853) (xy 89.123841 -351.91737) (xy 89.082629 -351.881658) (xy 89.04692 -351.840445)
			(xy 89.017438 -351.794569) (xy 88.994786 -351.744965) (xy 88.979423 -351.692642) (xy 88.971662 -351.638666)
			(xy 87.488814 -351.638666) (xy 87.488814 -351.638671) (xy 87.481052 -351.692658) (xy 87.465686 -351.744991)
			(xy 87.443029 -351.794605) (xy 87.413542 -351.840489) (xy 87.377826 -351.88171) (xy 87.336607 -351.917429)
			(xy 87.290724 -351.946919) (xy 87.241112 -351.969578) (xy 87.18878 -351.984947) (xy 87.134793 -351.992712)
			(xy 87.107522 -351.9932) (xy 86.243922 -351.9932) (xy 86.216653 -351.992662) (xy 86.162669 -351.984903)
			(xy 86.110339 -351.96954) (xy 86.060728 -351.946886) (xy 86.014846 -351.917402) (xy 85.973627 -351.881688)
			(xy 85.937911 -351.840472) (xy 85.908424 -351.794592) (xy 85.885767 -351.744982) (xy 85.870401 -351.692653)
			(xy 85.862639 -351.638669) (xy 84.379936 -351.638669) (xy 84.379936 -351.638675) (xy 84.372172 -351.692671)
			(xy 84.356803 -351.745012) (xy 84.33414 -351.794633) (xy 84.304646 -351.840523) (xy 84.268921 -351.881748)
			(xy 84.227692 -351.917469) (xy 84.181799 -351.946958) (xy 84.132176 -351.969616) (xy 84.079834 -351.98498)
			(xy 84.025837 -351.992739) (xy 83.998562 -351.9932) (xy 83.134962 -351.9932) (xy 83.107697 -351.992635)
			(xy 83.053723 -351.98487) (xy 83.001403 -351.969503) (xy 82.951803 -351.946847) (xy 82.905931 -351.917363)
			(xy 82.864722 -351.881651) (xy 82.829015 -351.840438) (xy 82.799535 -351.794564) (xy 82.776884 -351.744961)
			(xy 82.761522 -351.69264) (xy 82.753762 -351.638665) (xy 81.270913 -351.638665) (xy 81.270913 -351.638672)
			(xy 81.263151 -351.692661) (xy 81.247784 -351.744995) (xy 81.225126 -351.79461) (xy 81.195637 -351.840496)
			(xy 81.159919 -351.881717) (xy 81.118697 -351.917436) (xy 81.072812 -351.946925) (xy 81.023197 -351.969584)
			(xy 80.970863 -351.984951) (xy 80.916874 -351.992713) (xy 80.889602 -351.9932) (xy 80.026002 -351.9932)
			(xy 79.998734 -351.992661) (xy 79.944752 -351.9849) (xy 79.892424 -351.969535) (xy 79.842816 -351.94688)
			(xy 79.796936 -351.917395) (xy 79.75572 -351.881681) (xy 79.720006 -351.840465) (xy 79.690521 -351.794586)
			(xy 79.667866 -351.744978) (xy 79.652501 -351.69265) (xy 79.644739 -351.638668) (xy 78.161914 -351.638668)
			(xy 78.161914 -351.63867) (xy 78.154152 -351.692655) (xy 78.138788 -351.744987) (xy 78.116132 -351.794599)
			(xy 78.086647 -351.840483) (xy 78.050933 -351.881703) (xy 78.009716 -351.917422) (xy 77.963836 -351.946912)
			(xy 77.914226 -351.969573) (xy 77.861897 -351.984943) (xy 77.807912 -351.992711) (xy 77.780642 -351.9932)
			(xy 76.917042 -351.9932) (xy 76.889772 -351.992663) (xy 76.835786 -351.984907) (xy 76.783453 -351.969546)
			(xy 76.73384 -351.946893) (xy 76.687955 -351.917409) (xy 76.646734 -351.881695) (xy 76.611016 -351.840478)
			(xy 76.581527 -351.794597) (xy 76.558869 -351.744986) (xy 76.543502 -351.692655) (xy 76.53574 -351.63867)
			(xy 75.053036 -351.63867) (xy 75.053036 -351.638675) (xy 75.045273 -351.692668) (xy 75.029904 -351.745008)
			(xy 75.007243 -351.794627) (xy 74.977751 -351.840516) (xy 74.942028 -351.881741) (xy 74.900802 -351.917462)
			(xy 74.854911 -351.946952) (xy 74.805291 -351.969611) (xy 74.752951 -351.984977) (xy 74.698957 -351.992738)
			(xy 74.671682 -351.9932) (xy 73.808082 -351.9932) (xy 73.780816 -351.992636) (xy 73.72684 -351.984873)
			(xy 73.674518 -351.969508) (xy 73.624915 -351.946853) (xy 73.579041 -351.91737) (xy 73.537829 -351.881658)
			(xy 73.50212 -351.840445) (xy 73.472638 -351.794569) (xy 73.449986 -351.744965) (xy 73.434623 -351.692642)
			(xy 73.426862 -351.638666) (xy 71.944014 -351.638666) (xy 71.944014 -351.638671) (xy 71.936252 -351.692658)
			(xy 71.920886 -351.744991) (xy 71.898229 -351.794605) (xy 71.868742 -351.840489) (xy 71.833026 -351.88171)
			(xy 71.791807 -351.917429) (xy 71.745924 -351.946919) (xy 71.696312 -351.969578) (xy 71.64398 -351.984947)
			(xy 71.589993 -351.992712) (xy 71.562722 -351.9932) (xy 70.699122 -351.9932) (xy 70.671853 -351.992662)
			(xy 70.617869 -351.984903) (xy 70.565539 -351.96954) (xy 70.515928 -351.946886) (xy 70.470046 -351.917402)
			(xy 70.428827 -351.881688) (xy 70.393111 -351.840472) (xy 70.363624 -351.794592) (xy 70.340967 -351.744982)
			(xy 70.325601 -351.692653) (xy 70.317839 -351.638669) (xy 68.835136 -351.638669) (xy 68.835136 -351.638675)
			(xy 68.827372 -351.692671) (xy 68.812003 -351.745012) (xy 68.78934 -351.794633) (xy 68.759846 -351.840523)
			(xy 68.724121 -351.881748) (xy 68.682892 -351.917469) (xy 68.636999 -351.946958) (xy 68.587376 -351.969616)
			(xy 68.535034 -351.98498) (xy 68.481037 -351.992739) (xy 68.453762 -351.9932) (xy 67.590162 -351.9932)
			(xy 67.562897 -351.992635) (xy 67.508923 -351.98487) (xy 67.456603 -351.969503) (xy 67.407003 -351.946847)
			(xy 67.361131 -351.917363) (xy 67.319922 -351.881651) (xy 67.284215 -351.840438) (xy 67.254735 -351.794564)
			(xy 67.232084 -351.744961) (xy 67.216722 -351.69264) (xy 67.208962 -351.638665) (xy 65.726113 -351.638665)
			(xy 65.726113 -351.638672) (xy 65.718351 -351.692661) (xy 65.702984 -351.744995) (xy 65.680326 -351.79461)
			(xy 65.650837 -351.840496) (xy 65.615119 -351.881717) (xy 65.573897 -351.917436) (xy 65.528012 -351.946925)
			(xy 65.478397 -351.969584) (xy 65.426063 -351.984951) (xy 65.372074 -351.992713) (xy 65.344802 -351.9932)
			(xy 64.481202 -351.9932) (xy 64.453934 -351.992661) (xy 64.399952 -351.9849) (xy 64.347624 -351.969535)
			(xy 64.298016 -351.94688) (xy 64.252136 -351.917395) (xy 64.21092 -351.881681) (xy 64.175206 -351.840465)
			(xy 64.145721 -351.794586) (xy 64.123066 -351.744978) (xy 64.107701 -351.69265) (xy 64.099939 -351.638668)
			(xy 62.617114 -351.638668) (xy 62.617114 -351.63867) (xy 62.609352 -351.692655) (xy 62.593988 -351.744987)
			(xy 62.571332 -351.794599) (xy 62.541847 -351.840483) (xy 62.506133 -351.881703) (xy 62.464916 -351.917422)
			(xy 62.419036 -351.946912) (xy 62.369426 -351.969573) (xy 62.317097 -351.984943) (xy 62.263112 -351.992711)
			(xy 62.235842 -351.9932) (xy 61.372242 -351.9932) (xy 61.344972 -351.992663) (xy 61.290986 -351.984907)
			(xy 61.238653 -351.969546) (xy 61.18904 -351.946893) (xy 61.143155 -351.917409) (xy 61.101934 -351.881695)
			(xy 61.066216 -351.840478) (xy 61.036727 -351.794597) (xy 61.014069 -351.744986) (xy 60.998702 -351.692655)
			(xy 60.99094 -351.63867) (xy 51.666914 -351.63867) (xy 51.659152 -351.692655) (xy 51.643788 -351.744986)
			(xy 51.621133 -351.794597) (xy 51.591649 -351.840481) (xy 51.555935 -351.881701) (xy 51.514719 -351.91742)
			(xy 51.46884 -351.94691) (xy 51.419231 -351.969571) (xy 51.366902 -351.984942) (xy 51.312918 -351.99271)
			(xy 51.285648 -351.9932) (xy 50.422048 -351.9932) (xy 50.394777 -351.992664) (xy 50.340791 -351.984908)
			(xy 50.288458 -351.969547) (xy 50.238843 -351.946895) (xy 50.192958 -351.917411) (xy 50.151736 -351.881698)
			(xy 50.116017 -351.84048) (xy 50.086528 -351.794599) (xy 50.063869 -351.744987) (xy 50.048502 -351.692656)
			(xy 50.04074 -351.63867) (xy 48.558036 -351.63867) (xy 48.558036 -351.638674) (xy 48.550273 -351.692668)
			(xy 48.534905 -351.745006) (xy 48.512244 -351.794625) (xy 48.482752 -351.840514) (xy 48.44703 -351.881739)
			(xy 48.405804 -351.91746) (xy 48.359915 -351.94695) (xy 48.310295 -351.969609) (xy 48.257956 -351.984976)
			(xy 48.203962 -351.992737) (xy 48.176688 -351.9932) (xy 47.313088 -351.9932) (xy 47.285822 -351.992637)
			(xy 47.231845 -351.984875) (xy 47.179522 -351.96951) (xy 47.129918 -351.946855) (xy 47.084044 -351.917372)
			(xy 47.042831 -351.88166) (xy 47.007121 -351.840447) (xy 46.977639 -351.794571) (xy 46.954986 -351.744967)
			(xy 46.939623 -351.692643) (xy 46.931862 -351.638666) (xy 45.449014 -351.638666) (xy 45.449014 -351.638671)
			(xy 45.441252 -351.692657) (xy 45.425886 -351.74499) (xy 45.40323 -351.794603) (xy 45.373744 -351.840487)
			(xy 45.338028 -351.881708) (xy 45.29681 -351.917427) (xy 45.250928 -351.946917) (xy 45.201316 -351.969577)
			(xy 45.148985 -351.984946) (xy 45.094999 -351.992712) (xy 45.067728 -351.9932) (xy 44.204128 -351.9932)
			(xy 44.176858 -351.992663) (xy 44.122874 -351.984904) (xy 44.070543 -351.969542) (xy 44.020931 -351.946888)
			(xy 43.975049 -351.917404) (xy 43.933829 -351.881691) (xy 43.898112 -351.840474) (xy 43.868625 -351.794593)
			(xy 43.845968 -351.744983) (xy 43.830602 -351.692654) (xy 43.822839 -351.63867) (xy 42.340136 -351.63867)
			(xy 42.340136 -351.638675) (xy 42.332373 -351.69267) (xy 42.317003 -351.745011) (xy 42.294341 -351.794631)
			(xy 42.264847 -351.840521) (xy 42.229123 -351.881746) (xy 42.187895 -351.917467) (xy 42.142003 -351.946956)
			(xy 42.092381 -351.969614) (xy 42.040039 -351.984979) (xy 41.986043 -351.992739) (xy 41.958768 -351.9932)
			(xy 41.095168 -351.9932) (xy 41.067903 -351.992635) (xy 41.013928 -351.984871) (xy 40.961608 -351.969504)
			(xy 40.912006 -351.946849) (xy 40.866134 -351.917365) (xy 40.824924 -351.881653) (xy 40.789216 -351.84044)
			(xy 40.759736 -351.794566) (xy 40.737084 -351.744962) (xy 40.721722 -351.692641) (xy 40.713962 -351.638665)
			(xy 39.231114 -351.638665) (xy 39.231114 -351.638672) (xy 39.223351 -351.69266) (xy 39.207985 -351.744994)
			(xy 39.185327 -351.794609) (xy 39.155839 -351.840494) (xy 39.120121 -351.881715) (xy 39.0789 -351.917434)
			(xy 39.033016 -351.946923) (xy 38.983402 -351.969582) (xy 38.931068 -351.98495) (xy 38.87708 -351.992713)
			(xy 38.849808 -351.9932) (xy 37.986208 -351.9932) (xy 37.958939 -351.992661) (xy 37.904957 -351.984901)
			(xy 37.852629 -351.969537) (xy 37.803019 -351.946882) (xy 37.757139 -351.917397) (xy 37.715922 -351.881683)
			(xy 37.680207 -351.840467) (xy 37.650722 -351.794588) (xy 37.628066 -351.744979) (xy 37.612701 -351.692651)
			(xy 37.604939 -351.638669) (xy 36.122114 -351.638669) (xy 36.122114 -351.63867) (xy 36.114352 -351.692655)
			(xy 36.098988 -351.744986) (xy 36.076333 -351.794597) (xy 36.046849 -351.840481) (xy 36.011135 -351.881701)
			(xy 35.969919 -351.91742) (xy 35.92404 -351.94691) (xy 35.874431 -351.969571) (xy 35.822102 -351.984942)
			(xy 35.768118 -351.99271) (xy 35.740848 -351.9932) (xy 34.877248 -351.9932) (xy 34.849977 -351.992664)
			(xy 34.795991 -351.984908) (xy 34.743658 -351.969547) (xy 34.694043 -351.946895) (xy 34.648158 -351.917411)
			(xy 34.606936 -351.881698) (xy 34.571217 -351.84048) (xy 34.541728 -351.794599) (xy 34.519069 -351.744987)
			(xy 34.503702 -351.692656) (xy 34.49594 -351.63867) (xy 33.013236 -351.63867) (xy 33.013236 -351.638674)
			(xy 33.005473 -351.692668) (xy 32.990105 -351.745006) (xy 32.967444 -351.794625) (xy 32.937952 -351.840514)
			(xy 32.90223 -351.881739) (xy 32.861004 -351.91746) (xy 32.815115 -351.94695) (xy 32.765495 -351.969609)
			(xy 32.713156 -351.984976) (xy 32.659162 -351.992737) (xy 32.631888 -351.9932) (xy 31.768288 -351.9932)
			(xy 31.741022 -351.992637) (xy 31.687045 -351.984875) (xy 31.634722 -351.96951) (xy 31.585118 -351.946855)
			(xy 31.539244 -351.917372) (xy 31.498031 -351.88166) (xy 31.462321 -351.840447) (xy 31.432839 -351.794571)
			(xy 31.410186 -351.744967) (xy 31.394823 -351.692643) (xy 31.387062 -351.638666) (xy 29.904214 -351.638666)
			(xy 29.904214 -351.638671) (xy 29.896452 -351.692657) (xy 29.881086 -351.74499) (xy 29.85843 -351.794603)
			(xy 29.828944 -351.840487) (xy 29.793228 -351.881708) (xy 29.75201 -351.917427) (xy 29.706128 -351.946917)
			(xy 29.656516 -351.969577) (xy 29.604185 -351.984946) (xy 29.550199 -351.992712) (xy 29.522928 -351.9932)
			(xy 28.659328 -351.9932) (xy 28.632058 -351.992663) (xy 28.578074 -351.984904) (xy 28.525743 -351.969542)
			(xy 28.476131 -351.946888) (xy 28.430249 -351.917404) (xy 28.389029 -351.881691) (xy 28.353312 -351.840474)
			(xy 28.323825 -351.794593) (xy 28.301168 -351.744983) (xy 28.285802 -351.692654) (xy 28.278039 -351.63867)
			(xy 26.795336 -351.63867) (xy 26.795336 -351.638675) (xy 26.787573 -351.69267) (xy 26.772203 -351.745011)
			(xy 26.749541 -351.794631) (xy 26.720047 -351.840521) (xy 26.684323 -351.881746) (xy 26.643095 -351.917467)
			(xy 26.597203 -351.946956) (xy 26.547581 -351.969614) (xy 26.495239 -351.984979) (xy 26.441243 -351.992739)
			(xy 26.413968 -351.9932) (xy 25.550368 -351.9932) (xy 25.523103 -351.992635) (xy 25.469128 -351.984871)
			(xy 25.416808 -351.969504) (xy 25.367206 -351.946849) (xy 25.321334 -351.917365) (xy 25.280124 -351.881653)
			(xy 25.244416 -351.84044) (xy 25.214936 -351.794566) (xy 25.192284 -351.744962) (xy 25.176922 -351.692641)
			(xy 25.169162 -351.638665) (xy 23.686314 -351.638665) (xy 23.686314 -351.638672) (xy 23.678551 -351.69266)
			(xy 23.663185 -351.744994) (xy 23.640527 -351.794609) (xy 23.611039 -351.840494) (xy 23.575321 -351.881715)
			(xy 23.5341 -351.917434) (xy 23.488216 -351.946923) (xy 23.438602 -351.969582) (xy 23.386268 -351.98495)
			(xy 23.33228 -351.992713) (xy 23.305008 -351.9932) (xy 22.441408 -351.9932) (xy 22.414139 -351.992661)
			(xy 22.360157 -351.984901) (xy 22.307829 -351.969537) (xy 22.258219 -351.946882) (xy 22.212339 -351.917397)
			(xy 22.171122 -351.881683) (xy 22.135407 -351.840467) (xy 22.105922 -351.794588) (xy 22.083266 -351.744979)
			(xy 22.067901 -351.692651) (xy 22.060139 -351.638669) (xy 20.577347 -351.638669) (xy 20.577347 -351.638711)
			(xy 20.569584 -351.692698) (xy 20.554218 -351.74503) (xy 20.53156 -351.794643) (xy 20.502073 -351.840527)
			(xy 20.466355 -351.881747) (xy 20.425135 -351.917464) (xy 20.379252 -351.946951) (xy 20.329638 -351.969609)
			(xy 20.277306 -351.984975) (xy 20.223319 -351.992737) (xy 20.196048 -351.9932) (xy 19.332448 -351.9932)
			(xy 19.305179 -351.992717) (xy 19.251195 -351.984955) (xy 19.198865 -351.96959) (xy 19.149255 -351.946933)
			(xy 19.103374 -351.917447) (xy 19.062157 -351.881732) (xy 19.026441 -351.840514) (xy 18.996956 -351.794633)
			(xy 18.974299 -351.745023) (xy 18.958934 -351.692693) (xy 18.951172 -351.638709) (xy 0.508 -351.638709)
			(xy 0.508 -354.759373) (xy 22.060084 -354.759373) (xy 22.060084 -354.704827) (xy 22.067846 -354.650837)
			(xy 22.083214 -354.598501) (xy 22.105873 -354.548885) (xy 22.135363 -354.502999) (xy 22.171083 -354.461777)
			(xy 22.212306 -354.426058) (xy 22.258192 -354.396569) (xy 22.307809 -354.373911) (xy 22.360145 -354.358545)
			(xy 22.414135 -354.350783) (xy 22.441408 -354.35032) (xy 23.305008 -354.35032) (xy 23.332276 -354.350843)
			(xy 23.386256 -354.358605) (xy 23.438582 -354.37397) (xy 23.488189 -354.396626) (xy 23.534067 -354.426111)
			(xy 23.575281 -354.461824) (xy 23.610994 -354.50304) (xy 23.640478 -354.548918) (xy 23.663132 -354.598525)
			(xy 23.678497 -354.650852) (xy 23.686258 -354.704832) (xy 23.686258 -354.759368) (xy 23.686258 -354.759369)
			(xy 25.169106 -354.759369) (xy 25.169106 -354.704831) (xy 25.176868 -354.650847) (xy 25.192232 -354.598518)
			(xy 25.214887 -354.548908) (xy 25.244371 -354.503026) (xy 25.280085 -354.461807) (xy 25.3213 -354.42609)
			(xy 25.36718 -354.396602) (xy 25.416788 -354.373943) (xy 25.469116 -354.358574) (xy 25.523099 -354.350809)
			(xy 25.550368 -354.35032) (xy 26.413968 -354.35032) (xy 26.441239 -354.350817) (xy 26.495227 -354.358575)
			(xy 26.547561 -354.373938) (xy 26.597176 -354.396593) (xy 26.643061 -354.426078) (xy 26.684283 -354.461794)
			(xy 26.720003 -354.503013) (xy 26.749492 -354.548896) (xy 26.772151 -354.598509) (xy 26.787518 -354.650842)
			(xy 26.79528 -354.704829) (xy 26.79528 -354.759371) (xy 26.79528 -354.759374) (xy 28.277984 -354.759374)
			(xy 28.277984 -354.704826) (xy 28.285747 -354.650835) (xy 28.301115 -354.598497) (xy 28.323776 -354.54888)
			(xy 28.353268 -354.502993) (xy 28.38899 -354.46177) (xy 28.430215 -354.426051) (xy 28.476104 -354.396562)
			(xy 28.525723 -354.373905) (xy 28.578062 -354.358541) (xy 28.632054 -354.350782) (xy 28.659328 -354.35032)
			(xy 29.522928 -354.35032) (xy 29.550195 -354.350844) (xy 29.604173 -354.358609) (xy 29.656497 -354.373976)
			(xy 29.706101 -354.396633) (xy 29.751976 -354.426118) (xy 29.793188 -354.461831) (xy 29.828899 -354.503046)
			(xy 29.858381 -354.548924) (xy 29.881034 -354.59853) (xy 29.896397 -354.650855) (xy 29.904158 -354.704833)
			(xy 29.904158 -354.759367) (xy 29.904158 -354.75937) (xy 31.387006 -354.75937) (xy 31.387006 -354.70483)
			(xy 31.394768 -354.650845) (xy 31.410134 -354.598514) (xy 31.43279 -354.548902) (xy 31.462276 -354.50302)
			(xy 31.497992 -354.4618) (xy 31.53921 -354.426083) (xy 31.585091 -354.396596) (xy 31.634703 -354.373938)
			(xy 31.687033 -354.358571) (xy 31.741018 -354.350807) (xy 31.768288 -354.35032) (xy 32.631888 -354.35032)
			(xy 32.659158 -354.350819) (xy 32.713144 -354.358579) (xy 32.765476 -354.373944) (xy 32.815088 -354.396599)
			(xy 32.860971 -354.426085) (xy 32.902191 -354.461801) (xy 32.937908 -354.503019) (xy 32.967395 -354.548902)
			(xy 32.990052 -354.598513) (xy 33.005418 -354.650844) (xy 33.013181 -354.70483) (xy 33.013181 -354.75937)
			(xy 33.01318 -354.759374) (xy 34.495884 -354.759374) (xy 34.495884 -354.704826) (xy 34.503647 -354.650832)
			(xy 34.519017 -354.598493) (xy 34.541679 -354.548874) (xy 34.571172 -354.502986) (xy 34.606897 -354.461763)
			(xy 34.648125 -354.426044) (xy 34.694016 -354.396556) (xy 34.743638 -354.3739) (xy 34.795979 -354.358537)
			(xy 34.849973 -354.35078) (xy 34.877248 -354.35032) (xy 35.740848 -354.35032) (xy 35.768114 -354.350846)
			(xy 35.82209 -354.358613) (xy 35.874411 -354.373981) (xy 35.924013 -354.396639) (xy 35.969886 -354.426125)
			(xy 36.011095 -354.461839) (xy 36.046804 -354.503053) (xy 36.076284 -354.548929) (xy 36.098936 -354.598534)
			(xy 36.114298 -354.650857) (xy 36.122058 -354.704834) (xy 36.122058 -354.759366) (xy 36.122057 -354.759373)
			(xy 37.604884 -354.759373) (xy 37.604884 -354.704827) (xy 37.612646 -354.650837) (xy 37.628014 -354.598501)
			(xy 37.650673 -354.548885) (xy 37.680163 -354.502999) (xy 37.715883 -354.461777) (xy 37.757106 -354.426058)
			(xy 37.802992 -354.396569) (xy 37.852609 -354.373911) (xy 37.904945 -354.358545) (xy 37.958935 -354.350783)
			(xy 37.986208 -354.35032) (xy 38.849808 -354.35032) (xy 38.877076 -354.350843) (xy 38.931056 -354.358605)
			(xy 38.983382 -354.37397) (xy 39.032989 -354.396626) (xy 39.078867 -354.426111) (xy 39.120081 -354.461824)
			(xy 39.155794 -354.50304) (xy 39.185278 -354.548918) (xy 39.207932 -354.598525) (xy 39.223297 -354.650852)
			(xy 39.231058 -354.704832) (xy 39.231058 -354.759368) (xy 39.231058 -354.759369) (xy 40.713906 -354.759369)
			(xy 40.713906 -354.704831) (xy 40.721668 -354.650847) (xy 40.737032 -354.598518) (xy 40.759687 -354.548908)
			(xy 40.789171 -354.503026) (xy 40.824885 -354.461807) (xy 40.8661 -354.42609) (xy 40.91198 -354.396602)
			(xy 40.961588 -354.373943) (xy 41.013916 -354.358574) (xy 41.067899 -354.350809) (xy 41.095168 -354.35032)
			(xy 41.958768 -354.35032) (xy 41.986039 -354.350817) (xy 42.040027 -354.358575) (xy 42.092361 -354.373938)
			(xy 42.141976 -354.396593) (xy 42.187861 -354.426078) (xy 42.229083 -354.461794) (xy 42.264803 -354.503013)
			(xy 42.294292 -354.548896) (xy 42.316951 -354.598509) (xy 42.332318 -354.650842) (xy 42.34008 -354.704829)
			(xy 42.34008 -354.759371) (xy 42.34008 -354.759374) (xy 43.822784 -354.759374) (xy 43.822784 -354.704826)
			(xy 43.830547 -354.650835) (xy 43.845915 -354.598497) (xy 43.868576 -354.54888) (xy 43.898068 -354.502993)
			(xy 43.93379 -354.46177) (xy 43.975015 -354.426051) (xy 44.020904 -354.396562) (xy 44.070523 -354.373905)
			(xy 44.122862 -354.358541) (xy 44.176854 -354.350782) (xy 44.204128 -354.35032) (xy 45.067728 -354.35032)
			(xy 45.094995 -354.350844) (xy 45.148973 -354.358609) (xy 45.201297 -354.373976) (xy 45.250901 -354.396633)
			(xy 45.296776 -354.426118) (xy 45.337988 -354.461831) (xy 45.373699 -354.503046) (xy 45.403181 -354.548924)
			(xy 45.425834 -354.59853) (xy 45.441197 -354.650855) (xy 45.448958 -354.704833) (xy 45.448958 -354.759367)
			(xy 45.448958 -354.75937) (xy 46.931806 -354.75937) (xy 46.931806 -354.70483) (xy 46.939568 -354.650845)
			(xy 46.954934 -354.598514) (xy 46.97759 -354.548902) (xy 47.007076 -354.50302) (xy 47.042792 -354.4618)
			(xy 47.08401 -354.426083) (xy 47.129891 -354.396596) (xy 47.179503 -354.373938) (xy 47.231833 -354.358571)
			(xy 47.285818 -354.350807) (xy 47.313088 -354.35032) (xy 48.176688 -354.35032) (xy 48.203958 -354.350819)
			(xy 48.257944 -354.358579) (xy 48.310276 -354.373944) (xy 48.359888 -354.396599) (xy 48.405771 -354.426085)
			(xy 48.446991 -354.461801) (xy 48.482708 -354.503019) (xy 48.512195 -354.548902) (xy 48.534852 -354.598513)
			(xy 48.550218 -354.650844) (xy 48.557981 -354.70483) (xy 48.557981 -354.75937) (xy 48.55798 -354.759374)
			(xy 50.040684 -354.759374) (xy 50.040684 -354.704826) (xy 50.048447 -354.650832) (xy 50.063817 -354.598493)
			(xy 50.086479 -354.548874) (xy 50.115972 -354.502986) (xy 50.151697 -354.461763) (xy 50.192925 -354.426044)
			(xy 50.238816 -354.396556) (xy 50.288438 -354.3739) (xy 50.340779 -354.358537) (xy 50.394773 -354.35078)
			(xy 50.422048 -354.35032) (xy 51.285648 -354.35032) (xy 51.312914 -354.350846) (xy 51.36689 -354.358613)
			(xy 51.419211 -354.373981) (xy 51.468813 -354.396639) (xy 51.514686 -354.426125) (xy 51.555895 -354.461839)
			(xy 51.591604 -354.503053) (xy 51.621084 -354.548929) (xy 51.643736 -354.598534) (xy 51.659098 -354.650857)
			(xy 51.666858 -354.704834) (xy 51.666858 -354.759366) (xy 51.666857 -354.759372) (xy 64.099884 -354.759372)
			(xy 64.099884 -354.704828) (xy 64.107646 -354.650838) (xy 64.123013 -354.598503) (xy 64.145672 -354.548887)
			(xy 64.175161 -354.503001) (xy 64.210881 -354.461779) (xy 64.252103 -354.42606) (xy 64.297989 -354.396571)
			(xy 64.347605 -354.373912) (xy 64.39994 -354.358546) (xy 64.45393 -354.350783) (xy 64.481202 -354.35032)
			(xy 65.344802 -354.35032) (xy 65.37207 -354.350843) (xy 65.426051 -354.358604) (xy 65.478378 -354.373969)
			(xy 65.527985 -354.396624) (xy 65.573864 -354.426109) (xy 65.615079 -354.461822) (xy 65.650793 -354.503038)
			(xy 65.680277 -354.548917) (xy 65.702932 -354.598524) (xy 65.718296 -354.650851) (xy 65.726058 -354.704832)
			(xy 65.726058 -354.759368) (xy 65.726058 -354.759369) (xy 67.208906 -354.759369) (xy 67.208906 -354.704831)
			(xy 67.216667 -354.650848) (xy 67.232032 -354.598519) (xy 67.254686 -354.548909) (xy 67.28417 -354.503028)
			(xy 67.319883 -354.46181) (xy 67.361098 -354.426093) (xy 67.406976 -354.396604) (xy 67.456584 -354.373945)
			(xy 67.508911 -354.358575) (xy 67.562893 -354.350809) (xy 67.590162 -354.35032) (xy 68.453762 -354.35032)
			(xy 68.481033 -354.350817) (xy 68.535022 -354.358574) (xy 68.587357 -354.373936) (xy 68.636972 -354.396591)
			(xy 68.682859 -354.426076) (xy 68.724081 -354.461792) (xy 68.759801 -354.503011) (xy 68.789291 -354.548894)
			(xy 68.81195 -354.598508) (xy 68.827318 -354.650841) (xy 68.83508 -354.704829) (xy 68.83508 -354.759371)
			(xy 68.83508 -354.759373) (xy 70.317784 -354.759373) (xy 70.317784 -354.704827) (xy 70.325547 -354.650835)
			(xy 70.340915 -354.598498) (xy 70.363575 -354.548882) (xy 70.393066 -354.502995) (xy 70.428788 -354.461772)
			(xy 70.470012 -354.426053) (xy 70.515901 -354.396564) (xy 70.565519 -354.373907) (xy 70.617857 -354.358542)
			(xy 70.671849 -354.350782) (xy 70.699122 -354.35032) (xy 71.562722 -354.35032) (xy 71.589989 -354.350844)
			(xy 71.643968 -354.358608) (xy 71.696292 -354.373974) (xy 71.745897 -354.396631) (xy 71.791773 -354.426116)
			(xy 71.832986 -354.461829) (xy 71.868697 -354.503044) (xy 71.89818 -354.548922) (xy 71.920833 -354.598528)
			(xy 71.936197 -354.650854) (xy 71.943958 -354.704833) (xy 71.943958 -354.759367) (xy 71.943958 -354.75937)
			(xy 73.426806 -354.75937) (xy 73.426806 -354.70483) (xy 73.434568 -354.650846) (xy 73.449933 -354.598515)
			(xy 73.472589 -354.548904) (xy 73.502075 -354.503022) (xy 73.53779 -354.461802) (xy 73.579007 -354.426085)
			(xy 73.624888 -354.396598) (xy 73.674498 -354.373939) (xy 73.726828 -354.358572) (xy 73.780812 -354.350808)
			(xy 73.808082 -354.35032) (xy 74.671682 -354.35032) (xy 74.698953 -354.350818) (xy 74.752939 -354.358578)
			(xy 74.805271 -354.373942) (xy 74.854884 -354.396597) (xy 74.900768 -354.426083) (xy 74.941988 -354.461799)
			(xy 74.977706 -354.503018) (xy 75.007194 -354.5489) (xy 75.029852 -354.598512) (xy 75.045218 -354.650844)
			(xy 75.052981 -354.704829) (xy 75.052981 -354.759371) (xy 75.052981 -354.759374) (xy 76.535684 -354.759374)
			(xy 76.535684 -354.704826) (xy 76.543447 -354.650833) (xy 76.558816 -354.598494) (xy 76.581478 -354.548876)
			(xy 76.610971 -354.502988) (xy 76.646695 -354.461765) (xy 76.687922 -354.426046) (xy 76.733813 -354.396558)
			(xy 76.783434 -354.373902) (xy 76.835774 -354.358538) (xy 76.889768 -354.350781) (xy 76.917042 -354.35032)
			(xy 77.780642 -354.35032) (xy 77.807908 -354.350845) (xy 77.861885 -354.358611) (xy 77.914207 -354.37398)
			(xy 77.963809 -354.396637) (xy 78.009683 -354.426123) (xy 78.050893 -354.461836) (xy 78.086602 -354.503051)
			(xy 78.116083 -354.548928) (xy 78.138735 -354.598533) (xy 78.154098 -354.650856) (xy 78.161858 -354.704834)
			(xy 78.161858 -354.759366) (xy 78.161857 -354.759372) (xy 79.644684 -354.759372) (xy 79.644684 -354.704828)
			(xy 79.652446 -354.650838) (xy 79.667813 -354.598503) (xy 79.690472 -354.548887) (xy 79.719961 -354.503001)
			(xy 79.755681 -354.461779) (xy 79.796903 -354.42606) (xy 79.842789 -354.396571) (xy 79.892405 -354.373912)
			(xy 79.94474 -354.358546) (xy 79.99873 -354.350783) (xy 80.026002 -354.35032) (xy 80.889602 -354.35032)
			(xy 80.91687 -354.350843) (xy 80.970851 -354.358604) (xy 81.023178 -354.373969) (xy 81.072785 -354.396624)
			(xy 81.118664 -354.426109) (xy 81.159879 -354.461822) (xy 81.195593 -354.503038) (xy 81.225077 -354.548917)
			(xy 81.247732 -354.598524) (xy 81.263096 -354.650851) (xy 81.270858 -354.704832) (xy 81.270858 -354.759368)
			(xy 81.270858 -354.759369) (xy 82.753706 -354.759369) (xy 82.753706 -354.704831) (xy 82.761467 -354.650848)
			(xy 82.776832 -354.598519) (xy 82.799486 -354.548909) (xy 82.82897 -354.503028) (xy 82.864683 -354.46181)
			(xy 82.905898 -354.426093) (xy 82.951776 -354.396604) (xy 83.001384 -354.373945) (xy 83.053711 -354.358575)
			(xy 83.107693 -354.350809) (xy 83.134962 -354.35032) (xy 83.998562 -354.35032) (xy 84.025833 -354.350817)
			(xy 84.079822 -354.358574) (xy 84.132157 -354.373936) (xy 84.181772 -354.396591) (xy 84.227659 -354.426076)
			(xy 84.268881 -354.461792) (xy 84.304601 -354.503011) (xy 84.334091 -354.548894) (xy 84.35675 -354.598508)
			(xy 84.372118 -354.650841) (xy 84.37988 -354.704829) (xy 84.37988 -354.759371) (xy 84.37988 -354.759373)
			(xy 85.862584 -354.759373) (xy 85.862584 -354.704827) (xy 85.870347 -354.650835) (xy 85.885715 -354.598498)
			(xy 85.908375 -354.548882) (xy 85.937866 -354.502995) (xy 85.973588 -354.461772) (xy 86.014812 -354.426053)
			(xy 86.060701 -354.396564) (xy 86.110319 -354.373907) (xy 86.162657 -354.358542) (xy 86.216649 -354.350782)
			(xy 86.243922 -354.35032) (xy 87.107522 -354.35032) (xy 87.134789 -354.350844) (xy 87.188768 -354.358608)
			(xy 87.241092 -354.373974) (xy 87.290697 -354.396631) (xy 87.336573 -354.426116) (xy 87.377786 -354.461829)
			(xy 87.413497 -354.503044) (xy 87.44298 -354.548922) (xy 87.465633 -354.598528) (xy 87.480997 -354.650854)
			(xy 87.488758 -354.704833) (xy 87.488758 -354.759367) (xy 87.488758 -354.75937) (xy 88.971606 -354.75937)
			(xy 88.971606 -354.70483) (xy 88.979368 -354.650846) (xy 88.994733 -354.598515) (xy 89.017389 -354.548904)
			(xy 89.046875 -354.503022) (xy 89.08259 -354.461802) (xy 89.123807 -354.426085) (xy 89.169688 -354.396598)
			(xy 89.219298 -354.373939) (xy 89.271628 -354.358572) (xy 89.325612 -354.350808) (xy 89.352882 -354.35032)
			(xy 90.216482 -354.35032) (xy 90.243753 -354.350818) (xy 90.297739 -354.358578) (xy 90.350071 -354.373942)
			(xy 90.399684 -354.396597) (xy 90.445568 -354.426083) (xy 90.486788 -354.461799) (xy 90.522506 -354.503018)
			(xy 90.551994 -354.5489) (xy 90.574652 -354.598512) (xy 90.590018 -354.650844) (xy 90.597781 -354.704829)
			(xy 90.597781 -354.759371) (xy 90.597781 -354.759374) (xy 92.080484 -354.759374) (xy 92.080484 -354.704826)
			(xy 92.088247 -354.650833) (xy 92.103616 -354.598494) (xy 92.126278 -354.548876) (xy 92.155771 -354.502988)
			(xy 92.191495 -354.461765) (xy 92.232722 -354.426046) (xy 92.278613 -354.396558) (xy 92.328234 -354.373902)
			(xy 92.380574 -354.358538) (xy 92.434568 -354.350781) (xy 92.461842 -354.35032) (xy 93.325442 -354.35032)
			(xy 93.352708 -354.350845) (xy 93.406685 -354.358611) (xy 93.459007 -354.37398) (xy 93.508609 -354.396637)
			(xy 93.554483 -354.426123) (xy 93.595693 -354.461836) (xy 93.631402 -354.503051) (xy 93.660883 -354.548928)
			(xy 93.683535 -354.598533) (xy 93.698898 -354.650856) (xy 93.706658 -354.704834) (xy 93.706658 -354.759366)
			(xy 93.706658 -354.759369) (xy 114.589806 -354.759369) (xy 114.589806 -354.704831) (xy 114.597568 -354.650847)
			(xy 114.612932 -354.598518) (xy 114.635587 -354.548908) (xy 114.665071 -354.503026) (xy 114.700785 -354.461807)
			(xy 114.742 -354.42609) (xy 114.78788 -354.396602) (xy 114.837488 -354.373943) (xy 114.889816 -354.358574)
			(xy 114.943799 -354.350809) (xy 114.971068 -354.35032) (xy 115.834668 -354.35032) (xy 115.861939 -354.350817)
			(xy 115.915927 -354.358575) (xy 115.968261 -354.373938) (xy 116.017876 -354.396593) (xy 116.063761 -354.426078)
			(xy 116.104983 -354.461794) (xy 116.140703 -354.503013) (xy 116.170192 -354.548896) (xy 116.192851 -354.598509)
			(xy 116.208218 -354.650842) (xy 116.21598 -354.704829) (xy 116.21598 -354.759371) (xy 116.21598 -354.759374)
			(xy 117.698684 -354.759374) (xy 117.698684 -354.704826) (xy 117.706447 -354.650835) (xy 117.721815 -354.598497)
			(xy 117.744476 -354.54888) (xy 117.773968 -354.502993) (xy 117.80969 -354.46177) (xy 117.850915 -354.426051)
			(xy 117.896804 -354.396562) (xy 117.946423 -354.373905) (xy 117.998762 -354.358541) (xy 118.052754 -354.350782)
			(xy 118.080028 -354.35032) (xy 118.943628 -354.35032) (xy 118.970895 -354.350844) (xy 119.024873 -354.358609)
			(xy 119.077197 -354.373976) (xy 119.126801 -354.396633) (xy 119.172676 -354.426118) (xy 119.213888 -354.461831)
			(xy 119.249599 -354.503046) (xy 119.279081 -354.548924) (xy 119.301734 -354.59853) (xy 119.317097 -354.650855)
			(xy 119.324858 -354.704833) (xy 119.324858 -354.759367) (xy 119.324858 -354.75937) (xy 120.807706 -354.75937)
			(xy 120.807706 -354.70483) (xy 120.815468 -354.650845) (xy 120.830834 -354.598514) (xy 120.85349 -354.548902)
			(xy 120.882976 -354.50302) (xy 120.918692 -354.4618) (xy 120.95991 -354.426083) (xy 121.005791 -354.396596)
			(xy 121.055403 -354.373938) (xy 121.107733 -354.358571) (xy 121.161718 -354.350807) (xy 121.188988 -354.35032)
			(xy 122.052588 -354.35032) (xy 122.079858 -354.350819) (xy 122.133844 -354.358579) (xy 122.186176 -354.373944)
			(xy 122.235788 -354.396599) (xy 122.281671 -354.426085) (xy 122.322891 -354.461801) (xy 122.358608 -354.503019)
			(xy 122.388095 -354.548902) (xy 122.410752 -354.598513) (xy 122.426118 -354.650844) (xy 122.433881 -354.70483)
			(xy 122.433881 -354.75937) (xy 122.43388 -354.759374) (xy 123.916584 -354.759374) (xy 123.916584 -354.704826)
			(xy 123.924347 -354.650832) (xy 123.939717 -354.598493) (xy 123.962379 -354.548874) (xy 123.991872 -354.502986)
			(xy 124.027597 -354.461763) (xy 124.068825 -354.426044) (xy 124.114716 -354.396556) (xy 124.164338 -354.3739)
			(xy 124.216679 -354.358537) (xy 124.270673 -354.35078) (xy 124.297948 -354.35032) (xy 125.161548 -354.35032)
			(xy 125.188814 -354.350846) (xy 125.24279 -354.358613) (xy 125.295111 -354.373981) (xy 125.344713 -354.396639)
			(xy 125.390586 -354.426125) (xy 125.431795 -354.461839) (xy 125.467504 -354.503053) (xy 125.496984 -354.548929)
			(xy 125.519636 -354.598534) (xy 125.534998 -354.650857) (xy 125.542758 -354.704834) (xy 125.542758 -354.759366)
			(xy 125.542757 -354.759373) (xy 127.025584 -354.759373) (xy 127.025584 -354.704827) (xy 127.033346 -354.650837)
			(xy 127.048714 -354.598501) (xy 127.071373 -354.548885) (xy 127.100863 -354.502999) (xy 127.136583 -354.461777)
			(xy 127.177806 -354.426058) (xy 127.223692 -354.396569) (xy 127.273309 -354.373911) (xy 127.325645 -354.358545)
			(xy 127.379635 -354.350783) (xy 127.406908 -354.35032) (xy 128.270508 -354.35032) (xy 128.297776 -354.350843)
			(xy 128.351756 -354.358605) (xy 128.404082 -354.37397) (xy 128.453689 -354.396626) (xy 128.499567 -354.426111)
			(xy 128.540781 -354.461824) (xy 128.576494 -354.50304) (xy 128.605978 -354.548918) (xy 128.628632 -354.598525)
			(xy 128.643997 -354.650852) (xy 128.651758 -354.704832) (xy 128.651758 -354.759368) (xy 128.651758 -354.759369)
			(xy 130.134606 -354.759369) (xy 130.134606 -354.704831) (xy 130.142368 -354.650847) (xy 130.157732 -354.598518)
			(xy 130.180387 -354.548908) (xy 130.209871 -354.503026) (xy 130.245585 -354.461807) (xy 130.2868 -354.42609)
			(xy 130.33268 -354.396602) (xy 130.382288 -354.373943) (xy 130.434616 -354.358574) (xy 130.488599 -354.350809)
			(xy 130.515868 -354.35032) (xy 131.379468 -354.35032) (xy 131.406739 -354.350817) (xy 131.460727 -354.358575)
			(xy 131.513061 -354.373938) (xy 131.562676 -354.396593) (xy 131.608561 -354.426078) (xy 131.649783 -354.461794)
			(xy 131.685503 -354.503013) (xy 131.714992 -354.548896) (xy 131.737651 -354.598509) (xy 131.753018 -354.650842)
			(xy 131.76078 -354.704829) (xy 131.76078 -354.759371) (xy 131.76078 -354.759374) (xy 133.243484 -354.759374)
			(xy 133.243484 -354.704826) (xy 133.251247 -354.650835) (xy 133.266615 -354.598497) (xy 133.289276 -354.54888)
			(xy 133.318768 -354.502993) (xy 133.35449 -354.46177) (xy 133.395715 -354.426051) (xy 133.441604 -354.396562)
			(xy 133.491223 -354.373905) (xy 133.543562 -354.358541) (xy 133.597554 -354.350782) (xy 133.624828 -354.35032)
			(xy 134.488428 -354.35032) (xy 134.515695 -354.350844) (xy 134.569673 -354.358609) (xy 134.621997 -354.373976)
			(xy 134.671601 -354.396633) (xy 134.717476 -354.426118) (xy 134.758688 -354.461831) (xy 134.794399 -354.503046)
			(xy 134.823881 -354.548924) (xy 134.846534 -354.59853) (xy 134.861897 -354.650855) (xy 134.869658 -354.704833)
			(xy 134.869658 -354.759367) (xy 134.869658 -354.75937) (xy 136.352506 -354.75937) (xy 136.352506 -354.70483)
			(xy 136.360268 -354.650845) (xy 136.375634 -354.598514) (xy 136.39829 -354.548902) (xy 136.427776 -354.50302)
			(xy 136.463492 -354.4618) (xy 136.50471 -354.426083) (xy 136.550591 -354.396596) (xy 136.600203 -354.373938)
			(xy 136.652533 -354.358571) (xy 136.706518 -354.350807) (xy 136.733788 -354.35032) (xy 137.597388 -354.35032)
			(xy 137.624658 -354.350819) (xy 137.678644 -354.358579) (xy 137.730976 -354.373944) (xy 137.780588 -354.396599)
			(xy 137.826471 -354.426085) (xy 137.867691 -354.461801) (xy 137.903408 -354.503019) (xy 137.932895 -354.548902)
			(xy 137.955552 -354.598513) (xy 137.970918 -354.650844) (xy 137.978681 -354.70483) (xy 137.978681 -354.75937)
			(xy 137.97868 -354.759374) (xy 139.461384 -354.759374) (xy 139.461384 -354.704826) (xy 139.469147 -354.650832)
			(xy 139.484517 -354.598493) (xy 139.507179 -354.548874) (xy 139.536672 -354.502986) (xy 139.572397 -354.461763)
			(xy 139.613625 -354.426044) (xy 139.659516 -354.396556) (xy 139.709138 -354.3739) (xy 139.761479 -354.358537)
			(xy 139.815473 -354.35078) (xy 139.842748 -354.35032) (xy 140.706348 -354.35032) (xy 140.733614 -354.350846)
			(xy 140.78759 -354.358613) (xy 140.839911 -354.373981) (xy 140.889513 -354.396639) (xy 140.935386 -354.426125)
			(xy 140.976595 -354.461839) (xy 141.012304 -354.503053) (xy 141.041784 -354.548929) (xy 141.064436 -354.598534)
			(xy 141.079798 -354.650857) (xy 141.087558 -354.704834) (xy 141.087558 -354.759366) (xy 141.087557 -354.759373)
			(xy 142.570384 -354.759373) (xy 142.570384 -354.704827) (xy 142.578146 -354.650837) (xy 142.593514 -354.598501)
			(xy 142.616173 -354.548885) (xy 142.645663 -354.502999) (xy 142.681383 -354.461777) (xy 142.722606 -354.426058)
			(xy 142.768492 -354.396569) (xy 142.818109 -354.373911) (xy 142.870445 -354.358545) (xy 142.924435 -354.350783)
			(xy 142.951708 -354.35032) (xy 143.815308 -354.35032) (xy 143.842576 -354.350843) (xy 143.896556 -354.358605)
			(xy 143.948882 -354.37397) (xy 143.998489 -354.396626) (xy 144.044367 -354.426111) (xy 144.085581 -354.461824)
			(xy 144.121294 -354.50304) (xy 144.150778 -354.548918) (xy 144.173432 -354.598525) (xy 144.188797 -354.650852)
			(xy 144.196558 -354.704832) (xy 144.196558 -354.759368) (xy 158.695906 -354.759368) (xy 158.695906 -354.704832)
			(xy 158.703667 -354.65085) (xy 158.719031 -354.598521) (xy 158.741685 -354.548912) (xy 158.771167 -354.503031)
			(xy 158.806879 -354.461813) (xy 158.848093 -354.426096) (xy 158.89397 -354.396608) (xy 158.943576 -354.373948)
			(xy 158.995903 -354.358577) (xy 159.049884 -354.35081) (xy 159.077152 -354.35032) (xy 159.940752 -354.35032)
			(xy 159.968024 -354.350816) (xy 160.022013 -354.358572) (xy 160.074349 -354.373934) (xy 160.123966 -354.396588)
			(xy 160.169854 -354.426072) (xy 160.211078 -354.461788) (xy 160.246799 -354.503008) (xy 160.276289 -354.548891)
			(xy 160.298949 -354.598506) (xy 160.314317 -354.65084) (xy 160.32208 -354.704828) (xy 160.32208 -354.759372)
			(xy 160.32208 -354.759373) (xy 161.804784 -354.759373) (xy 161.804784 -354.704827) (xy 161.812546 -354.650837)
			(xy 161.827914 -354.598501) (xy 161.850573 -354.548884) (xy 161.880064 -354.502998) (xy 161.915784 -354.461776)
			(xy 161.957008 -354.426056) (xy 162.002895 -354.396568) (xy 162.052512 -354.37391) (xy 162.104848 -354.358544)
			(xy 162.158839 -354.350783) (xy 162.186112 -354.35032) (xy 163.049712 -354.35032) (xy 163.07698 -354.350843)
			(xy 163.130959 -354.358606) (xy 163.183285 -354.373972) (xy 163.232891 -354.396627) (xy 163.278768 -354.426112)
			(xy 163.319983 -354.461826) (xy 163.355695 -354.503041) (xy 163.385178 -354.548919) (xy 163.407833 -354.598526)
			(xy 163.423197 -354.650852) (xy 163.430958 -354.704832) (xy 163.430958 -354.759368) (xy 163.430958 -354.759369)
			(xy 164.913806 -354.759369) (xy 164.913806 -354.704831) (xy 164.921568 -354.650847) (xy 164.936932 -354.598517)
			(xy 164.959588 -354.548907) (xy 164.989072 -354.503025) (xy 165.024786 -354.461806) (xy 165.066002 -354.426089)
			(xy 165.111882 -354.396601) (xy 165.161491 -354.373942) (xy 165.21382 -354.358574) (xy 165.267803 -354.350808)
			(xy 165.295072 -354.35032) (xy 166.158672 -354.35032) (xy 166.185943 -354.350818) (xy 166.23993 -354.358576)
			(xy 166.292264 -354.373939) (xy 166.341878 -354.396594) (xy 166.387763 -354.42608) (xy 166.428985 -354.461795)
			(xy 166.464704 -354.503014) (xy 166.494192 -354.548897) (xy 166.516851 -354.59851) (xy 166.532218 -354.650842)
			(xy 166.53998 -354.704829) (xy 166.53998 -354.759371) (xy 166.53998 -354.759374) (xy 168.022684 -354.759374)
			(xy 168.022684 -354.704826) (xy 168.030447 -354.650834) (xy 168.045816 -354.598496) (xy 168.068477 -354.548879)
			(xy 168.097969 -354.502991) (xy 168.133691 -354.461768) (xy 168.174917 -354.426049) (xy 168.220807 -354.396561)
			(xy 168.270426 -354.373904) (xy 168.322765 -354.35854) (xy 168.376758 -354.350781) (xy 168.404032 -354.35032)
			(xy 169.267632 -354.35032) (xy 169.294899 -354.350845) (xy 169.348876 -354.35861) (xy 169.401199 -354.373977)
			(xy 169.450803 -354.396634) (xy 169.496678 -354.426119) (xy 169.53789 -354.461833) (xy 169.5736 -354.503048)
			(xy 169.603081 -354.548925) (xy 169.625734 -354.598531) (xy 169.641097 -354.650855) (xy 169.648858 -354.704833)
			(xy 169.648858 -354.759367) (xy 169.648858 -354.75937) (xy 171.131706 -354.75937) (xy 171.131706 -354.70483)
			(xy 171.139468 -354.650844) (xy 171.154834 -354.598513) (xy 171.177491 -354.548901) (xy 171.206977 -354.503018)
			(xy 171.242693 -354.461799) (xy 171.283912 -354.426082) (xy 171.329794 -354.396594) (xy 171.379405 -354.373937)
			(xy 171.431736 -354.35857) (xy 171.485722 -354.350807) (xy 171.512992 -354.35032) (xy 172.376592 -354.35032)
			(xy 172.403862 -354.350819) (xy 172.457847 -354.35858) (xy 172.510178 -354.373945) (xy 172.55979 -354.396601)
			(xy 172.605673 -354.426087) (xy 172.646892 -354.461802) (xy 172.682609 -354.503021) (xy 172.712096 -354.548903)
			(xy 172.734753 -354.598514) (xy 172.750119 -354.650845) (xy 172.757881 -354.70483) (xy 172.757881 -354.759368)
			(xy 174.240706 -354.759368) (xy 174.240706 -354.704832) (xy 174.248467 -354.65085) (xy 174.263831 -354.598521)
			(xy 174.286485 -354.548912) (xy 174.315967 -354.503031) (xy 174.351679 -354.461813) (xy 174.392893 -354.426096)
			(xy 174.43877 -354.396608) (xy 174.488376 -354.373948) (xy 174.540703 -354.358577) (xy 174.594684 -354.35081)
			(xy 174.621952 -354.35032) (xy 175.485552 -354.35032) (xy 175.512824 -354.350816) (xy 175.566813 -354.358572)
			(xy 175.619149 -354.373934) (xy 175.668766 -354.396588) (xy 175.714654 -354.426072) (xy 175.755878 -354.461788)
			(xy 175.791599 -354.503008) (xy 175.821089 -354.548891) (xy 175.843749 -354.598506) (xy 175.859117 -354.65084)
			(xy 175.86688 -354.704828) (xy 175.86688 -354.759372) (xy 175.86688 -354.759373) (xy 177.349584 -354.759373)
			(xy 177.349584 -354.704827) (xy 177.357346 -354.650837) (xy 177.372714 -354.598501) (xy 177.395373 -354.548884)
			(xy 177.424864 -354.502998) (xy 177.460584 -354.461776) (xy 177.501808 -354.426056) (xy 177.547695 -354.396568)
			(xy 177.597312 -354.37391) (xy 177.649648 -354.358544) (xy 177.703639 -354.350783) (xy 177.730912 -354.35032)
			(xy 178.594512 -354.35032) (xy 178.62178 -354.350843) (xy 178.675759 -354.358606) (xy 178.728085 -354.373972)
			(xy 178.777691 -354.396627) (xy 178.823568 -354.426112) (xy 178.864783 -354.461826) (xy 178.900495 -354.503041)
			(xy 178.929978 -354.548919) (xy 178.952633 -354.598526) (xy 178.967997 -354.650852) (xy 178.975758 -354.704832)
			(xy 178.975758 -354.759368) (xy 178.975758 -354.759369) (xy 180.458606 -354.759369) (xy 180.458606 -354.704831)
			(xy 180.466368 -354.650847) (xy 180.481732 -354.598517) (xy 180.504388 -354.548907) (xy 180.533872 -354.503025)
			(xy 180.569586 -354.461806) (xy 180.610802 -354.426089) (xy 180.656682 -354.396601) (xy 180.706291 -354.373942)
			(xy 180.75862 -354.358574) (xy 180.812603 -354.350808) (xy 180.839872 -354.35032) (xy 181.703472 -354.35032)
			(xy 181.730743 -354.350818) (xy 181.78473 -354.358576) (xy 181.837064 -354.373939) (xy 181.886678 -354.396594)
			(xy 181.932563 -354.42608) (xy 181.973785 -354.461795) (xy 182.009504 -354.503014) (xy 182.038992 -354.548897)
			(xy 182.061651 -354.59851) (xy 182.077018 -354.650842) (xy 182.08478 -354.704829) (xy 182.08478 -354.735472)
			(xy 183.567508 -354.735472) (xy 183.567508 -354.680928) (xy 183.57527 -354.626939) (xy 183.590638 -354.574605)
			(xy 183.613298 -354.52499) (xy 183.642788 -354.479106) (xy 183.678508 -354.437885) (xy 183.719731 -354.402169)
			(xy 183.765618 -354.372682) (xy 183.815235 -354.350027) (xy 183.86757 -354.334664) (xy 183.92156 -354.326905)
			(xy 183.948832 -354.326444) (xy 184.812432 -354.326444) (xy 184.8397 -354.326921) (xy 184.893681 -354.334686)
			(xy 184.946008 -354.350054) (xy 184.995615 -354.372713) (xy 185.041492 -354.4022) (xy 185.082707 -354.437916)
			(xy 185.118419 -354.479133) (xy 185.147903 -354.525013) (xy 185.170557 -354.574622) (xy 185.185921 -354.62695)
			(xy 185.193682 -354.680932) (xy 185.193682 -354.735468) (xy 185.193682 -354.735469) (xy 186.67653 -354.735469)
			(xy 186.67653 -354.680931) (xy 186.684292 -354.626949) (xy 186.699656 -354.574621) (xy 186.722312 -354.525012)
			(xy 186.751796 -354.479133) (xy 186.78751 -354.437916) (xy 186.828726 -354.402201) (xy 186.874605 -354.372716)
			(xy 186.924214 -354.350059) (xy 186.976542 -354.334693) (xy 187.030523 -354.326931) (xy 187.057792 -354.326444)
			(xy 187.921392 -354.326444) (xy 187.948664 -354.326895) (xy 188.002652 -354.334656) (xy 188.054987 -354.350022)
			(xy 188.104602 -354.37268) (xy 188.150487 -354.402167) (xy 188.191709 -354.437885) (xy 188.227428 -354.479106)
			(xy 188.256917 -354.524991) (xy 188.279575 -354.574606) (xy 188.294942 -354.62694) (xy 188.302704 -354.680928)
			(xy 188.302704 -354.735472) (xy 188.299268 -354.759369) (xy 270.624806 -354.759369) (xy 270.624806 -354.704831)
			(xy 270.632567 -354.650848) (xy 270.647932 -354.598519) (xy 270.670586 -354.548909) (xy 270.70007 -354.503028)
			(xy 270.735783 -354.46181) (xy 270.776998 -354.426093) (xy 270.822876 -354.396604) (xy 270.872484 -354.373945)
			(xy 270.924811 -354.358575) (xy 270.978793 -354.350809) (xy 271.006062 -354.35032) (xy 271.869662 -354.35032)
			(xy 271.896933 -354.350817) (xy 271.950922 -354.358574) (xy 272.003257 -354.373936) (xy 272.052872 -354.396591)
			(xy 272.098759 -354.426076) (xy 272.139981 -354.461792) (xy 272.175701 -354.503011) (xy 272.205191 -354.548894)
			(xy 272.22785 -354.598508) (xy 272.243218 -354.650841) (xy 272.25098 -354.704829) (xy 272.25098 -354.759371)
			(xy 272.25098 -354.759373) (xy 273.733684 -354.759373) (xy 273.733684 -354.704827) (xy 273.741447 -354.650835)
			(xy 273.756815 -354.598498) (xy 273.779475 -354.548882) (xy 273.808966 -354.502995) (xy 273.844688 -354.461772)
			(xy 273.885912 -354.426053) (xy 273.931801 -354.396564) (xy 273.981419 -354.373907) (xy 274.033757 -354.358542)
			(xy 274.087749 -354.350782) (xy 274.115022 -354.35032) (xy 274.978622 -354.35032) (xy 275.005889 -354.350844)
			(xy 275.059868 -354.358608) (xy 275.112192 -354.373974) (xy 275.161797 -354.396631) (xy 275.207673 -354.426116)
			(xy 275.248886 -354.461829) (xy 275.284597 -354.503044) (xy 275.31408 -354.548922) (xy 275.336733 -354.598528)
			(xy 275.352097 -354.650854) (xy 275.359858 -354.704833) (xy 275.359858 -354.759367) (xy 275.359858 -354.75937)
			(xy 276.842706 -354.75937) (xy 276.842706 -354.70483) (xy 276.850468 -354.650846) (xy 276.865833 -354.598515)
			(xy 276.888489 -354.548904) (xy 276.917975 -354.503022) (xy 276.95369 -354.461802) (xy 276.994907 -354.426085)
			(xy 277.040788 -354.396598) (xy 277.090398 -354.373939) (xy 277.142728 -354.358572) (xy 277.196712 -354.350808)
			(xy 277.223982 -354.35032) (xy 278.087582 -354.35032) (xy 278.114853 -354.350818) (xy 278.168839 -354.358578)
			(xy 278.221171 -354.373942) (xy 278.270784 -354.396597) (xy 278.316668 -354.426083) (xy 278.357888 -354.461799)
			(xy 278.393606 -354.503018) (xy 278.423094 -354.5489) (xy 278.445752 -354.598512) (xy 278.461118 -354.650844)
			(xy 278.468881 -354.704829) (xy 278.468881 -354.759371) (xy 278.468881 -354.759374) (xy 279.951584 -354.759374)
			(xy 279.951584 -354.704826) (xy 279.959347 -354.650833) (xy 279.974716 -354.598494) (xy 279.997378 -354.548876)
			(xy 280.026871 -354.502988) (xy 280.062595 -354.461765) (xy 280.103822 -354.426046) (xy 280.149713 -354.396558)
			(xy 280.199334 -354.373902) (xy 280.251674 -354.358538) (xy 280.305668 -354.350781) (xy 280.332942 -354.35032)
			(xy 281.196542 -354.35032) (xy 281.223808 -354.350845) (xy 281.277785 -354.358611) (xy 281.330107 -354.37398)
			(xy 281.379709 -354.396637) (xy 281.425583 -354.426123) (xy 281.466793 -354.461836) (xy 281.502502 -354.503051)
			(xy 281.531983 -354.548928) (xy 281.554635 -354.598533) (xy 281.569998 -354.650856) (xy 281.577758 -354.704834)
			(xy 281.577758 -354.759366) (xy 281.577757 -354.759372) (xy 283.060584 -354.759372) (xy 283.060584 -354.704828)
			(xy 283.068346 -354.650838) (xy 283.083713 -354.598503) (xy 283.106372 -354.548887) (xy 283.135861 -354.503001)
			(xy 283.171581 -354.461779) (xy 283.212803 -354.42606) (xy 283.258689 -354.396571) (xy 283.308305 -354.373912)
			(xy 283.36064 -354.358546) (xy 283.41463 -354.350783) (xy 283.441902 -354.35032) (xy 284.305502 -354.35032)
			(xy 284.33277 -354.350843) (xy 284.386751 -354.358604) (xy 284.439078 -354.373969) (xy 284.488685 -354.396624)
			(xy 284.534564 -354.426109) (xy 284.575779 -354.461822) (xy 284.611493 -354.503038) (xy 284.640977 -354.548917)
			(xy 284.663632 -354.598524) (xy 284.678996 -354.650851) (xy 284.686758 -354.704832) (xy 284.686758 -354.759368)
			(xy 284.686758 -354.759369) (xy 286.169606 -354.759369) (xy 286.169606 -354.704831) (xy 286.177367 -354.650848)
			(xy 286.192732 -354.598519) (xy 286.215386 -354.548909) (xy 286.24487 -354.503028) (xy 286.280583 -354.46181)
			(xy 286.321798 -354.426093) (xy 286.367676 -354.396604) (xy 286.417284 -354.373945) (xy 286.469611 -354.358575)
			(xy 286.523593 -354.350809) (xy 286.550862 -354.35032) (xy 287.414462 -354.35032) (xy 287.441733 -354.350817)
			(xy 287.495722 -354.358574) (xy 287.548057 -354.373936) (xy 287.597672 -354.396591) (xy 287.643559 -354.426076)
			(xy 287.684781 -354.461792) (xy 287.720501 -354.503011) (xy 287.749991 -354.548894) (xy 287.77265 -354.598508)
			(xy 287.788018 -354.650841) (xy 287.79578 -354.704829) (xy 287.79578 -354.759371) (xy 287.79578 -354.759373)
			(xy 289.278484 -354.759373) (xy 289.278484 -354.704827) (xy 289.286247 -354.650835) (xy 289.301615 -354.598498)
			(xy 289.324275 -354.548882) (xy 289.353766 -354.502995) (xy 289.389488 -354.461772) (xy 289.430712 -354.426053)
			(xy 289.476601 -354.396564) (xy 289.526219 -354.373907) (xy 289.578557 -354.358542) (xy 289.632549 -354.350782)
			(xy 289.659822 -354.35032) (xy 290.523422 -354.35032) (xy 290.550689 -354.350844) (xy 290.604668 -354.358608)
			(xy 290.656992 -354.373974) (xy 290.706597 -354.396631) (xy 290.752473 -354.426116) (xy 290.793686 -354.461829)
			(xy 290.829397 -354.503044) (xy 290.85888 -354.548922) (xy 290.881533 -354.598528) (xy 290.896897 -354.650854)
			(xy 290.904658 -354.704833) (xy 290.904658 -354.759367) (xy 290.904658 -354.75937) (xy 292.387506 -354.75937)
			(xy 292.387506 -354.70483) (xy 292.395268 -354.650846) (xy 292.410633 -354.598515) (xy 292.433289 -354.548904)
			(xy 292.462775 -354.503022) (xy 292.49849 -354.461802) (xy 292.539707 -354.426085) (xy 292.585588 -354.396598)
			(xy 292.635198 -354.373939) (xy 292.687528 -354.358572) (xy 292.741512 -354.350808) (xy 292.768782 -354.35032)
			(xy 293.632382 -354.35032) (xy 293.659653 -354.350818) (xy 293.713639 -354.358578) (xy 293.765971 -354.373942)
			(xy 293.815584 -354.396597) (xy 293.861468 -354.426083) (xy 293.902688 -354.461799) (xy 293.938406 -354.503018)
			(xy 293.967894 -354.5489) (xy 293.990552 -354.598512) (xy 294.005918 -354.650844) (xy 294.013681 -354.704829)
			(xy 294.013681 -354.759371) (xy 294.013681 -354.759374) (xy 295.496384 -354.759374) (xy 295.496384 -354.704826)
			(xy 295.504147 -354.650833) (xy 295.519516 -354.598494) (xy 295.542178 -354.548876) (xy 295.571671 -354.502988)
			(xy 295.607395 -354.461765) (xy 295.648622 -354.426046) (xy 295.694513 -354.396558) (xy 295.744134 -354.373902)
			(xy 295.796474 -354.358538) (xy 295.850468 -354.350781) (xy 295.877742 -354.35032) (xy 296.741342 -354.35032)
			(xy 296.768608 -354.350845) (xy 296.822585 -354.358611) (xy 296.874907 -354.37398) (xy 296.924509 -354.396637)
			(xy 296.970383 -354.426123) (xy 297.011593 -354.461836) (xy 297.047302 -354.503051) (xy 297.076783 -354.548928)
			(xy 297.099435 -354.598533) (xy 297.114798 -354.650856) (xy 297.122558 -354.704834) (xy 297.122558 -354.759366)
			(xy 297.122557 -354.759372) (xy 298.605384 -354.759372) (xy 298.605384 -354.704828) (xy 298.613146 -354.650838)
			(xy 298.628513 -354.598503) (xy 298.651172 -354.548887) (xy 298.680661 -354.503001) (xy 298.716381 -354.461779)
			(xy 298.757603 -354.42606) (xy 298.803489 -354.396571) (xy 298.853105 -354.373912) (xy 298.90544 -354.358546)
			(xy 298.95943 -354.350783) (xy 298.986702 -354.35032) (xy 299.850302 -354.35032) (xy 299.87757 -354.350843)
			(xy 299.931551 -354.358604) (xy 299.983878 -354.373969) (xy 300.033485 -354.396624) (xy 300.079364 -354.426109)
			(xy 300.120579 -354.461822) (xy 300.156293 -354.503038) (xy 300.185777 -354.548917) (xy 300.208432 -354.598524)
			(xy 300.223796 -354.650851) (xy 300.231558 -354.704832) (xy 300.231558 -354.759368) (xy 300.231558 -354.759369)
			(xy 315.230506 -354.759369) (xy 315.230506 -354.704831) (xy 315.238267 -354.650848) (xy 315.253632 -354.598519)
			(xy 315.276286 -354.548909) (xy 315.30577 -354.503027) (xy 315.341483 -354.461809) (xy 315.382699 -354.426092)
			(xy 315.428577 -354.396604) (xy 315.478185 -354.373944) (xy 315.530513 -354.358575) (xy 315.584495 -354.350809)
			(xy 315.611764 -354.35032) (xy 316.475364 -354.35032) (xy 316.502635 -354.350817) (xy 316.556624 -354.358575)
			(xy 316.608958 -354.373937) (xy 316.658574 -354.396591) (xy 316.70446 -354.426077) (xy 316.745682 -354.461793)
			(xy 316.781402 -354.503012) (xy 316.810891 -354.548895) (xy 316.83355 -354.598508) (xy 316.848918 -354.650841)
			(xy 316.85668 -354.704829) (xy 316.85668 -354.759371) (xy 316.85668 -354.759373) (xy 318.339384 -354.759373)
			(xy 318.339384 -354.704827) (xy 318.347147 -354.650835) (xy 318.362515 -354.598498) (xy 318.385175 -354.548881)
			(xy 318.414667 -354.502994) (xy 318.450388 -354.461771) (xy 318.491613 -354.426052) (xy 318.537502 -354.396564)
			(xy 318.587121 -354.373907) (xy 318.639459 -354.358542) (xy 318.693451 -354.350782) (xy 318.720724 -354.35032)
			(xy 319.584324 -354.35032) (xy 319.611591 -354.350844) (xy 319.665569 -354.358608) (xy 319.717894 -354.373975)
			(xy 319.767498 -354.396631) (xy 319.813374 -354.426116) (xy 319.854587 -354.46183) (xy 319.890298 -354.503045)
			(xy 319.91978 -354.548923) (xy 319.942434 -354.598529) (xy 319.957797 -354.650854) (xy 319.965558 -354.704833)
			(xy 319.965558 -354.759367) (xy 319.965558 -354.75937) (xy 321.448406 -354.75937) (xy 321.448406 -354.70483)
			(xy 321.456168 -354.650845) (xy 321.471533 -354.598515) (xy 321.494189 -354.548903) (xy 321.523675 -354.503021)
			(xy 321.55939 -354.461802) (xy 321.600608 -354.426085) (xy 321.646489 -354.396597) (xy 321.6961 -354.373939)
			(xy 321.74843 -354.358571) (xy 321.802414 -354.350808) (xy 321.829684 -354.35032) (xy 322.693284 -354.35032)
			(xy 322.720554 -354.350818) (xy 322.774541 -354.358578) (xy 322.826873 -354.373942) (xy 322.876485 -354.396598)
			(xy 322.922369 -354.426084) (xy 322.963589 -354.4618) (xy 322.999307 -354.503018) (xy 323.028794 -354.5489)
			(xy 323.051452 -354.598512) (xy 323.066818 -354.650844) (xy 323.074581 -354.70483) (xy 323.074581 -354.75937)
			(xy 323.07458 -354.759374) (xy 324.557284 -354.759374) (xy 324.557284 -354.704826) (xy 324.565047 -354.650832)
			(xy 324.580417 -354.598494) (xy 324.603078 -354.548875) (xy 324.632571 -354.502987) (xy 324.668295 -354.461764)
			(xy 324.709523 -354.426045) (xy 324.755414 -354.396557) (xy 324.805035 -354.373901) (xy 324.857375 -354.358538)
			(xy 324.91137 -354.350781) (xy 324.938644 -354.35032) (xy 325.802244 -354.35032) (xy 325.82951 -354.350845)
			(xy 325.883486 -354.358612) (xy 325.935808 -354.37398) (xy 325.98541 -354.396638) (xy 326.031284 -354.426124)
			(xy 326.072494 -354.461837) (xy 326.108203 -354.503052) (xy 326.137683 -354.548928) (xy 326.160335 -354.598533)
			(xy 326.175698 -354.650857) (xy 326.183458 -354.704834) (xy 326.183458 -354.759366) (xy 326.183457 -354.759372)
			(xy 327.666284 -354.759372) (xy 327.666284 -354.704828) (xy 327.674046 -354.650838) (xy 327.689413 -354.598502)
			(xy 327.712072 -354.548887) (xy 327.741562 -354.503001) (xy 327.777281 -354.461778) (xy 327.818504 -354.426059)
			(xy 327.86439 -354.39657) (xy 327.914006 -354.373912) (xy 327.966342 -354.358545) (xy 328.020332 -354.350783)
			(xy 328.047604 -354.35032) (xy 328.911204 -354.35032) (xy 328.938472 -354.350843) (xy 328.992453 -354.358604)
			(xy 329.044779 -354.373969) (xy 329.094386 -354.396625) (xy 329.140265 -354.426109) (xy 329.18148 -354.461823)
			(xy 329.217193 -354.503039) (xy 329.246677 -354.548917) (xy 329.269332 -354.598525) (xy 329.284696 -354.650851)
			(xy 329.292458 -354.704832) (xy 329.292458 -354.759368) (xy 329.292458 -354.759369) (xy 330.775306 -354.759369)
			(xy 330.775306 -354.704831) (xy 330.783067 -354.650848) (xy 330.798432 -354.598519) (xy 330.821086 -354.548909)
			(xy 330.85057 -354.503027) (xy 330.886283 -354.461809) (xy 330.927499 -354.426092) (xy 330.973377 -354.396604)
			(xy 331.022985 -354.373944) (xy 331.075313 -354.358575) (xy 331.129295 -354.350809) (xy 331.156564 -354.35032)
			(xy 332.020164 -354.35032) (xy 332.047435 -354.350817) (xy 332.101424 -354.358575) (xy 332.153758 -354.373937)
			(xy 332.203374 -354.396591) (xy 332.24926 -354.426077) (xy 332.290482 -354.461793) (xy 332.326202 -354.503012)
			(xy 332.355691 -354.548895) (xy 332.37835 -354.598508) (xy 332.393718 -354.650841) (xy 332.40148 -354.704829)
			(xy 332.40148 -354.759371) (xy 332.40148 -354.759373) (xy 333.884184 -354.759373) (xy 333.884184 -354.704827)
			(xy 333.891947 -354.650835) (xy 333.907315 -354.598498) (xy 333.929975 -354.548881) (xy 333.959467 -354.502994)
			(xy 333.995188 -354.461771) (xy 334.036413 -354.426052) (xy 334.082302 -354.396564) (xy 334.131921 -354.373907)
			(xy 334.184259 -354.358542) (xy 334.238251 -354.350782) (xy 334.265524 -354.35032) (xy 335.129124 -354.35032)
			(xy 335.156391 -354.350844) (xy 335.210369 -354.358608) (xy 335.262694 -354.373975) (xy 335.312298 -354.396631)
			(xy 335.358174 -354.426116) (xy 335.399387 -354.46183) (xy 335.435098 -354.503045) (xy 335.46458 -354.548923)
			(xy 335.487234 -354.598529) (xy 335.502597 -354.650854) (xy 335.510358 -354.704833) (xy 335.510358 -354.759367)
			(xy 335.510358 -354.75937) (xy 336.993206 -354.75937) (xy 336.993206 -354.70483) (xy 337.000968 -354.650845)
			(xy 337.016333 -354.598515) (xy 337.038989 -354.548903) (xy 337.068475 -354.503021) (xy 337.10419 -354.461802)
			(xy 337.145408 -354.426085) (xy 337.191289 -354.396597) (xy 337.2409 -354.373939) (xy 337.29323 -354.358571)
			(xy 337.347214 -354.350808) (xy 337.374484 -354.35032) (xy 338.238084 -354.35032) (xy 338.265354 -354.350818)
			(xy 338.319341 -354.358578) (xy 338.371673 -354.373942) (xy 338.421285 -354.396598) (xy 338.467169 -354.426084)
			(xy 338.508389 -354.4618) (xy 338.544107 -354.503018) (xy 338.573594 -354.5489) (xy 338.596252 -354.598512)
			(xy 338.611618 -354.650844) (xy 338.619381 -354.70483) (xy 338.619381 -354.75937) (xy 338.61938 -354.759374)
			(xy 340.102084 -354.759374) (xy 340.102084 -354.704826) (xy 340.109847 -354.650832) (xy 340.125217 -354.598494)
			(xy 340.147878 -354.548875) (xy 340.177371 -354.502987) (xy 340.213095 -354.461764) (xy 340.254323 -354.426045)
			(xy 340.300214 -354.396557) (xy 340.349835 -354.373901) (xy 340.402175 -354.358538) (xy 340.45617 -354.350781)
			(xy 340.483444 -354.35032) (xy 341.347044 -354.35032) (xy 341.37431 -354.350845) (xy 341.428286 -354.358612)
			(xy 341.480608 -354.37398) (xy 341.53021 -354.396638) (xy 341.576084 -354.426124) (xy 341.617294 -354.461837)
			(xy 341.653003 -354.503052) (xy 341.682483 -354.548928) (xy 341.705135 -354.598533) (xy 341.720498 -354.650857)
			(xy 341.728258 -354.704834) (xy 341.728258 -354.759366) (xy 341.728257 -354.759372) (xy 343.211084 -354.759372)
			(xy 343.211084 -354.704828) (xy 343.218846 -354.650838) (xy 343.234213 -354.598502) (xy 343.256872 -354.548887)
			(xy 343.286362 -354.503001) (xy 343.322081 -354.461778) (xy 343.363304 -354.426059) (xy 343.40919 -354.39657)
			(xy 343.458806 -354.373912) (xy 343.511142 -354.358545) (xy 343.565132 -354.350783) (xy 343.592404 -354.35032)
			(xy 344.456004 -354.35032) (xy 344.483272 -354.350843) (xy 344.537253 -354.358604) (xy 344.589579 -354.373969)
			(xy 344.639186 -354.396625) (xy 344.685065 -354.426109) (xy 344.72628 -354.461823) (xy 344.761993 -354.503039)
			(xy 344.791477 -354.548917) (xy 344.814132 -354.598525) (xy 344.829496 -354.650851) (xy 344.837258 -354.704832)
			(xy 344.837258 -354.759368) (xy 344.837257 -354.759374) (xy 373.915584 -354.759374) (xy 373.915584 -354.704826)
			(xy 373.923347 -354.650833) (xy 373.938716 -354.598495) (xy 373.961378 -354.548876) (xy 373.990871 -354.502989)
			(xy 374.026594 -354.461766) (xy 374.067821 -354.426047) (xy 374.113712 -354.396559) (xy 374.163332 -354.373902)
			(xy 374.215672 -354.358539) (xy 374.269666 -354.350781) (xy 374.29694 -354.35032) (xy 375.16054 -354.35032)
			(xy 375.187806 -354.350845) (xy 375.241783 -354.358611) (xy 375.294105 -354.373979) (xy 375.343708 -354.396637)
			(xy 375.389582 -354.426122) (xy 375.430793 -354.461836) (xy 375.466502 -354.50305) (xy 375.495983 -354.548927)
			(xy 375.518635 -354.598532) (xy 375.533997 -354.650856) (xy 375.541758 -354.704834) (xy 375.541758 -354.759366)
			(xy 375.541757 -354.759371) (xy 377.024606 -354.759371) (xy 377.024606 -354.704829) (xy 377.032369 -354.650843)
			(xy 377.047735 -354.598511) (xy 377.070392 -354.548899) (xy 377.099879 -354.503016) (xy 377.135596 -354.461796)
			(xy 377.176816 -354.426079) (xy 377.222699 -354.396592) (xy 377.272311 -354.373935) (xy 377.324643 -354.358569)
			(xy 377.378629 -354.350806) (xy 377.4059 -354.35032) (xy 378.2695 -354.35032) (xy 378.296768 -354.350842)
			(xy 378.350749 -354.358604) (xy 378.403076 -354.373968) (xy 378.452684 -354.396623) (xy 378.498563 -354.426108)
			(xy 378.539778 -354.461822) (xy 378.575492 -354.503037) (xy 378.604977 -354.548916) (xy 378.627632 -354.598524)
			(xy 378.642996 -354.650851) (xy 378.650758 -354.704832) (xy 378.650758 -354.759368) (xy 378.650758 -354.759369)
			(xy 380.133606 -354.759369) (xy 380.133606 -354.704831) (xy 380.141367 -354.650849) (xy 380.156731 -354.59852)
			(xy 380.179386 -354.54891) (xy 380.208869 -354.503029) (xy 380.244582 -354.46181) (xy 380.285797 -354.426093)
			(xy 380.331675 -354.396605) (xy 380.381282 -354.373945) (xy 380.433609 -354.358576) (xy 380.487591 -354.350809)
			(xy 380.51486 -354.35032) (xy 381.37846 -354.35032) (xy 381.405732 -354.350817) (xy 381.45972 -354.358574)
			(xy 381.512055 -354.373936) (xy 381.561671 -354.39659) (xy 381.607558 -354.426075) (xy 381.648781 -354.461791)
			(xy 381.684501 -354.50301) (xy 381.713991 -354.548894) (xy 381.73665 -354.598507) (xy 381.752018 -354.650841)
			(xy 381.75978 -354.704828) (xy 381.75978 -354.759372) (xy 381.75978 -354.759373) (xy 383.242484 -354.759373)
			(xy 383.242484 -354.704827) (xy 383.250247 -354.650836) (xy 383.265615 -354.598499) (xy 383.288275 -354.548882)
			(xy 383.317766 -354.502995) (xy 383.353487 -354.461773) (xy 383.394711 -354.426054) (xy 383.4406 -354.396565)
			(xy 383.490218 -354.373908) (xy 383.542555 -354.358542) (xy 383.596547 -354.350782) (xy 383.62382 -354.35032)
			(xy 384.48742 -354.35032) (xy 384.514687 -354.350844) (xy 384.568666 -354.358607) (xy 384.620991 -354.373974)
			(xy 384.670596 -354.39663) (xy 384.716472 -354.426115) (xy 384.757686 -354.461829) (xy 384.793397 -354.503044)
			(xy 384.82288 -354.548922) (xy 384.845533 -354.598528) (xy 384.860897 -354.650854) (xy 384.868658 -354.704833)
			(xy 384.868658 -354.759367) (xy 384.868658 -354.75937) (xy 386.351506 -354.75937) (xy 386.351506 -354.70483)
			(xy 386.359268 -354.650846) (xy 386.374633 -354.598515) (xy 386.397289 -354.548904) (xy 386.426774 -354.503022)
			(xy 386.462489 -354.461803) (xy 386.503706 -354.426086) (xy 386.549587 -354.396598) (xy 386.599197 -354.37394)
			(xy 386.651526 -354.358572) (xy 386.70551 -354.350808) (xy 386.73278 -354.35032) (xy 387.59638 -354.35032)
			(xy 387.623651 -354.350818) (xy 387.677637 -354.358578) (xy 387.72997 -354.373941) (xy 387.779583 -354.396597)
			(xy 387.825467 -354.426082) (xy 387.866688 -354.461798) (xy 387.902406 -354.503017) (xy 387.931894 -354.548899)
			(xy 387.954552 -354.598511) (xy 387.969918 -354.650843) (xy 387.97768 -354.704829) (xy 387.97768 -354.759371)
			(xy 387.97768 -354.759374) (xy 389.460384 -354.759374) (xy 389.460384 -354.704826) (xy 389.468147 -354.650833)
			(xy 389.483516 -354.598495) (xy 389.506178 -354.548876) (xy 389.535671 -354.502989) (xy 389.571394 -354.461766)
			(xy 389.612621 -354.426047) (xy 389.658512 -354.396559) (xy 389.708132 -354.373902) (xy 389.760472 -354.358539)
			(xy 389.814466 -354.350781) (xy 389.84174 -354.35032) (xy 390.70534 -354.35032) (xy 390.732606 -354.350845)
			(xy 390.786583 -354.358611) (xy 390.838905 -354.373979) (xy 390.888508 -354.396637) (xy 390.934382 -354.426122)
			(xy 390.975593 -354.461836) (xy 391.011302 -354.50305) (xy 391.040783 -354.548927) (xy 391.063435 -354.598532)
			(xy 391.078797 -354.650856) (xy 391.086558 -354.704834) (xy 391.086558 -354.759366) (xy 391.086557 -354.759371)
			(xy 392.569406 -354.759371) (xy 392.569406 -354.704829) (xy 392.577169 -354.650843) (xy 392.592535 -354.598511)
			(xy 392.615192 -354.548899) (xy 392.644679 -354.503016) (xy 392.680396 -354.461796) (xy 392.721616 -354.426079)
			(xy 392.767499 -354.396592) (xy 392.817111 -354.373935) (xy 392.869443 -354.358569) (xy 392.923429 -354.350806)
			(xy 392.9507 -354.35032) (xy 393.8143 -354.35032) (xy 393.841568 -354.350842) (xy 393.895549 -354.358604)
			(xy 393.947876 -354.373968) (xy 393.997484 -354.396623) (xy 394.043363 -354.426108) (xy 394.084578 -354.461822)
			(xy 394.120292 -354.503037) (xy 394.149777 -354.548916) (xy 394.172432 -354.598524) (xy 394.187796 -354.650851)
			(xy 394.195558 -354.704832) (xy 394.195558 -354.759368) (xy 394.195558 -354.759369) (xy 395.678406 -354.759369)
			(xy 395.678406 -354.704831) (xy 395.686167 -354.650849) (xy 395.701531 -354.59852) (xy 395.724186 -354.54891)
			(xy 395.753669 -354.503029) (xy 395.789382 -354.46181) (xy 395.830597 -354.426093) (xy 395.876475 -354.396605)
			(xy 395.926082 -354.373945) (xy 395.978409 -354.358576) (xy 396.032391 -354.350809) (xy 396.05966 -354.35032)
			(xy 396.92326 -354.35032) (xy 396.950532 -354.350817) (xy 397.00452 -354.358574) (xy 397.056855 -354.373936)
			(xy 397.106471 -354.39659) (xy 397.152358 -354.426075) (xy 397.193581 -354.461791) (xy 397.229301 -354.50301)
			(xy 397.258791 -354.548894) (xy 397.28145 -354.598507) (xy 397.296818 -354.650841) (xy 397.30458 -354.704828)
			(xy 397.30458 -354.759372) (xy 397.30458 -354.759373) (xy 398.787284 -354.759373) (xy 398.787284 -354.704827)
			(xy 398.795047 -354.650836) (xy 398.810415 -354.598499) (xy 398.833075 -354.548882) (xy 398.862566 -354.502995)
			(xy 398.898287 -354.461773) (xy 398.939511 -354.426054) (xy 398.9854 -354.396565) (xy 399.035018 -354.373908)
			(xy 399.087355 -354.358542) (xy 399.141347 -354.350782) (xy 399.16862 -354.35032) (xy 400.03222 -354.35032)
			(xy 400.059487 -354.350844) (xy 400.113466 -354.358607) (xy 400.165791 -354.373974) (xy 400.215396 -354.39663)
			(xy 400.261272 -354.426115) (xy 400.302486 -354.461829) (xy 400.338197 -354.503044) (xy 400.36768 -354.548922)
			(xy 400.390333 -354.598528) (xy 400.405697 -354.650854) (xy 400.413458 -354.704833) (xy 400.413458 -354.759367)
			(xy 400.413458 -354.75937) (xy 401.896306 -354.75937) (xy 401.896306 -354.70483) (xy 401.904068 -354.650846)
			(xy 401.919433 -354.598515) (xy 401.942089 -354.548904) (xy 401.971574 -354.503022) (xy 402.007289 -354.461803)
			(xy 402.048506 -354.426086) (xy 402.094387 -354.396598) (xy 402.143997 -354.37394) (xy 402.196326 -354.358572)
			(xy 402.25031 -354.350808) (xy 402.27758 -354.35032) (xy 403.14118 -354.35032) (xy 403.168451 -354.350818)
			(xy 403.222437 -354.358578) (xy 403.27477 -354.373941) (xy 403.324383 -354.396597) (xy 403.370267 -354.426082)
			(xy 403.411488 -354.461798) (xy 403.447206 -354.503017) (xy 403.476694 -354.548899) (xy 403.499352 -354.598511)
			(xy 403.514718 -354.650843) (xy 403.52248 -354.704829) (xy 403.52248 -354.759368) (xy 412.022806 -354.759368)
			(xy 412.022806 -354.704832) (xy 412.030567 -354.65085) (xy 412.045931 -354.598521) (xy 412.068585 -354.548912)
			(xy 412.098067 -354.503031) (xy 412.133779 -354.461813) (xy 412.174993 -354.426096) (xy 412.22087 -354.396608)
			(xy 412.270476 -354.373948) (xy 412.322803 -354.358577) (xy 412.376784 -354.35081) (xy 412.404052 -354.35032)
			(xy 413.267652 -354.35032) (xy 413.294924 -354.350816) (xy 413.348913 -354.358572) (xy 413.401249 -354.373934)
			(xy 413.450866 -354.396588) (xy 413.496754 -354.426072) (xy 413.537978 -354.461788) (xy 413.573699 -354.503008)
			(xy 413.603189 -354.548891) (xy 413.625849 -354.598506) (xy 413.641217 -354.65084) (xy 413.64898 -354.704828)
			(xy 413.64898 -354.759372) (xy 413.64898 -354.759373) (xy 415.131684 -354.759373) (xy 415.131684 -354.704827)
			(xy 415.139446 -354.650837) (xy 415.154814 -354.598501) (xy 415.177473 -354.548884) (xy 415.206964 -354.502998)
			(xy 415.242684 -354.461776) (xy 415.283908 -354.426056) (xy 415.329795 -354.396568) (xy 415.379412 -354.37391)
			(xy 415.431748 -354.358544) (xy 415.485739 -354.350783) (xy 415.513012 -354.35032) (xy 416.376612 -354.35032)
			(xy 416.40388 -354.350843) (xy 416.457859 -354.358606) (xy 416.510185 -354.373972) (xy 416.559791 -354.396627)
			(xy 416.605668 -354.426112) (xy 416.646883 -354.461826) (xy 416.682595 -354.503041) (xy 416.712078 -354.548919)
			(xy 416.734733 -354.598526) (xy 416.750097 -354.650852) (xy 416.757858 -354.704832) (xy 416.757858 -354.759368)
			(xy 416.757858 -354.759369) (xy 418.240706 -354.759369) (xy 418.240706 -354.704831) (xy 418.248468 -354.650847)
			(xy 418.263832 -354.598517) (xy 418.286488 -354.548907) (xy 418.315972 -354.503025) (xy 418.351686 -354.461806)
			(xy 418.392902 -354.426089) (xy 418.438782 -354.396601) (xy 418.488391 -354.373942) (xy 418.54072 -354.358574)
			(xy 418.594703 -354.350808) (xy 418.621972 -354.35032) (xy 419.485572 -354.35032) (xy 419.512843 -354.350818)
			(xy 419.56683 -354.358576) (xy 419.619164 -354.373939) (xy 419.668778 -354.396594) (xy 419.714663 -354.42608)
			(xy 419.755885 -354.461795) (xy 419.791604 -354.503014) (xy 419.821092 -354.548897) (xy 419.843751 -354.59851)
			(xy 419.859118 -354.650842) (xy 419.86688 -354.704829) (xy 419.86688 -354.759371) (xy 419.86688 -354.759374)
			(xy 421.349584 -354.759374) (xy 421.349584 -354.704826) (xy 421.357347 -354.650834) (xy 421.372716 -354.598496)
			(xy 421.395377 -354.548879) (xy 421.424869 -354.502991) (xy 421.460591 -354.461768) (xy 421.501817 -354.426049)
			(xy 421.547707 -354.396561) (xy 421.597326 -354.373904) (xy 421.649665 -354.35854) (xy 421.703658 -354.350781)
			(xy 421.730932 -354.35032) (xy 422.594532 -354.35032) (xy 422.621799 -354.350845) (xy 422.675776 -354.35861)
			(xy 422.728099 -354.373977) (xy 422.777703 -354.396634) (xy 422.823578 -354.426119) (xy 422.86479 -354.461833)
			(xy 422.9005 -354.503048) (xy 422.929981 -354.548925) (xy 422.952634 -354.598531) (xy 422.967997 -354.650855)
			(xy 422.975758 -354.704833) (xy 422.975758 -354.759367) (xy 422.975758 -354.75937) (xy 424.458606 -354.75937)
			(xy 424.458606 -354.70483) (xy 424.466368 -354.650844) (xy 424.481734 -354.598513) (xy 424.504391 -354.548901)
			(xy 424.533877 -354.503018) (xy 424.569593 -354.461799) (xy 424.610812 -354.426082) (xy 424.656694 -354.396594)
			(xy 424.706305 -354.373937) (xy 424.758636 -354.35857) (xy 424.812622 -354.350807) (xy 424.839892 -354.35032)
			(xy 425.703492 -354.35032) (xy 425.730762 -354.350819) (xy 425.784747 -354.35858) (xy 425.837078 -354.373945)
			(xy 425.88669 -354.396601) (xy 425.932573 -354.426087) (xy 425.973792 -354.461802) (xy 426.009509 -354.503021)
			(xy 426.038996 -354.548903) (xy 426.061653 -354.598514) (xy 426.077019 -354.650845) (xy 426.084781 -354.70483)
			(xy 426.084781 -354.759368) (xy 427.567606 -354.759368) (xy 427.567606 -354.704832) (xy 427.575367 -354.65085)
			(xy 427.590731 -354.598521) (xy 427.613385 -354.548912) (xy 427.642867 -354.503031) (xy 427.678579 -354.461813)
			(xy 427.719793 -354.426096) (xy 427.76567 -354.396608) (xy 427.815276 -354.373948) (xy 427.867603 -354.358577)
			(xy 427.921584 -354.35081) (xy 427.948852 -354.35032) (xy 428.812452 -354.35032) (xy 428.839724 -354.350816)
			(xy 428.893713 -354.358572) (xy 428.946049 -354.373934) (xy 428.995666 -354.396588) (xy 429.041554 -354.426072)
			(xy 429.082778 -354.461788) (xy 429.118499 -354.503008) (xy 429.147989 -354.548891) (xy 429.170649 -354.598506)
			(xy 429.186017 -354.65084) (xy 429.19378 -354.704828) (xy 429.19378 -354.759372) (xy 429.19378 -354.759373)
			(xy 430.676484 -354.759373) (xy 430.676484 -354.704827) (xy 430.684246 -354.650837) (xy 430.699614 -354.598501)
			(xy 430.722273 -354.548884) (xy 430.751764 -354.502998) (xy 430.787484 -354.461776) (xy 430.828708 -354.426056)
			(xy 430.874595 -354.396568) (xy 430.924212 -354.37391) (xy 430.976548 -354.358544) (xy 431.030539 -354.350783)
			(xy 431.057812 -354.35032) (xy 431.921412 -354.35032) (xy 431.94868 -354.350843) (xy 432.002659 -354.358606)
			(xy 432.054985 -354.373972) (xy 432.104591 -354.396627) (xy 432.150468 -354.426112) (xy 432.191683 -354.461826)
			(xy 432.227395 -354.503041) (xy 432.256878 -354.548919) (xy 432.279533 -354.598526) (xy 432.294897 -354.650852)
			(xy 432.302658 -354.704832) (xy 432.302658 -354.759368) (xy 432.302658 -354.759369) (xy 433.785506 -354.759369)
			(xy 433.785506 -354.704831) (xy 433.793268 -354.650847) (xy 433.808632 -354.598517) (xy 433.831288 -354.548907)
			(xy 433.860772 -354.503025) (xy 433.896486 -354.461806) (xy 433.937702 -354.426089) (xy 433.983582 -354.396601)
			(xy 434.033191 -354.373942) (xy 434.08552 -354.358574) (xy 434.139503 -354.350808) (xy 434.166772 -354.35032)
			(xy 435.030372 -354.35032) (xy 435.057643 -354.350818) (xy 435.11163 -354.358576) (xy 435.163964 -354.373939)
			(xy 435.213578 -354.396594) (xy 435.259463 -354.42608) (xy 435.300685 -354.461795) (xy 435.336404 -354.503014)
			(xy 435.365892 -354.548897) (xy 435.388551 -354.59851) (xy 435.403918 -354.650842) (xy 435.41168 -354.704829)
			(xy 435.41168 -354.759371) (xy 435.41168 -354.759374) (xy 436.894384 -354.759374) (xy 436.894384 -354.704826)
			(xy 436.902147 -354.650834) (xy 436.917516 -354.598496) (xy 436.940177 -354.548879) (xy 436.969669 -354.502991)
			(xy 437.005391 -354.461768) (xy 437.046617 -354.426049) (xy 437.092507 -354.396561) (xy 437.142126 -354.373904)
			(xy 437.194465 -354.35854) (xy 437.248458 -354.350781) (xy 437.275732 -354.35032) (xy 438.139332 -354.35032)
			(xy 438.166599 -354.350845) (xy 438.220576 -354.35861) (xy 438.272899 -354.373977) (xy 438.322503 -354.396634)
			(xy 438.368378 -354.426119) (xy 438.40959 -354.461833) (xy 438.4453 -354.503048) (xy 438.474781 -354.548925)
			(xy 438.497434 -354.598531) (xy 438.512797 -354.650855) (xy 438.520558 -354.704833) (xy 438.520558 -354.759367)
			(xy 438.520558 -354.75937) (xy 440.003406 -354.75937) (xy 440.003406 -354.70483) (xy 440.011168 -354.650844)
			(xy 440.026534 -354.598513) (xy 440.049191 -354.548901) (xy 440.078677 -354.503018) (xy 440.114393 -354.461799)
			(xy 440.155612 -354.426082) (xy 440.201494 -354.396594) (xy 440.251105 -354.373937) (xy 440.303436 -354.35857)
			(xy 440.357422 -354.350807) (xy 440.384692 -354.35032) (xy 441.248292 -354.35032) (xy 441.275562 -354.350819)
			(xy 441.329547 -354.35858) (xy 441.381878 -354.373945) (xy 441.43149 -354.396601) (xy 441.477373 -354.426087)
			(xy 441.518592 -354.461802) (xy 441.554309 -354.503021) (xy 441.583796 -354.548903) (xy 441.606453 -354.598514)
			(xy 441.621819 -354.650845) (xy 441.629581 -354.70483) (xy 441.629581 -354.75937) (xy 441.621819 -354.813355)
			(xy 441.606453 -354.865686) (xy 441.583796 -354.915297) (xy 441.554309 -354.961179) (xy 441.518592 -355.002398)
			(xy 441.477373 -355.038113) (xy 441.43149 -355.067599) (xy 441.381878 -355.090255) (xy 441.329547 -355.10562)
			(xy 441.275562 -355.113381) (xy 441.248292 -355.113844) (xy 440.384692 -355.113844) (xy 440.357422 -355.113393)
			(xy 440.303436 -355.10563) (xy 440.251105 -355.090263) (xy 440.201494 -355.067606) (xy 440.155612 -355.038118)
			(xy 440.114393 -355.002401) (xy 440.078677 -354.961182) (xy 440.049191 -354.915299) (xy 440.026534 -354.865687)
			(xy 440.011168 -354.813356) (xy 440.003406 -354.75937) (xy 438.520558 -354.75937) (xy 438.512797 -354.813345)
			(xy 438.497434 -354.865669) (xy 438.474781 -354.915275) (xy 438.4453 -354.961152) (xy 438.40959 -355.002367)
			(xy 438.368378 -355.038081) (xy 438.322503 -355.067566) (xy 438.272899 -355.090223) (xy 438.220576 -355.10559)
			(xy 438.166599 -355.113355) (xy 438.139332 -355.113844) (xy 437.275732 -355.113844) (xy 437.248458 -355.113419)
			(xy 437.194465 -355.10566) (xy 437.142126 -355.090296) (xy 437.092507 -355.067639) (xy 437.046617 -355.038151)
			(xy 437.005391 -355.002432) (xy 436.969669 -354.961209) (xy 436.940177 -354.915321) (xy 436.917516 -354.865704)
			(xy 436.902147 -354.813366) (xy 436.894384 -354.759374) (xy 435.41168 -354.759374) (xy 435.403918 -354.813358)
			(xy 435.388551 -354.86569) (xy 435.365892 -354.915303) (xy 435.336404 -354.961186) (xy 435.300685 -355.002405)
			(xy 435.259463 -355.03812) (xy 435.213578 -355.067606) (xy 435.163964 -355.090261) (xy 435.11163 -355.105624)
			(xy 435.057643 -355.113382) (xy 435.030372 -355.113844) (xy 434.166772 -355.113844) (xy 434.139503 -355.113392)
			(xy 434.08552 -355.105626) (xy 434.033191 -355.090258) (xy 433.983582 -355.067599) (xy 433.937702 -355.038111)
			(xy 433.896486 -355.002394) (xy 433.860772 -354.961175) (xy 433.831288 -354.915293) (xy 433.808632 -354.865683)
			(xy 433.793268 -354.813353) (xy 433.785506 -354.759369) (xy 432.302658 -354.759369) (xy 432.294897 -354.813348)
			(xy 432.279533 -354.865674) (xy 432.256878 -354.915281) (xy 432.227395 -354.961159) (xy 432.191683 -355.002374)
			(xy 432.150468 -355.038088) (xy 432.104591 -355.067573) (xy 432.054985 -355.090228) (xy 432.002659 -355.105594)
			(xy 431.94868 -355.113357) (xy 431.921412 -355.113844) (xy 431.057812 -355.113844) (xy 431.030539 -355.113417)
			(xy 430.976548 -355.105656) (xy 430.924212 -355.09029) (xy 430.874595 -355.067632) (xy 430.828708 -355.038144)
			(xy 430.787484 -355.002424) (xy 430.751764 -354.961202) (xy 430.722273 -354.915316) (xy 430.699614 -354.865699)
			(xy 430.684246 -354.813363) (xy 430.676484 -354.759373) (xy 429.19378 -354.759373) (xy 429.186017 -354.81336)
			(xy 429.170649 -354.865694) (xy 429.147989 -354.915309) (xy 429.118499 -354.961192) (xy 429.082778 -355.002412)
			(xy 429.041554 -355.038128) (xy 428.995666 -355.067612) (xy 428.946049 -355.090266) (xy 428.893713 -355.105628)
			(xy 428.839724 -355.113384) (xy 428.812452 -355.113844) (xy 427.948852 -355.113844) (xy 427.921584 -355.11339)
			(xy 427.867603 -355.105623) (xy 427.815276 -355.090252) (xy 427.76567 -355.067592) (xy 427.719793 -355.038104)
			(xy 427.678579 -355.002387) (xy 427.642867 -354.961169) (xy 427.613385 -354.915288) (xy 427.590731 -354.865679)
			(xy 427.575367 -354.81335) (xy 427.567606 -354.759368) (xy 426.084781 -354.759368) (xy 426.084781 -354.75937)
			(xy 426.077019 -354.813355) (xy 426.061653 -354.865686) (xy 426.038996 -354.915297) (xy 426.009509 -354.961179)
			(xy 425.973792 -355.002398) (xy 425.932573 -355.038113) (xy 425.88669 -355.067599) (xy 425.837078 -355.090255)
			(xy 425.784747 -355.10562) (xy 425.730762 -355.113381) (xy 425.703492 -355.113844) (xy 424.839892 -355.113844)
			(xy 424.812622 -355.113393) (xy 424.758636 -355.10563) (xy 424.706305 -355.090263) (xy 424.656694 -355.067606)
			(xy 424.610812 -355.038118) (xy 424.569593 -355.002401) (xy 424.533877 -354.961182) (xy 424.504391 -354.915299)
			(xy 424.481734 -354.865687) (xy 424.466368 -354.813356) (xy 424.458606 -354.75937) (xy 422.975758 -354.75937)
			(xy 422.967997 -354.813345) (xy 422.952634 -354.865669) (xy 422.929981 -354.915275) (xy 422.9005 -354.961152)
			(xy 422.86479 -355.002367) (xy 422.823578 -355.038081) (xy 422.777703 -355.067566) (xy 422.728099 -355.090223)
			(xy 422.675776 -355.10559) (xy 422.621799 -355.113355) (xy 422.594532 -355.113844) (xy 421.730932 -355.113844)
			(xy 421.703658 -355.113419) (xy 421.649665 -355.10566) (xy 421.597326 -355.090296) (xy 421.547707 -355.067639)
			(xy 421.501817 -355.038151) (xy 421.460591 -355.002432) (xy 421.424869 -354.961209) (xy 421.395377 -354.915321)
			(xy 421.372716 -354.865704) (xy 421.357347 -354.813366) (xy 421.349584 -354.759374) (xy 419.86688 -354.759374)
			(xy 419.859118 -354.813358) (xy 419.843751 -354.86569) (xy 419.821092 -354.915303) (xy 419.791604 -354.961186)
			(xy 419.755885 -355.002405) (xy 419.714663 -355.03812) (xy 419.668778 -355.067606) (xy 419.619164 -355.090261)
			(xy 419.56683 -355.105624) (xy 419.512843 -355.113382) (xy 419.485572 -355.113844) (xy 418.621972 -355.113844)
			(xy 418.594703 -355.113392) (xy 418.54072 -355.105626) (xy 418.488391 -355.090258) (xy 418.438782 -355.067599)
			(xy 418.392902 -355.038111) (xy 418.351686 -355.002394) (xy 418.315972 -354.961175) (xy 418.286488 -354.915293)
			(xy 418.263832 -354.865683) (xy 418.248468 -354.813353) (xy 418.240706 -354.759369) (xy 416.757858 -354.759369)
			(xy 416.750097 -354.813348) (xy 416.734733 -354.865674) (xy 416.712078 -354.915281) (xy 416.682595 -354.961159)
			(xy 416.646883 -355.002374) (xy 416.605668 -355.038088) (xy 416.559791 -355.067573) (xy 416.510185 -355.090228)
			(xy 416.457859 -355.105594) (xy 416.40388 -355.113357) (xy 416.376612 -355.113844) (xy 415.513012 -355.113844)
			(xy 415.485739 -355.113417) (xy 415.431748 -355.105656) (xy 415.379412 -355.09029) (xy 415.329795 -355.067632)
			(xy 415.283908 -355.038144) (xy 415.242684 -355.002424) (xy 415.206964 -354.961202) (xy 415.177473 -354.915316)
			(xy 415.154814 -354.865699) (xy 415.139446 -354.813363) (xy 415.131684 -354.759373) (xy 413.64898 -354.759373)
			(xy 413.641217 -354.81336) (xy 413.625849 -354.865694) (xy 413.603189 -354.915309) (xy 413.573699 -354.961192)
			(xy 413.537978 -355.002412) (xy 413.496754 -355.038128) (xy 413.450866 -355.067612) (xy 413.401249 -355.090266)
			(xy 413.348913 -355.105628) (xy 413.294924 -355.113384) (xy 413.267652 -355.113844) (xy 412.404052 -355.113844)
			(xy 412.376784 -355.11339) (xy 412.322803 -355.105623) (xy 412.270476 -355.090252) (xy 412.22087 -355.067592)
			(xy 412.174993 -355.038104) (xy 412.133779 -355.002387) (xy 412.098067 -354.961169) (xy 412.068585 -354.915288)
			(xy 412.045931 -354.865679) (xy 412.030567 -354.81335) (xy 412.022806 -354.759368) (xy 403.52248 -354.759368)
			(xy 403.52248 -354.759371) (xy 403.514718 -354.813357) (xy 403.499352 -354.865689) (xy 403.476694 -354.915301)
			(xy 403.447206 -354.961183) (xy 403.411488 -355.002402) (xy 403.370267 -355.038118) (xy 403.324383 -355.067603)
			(xy 403.27477 -355.090259) (xy 403.222437 -355.105622) (xy 403.168451 -355.113382) (xy 403.14118 -355.113844)
			(xy 402.27758 -355.113844) (xy 402.25031 -355.113392) (xy 402.196326 -355.105628) (xy 402.143997 -355.09026)
			(xy 402.094387 -355.067602) (xy 402.048506 -355.038114) (xy 402.007289 -355.002397) (xy 401.971574 -354.961178)
			(xy 401.942089 -354.915296) (xy 401.919433 -354.865685) (xy 401.904068 -354.813354) (xy 401.896306 -354.75937)
			(xy 400.413458 -354.75937) (xy 400.405697 -354.813346) (xy 400.390333 -354.865672) (xy 400.36768 -354.915278)
			(xy 400.338197 -354.961156) (xy 400.302486 -355.002371) (xy 400.261272 -355.038085) (xy 400.215396 -355.06757)
			(xy 400.165791 -355.090226) (xy 400.113466 -355.105593) (xy 400.059487 -355.113356) (xy 400.03222 -355.113844)
			(xy 399.16862 -355.113844) (xy 399.141347 -355.113418) (xy 399.087355 -355.105658) (xy 399.035018 -355.090292)
			(xy 398.9854 -355.067635) (xy 398.939511 -355.038146) (xy 398.898287 -355.002427) (xy 398.862566 -354.961205)
			(xy 398.833075 -354.915318) (xy 398.810415 -354.865701) (xy 398.795047 -354.813364) (xy 398.787284 -354.759373)
			(xy 397.30458 -354.759373) (xy 397.296818 -354.813359) (xy 397.28145 -354.865693) (xy 397.258791 -354.915306)
			(xy 397.229301 -354.96119) (xy 397.193581 -355.002409) (xy 397.152358 -355.038125) (xy 397.106471 -355.06761)
			(xy 397.056855 -355.090264) (xy 397.00452 -355.105626) (xy 396.950532 -355.113383) (xy 396.92326 -355.113844)
			(xy 396.05966 -355.113844) (xy 396.032391 -355.113391) (xy 395.978409 -355.105624) (xy 395.926082 -355.090255)
			(xy 395.876475 -355.067595) (xy 395.830597 -355.038107) (xy 395.789382 -355.00239) (xy 395.753669 -354.961171)
			(xy 395.724186 -354.91529) (xy 395.701531 -354.86568) (xy 395.686167 -354.813351) (xy 395.678406 -354.759369)
			(xy 394.195558 -354.759369) (xy 394.187796 -354.813349) (xy 394.172432 -354.865676) (xy 394.149777 -354.915284)
			(xy 394.120292 -354.961163) (xy 394.084578 -355.002378) (xy 394.043363 -355.038092) (xy 393.997484 -355.067577)
			(xy 393.947876 -355.090232) (xy 393.895549 -355.105596) (xy 393.841568 -355.113358) (xy 393.8143 -355.113844)
			(xy 392.9507 -355.113844) (xy 392.923429 -355.113394) (xy 392.869443 -355.105631) (xy 392.817111 -355.090265)
			(xy 392.767499 -355.067608) (xy 392.721616 -355.038121) (xy 392.680396 -355.002404) (xy 392.644679 -354.961184)
			(xy 392.615192 -354.915301) (xy 392.592535 -354.865689) (xy 392.577169 -354.813357) (xy 392.569406 -354.759371)
			(xy 391.086557 -354.759371) (xy 391.078797 -354.813344) (xy 391.063435 -354.865668) (xy 391.040783 -354.915273)
			(xy 391.011302 -354.96115) (xy 390.975593 -355.002364) (xy 390.934382 -355.038078) (xy 390.888508 -355.067563)
			(xy 390.838905 -355.090221) (xy 390.786583 -355.105589) (xy 390.732606 -355.113355) (xy 390.70534 -355.113844)
			(xy 389.84174 -355.113844) (xy 389.814466 -355.113419) (xy 389.760472 -355.105661) (xy 389.708132 -355.090298)
			(xy 389.658512 -355.067641) (xy 389.612621 -355.038153) (xy 389.571394 -355.002434) (xy 389.535671 -354.961211)
			(xy 389.506178 -354.915324) (xy 389.483516 -354.865705) (xy 389.468147 -354.813367) (xy 389.460384 -354.759374)
			(xy 387.97768 -354.759374) (xy 387.969918 -354.813357) (xy 387.954552 -354.865689) (xy 387.931894 -354.915301)
			(xy 387.902406 -354.961183) (xy 387.866688 -355.002402) (xy 387.825467 -355.038118) (xy 387.779583 -355.067603)
			(xy 387.72997 -355.090259) (xy 387.677637 -355.105622) (xy 387.623651 -355.113382) (xy 387.59638 -355.113844)
			(xy 386.73278 -355.113844) (xy 386.70551 -355.113392) (xy 386.651526 -355.105628) (xy 386.599197 -355.09026)
			(xy 386.549587 -355.067602) (xy 386.503706 -355.038114) (xy 386.462489 -355.002397) (xy 386.426774 -354.961178)
			(xy 386.397289 -354.915296) (xy 386.374633 -354.865685) (xy 386.359268 -354.813354) (xy 386.351506 -354.75937)
			(xy 384.868658 -354.75937) (xy 384.860897 -354.813346) (xy 384.845533 -354.865672) (xy 384.82288 -354.915278)
			(xy 384.793397 -354.961156) (xy 384.757686 -355.002371) (xy 384.716472 -355.038085) (xy 384.670596 -355.06757)
			(xy 384.620991 -355.090226) (xy 384.568666 -355.105593) (xy 384.514687 -355.113356) (xy 384.48742 -355.113844)
			(xy 383.62382 -355.113844) (xy 383.596547 -355.113418) (xy 383.542555 -355.105658) (xy 383.490218 -355.090292)
			(xy 383.4406 -355.067635) (xy 383.394711 -355.038146) (xy 383.353487 -355.002427) (xy 383.317766 -354.961205)
			(xy 383.288275 -354.915318) (xy 383.265615 -354.865701) (xy 383.250247 -354.813364) (xy 383.242484 -354.759373)
			(xy 381.75978 -354.759373) (xy 381.752018 -354.813359) (xy 381.73665 -354.865693) (xy 381.713991 -354.915306)
			(xy 381.684501 -354.96119) (xy 381.648781 -355.002409) (xy 381.607558 -355.038125) (xy 381.561671 -355.06761)
			(xy 381.512055 -355.090264) (xy 381.45972 -355.105626) (xy 381.405732 -355.113383) (xy 381.37846 -355.113844)
			(xy 380.51486 -355.113844) (xy 380.487591 -355.113391) (xy 380.433609 -355.105624) (xy 380.381282 -355.090255)
			(xy 380.331675 -355.067595) (xy 380.285797 -355.038107) (xy 380.244582 -355.00239) (xy 380.208869 -354.961171)
			(xy 380.179386 -354.91529) (xy 380.156731 -354.86568) (xy 380.141367 -354.813351) (xy 380.133606 -354.759369)
			(xy 378.650758 -354.759369) (xy 378.642996 -354.813349) (xy 378.627632 -354.865676) (xy 378.604977 -354.915284)
			(xy 378.575492 -354.961163) (xy 378.539778 -355.002378) (xy 378.498563 -355.038092) (xy 378.452684 -355.067577)
			(xy 378.403076 -355.090232) (xy 378.350749 -355.105596) (xy 378.296768 -355.113358) (xy 378.2695 -355.113844)
			(xy 377.4059 -355.113844) (xy 377.378629 -355.113394) (xy 377.324643 -355.105631) (xy 377.272311 -355.090265)
			(xy 377.222699 -355.067608) (xy 377.176816 -355.038121) (xy 377.135596 -355.002404) (xy 377.099879 -354.961184)
			(xy 377.070392 -354.915301) (xy 377.047735 -354.865689) (xy 377.032369 -354.813357) (xy 377.024606 -354.759371)
			(xy 375.541757 -354.759371) (xy 375.533997 -354.813344) (xy 375.518635 -354.865668) (xy 375.495983 -354.915273)
			(xy 375.466502 -354.96115) (xy 375.430793 -355.002364) (xy 375.389582 -355.038078) (xy 375.343708 -355.067563)
			(xy 375.294105 -355.090221) (xy 375.241783 -355.105589) (xy 375.187806 -355.113355) (xy 375.16054 -355.113844)
			(xy 374.29694 -355.113844) (xy 374.269666 -355.113419) (xy 374.215672 -355.105661) (xy 374.163332 -355.090298)
			(xy 374.113712 -355.067641) (xy 374.067821 -355.038153) (xy 374.026594 -355.002434) (xy 373.990871 -354.961211)
			(xy 373.961378 -354.915324) (xy 373.938716 -354.865705) (xy 373.923347 -354.813367) (xy 373.915584 -354.759374)
			(xy 344.837257 -354.759374) (xy 344.829496 -354.813349) (xy 344.814132 -354.865675) (xy 344.791477 -354.915283)
			(xy 344.761993 -354.961161) (xy 344.72628 -355.002377) (xy 344.685065 -355.038091) (xy 344.639186 -355.067575)
			(xy 344.589579 -355.090231) (xy 344.537253 -355.105596) (xy 344.483272 -355.113357) (xy 344.456004 -355.113844)
			(xy 343.592404 -355.113844) (xy 343.565132 -355.113417) (xy 343.511142 -355.105655) (xy 343.458806 -355.090288)
			(xy 343.40919 -355.06763) (xy 343.363304 -355.038141) (xy 343.322081 -355.002422) (xy 343.286362 -354.961199)
			(xy 343.256872 -354.915313) (xy 343.234213 -354.865698) (xy 343.218846 -354.813362) (xy 343.211084 -354.759372)
			(xy 341.728257 -354.759372) (xy 341.720498 -354.813343) (xy 341.705135 -354.865667) (xy 341.682483 -354.915272)
			(xy 341.653003 -354.961148) (xy 341.617294 -355.002363) (xy 341.576084 -355.038076) (xy 341.53021 -355.067562)
			(xy 341.480608 -355.09022) (xy 341.428286 -355.105588) (xy 341.37431 -355.113355) (xy 341.347044 -355.113844)
			(xy 340.483444 -355.113844) (xy 340.45617 -355.113419) (xy 340.402175 -355.105662) (xy 340.349835 -355.090299)
			(xy 340.300214 -355.067643) (xy 340.254323 -355.038155) (xy 340.213095 -355.002436) (xy 340.177371 -354.961213)
			(xy 340.147878 -354.915325) (xy 340.125217 -354.865706) (xy 340.109847 -354.813368) (xy 340.102084 -354.759374)
			(xy 338.61938 -354.759374) (xy 338.611618 -354.813356) (xy 338.596252 -354.865688) (xy 338.573594 -354.9153)
			(xy 338.544107 -354.961182) (xy 338.508389 -355.0024) (xy 338.467169 -355.038116) (xy 338.421285 -355.067602)
			(xy 338.371673 -355.090258) (xy 338.319341 -355.105622) (xy 338.265354 -355.113382) (xy 338.238084 -355.113844)
			(xy 337.374484 -355.113844) (xy 337.347214 -355.113392) (xy 337.29323 -355.105629) (xy 337.2409 -355.090261)
			(xy 337.191289 -355.067603) (xy 337.145408 -355.038115) (xy 337.10419 -355.002398) (xy 337.068475 -354.961179)
			(xy 337.038989 -354.915297) (xy 337.016333 -354.865685) (xy 337.000968 -354.813355) (xy 336.993206 -354.75937)
			(xy 335.510358 -354.75937) (xy 335.502597 -354.813346) (xy 335.487234 -354.865671) (xy 335.46458 -354.915277)
			(xy 335.435098 -354.961155) (xy 335.399387 -355.00237) (xy 335.358174 -355.038084) (xy 335.312298 -355.067569)
			(xy 335.262694 -355.090225) (xy 335.210369 -355.105592) (xy 335.156391 -355.113356) (xy 335.129124 -355.113844)
			(xy 334.265524 -355.113844) (xy 334.238251 -355.113418) (xy 334.184259 -355.105658) (xy 334.131921 -355.090293)
			(xy 334.082302 -355.067636) (xy 334.036413 -355.038148) (xy 333.995188 -355.002429) (xy 333.959467 -354.961206)
			(xy 333.929975 -354.915319) (xy 333.907315 -354.865702) (xy 333.891947 -354.813365) (xy 333.884184 -354.759373)
			(xy 332.40148 -354.759373) (xy 332.393718 -354.813359) (xy 332.37835 -354.865692) (xy 332.355691 -354.915305)
			(xy 332.326202 -354.961188) (xy 332.290482 -355.002407) (xy 332.24926 -355.038123) (xy 332.203374 -355.067609)
			(xy 332.153758 -355.090263) (xy 332.101424 -355.105625) (xy 332.047435 -355.113383) (xy 332.020164 -355.113844)
			(xy 331.156564 -355.113844) (xy 331.129295 -355.113391) (xy 331.075313 -355.105625) (xy 331.022985 -355.090256)
			(xy 330.973377 -355.067596) (xy 330.927499 -355.038108) (xy 330.886283 -355.002391) (xy 330.85057 -354.961173)
			(xy 330.821086 -354.915291) (xy 330.798432 -354.865681) (xy 330.783067 -354.813352) (xy 330.775306 -354.759369)
			(xy 329.292458 -354.759369) (xy 329.284696 -354.813349) (xy 329.269332 -354.865675) (xy 329.246677 -354.915283)
			(xy 329.217193 -354.961161) (xy 329.18148 -355.002377) (xy 329.140265 -355.038091) (xy 329.094386 -355.067575)
			(xy 329.044779 -355.090231) (xy 328.992453 -355.105596) (xy 328.938472 -355.113357) (xy 328.911204 -355.113844)
			(xy 328.047604 -355.113844) (xy 328.020332 -355.113417) (xy 327.966342 -355.105655) (xy 327.914006 -355.090288)
			(xy 327.86439 -355.06763) (xy 327.818504 -355.038141) (xy 327.777281 -355.002422) (xy 327.741562 -354.961199)
			(xy 327.712072 -354.915313) (xy 327.689413 -354.865698) (xy 327.674046 -354.813362) (xy 327.666284 -354.759372)
			(xy 326.183457 -354.759372) (xy 326.175698 -354.813343) (xy 326.160335 -354.865667) (xy 326.137683 -354.915272)
			(xy 326.108203 -354.961148) (xy 326.072494 -355.002363) (xy 326.031284 -355.038076) (xy 325.98541 -355.067562)
			(xy 325.935808 -355.09022) (xy 325.883486 -355.105588) (xy 325.82951 -355.113355) (xy 325.802244 -355.113844)
			(xy 324.938644 -355.113844) (xy 324.91137 -355.113419) (xy 324.857375 -355.105662) (xy 324.805035 -355.090299)
			(xy 324.755414 -355.067643) (xy 324.709523 -355.038155) (xy 324.668295 -355.002436) (xy 324.632571 -354.961213)
			(xy 324.603078 -354.915325) (xy 324.580417 -354.865706) (xy 324.565047 -354.813368) (xy 324.557284 -354.759374)
			(xy 323.07458 -354.759374) (xy 323.066818 -354.813356) (xy 323.051452 -354.865688) (xy 323.028794 -354.9153)
			(xy 322.999307 -354.961182) (xy 322.963589 -355.0024) (xy 322.922369 -355.038116) (xy 322.876485 -355.067602)
			(xy 322.826873 -355.090258) (xy 322.774541 -355.105622) (xy 322.720554 -355.113382) (xy 322.693284 -355.113844)
			(xy 321.829684 -355.113844) (xy 321.802414 -355.113392) (xy 321.74843 -355.105629) (xy 321.6961 -355.090261)
			(xy 321.646489 -355.067603) (xy 321.600608 -355.038115) (xy 321.55939 -355.002398) (xy 321.523675 -354.961179)
			(xy 321.494189 -354.915297) (xy 321.471533 -354.865685) (xy 321.456168 -354.813355) (xy 321.448406 -354.75937)
			(xy 319.965558 -354.75937) (xy 319.957797 -354.813346) (xy 319.942434 -354.865671) (xy 319.91978 -354.915277)
			(xy 319.890298 -354.961155) (xy 319.854587 -355.00237) (xy 319.813374 -355.038084) (xy 319.767498 -355.067569)
			(xy 319.717894 -355.090225) (xy 319.665569 -355.105592) (xy 319.611591 -355.113356) (xy 319.584324 -355.113844)
			(xy 318.720724 -355.113844) (xy 318.693451 -355.113418) (xy 318.639459 -355.105658) (xy 318.587121 -355.090293)
			(xy 318.537502 -355.067636) (xy 318.491613 -355.038148) (xy 318.450388 -355.002429) (xy 318.414667 -354.961206)
			(xy 318.385175 -354.915319) (xy 318.362515 -354.865702) (xy 318.347147 -354.813365) (xy 318.339384 -354.759373)
			(xy 316.85668 -354.759373) (xy 316.848918 -354.813359) (xy 316.83355 -354.865692) (xy 316.810891 -354.915305)
			(xy 316.781402 -354.961188) (xy 316.745682 -355.002407) (xy 316.70446 -355.038123) (xy 316.658574 -355.067609)
			(xy 316.608958 -355.090263) (xy 316.556624 -355.105625) (xy 316.502635 -355.113383) (xy 316.475364 -355.113844)
			(xy 315.611764 -355.113844) (xy 315.584495 -355.113391) (xy 315.530513 -355.105625) (xy 315.478185 -355.090256)
			(xy 315.428577 -355.067596) (xy 315.382699 -355.038108) (xy 315.341483 -355.002391) (xy 315.30577 -354.961173)
			(xy 315.276286 -354.915291) (xy 315.253632 -354.865681) (xy 315.238267 -354.813352) (xy 315.230506 -354.759369)
			(xy 300.231558 -354.759369) (xy 300.223796 -354.813349) (xy 300.208432 -354.865676) (xy 300.185777 -354.915283)
			(xy 300.156293 -354.961162) (xy 300.120579 -355.002378) (xy 300.079364 -355.038091) (xy 300.033485 -355.067576)
			(xy 299.983878 -355.090231) (xy 299.931551 -355.105596) (xy 299.87757 -355.113357) (xy 299.850302 -355.113844)
			(xy 298.986702 -355.113844) (xy 298.95943 -355.113417) (xy 298.90544 -355.105654) (xy 298.853105 -355.090288)
			(xy 298.803489 -355.067629) (xy 298.757603 -355.03814) (xy 298.716381 -355.002421) (xy 298.680661 -354.961199)
			(xy 298.651172 -354.915313) (xy 298.628513 -354.865697) (xy 298.613146 -354.813362) (xy 298.605384 -354.759372)
			(xy 297.122557 -354.759372) (xy 297.114798 -354.813344) (xy 297.099435 -354.865667) (xy 297.076783 -354.915272)
			(xy 297.047302 -354.961149) (xy 297.011593 -355.002364) (xy 296.970383 -355.038077) (xy 296.924509 -355.067563)
			(xy 296.874907 -355.09022) (xy 296.822585 -355.105589) (xy 296.768608 -355.113355) (xy 296.741342 -355.113844)
			(xy 295.877742 -355.113844) (xy 295.850468 -355.113419) (xy 295.796474 -355.105662) (xy 295.744134 -355.090298)
			(xy 295.694513 -355.067642) (xy 295.648622 -355.038154) (xy 295.607395 -355.002435) (xy 295.571671 -354.961212)
			(xy 295.542178 -354.915324) (xy 295.519516 -354.865706) (xy 295.504147 -354.813367) (xy 295.496384 -354.759374)
			(xy 294.013681 -354.759374) (xy 294.005918 -354.813356) (xy 293.990552 -354.865688) (xy 293.967894 -354.9153)
			(xy 293.938406 -354.961182) (xy 293.902688 -355.002401) (xy 293.861468 -355.038117) (xy 293.815584 -355.067603)
			(xy 293.765971 -355.090258) (xy 293.713639 -355.105622) (xy 293.659653 -355.113382) (xy 293.632382 -355.113844)
			(xy 292.768782 -355.113844) (xy 292.741512 -355.113392) (xy 292.687528 -355.105628) (xy 292.635198 -355.090261)
			(xy 292.585588 -355.067602) (xy 292.539707 -355.038115) (xy 292.49849 -355.002398) (xy 292.462775 -354.961178)
			(xy 292.433289 -354.915296) (xy 292.410633 -354.865685) (xy 292.395268 -354.813354) (xy 292.387506 -354.75937)
			(xy 290.904658 -354.75937) (xy 290.896897 -354.813346) (xy 290.881533 -354.865672) (xy 290.85888 -354.915278)
			(xy 290.829397 -354.961156) (xy 290.793686 -355.002371) (xy 290.752473 -355.038084) (xy 290.706597 -355.067569)
			(xy 290.656992 -355.090226) (xy 290.604668 -355.105592) (xy 290.550689 -355.113356) (xy 290.523422 -355.113844)
			(xy 289.659822 -355.113844) (xy 289.632549 -355.113418) (xy 289.578557 -355.105658) (xy 289.526219 -355.090293)
			(xy 289.476601 -355.067636) (xy 289.430712 -355.038147) (xy 289.389488 -355.002428) (xy 289.353766 -354.961205)
			(xy 289.324275 -354.915318) (xy 289.301615 -354.865702) (xy 289.286247 -354.813365) (xy 289.278484 -354.759373)
			(xy 287.79578 -354.759373) (xy 287.788018 -354.813359) (xy 287.77265 -354.865692) (xy 287.749991 -354.915306)
			(xy 287.720501 -354.961189) (xy 287.684781 -355.002408) (xy 287.643559 -355.038124) (xy 287.597672 -355.067609)
			(xy 287.548057 -355.090264) (xy 287.495722 -355.105626) (xy 287.441733 -355.113383) (xy 287.414462 -355.113844)
			(xy 286.550862 -355.113844) (xy 286.523593 -355.113391) (xy 286.469611 -355.105625) (xy 286.417284 -355.090255)
			(xy 286.367676 -355.067596) (xy 286.321798 -355.038107) (xy 286.280583 -355.00239) (xy 286.24487 -354.961172)
			(xy 286.215386 -354.915291) (xy 286.192732 -354.865681) (xy 286.177367 -354.813352) (xy 286.169606 -354.759369)
			(xy 284.686758 -354.759369) (xy 284.678996 -354.813349) (xy 284.663632 -354.865676) (xy 284.640977 -354.915283)
			(xy 284.611493 -354.961162) (xy 284.575779 -355.002378) (xy 284.534564 -355.038091) (xy 284.488685 -355.067576)
			(xy 284.439078 -355.090231) (xy 284.386751 -355.105596) (xy 284.33277 -355.113357) (xy 284.305502 -355.113844)
			(xy 283.441902 -355.113844) (xy 283.41463 -355.113417) (xy 283.36064 -355.105654) (xy 283.308305 -355.090288)
			(xy 283.258689 -355.067629) (xy 283.212803 -355.03814) (xy 283.171581 -355.002421) (xy 283.135861 -354.961199)
			(xy 283.106372 -354.915313) (xy 283.083713 -354.865697) (xy 283.068346 -354.813362) (xy 283.060584 -354.759372)
			(xy 281.577757 -354.759372) (xy 281.569998 -354.813344) (xy 281.554635 -354.865667) (xy 281.531983 -354.915272)
			(xy 281.502502 -354.961149) (xy 281.466793 -355.002364) (xy 281.425583 -355.038077) (xy 281.379709 -355.067563)
			(xy 281.330107 -355.09022) (xy 281.277785 -355.105589) (xy 281.223808 -355.113355) (xy 281.196542 -355.113844)
			(xy 280.332942 -355.113844) (xy 280.305668 -355.113419) (xy 280.251674 -355.105662) (xy 280.199334 -355.090298)
			(xy 280.149713 -355.067642) (xy 280.103822 -355.038154) (xy 280.062595 -355.002435) (xy 280.026871 -354.961212)
			(xy 279.997378 -354.915324) (xy 279.974716 -354.865706) (xy 279.959347 -354.813367) (xy 279.951584 -354.759374)
			(xy 278.468881 -354.759374) (xy 278.461118 -354.813356) (xy 278.445752 -354.865688) (xy 278.423094 -354.9153)
			(xy 278.393606 -354.961182) (xy 278.357888 -355.002401) (xy 278.316668 -355.038117) (xy 278.270784 -355.067603)
			(xy 278.221171 -355.090258) (xy 278.168839 -355.105622) (xy 278.114853 -355.113382) (xy 278.087582 -355.113844)
			(xy 277.223982 -355.113844) (xy 277.196712 -355.113392) (xy 277.142728 -355.105628) (xy 277.090398 -355.090261)
			(xy 277.040788 -355.067602) (xy 276.994907 -355.038115) (xy 276.95369 -355.002398) (xy 276.917975 -354.961178)
			(xy 276.888489 -354.915296) (xy 276.865833 -354.865685) (xy 276.850468 -354.813354) (xy 276.842706 -354.75937)
			(xy 275.359858 -354.75937) (xy 275.352097 -354.813346) (xy 275.336733 -354.865672) (xy 275.31408 -354.915278)
			(xy 275.284597 -354.961156) (xy 275.248886 -355.002371) (xy 275.207673 -355.038084) (xy 275.161797 -355.067569)
			(xy 275.112192 -355.090226) (xy 275.059868 -355.105592) (xy 275.005889 -355.113356) (xy 274.978622 -355.113844)
			(xy 274.115022 -355.113844) (xy 274.087749 -355.113418) (xy 274.033757 -355.105658) (xy 273.981419 -355.090293)
			(xy 273.931801 -355.067636) (xy 273.885912 -355.038147) (xy 273.844688 -355.002428) (xy 273.808966 -354.961205)
			(xy 273.779475 -354.915318) (xy 273.756815 -354.865702) (xy 273.741447 -354.813365) (xy 273.733684 -354.759373)
			(xy 272.25098 -354.759373) (xy 272.243218 -354.813359) (xy 272.22785 -354.865692) (xy 272.205191 -354.915306)
			(xy 272.175701 -354.961189) (xy 272.139981 -355.002408) (xy 272.098759 -355.038124) (xy 272.052872 -355.067609)
			(xy 272.003257 -355.090264) (xy 271.950922 -355.105626) (xy 271.896933 -355.113383) (xy 271.869662 -355.113844)
			(xy 271.006062 -355.113844) (xy 270.978793 -355.113391) (xy 270.924811 -355.105625) (xy 270.872484 -355.090255)
			(xy 270.822876 -355.067596) (xy 270.776998 -355.038107) (xy 270.735783 -355.00239) (xy 270.70007 -354.961172)
			(xy 270.670586 -354.915291) (xy 270.647932 -354.865681) (xy 270.632567 -354.813352) (xy 270.624806 -354.759369)
			(xy 188.299268 -354.759369) (xy 188.294942 -354.78946) (xy 188.279575 -354.841794) (xy 188.256917 -354.891409)
			(xy 188.227428 -354.937294) (xy 188.191709 -354.978515) (xy 188.150487 -355.014233) (xy 188.104602 -355.04372)
			(xy 188.054987 -355.066378) (xy 188.002652 -355.081744) (xy 187.948664 -355.089505) (xy 187.921392 -355.089968)
			(xy 187.057792 -355.089968) (xy 187.030523 -355.089469) (xy 186.976542 -355.081707) (xy 186.924214 -355.066341)
			(xy 186.874605 -355.043684) (xy 186.828726 -355.014199) (xy 186.78751 -354.978484) (xy 186.751796 -354.937267)
			(xy 186.722312 -354.891388) (xy 186.699656 -354.841779) (xy 186.684292 -354.789451) (xy 186.67653 -354.735469)
			(xy 185.193682 -354.735469) (xy 185.185921 -354.78945) (xy 185.170557 -354.841778) (xy 185.147903 -354.891387)
			(xy 185.118419 -354.937267) (xy 185.082707 -354.978484) (xy 185.041492 -355.0142) (xy 184.995615 -355.043687)
			(xy 184.946008 -355.066346) (xy 184.893681 -355.081714) (xy 184.8397 -355.089479) (xy 184.812432 -355.089968)
			(xy 183.948832 -355.089968) (xy 183.92156 -355.089495) (xy 183.86757 -355.081736) (xy 183.815235 -355.066373)
			(xy 183.765618 -355.043718) (xy 183.719731 -355.014231) (xy 183.678508 -354.978515) (xy 183.642788 -354.937294)
			(xy 183.613298 -354.89141) (xy 183.590638 -354.841795) (xy 183.57527 -354.789461) (xy 183.567508 -354.735472)
			(xy 182.08478 -354.735472) (xy 182.08478 -354.759371) (xy 182.077018 -354.813358) (xy 182.061651 -354.86569)
			(xy 182.038992 -354.915303) (xy 182.009504 -354.961186) (xy 181.973785 -355.002405) (xy 181.932563 -355.03812)
			(xy 181.886678 -355.067606) (xy 181.837064 -355.090261) (xy 181.78473 -355.105624) (xy 181.730743 -355.113382)
			(xy 181.703472 -355.113844) (xy 180.839872 -355.113844) (xy 180.812603 -355.113392) (xy 180.75862 -355.105626)
			(xy 180.706291 -355.090258) (xy 180.656682 -355.067599) (xy 180.610802 -355.038111) (xy 180.569586 -355.002394)
			(xy 180.533872 -354.961175) (xy 180.504388 -354.915293) (xy 180.481732 -354.865683) (xy 180.466368 -354.813353)
			(xy 180.458606 -354.759369) (xy 178.975758 -354.759369) (xy 178.967997 -354.813348) (xy 178.952633 -354.865674)
			(xy 178.929978 -354.915281) (xy 178.900495 -354.961159) (xy 178.864783 -355.002374) (xy 178.823568 -355.038088)
			(xy 178.777691 -355.067573) (xy 178.728085 -355.090228) (xy 178.675759 -355.105594) (xy 178.62178 -355.113357)
			(xy 178.594512 -355.113844) (xy 177.730912 -355.113844) (xy 177.703639 -355.113417) (xy 177.649648 -355.105656)
			(xy 177.597312 -355.09029) (xy 177.547695 -355.067632) (xy 177.501808 -355.038144) (xy 177.460584 -355.002424)
			(xy 177.424864 -354.961202) (xy 177.395373 -354.915316) (xy 177.372714 -354.865699) (xy 177.357346 -354.813363)
			(xy 177.349584 -354.759373) (xy 175.86688 -354.759373) (xy 175.859117 -354.81336) (xy 175.843749 -354.865694)
			(xy 175.821089 -354.915309) (xy 175.791599 -354.961192) (xy 175.755878 -355.002412) (xy 175.714654 -355.038128)
			(xy 175.668766 -355.067612) (xy 175.619149 -355.090266) (xy 175.566813 -355.105628) (xy 175.512824 -355.113384)
			(xy 175.485552 -355.113844) (xy 174.621952 -355.113844) (xy 174.594684 -355.11339) (xy 174.540703 -355.105623)
			(xy 174.488376 -355.090252) (xy 174.43877 -355.067592) (xy 174.392893 -355.038104) (xy 174.351679 -355.002387)
			(xy 174.315967 -354.961169) (xy 174.286485 -354.915288) (xy 174.263831 -354.865679) (xy 174.248467 -354.81335)
			(xy 174.240706 -354.759368) (xy 172.757881 -354.759368) (xy 172.757881 -354.75937) (xy 172.750119 -354.813355)
			(xy 172.734753 -354.865686) (xy 172.712096 -354.915297) (xy 172.682609 -354.961179) (xy 172.646892 -355.002398)
			(xy 172.605673 -355.038113) (xy 172.55979 -355.067599) (xy 172.510178 -355.090255) (xy 172.457847 -355.10562)
			(xy 172.403862 -355.113381) (xy 172.376592 -355.113844) (xy 171.512992 -355.113844) (xy 171.485722 -355.113393)
			(xy 171.431736 -355.10563) (xy 171.379405 -355.090263) (xy 171.329794 -355.067606) (xy 171.283912 -355.038118)
			(xy 171.242693 -355.002401) (xy 171.206977 -354.961182) (xy 171.177491 -354.915299) (xy 171.154834 -354.865687)
			(xy 171.139468 -354.813356) (xy 171.131706 -354.75937) (xy 169.648858 -354.75937) (xy 169.641097 -354.813345)
			(xy 169.625734 -354.865669) (xy 169.603081 -354.915275) (xy 169.5736 -354.961152) (xy 169.53789 -355.002367)
			(xy 169.496678 -355.038081) (xy 169.450803 -355.067566) (xy 169.401199 -355.090223) (xy 169.348876 -355.10559)
			(xy 169.294899 -355.113355) (xy 169.267632 -355.113844) (xy 168.404032 -355.113844) (xy 168.376758 -355.113419)
			(xy 168.322765 -355.10566) (xy 168.270426 -355.090296) (xy 168.220807 -355.067639) (xy 168.174917 -355.038151)
			(xy 168.133691 -355.002432) (xy 168.097969 -354.961209) (xy 168.068477 -354.915321) (xy 168.045816 -354.865704)
			(xy 168.030447 -354.813366) (xy 168.022684 -354.759374) (xy 166.53998 -354.759374) (xy 166.532218 -354.813358)
			(xy 166.516851 -354.86569) (xy 166.494192 -354.915303) (xy 166.464704 -354.961186) (xy 166.428985 -355.002405)
			(xy 166.387763 -355.03812) (xy 166.341878 -355.067606) (xy 166.292264 -355.090261) (xy 166.23993 -355.105624)
			(xy 166.185943 -355.113382) (xy 166.158672 -355.113844) (xy 165.295072 -355.113844) (xy 165.267803 -355.113392)
			(xy 165.21382 -355.105626) (xy 165.161491 -355.090258) (xy 165.111882 -355.067599) (xy 165.066002 -355.038111)
			(xy 165.024786 -355.002394) (xy 164.989072 -354.961175) (xy 164.959588 -354.915293) (xy 164.936932 -354.865683)
			(xy 164.921568 -354.813353) (xy 164.913806 -354.759369) (xy 163.430958 -354.759369) (xy 163.423197 -354.813348)
			(xy 163.407833 -354.865674) (xy 163.385178 -354.915281) (xy 163.355695 -354.961159) (xy 163.319983 -355.002374)
			(xy 163.278768 -355.038088) (xy 163.232891 -355.067573) (xy 163.183285 -355.090228) (xy 163.130959 -355.105594)
			(xy 163.07698 -355.113357) (xy 163.049712 -355.113844) (xy 162.186112 -355.113844) (xy 162.158839 -355.113417)
			(xy 162.104848 -355.105656) (xy 162.052512 -355.09029) (xy 162.002895 -355.067632) (xy 161.957008 -355.038144)
			(xy 161.915784 -355.002424) (xy 161.880064 -354.961202) (xy 161.850573 -354.915316) (xy 161.827914 -354.865699)
			(xy 161.812546 -354.813363) (xy 161.804784 -354.759373) (xy 160.32208 -354.759373) (xy 160.314317 -354.81336)
			(xy 160.298949 -354.865694) (xy 160.276289 -354.915309) (xy 160.246799 -354.961192) (xy 160.211078 -355.002412)
			(xy 160.169854 -355.038128) (xy 160.123966 -355.067612) (xy 160.074349 -355.090266) (xy 160.022013 -355.105628)
			(xy 159.968024 -355.113384) (xy 159.940752 -355.113844) (xy 159.077152 -355.113844) (xy 159.049884 -355.11339)
			(xy 158.995903 -355.105623) (xy 158.943576 -355.090252) (xy 158.89397 -355.067592) (xy 158.848093 -355.038104)
			(xy 158.806879 -355.002387) (xy 158.771167 -354.961169) (xy 158.741685 -354.915288) (xy 158.719031 -354.865679)
			(xy 158.703667 -354.81335) (xy 158.695906 -354.759368) (xy 144.196558 -354.759368) (xy 144.188797 -354.813348)
			(xy 144.173432 -354.865675) (xy 144.150778 -354.915282) (xy 144.121294 -354.96116) (xy 144.085581 -355.002376)
			(xy 144.044367 -355.038089) (xy 143.998489 -355.067574) (xy 143.948882 -355.09023) (xy 143.896556 -355.105595)
			(xy 143.842576 -355.113357) (xy 143.815308 -355.113844) (xy 142.951708 -355.113844) (xy 142.924435 -355.113417)
			(xy 142.870445 -355.105655) (xy 142.818109 -355.090289) (xy 142.768492 -355.067631) (xy 142.722606 -355.038142)
			(xy 142.681383 -355.002423) (xy 142.645663 -354.961201) (xy 142.616173 -354.915315) (xy 142.593514 -354.865699)
			(xy 142.578146 -354.813363) (xy 142.570384 -354.759373) (xy 141.087557 -354.759373) (xy 141.079798 -354.813343)
			(xy 141.064436 -354.865666) (xy 141.041784 -354.915271) (xy 141.012304 -354.961147) (xy 140.976595 -355.002361)
			(xy 140.935386 -355.038075) (xy 140.889513 -355.067561) (xy 140.839911 -355.090219) (xy 140.78759 -355.105587)
			(xy 140.733614 -355.113354) (xy 140.706348 -355.113844) (xy 139.842748 -355.113844) (xy 139.815473 -355.11342)
			(xy 139.761479 -355.105663) (xy 139.709138 -355.0903) (xy 139.659516 -355.067644) (xy 139.613625 -355.038156)
			(xy 139.572397 -355.002437) (xy 139.536672 -354.961214) (xy 139.507179 -354.915326) (xy 139.484517 -354.865707)
			(xy 139.469147 -354.813368) (xy 139.461384 -354.759374) (xy 137.97868 -354.759374) (xy 137.970918 -354.813356)
			(xy 137.955552 -354.865687) (xy 137.932895 -354.915298) (xy 137.903408 -354.961181) (xy 137.867691 -355.002399)
			(xy 137.826471 -355.038115) (xy 137.780588 -355.067601) (xy 137.730976 -355.090256) (xy 137.678644 -355.105621)
			(xy 137.624658 -355.113381) (xy 137.597388 -355.113844) (xy 136.733788 -355.113844) (xy 136.706518 -355.113393)
			(xy 136.652533 -355.105629) (xy 136.600203 -355.090262) (xy 136.550591 -355.067604) (xy 136.50471 -355.038117)
			(xy 136.463492 -355.0024) (xy 136.427776 -354.96118) (xy 136.39829 -354.915298) (xy 136.375634 -354.865686)
			(xy 136.360268 -354.813355) (xy 136.352506 -354.75937) (xy 134.869658 -354.75937) (xy 134.861897 -354.813345)
			(xy 134.846534 -354.86567) (xy 134.823881 -354.915276) (xy 134.794399 -354.961154) (xy 134.758688 -355.002369)
			(xy 134.717476 -355.038082) (xy 134.671601 -355.067567) (xy 134.621997 -355.090224) (xy 134.569673 -355.105591)
			(xy 134.515695 -355.113356) (xy 134.488428 -355.113844) (xy 133.624828 -355.113844) (xy 133.597554 -355.113418)
			(xy 133.543562 -355.105659) (xy 133.491223 -355.090295) (xy 133.441604 -355.067638) (xy 133.395715 -355.038149)
			(xy 133.35449 -355.00243) (xy 133.318768 -354.961207) (xy 133.289276 -354.91532) (xy 133.266615 -354.865703)
			(xy 133.251247 -354.813365) (xy 133.243484 -354.759374) (xy 131.76078 -354.759374) (xy 131.753018 -354.813358)
			(xy 131.737651 -354.865691) (xy 131.714992 -354.915304) (xy 131.685503 -354.961187) (xy 131.649783 -355.002406)
			(xy 131.608561 -355.038122) (xy 131.562676 -355.067607) (xy 131.513061 -355.090262) (xy 131.460727 -355.105625)
			(xy 131.406739 -355.113383) (xy 131.379468 -355.113844) (xy 130.515868 -355.113844) (xy 130.488599 -355.113391)
			(xy 130.434616 -355.105626) (xy 130.382288 -355.090257) (xy 130.33268 -355.067598) (xy 130.2868 -355.03811)
			(xy 130.245585 -355.002393) (xy 130.209871 -354.961174) (xy 130.180387 -354.915292) (xy 130.157732 -354.865682)
			(xy 130.142368 -354.813353) (xy 130.134606 -354.759369) (xy 128.651758 -354.759369) (xy 128.643997 -354.813348)
			(xy 128.628632 -354.865675) (xy 128.605978 -354.915282) (xy 128.576494 -354.96116) (xy 128.540781 -355.002376)
			(xy 128.499567 -355.038089) (xy 128.453689 -355.067574) (xy 128.404082 -355.09023) (xy 128.351756 -355.105595)
			(xy 128.297776 -355.113357) (xy 128.270508 -355.113844) (xy 127.406908 -355.113844) (xy 127.379635 -355.113417)
			(xy 127.325645 -355.105655) (xy 127.273309 -355.090289) (xy 127.223692 -355.067631) (xy 127.177806 -355.038142)
			(xy 127.136583 -355.002423) (xy 127.100863 -354.961201) (xy 127.071373 -354.915315) (xy 127.048714 -354.865699)
			(xy 127.033346 -354.813363) (xy 127.025584 -354.759373) (xy 125.542757 -354.759373) (xy 125.534998 -354.813343)
			(xy 125.519636 -354.865666) (xy 125.496984 -354.915271) (xy 125.467504 -354.961147) (xy 125.431795 -355.002361)
			(xy 125.390586 -355.038075) (xy 125.344713 -355.067561) (xy 125.295111 -355.090219) (xy 125.24279 -355.105587)
			(xy 125.188814 -355.113354) (xy 125.161548 -355.113844) (xy 124.297948 -355.113844) (xy 124.270673 -355.11342)
			(xy 124.216679 -355.105663) (xy 124.164338 -355.0903) (xy 124.114716 -355.067644) (xy 124.068825 -355.038156)
			(xy 124.027597 -355.002437) (xy 123.991872 -354.961214) (xy 123.962379 -354.915326) (xy 123.939717 -354.865707)
			(xy 123.924347 -354.813368) (xy 123.916584 -354.759374) (xy 122.43388 -354.759374) (xy 122.426118 -354.813356)
			(xy 122.410752 -354.865687) (xy 122.388095 -354.915298) (xy 122.358608 -354.961181) (xy 122.322891 -355.002399)
			(xy 122.281671 -355.038115) (xy 122.235788 -355.067601) (xy 122.186176 -355.090256) (xy 122.133844 -355.105621)
			(xy 122.079858 -355.113381) (xy 122.052588 -355.113844) (xy 121.188988 -355.113844) (xy 121.161718 -355.113393)
			(xy 121.107733 -355.105629) (xy 121.055403 -355.090262) (xy 121.005791 -355.067604) (xy 120.95991 -355.038117)
			(xy 120.918692 -355.0024) (xy 120.882976 -354.96118) (xy 120.85349 -354.915298) (xy 120.830834 -354.865686)
			(xy 120.815468 -354.813355) (xy 120.807706 -354.75937) (xy 119.324858 -354.75937) (xy 119.317097 -354.813345)
			(xy 119.301734 -354.86567) (xy 119.279081 -354.915276) (xy 119.249599 -354.961154) (xy 119.213888 -355.002369)
			(xy 119.172676 -355.038082) (xy 119.126801 -355.067567) (xy 119.077197 -355.090224) (xy 119.024873 -355.105591)
			(xy 118.970895 -355.113356) (xy 118.943628 -355.113844) (xy 118.080028 -355.113844) (xy 118.052754 -355.113418)
			(xy 117.998762 -355.105659) (xy 117.946423 -355.090295) (xy 117.896804 -355.067638) (xy 117.850915 -355.038149)
			(xy 117.80969 -355.00243) (xy 117.773968 -354.961207) (xy 117.744476 -354.91532) (xy 117.721815 -354.865703)
			(xy 117.706447 -354.813365) (xy 117.698684 -354.759374) (xy 116.21598 -354.759374) (xy 116.208218 -354.813358)
			(xy 116.192851 -354.865691) (xy 116.170192 -354.915304) (xy 116.140703 -354.961187) (xy 116.104983 -355.002406)
			(xy 116.063761 -355.038122) (xy 116.017876 -355.067607) (xy 115.968261 -355.090262) (xy 115.915927 -355.105625)
			(xy 115.861939 -355.113383) (xy 115.834668 -355.113844) (xy 114.971068 -355.113844) (xy 114.943799 -355.113391)
			(xy 114.889816 -355.105626) (xy 114.837488 -355.090257) (xy 114.78788 -355.067598) (xy 114.742 -355.03811)
			(xy 114.700785 -355.002393) (xy 114.665071 -354.961174) (xy 114.635587 -354.915292) (xy 114.612932 -354.865682)
			(xy 114.597568 -354.813353) (xy 114.589806 -354.759369) (xy 93.706658 -354.759369) (xy 93.698898 -354.813344)
			(xy 93.683535 -354.865667) (xy 93.660883 -354.915272) (xy 93.631402 -354.961149) (xy 93.595693 -355.002364)
			(xy 93.554483 -355.038077) (xy 93.508609 -355.067563) (xy 93.459007 -355.09022) (xy 93.406685 -355.105589)
			(xy 93.352708 -355.113355) (xy 93.325442 -355.113844) (xy 92.461842 -355.113844) (xy 92.434568 -355.113419)
			(xy 92.380574 -355.105662) (xy 92.328234 -355.090298) (xy 92.278613 -355.067642) (xy 92.232722 -355.038154)
			(xy 92.191495 -355.002435) (xy 92.155771 -354.961212) (xy 92.126278 -354.915324) (xy 92.103616 -354.865706)
			(xy 92.088247 -354.813367) (xy 92.080484 -354.759374) (xy 90.597781 -354.759374) (xy 90.590018 -354.813356)
			(xy 90.574652 -354.865688) (xy 90.551994 -354.9153) (xy 90.522506 -354.961182) (xy 90.486788 -355.002401)
			(xy 90.445568 -355.038117) (xy 90.399684 -355.067603) (xy 90.350071 -355.090258) (xy 90.297739 -355.105622)
			(xy 90.243753 -355.113382) (xy 90.216482 -355.113844) (xy 89.352882 -355.113844) (xy 89.325612 -355.113392)
			(xy 89.271628 -355.105628) (xy 89.219298 -355.090261) (xy 89.169688 -355.067602) (xy 89.123807 -355.038115)
			(xy 89.08259 -355.002398) (xy 89.046875 -354.961178) (xy 89.017389 -354.915296) (xy 88.994733 -354.865685)
			(xy 88.979368 -354.813354) (xy 88.971606 -354.75937) (xy 87.488758 -354.75937) (xy 87.480997 -354.813346)
			(xy 87.465633 -354.865672) (xy 87.44298 -354.915278) (xy 87.413497 -354.961156) (xy 87.377786 -355.002371)
			(xy 87.336573 -355.038084) (xy 87.290697 -355.067569) (xy 87.241092 -355.090226) (xy 87.188768 -355.105592)
			(xy 87.134789 -355.113356) (xy 87.107522 -355.113844) (xy 86.243922 -355.113844) (xy 86.216649 -355.113418)
			(xy 86.162657 -355.105658) (xy 86.110319 -355.090293) (xy 86.060701 -355.067636) (xy 86.014812 -355.038147)
			(xy 85.973588 -355.002428) (xy 85.937866 -354.961205) (xy 85.908375 -354.915318) (xy 85.885715 -354.865702)
			(xy 85.870347 -354.813365) (xy 85.862584 -354.759373) (xy 84.37988 -354.759373) (xy 84.372118 -354.813359)
			(xy 84.35675 -354.865692) (xy 84.334091 -354.915306) (xy 84.304601 -354.961189) (xy 84.268881 -355.002408)
			(xy 84.227659 -355.038124) (xy 84.181772 -355.067609) (xy 84.132157 -355.090264) (xy 84.079822 -355.105626)
			(xy 84.025833 -355.113383) (xy 83.998562 -355.113844) (xy 83.134962 -355.113844) (xy 83.107693 -355.113391)
			(xy 83.053711 -355.105625) (xy 83.001384 -355.090255) (xy 82.951776 -355.067596) (xy 82.905898 -355.038107)
			(xy 82.864683 -355.00239) (xy 82.82897 -354.961172) (xy 82.799486 -354.915291) (xy 82.776832 -354.865681)
			(xy 82.761467 -354.813352) (xy 82.753706 -354.759369) (xy 81.270858 -354.759369) (xy 81.263096 -354.813349)
			(xy 81.247732 -354.865676) (xy 81.225077 -354.915283) (xy 81.195593 -354.961162) (xy 81.159879 -355.002378)
			(xy 81.118664 -355.038091) (xy 81.072785 -355.067576) (xy 81.023178 -355.090231) (xy 80.970851 -355.105596)
			(xy 80.91687 -355.113357) (xy 80.889602 -355.113844) (xy 80.026002 -355.113844) (xy 79.99873 -355.113417)
			(xy 79.94474 -355.105654) (xy 79.892405 -355.090288) (xy 79.842789 -355.067629) (xy 79.796903 -355.03814)
			(xy 79.755681 -355.002421) (xy 79.719961 -354.961199) (xy 79.690472 -354.915313) (xy 79.667813 -354.865697)
			(xy 79.652446 -354.813362) (xy 79.644684 -354.759372) (xy 78.161857 -354.759372) (xy 78.154098 -354.813344)
			(xy 78.138735 -354.865667) (xy 78.116083 -354.915272) (xy 78.086602 -354.961149) (xy 78.050893 -355.002364)
			(xy 78.009683 -355.038077) (xy 77.963809 -355.067563) (xy 77.914207 -355.09022) (xy 77.861885 -355.105589)
			(xy 77.807908 -355.113355) (xy 77.780642 -355.113844) (xy 76.917042 -355.113844) (xy 76.889768 -355.113419)
			(xy 76.835774 -355.105662) (xy 76.783434 -355.090298) (xy 76.733813 -355.067642) (xy 76.687922 -355.038154)
			(xy 76.646695 -355.002435) (xy 76.610971 -354.961212) (xy 76.581478 -354.915324) (xy 76.558816 -354.865706)
			(xy 76.543447 -354.813367) (xy 76.535684 -354.759374) (xy 75.052981 -354.759374) (xy 75.045218 -354.813356)
			(xy 75.029852 -354.865688) (xy 75.007194 -354.9153) (xy 74.977706 -354.961182) (xy 74.941988 -355.002401)
			(xy 74.900768 -355.038117) (xy 74.854884 -355.067603) (xy 74.805271 -355.090258) (xy 74.752939 -355.105622)
			(xy 74.698953 -355.113382) (xy 74.671682 -355.113844) (xy 73.808082 -355.113844) (xy 73.780812 -355.113392)
			(xy 73.726828 -355.105628) (xy 73.674498 -355.090261) (xy 73.624888 -355.067602) (xy 73.579007 -355.038115)
			(xy 73.53779 -355.002398) (xy 73.502075 -354.961178) (xy 73.472589 -354.915296) (xy 73.449933 -354.865685)
			(xy 73.434568 -354.813354) (xy 73.426806 -354.75937) (xy 71.943958 -354.75937) (xy 71.936197 -354.813346)
			(xy 71.920833 -354.865672) (xy 71.89818 -354.915278) (xy 71.868697 -354.961156) (xy 71.832986 -355.002371)
			(xy 71.791773 -355.038084) (xy 71.745897 -355.067569) (xy 71.696292 -355.090226) (xy 71.643968 -355.105592)
			(xy 71.589989 -355.113356) (xy 71.562722 -355.113844) (xy 70.699122 -355.113844) (xy 70.671849 -355.113418)
			(xy 70.617857 -355.105658) (xy 70.565519 -355.090293) (xy 70.515901 -355.067636) (xy 70.470012 -355.038147)
			(xy 70.428788 -355.002428) (xy 70.393066 -354.961205) (xy 70.363575 -354.915318) (xy 70.340915 -354.865702)
			(xy 70.325547 -354.813365) (xy 70.317784 -354.759373) (xy 68.83508 -354.759373) (xy 68.827318 -354.813359)
			(xy 68.81195 -354.865692) (xy 68.789291 -354.915306) (xy 68.759801 -354.961189) (xy 68.724081 -355.002408)
			(xy 68.682859 -355.038124) (xy 68.636972 -355.067609) (xy 68.587357 -355.090264) (xy 68.535022 -355.105626)
			(xy 68.481033 -355.113383) (xy 68.453762 -355.113844) (xy 67.590162 -355.113844) (xy 67.562893 -355.113391)
			(xy 67.508911 -355.105625) (xy 67.456584 -355.090255) (xy 67.406976 -355.067596) (xy 67.361098 -355.038107)
			(xy 67.319883 -355.00239) (xy 67.28417 -354.961172) (xy 67.254686 -354.915291) (xy 67.232032 -354.865681)
			(xy 67.216667 -354.813352) (xy 67.208906 -354.759369) (xy 65.726058 -354.759369) (xy 65.718296 -354.813349)
			(xy 65.702932 -354.865676) (xy 65.680277 -354.915283) (xy 65.650793 -354.961162) (xy 65.615079 -355.002378)
			(xy 65.573864 -355.038091) (xy 65.527985 -355.067576) (xy 65.478378 -355.090231) (xy 65.426051 -355.105596)
			(xy 65.37207 -355.113357) (xy 65.344802 -355.113844) (xy 64.481202 -355.113844) (xy 64.45393 -355.113417)
			(xy 64.39994 -355.105654) (xy 64.347605 -355.090288) (xy 64.297989 -355.067629) (xy 64.252103 -355.03814)
			(xy 64.210881 -355.002421) (xy 64.175161 -354.961199) (xy 64.145672 -354.915313) (xy 64.123013 -354.865697)
			(xy 64.107646 -354.813362) (xy 64.099884 -354.759372) (xy 51.666857 -354.759372) (xy 51.659098 -354.813343)
			(xy 51.643736 -354.865666) (xy 51.621084 -354.915271) (xy 51.591604 -354.961147) (xy 51.555895 -355.002361)
			(xy 51.514686 -355.038075) (xy 51.468813 -355.067561) (xy 51.419211 -355.090219) (xy 51.36689 -355.105587)
			(xy 51.312914 -355.113354) (xy 51.285648 -355.113844) (xy 50.422048 -355.113844) (xy 50.394773 -355.11342)
			(xy 50.340779 -355.105663) (xy 50.288438 -355.0903) (xy 50.238816 -355.067644) (xy 50.192925 -355.038156)
			(xy 50.151697 -355.002437) (xy 50.115972 -354.961214) (xy 50.086479 -354.915326) (xy 50.063817 -354.865707)
			(xy 50.048447 -354.813368) (xy 50.040684 -354.759374) (xy 48.55798 -354.759374) (xy 48.550218 -354.813356)
			(xy 48.534852 -354.865687) (xy 48.512195 -354.915298) (xy 48.482708 -354.961181) (xy 48.446991 -355.002399)
			(xy 48.405771 -355.038115) (xy 48.359888 -355.067601) (xy 48.310276 -355.090256) (xy 48.257944 -355.105621)
			(xy 48.203958 -355.113381) (xy 48.176688 -355.113844) (xy 47.313088 -355.113844) (xy 47.285818 -355.113393)
			(xy 47.231833 -355.105629) (xy 47.179503 -355.090262) (xy 47.129891 -355.067604) (xy 47.08401 -355.038117)
			(xy 47.042792 -355.0024) (xy 47.007076 -354.96118) (xy 46.97759 -354.915298) (xy 46.954934 -354.865686)
			(xy 46.939568 -354.813355) (xy 46.931806 -354.75937) (xy 45.448958 -354.75937) (xy 45.441197 -354.813345)
			(xy 45.425834 -354.86567) (xy 45.403181 -354.915276) (xy 45.373699 -354.961154) (xy 45.337988 -355.002369)
			(xy 45.296776 -355.038082) (xy 45.250901 -355.067567) (xy 45.201297 -355.090224) (xy 45.148973 -355.105591)
			(xy 45.094995 -355.113356) (xy 45.067728 -355.113844) (xy 44.204128 -355.113844) (xy 44.176854 -355.113418)
			(xy 44.122862 -355.105659) (xy 44.070523 -355.090295) (xy 44.020904 -355.067638) (xy 43.975015 -355.038149)
			(xy 43.93379 -355.00243) (xy 43.898068 -354.961207) (xy 43.868576 -354.91532) (xy 43.845915 -354.865703)
			(xy 43.830547 -354.813365) (xy 43.822784 -354.759374) (xy 42.34008 -354.759374) (xy 42.332318 -354.813358)
			(xy 42.316951 -354.865691) (xy 42.294292 -354.915304) (xy 42.264803 -354.961187) (xy 42.229083 -355.002406)
			(xy 42.187861 -355.038122) (xy 42.141976 -355.067607) (xy 42.092361 -355.090262) (xy 42.040027 -355.105625)
			(xy 41.986039 -355.113383) (xy 41.958768 -355.113844) (xy 41.095168 -355.113844) (xy 41.067899 -355.113391)
			(xy 41.013916 -355.105626) (xy 40.961588 -355.090257) (xy 40.91198 -355.067598) (xy 40.8661 -355.03811)
			(xy 40.824885 -355.002393) (xy 40.789171 -354.961174) (xy 40.759687 -354.915292) (xy 40.737032 -354.865682)
			(xy 40.721668 -354.813353) (xy 40.713906 -354.759369) (xy 39.231058 -354.759369) (xy 39.223297 -354.813348)
			(xy 39.207932 -354.865675) (xy 39.185278 -354.915282) (xy 39.155794 -354.96116) (xy 39.120081 -355.002376)
			(xy 39.078867 -355.038089) (xy 39.032989 -355.067574) (xy 38.983382 -355.09023) (xy 38.931056 -355.105595)
			(xy 38.877076 -355.113357) (xy 38.849808 -355.113844) (xy 37.986208 -355.113844) (xy 37.958935 -355.113417)
			(xy 37.904945 -355.105655) (xy 37.852609 -355.090289) (xy 37.802992 -355.067631) (xy 37.757106 -355.038142)
			(xy 37.715883 -355.002423) (xy 37.680163 -354.961201) (xy 37.650673 -354.915315) (xy 37.628014 -354.865699)
			(xy 37.612646 -354.813363) (xy 37.604884 -354.759373) (xy 36.122057 -354.759373) (xy 36.114298 -354.813343)
			(xy 36.098936 -354.865666) (xy 36.076284 -354.915271) (xy 36.046804 -354.961147) (xy 36.011095 -355.002361)
			(xy 35.969886 -355.038075) (xy 35.924013 -355.067561) (xy 35.874411 -355.090219) (xy 35.82209 -355.105587)
			(xy 35.768114 -355.113354) (xy 35.740848 -355.113844) (xy 34.877248 -355.113844) (xy 34.849973 -355.11342)
			(xy 34.795979 -355.105663) (xy 34.743638 -355.0903) (xy 34.694016 -355.067644) (xy 34.648125 -355.038156)
			(xy 34.606897 -355.002437) (xy 34.571172 -354.961214) (xy 34.541679 -354.915326) (xy 34.519017 -354.865707)
			(xy 34.503647 -354.813368) (xy 34.495884 -354.759374) (xy 33.01318 -354.759374) (xy 33.005418 -354.813356)
			(xy 32.990052 -354.865687) (xy 32.967395 -354.915298) (xy 32.937908 -354.961181) (xy 32.902191 -355.002399)
			(xy 32.860971 -355.038115) (xy 32.815088 -355.067601) (xy 32.765476 -355.090256) (xy 32.713144 -355.105621)
			(xy 32.659158 -355.113381) (xy 32.631888 -355.113844) (xy 31.768288 -355.113844) (xy 31.741018 -355.113393)
			(xy 31.687033 -355.105629) (xy 31.634703 -355.090262) (xy 31.585091 -355.067604) (xy 31.53921 -355.038117)
			(xy 31.497992 -355.0024) (xy 31.462276 -354.96118) (xy 31.43279 -354.915298) (xy 31.410134 -354.865686)
			(xy 31.394768 -354.813355) (xy 31.387006 -354.75937) (xy 29.904158 -354.75937) (xy 29.896397 -354.813345)
			(xy 29.881034 -354.86567) (xy 29.858381 -354.915276) (xy 29.828899 -354.961154) (xy 29.793188 -355.002369)
			(xy 29.751976 -355.038082) (xy 29.706101 -355.067567) (xy 29.656497 -355.090224) (xy 29.604173 -355.105591)
			(xy 29.550195 -355.113356) (xy 29.522928 -355.113844) (xy 28.659328 -355.113844) (xy 28.632054 -355.113418)
			(xy 28.578062 -355.105659) (xy 28.525723 -355.090295) (xy 28.476104 -355.067638) (xy 28.430215 -355.038149)
			(xy 28.38899 -355.00243) (xy 28.353268 -354.961207) (xy 28.323776 -354.91532) (xy 28.301115 -354.865703)
			(xy 28.285747 -354.813365) (xy 28.277984 -354.759374) (xy 26.79528 -354.759374) (xy 26.787518 -354.813358)
			(xy 26.772151 -354.865691) (xy 26.749492 -354.915304) (xy 26.720003 -354.961187) (xy 26.684283 -355.002406)
			(xy 26.643061 -355.038122) (xy 26.597176 -355.067607) (xy 26.547561 -355.090262) (xy 26.495227 -355.105625)
			(xy 26.441239 -355.113383) (xy 26.413968 -355.113844) (xy 25.550368 -355.113844) (xy 25.523099 -355.113391)
			(xy 25.469116 -355.105626) (xy 25.416788 -355.090257) (xy 25.36718 -355.067598) (xy 25.3213 -355.03811)
			(xy 25.280085 -355.002393) (xy 25.244371 -354.961174) (xy 25.214887 -354.915292) (xy 25.192232 -354.865682)
			(xy 25.176868 -354.813353) (xy 25.169106 -354.759369) (xy 23.686258 -354.759369) (xy 23.678497 -354.813348)
			(xy 23.663132 -354.865675) (xy 23.640478 -354.915282) (xy 23.610994 -354.96116) (xy 23.575281 -355.002376)
			(xy 23.534067 -355.038089) (xy 23.488189 -355.067574) (xy 23.438582 -355.09023) (xy 23.386256 -355.105595)
			(xy 23.332276 -355.113357) (xy 23.305008 -355.113844) (xy 22.441408 -355.113844) (xy 22.414135 -355.113417)
			(xy 22.360145 -355.105655) (xy 22.307809 -355.090289) (xy 22.258192 -355.067631) (xy 22.212306 -355.038142)
			(xy 22.171083 -355.002423) (xy 22.135363 -354.961201) (xy 22.105873 -354.915315) (xy 22.083214 -354.865699)
			(xy 22.067846 -354.813363) (xy 22.060084 -354.759373) (xy 0.508 -354.759373) (xy 0.508 -357.784969)
			(xy 22.060131 -357.784969) (xy 22.060131 -357.730431) (xy 22.067893 -357.676447) (xy 22.083259 -357.624118)
			(xy 22.105915 -357.574508) (xy 22.135401 -357.528628) (xy 22.171117 -357.487411) (xy 22.212334 -357.451696)
			(xy 22.258215 -357.422211) (xy 22.307826 -357.399556) (xy 22.360155 -357.384191) (xy 22.414139 -357.376431)
			(xy 22.441408 -357.375968) (xy 23.305008 -357.375968) (xy 23.332279 -357.376395) (xy 23.386266 -357.384158)
			(xy 23.438599 -357.399525) (xy 23.488212 -357.422184) (xy 23.534095 -357.451672) (xy 23.575315 -357.48739)
			(xy 23.611032 -357.528611) (xy 23.64052 -357.574495) (xy 23.663177 -357.624109) (xy 23.678543 -357.676442)
			(xy 23.686306 -357.730429) (xy 23.686306 -357.784966) (xy 25.169154 -357.784966) (xy 25.169154 -357.730434)
			(xy 25.176914 -357.676458) (xy 25.192277 -357.624135) (xy 25.214929 -357.574531) (xy 25.24441 -357.528655)
			(xy 25.280119 -357.487441) (xy 25.321329 -357.451729) (xy 25.367203 -357.422244) (xy 25.416805 -357.399588)
			(xy 25.469126 -357.384221) (xy 25.523102 -357.376457) (xy 25.550368 -357.375968) (xy 26.413968 -357.375968)
			(xy 26.441243 -357.376369) (xy 26.495237 -357.384128) (xy 26.547578 -357.399493) (xy 26.597199 -357.422151)
			(xy 26.64309 -357.45164) (xy 26.684317 -357.48736) (xy 26.720041 -357.528584) (xy 26.749534 -357.574473)
			(xy 26.772196 -357.624092) (xy 26.787565 -357.676431) (xy 26.795328 -357.730425) (xy 26.795328 -357.78497)
			(xy 28.278031 -357.78497) (xy 28.278032 -357.73043) (xy 28.285794 -357.676445) (xy 28.30116 -357.624114)
			(xy 28.323818 -357.574503) (xy 28.353306 -357.528621) (xy 28.389024 -357.487404) (xy 28.430244 -357.451689)
			(xy 28.476127 -357.422205) (xy 28.52574 -357.39955) (xy 28.578072 -357.384188) (xy 28.632058 -357.37643)
			(xy 28.659328 -357.375968) (xy 29.522928 -357.375968) (xy 29.550198 -357.376396) (xy 29.604183 -357.384162)
			(xy 29.656513 -357.399531) (xy 29.706124 -357.42219) (xy 29.752005 -357.451679) (xy 29.793222 -357.487397)
			(xy 29.828937 -357.528618) (xy 29.858423 -357.574501) (xy 29.881079 -357.624113) (xy 29.896444 -357.676444)
			(xy 29.904206 -357.73043) (xy 29.904206 -357.784967) (xy 31.387054 -357.784967) (xy 31.387054 -357.730433)
			(xy 31.394815 -357.676455) (xy 31.410179 -357.624131) (xy 31.432832 -357.574525) (xy 31.462315 -357.528648)
			(xy 31.498026 -357.487434) (xy 31.539239 -357.451722) (xy 31.585115 -357.422238) (xy 31.634719 -357.399583)
			(xy 31.687043 -357.384218) (xy 31.741021 -357.376455) (xy 31.768288 -357.375968) (xy 32.631888 -357.375968)
			(xy 32.659162 -357.376371) (xy 32.713154 -357.384132) (xy 32.765492 -357.399499) (xy 32.815111 -357.422157)
			(xy 32.861 -357.451647) (xy 32.902224 -357.487367) (xy 32.937946 -357.528591) (xy 32.967437 -357.574479)
			(xy 32.990097 -357.624096) (xy 33.005465 -357.676434) (xy 33.013228 -357.730426) (xy 33.013228 -357.784971)
			(xy 34.495932 -357.784971) (xy 34.495932 -357.730429) (xy 34.503694 -357.676442) (xy 34.519062 -357.62411)
			(xy 34.541721 -357.574497) (xy 34.571211 -357.528615) (xy 34.606931 -357.487397) (xy 34.648153 -357.451682)
			(xy 34.694039 -357.422198) (xy 34.743655 -357.399545) (xy 34.795989 -357.384184) (xy 34.849977 -357.376428)
			(xy 34.877248 -357.375968) (xy 35.740848 -357.375968) (xy 35.768117 -357.376398) (xy 35.8221 -357.384166)
			(xy 35.874428 -357.399536) (xy 35.924036 -357.422197) (xy 35.969914 -357.451687) (xy 36.011129 -357.487405)
			(xy 36.046842 -357.528624) (xy 36.076326 -357.574506) (xy 36.09898 -357.624117) (xy 36.114345 -357.676447)
			(xy 36.122106 -357.730431) (xy 36.122106 -357.784969) (xy 37.604931 -357.784969) (xy 37.604931 -357.730431)
			(xy 37.612693 -357.676447) (xy 37.628059 -357.624118) (xy 37.650715 -357.574508) (xy 37.680201 -357.528628)
			(xy 37.715917 -357.487411) (xy 37.757134 -357.451696) (xy 37.803015 -357.422211) (xy 37.852626 -357.399556)
			(xy 37.904955 -357.384191) (xy 37.958939 -357.376431) (xy 37.986208 -357.375968) (xy 38.849808 -357.375968)
			(xy 38.877079 -357.376395) (xy 38.931066 -357.384158) (xy 38.983399 -357.399525) (xy 39.033012 -357.422184)
			(xy 39.078895 -357.451672) (xy 39.120115 -357.48739) (xy 39.155832 -357.528611) (xy 39.18532 -357.574495)
			(xy 39.207977 -357.624109) (xy 39.223343 -357.676442) (xy 39.231106 -357.730429) (xy 39.231106 -357.784966)
			(xy 40.713954 -357.784966) (xy 40.713954 -357.730434) (xy 40.721714 -357.676458) (xy 40.737077 -357.624135)
			(xy 40.759729 -357.574531) (xy 40.78921 -357.528655) (xy 40.824919 -357.487441) (xy 40.866129 -357.451729)
			(xy 40.912003 -357.422244) (xy 40.961605 -357.399588) (xy 41.013926 -357.384221) (xy 41.067902 -357.376457)
			(xy 41.095168 -357.375968) (xy 41.958768 -357.375968) (xy 41.986043 -357.376369) (xy 42.040037 -357.384128)
			(xy 42.092378 -357.399493) (xy 42.141999 -357.422151) (xy 42.18789 -357.45164) (xy 42.229117 -357.48736)
			(xy 42.264841 -357.528584) (xy 42.294334 -357.574473) (xy 42.316996 -357.624092) (xy 42.332365 -357.676431)
			(xy 42.340128 -357.730425) (xy 42.340128 -357.78497) (xy 43.822831 -357.78497) (xy 43.822832 -357.73043)
			(xy 43.830594 -357.676445) (xy 43.84596 -357.624114) (xy 43.868618 -357.574503) (xy 43.898106 -357.528621)
			(xy 43.933824 -357.487404) (xy 43.975044 -357.451689) (xy 44.020927 -357.422205) (xy 44.07054 -357.39955)
			(xy 44.122872 -357.384188) (xy 44.176858 -357.37643) (xy 44.204128 -357.375968) (xy 45.067728 -357.375968)
			(xy 45.094998 -357.376396) (xy 45.148983 -357.384162) (xy 45.201313 -357.399531) (xy 45.250924 -357.42219)
			(xy 45.296805 -357.451679) (xy 45.338022 -357.487397) (xy 45.373737 -357.528618) (xy 45.403223 -357.574501)
			(xy 45.425879 -357.624113) (xy 45.441244 -357.676444) (xy 45.449006 -357.73043) (xy 45.449006 -357.784967)
			(xy 46.931854 -357.784967) (xy 46.931854 -357.730433) (xy 46.939615 -357.676455) (xy 46.954979 -357.624131)
			(xy 46.977632 -357.574525) (xy 47.007115 -357.528648) (xy 47.042826 -357.487434) (xy 47.084039 -357.451722)
			(xy 47.129915 -357.422238) (xy 47.179519 -357.399583) (xy 47.231843 -357.384218) (xy 47.285821 -357.376455)
			(xy 47.313088 -357.375968) (xy 48.176688 -357.375968) (xy 48.203962 -357.376371) (xy 48.257954 -357.384132)
			(xy 48.310292 -357.399499) (xy 48.359911 -357.422157) (xy 48.4058 -357.451647) (xy 48.447024 -357.487367)
			(xy 48.482746 -357.528591) (xy 48.512237 -357.574479) (xy 48.534897 -357.624096) (xy 48.550265 -357.676434)
			(xy 48.558028 -357.730426) (xy 48.558028 -357.784971) (xy 50.040732 -357.784971) (xy 50.040732 -357.730429)
			(xy 50.048494 -357.676442) (xy 50.063862 -357.62411) (xy 50.086521 -357.574497) (xy 50.116011 -357.528615)
			(xy 50.151731 -357.487397) (xy 50.192953 -357.451682) (xy 50.238839 -357.422198) (xy 50.288455 -357.399545)
			(xy 50.340789 -357.384184) (xy 50.394777 -357.376428) (xy 50.422048 -357.375968) (xy 51.285648 -357.375968)
			(xy 51.312917 -357.376398) (xy 51.3669 -357.384166) (xy 51.419228 -357.399536) (xy 51.468836 -357.422197)
			(xy 51.514714 -357.451687) (xy 51.555929 -357.487405) (xy 51.591642 -357.528624) (xy 51.621126 -357.574506)
			(xy 51.64378 -357.624117) (xy 51.659145 -357.676447) (xy 51.666906 -357.730431) (xy 51.666906 -357.784969)
			(xy 64.099931 -357.784969) (xy 64.099931 -357.730431) (xy 64.107693 -357.676448) (xy 64.123058 -357.62412)
			(xy 64.145714 -357.57451) (xy 64.1752 -357.52863) (xy 64.210914 -357.487413) (xy 64.252132 -357.451698)
			(xy 64.298012 -357.422213) (xy 64.347621 -357.399557) (xy 64.39995 -357.384193) (xy 64.453933 -357.376431)
			(xy 64.481202 -357.375968) (xy 65.344802 -357.375968) (xy 65.372073 -357.376395) (xy 65.426061 -357.384157)
			(xy 65.478394 -357.399524) (xy 65.528008 -357.422182) (xy 65.573893 -357.45167) (xy 65.615113 -357.487388)
			(xy 65.650831 -357.528609) (xy 65.680319 -357.574493) (xy 65.702977 -357.624107) (xy 65.718343 -357.676441)
			(xy 65.726106 -357.730429) (xy 65.726106 -357.784966) (xy 67.208954 -357.784966) (xy 67.208954 -357.730435)
			(xy 67.216714 -357.676458) (xy 67.232077 -357.624136) (xy 67.254728 -357.574532) (xy 67.284208 -357.528657)
			(xy 67.319917 -357.487443) (xy 67.361126 -357.451731) (xy 67.406999 -357.422246) (xy 67.4566 -357.39959)
			(xy 67.508921 -357.384222) (xy 67.562897 -357.376457) (xy 67.590162 -357.375968) (xy 68.453762 -357.375968)
			(xy 68.481037 -357.376369) (xy 68.535032 -357.384127) (xy 68.587373 -357.399491) (xy 68.636995 -357.422149)
			(xy 68.682887 -357.451638) (xy 68.724115 -357.487358) (xy 68.75984 -357.528582) (xy 68.789333 -357.574471)
			(xy 68.811995 -357.624091) (xy 68.827365 -357.676431) (xy 68.835128 -357.730425) (xy 68.835128 -357.78497)
			(xy 70.317831 -357.78497) (xy 70.317831 -357.73043) (xy 70.325594 -357.676446) (xy 70.34096 -357.624115)
			(xy 70.363617 -357.574505) (xy 70.393105 -357.528623) (xy 70.428822 -357.487406) (xy 70.470041 -357.451691)
			(xy 70.515924 -357.422207) (xy 70.565536 -357.399552) (xy 70.617867 -357.384189) (xy 70.671852 -357.37643)
			(xy 70.699122 -357.375968) (xy 71.562722 -357.375968) (xy 71.589992 -357.376396) (xy 71.643978 -357.384161)
			(xy 71.696309 -357.399529) (xy 71.74592 -357.422189) (xy 71.791802 -357.451677) (xy 71.83302 -357.487395)
			(xy 71.868736 -357.528616) (xy 71.898222 -357.574499) (xy 71.920878 -357.624112) (xy 71.936244 -357.676444)
			(xy 71.944006 -357.730429) (xy 71.944006 -357.784966) (xy 73.426854 -357.784966) (xy 73.426854 -357.730434)
			(xy 73.434615 -357.676456) (xy 73.449978 -357.624132) (xy 73.472631 -357.574527) (xy 73.502113 -357.52865)
			(xy 73.537824 -357.487436) (xy 73.579036 -357.451724) (xy 73.624911 -357.42224) (xy 73.674515 -357.399584)
			(xy 73.726838 -357.384219) (xy 73.780816 -357.376456) (xy 73.808082 -357.375968) (xy 74.671682 -357.375968)
			(xy 74.698956 -357.37637) (xy 74.752949 -357.384131) (xy 74.805288 -357.399497) (xy 74.854907 -357.422155)
			(xy 74.900797 -357.451645) (xy 74.942022 -357.487365) (xy 74.977744 -357.528589) (xy 75.007236 -357.574477)
			(xy 75.029897 -357.624095) (xy 75.045265 -357.676433) (xy 75.053028 -357.730426) (xy 75.053028 -357.784971)
			(xy 76.535732 -357.784971) (xy 76.535732 -357.730429) (xy 76.543494 -357.676443) (xy 76.558861 -357.624111)
			(xy 76.58152 -357.574499) (xy 76.611009 -357.528617) (xy 76.646729 -357.487399) (xy 76.687951 -357.451684)
			(xy 76.733836 -357.4222) (xy 76.78345 -357.399547) (xy 76.835784 -357.384185) (xy 76.889771 -357.376429)
			(xy 76.917042 -357.375968) (xy 77.780642 -357.375968) (xy 77.807912 -357.376397) (xy 77.861895 -357.384165)
			(xy 77.914223 -357.399535) (xy 77.963832 -357.422195) (xy 78.009711 -357.451684) (xy 78.050927 -357.487402)
			(xy 78.086641 -357.528622) (xy 78.116125 -357.574505) (xy 78.13878 -357.624116) (xy 78.154144 -357.676446)
			(xy 78.161906 -357.73043) (xy 78.161906 -357.784969) (xy 79.644731 -357.784969) (xy 79.644731 -357.730431)
			(xy 79.652493 -357.676448) (xy 79.667858 -357.62412) (xy 79.690514 -357.57451) (xy 79.72 -357.52863)
			(xy 79.755714 -357.487413) (xy 79.796932 -357.451698) (xy 79.842812 -357.422213) (xy 79.892421 -357.399557)
			(xy 79.94475 -357.384193) (xy 79.998733 -357.376431) (xy 80.026002 -357.375968) (xy 80.889602 -357.375968)
			(xy 80.916873 -357.376395) (xy 80.970861 -357.384157) (xy 81.023194 -357.399524) (xy 81.072808 -357.422182)
			(xy 81.118693 -357.45167) (xy 81.159913 -357.487388) (xy 81.195631 -357.528609) (xy 81.225119 -357.574493)
			(xy 81.247777 -357.624107) (xy 81.263143 -357.676441) (xy 81.270906 -357.730429) (xy 81.270906 -357.784966)
			(xy 82.753754 -357.784966) (xy 82.753754 -357.730435) (xy 82.761514 -357.676458) (xy 82.776877 -357.624136)
			(xy 82.799528 -357.574532) (xy 82.829008 -357.528657) (xy 82.864717 -357.487443) (xy 82.905926 -357.451731)
			(xy 82.951799 -357.422246) (xy 83.0014 -357.39959) (xy 83.053721 -357.384222) (xy 83.107697 -357.376457)
			(xy 83.134962 -357.375968) (xy 83.998562 -357.375968) (xy 84.025837 -357.376369) (xy 84.079832 -357.384127)
			(xy 84.132173 -357.399491) (xy 84.181795 -357.422149) (xy 84.227687 -357.451638) (xy 84.268915 -357.487358)
			(xy 84.30464 -357.528582) (xy 84.334133 -357.574471) (xy 84.356795 -357.624091) (xy 84.372165 -357.676431)
			(xy 84.379928 -357.730425) (xy 84.379928 -357.78497) (xy 85.862631 -357.78497) (xy 85.862631 -357.73043)
			(xy 85.870394 -357.676446) (xy 85.88576 -357.624115) (xy 85.908417 -357.574505) (xy 85.937905 -357.528623)
			(xy 85.973622 -357.487406) (xy 86.014841 -357.451691) (xy 86.060724 -357.422207) (xy 86.110336 -357.399552)
			(xy 86.162667 -357.384189) (xy 86.216652 -357.37643) (xy 86.243922 -357.375968) (xy 87.107522 -357.375968)
			(xy 87.134792 -357.376396) (xy 87.188778 -357.384161) (xy 87.241109 -357.399529) (xy 87.29072 -357.422189)
			(xy 87.336602 -357.451677) (xy 87.37782 -357.487395) (xy 87.413536 -357.528616) (xy 87.443022 -357.574499)
			(xy 87.465678 -357.624112) (xy 87.481044 -357.676444) (xy 87.488806 -357.730429) (xy 87.488806 -357.784966)
			(xy 88.971654 -357.784966) (xy 88.971654 -357.730434) (xy 88.979415 -357.676456) (xy 88.994778 -357.624132)
			(xy 89.017431 -357.574527) (xy 89.046913 -357.52865) (xy 89.082624 -357.487436) (xy 89.123836 -357.451724)
			(xy 89.169711 -357.42224) (xy 89.219315 -357.399584) (xy 89.271638 -357.384219) (xy 89.325616 -357.376456)
			(xy 89.352882 -357.375968) (xy 90.216482 -357.375968) (xy 90.243756 -357.37637) (xy 90.297749 -357.384131)
			(xy 90.350088 -357.399497) (xy 90.399707 -357.422155) (xy 90.445597 -357.451645) (xy 90.486822 -357.487365)
			(xy 90.522544 -357.528589) (xy 90.552036 -357.574477) (xy 90.574697 -357.624095) (xy 90.590065 -357.676433)
			(xy 90.597828 -357.730426) (xy 90.597828 -357.784971) (xy 92.080532 -357.784971) (xy 92.080532 -357.730429)
			(xy 92.088294 -357.676443) (xy 92.103661 -357.624111) (xy 92.12632 -357.574499) (xy 92.155809 -357.528617)
			(xy 92.191529 -357.487399) (xy 92.232751 -357.451684) (xy 92.278636 -357.4222) (xy 92.32825 -357.399547)
			(xy 92.380584 -357.384185) (xy 92.434571 -357.376429) (xy 92.461842 -357.375968) (xy 93.325442 -357.375968)
			(xy 93.352712 -357.376397) (xy 93.406695 -357.384165) (xy 93.459023 -357.399535) (xy 93.508632 -357.422195)
			(xy 93.554511 -357.451684) (xy 93.595727 -357.487402) (xy 93.631441 -357.528622) (xy 93.660925 -357.574505)
			(xy 93.68358 -357.624116) (xy 93.698944 -357.676446) (xy 93.706706 -357.73043) (xy 93.706706 -357.784966)
			(xy 114.589854 -357.784966) (xy 114.589854 -357.730434) (xy 114.597614 -357.676458) (xy 114.612977 -357.624135)
			(xy 114.635629 -357.574531) (xy 114.66511 -357.528655) (xy 114.700819 -357.487441) (xy 114.742029 -357.451729)
			(xy 114.787903 -357.422244) (xy 114.837505 -357.399588) (xy 114.889826 -357.384221) (xy 114.943802 -357.376457)
			(xy 114.971068 -357.375968) (xy 115.834668 -357.375968) (xy 115.861943 -357.376369) (xy 115.915937 -357.384128)
			(xy 115.968278 -357.399493) (xy 116.017899 -357.422151) (xy 116.06379 -357.45164) (xy 116.105017 -357.48736)
			(xy 116.140741 -357.528584) (xy 116.170234 -357.574473) (xy 116.192896 -357.624092) (xy 116.208265 -357.676431)
			(xy 116.216028 -357.730425) (xy 116.216028 -357.78497) (xy 117.698731 -357.78497) (xy 117.698732 -357.73043)
			(xy 117.706494 -357.676445) (xy 117.72186 -357.624114) (xy 117.744518 -357.574503) (xy 117.774006 -357.528621)
			(xy 117.809724 -357.487404) (xy 117.850944 -357.451689) (xy 117.896827 -357.422205) (xy 117.94644 -357.39955)
			(xy 117.998772 -357.384188) (xy 118.052758 -357.37643) (xy 118.080028 -357.375968) (xy 118.943628 -357.375968)
			(xy 118.970898 -357.376396) (xy 119.024883 -357.384162) (xy 119.077213 -357.399531) (xy 119.126824 -357.42219)
			(xy 119.172705 -357.451679) (xy 119.213922 -357.487397) (xy 119.249637 -357.528618) (xy 119.279123 -357.574501)
			(xy 119.301779 -357.624113) (xy 119.317144 -357.676444) (xy 119.324906 -357.73043) (xy 119.324906 -357.784967)
			(xy 120.807754 -357.784967) (xy 120.807754 -357.730433) (xy 120.815515 -357.676455) (xy 120.830879 -357.624131)
			(xy 120.853532 -357.574525) (xy 120.883015 -357.528648) (xy 120.918726 -357.487434) (xy 120.959939 -357.451722)
			(xy 121.005815 -357.422238) (xy 121.055419 -357.399583) (xy 121.107743 -357.384218) (xy 121.161721 -357.376455)
			(xy 121.188988 -357.375968) (xy 122.052588 -357.375968) (xy 122.079862 -357.376371) (xy 122.133854 -357.384132)
			(xy 122.186192 -357.399499) (xy 122.235811 -357.422157) (xy 122.2817 -357.451647) (xy 122.322924 -357.487367)
			(xy 122.358646 -357.528591) (xy 122.388137 -357.574479) (xy 122.410797 -357.624096) (xy 122.426165 -357.676434)
			(xy 122.433928 -357.730426) (xy 122.433928 -357.784971) (xy 123.916632 -357.784971) (xy 123.916632 -357.730429)
			(xy 123.924394 -357.676442) (xy 123.939762 -357.62411) (xy 123.962421 -357.574497) (xy 123.991911 -357.528615)
			(xy 124.027631 -357.487397) (xy 124.068853 -357.451682) (xy 124.114739 -357.422198) (xy 124.164355 -357.399545)
			(xy 124.216689 -357.384184) (xy 124.270677 -357.376428) (xy 124.297948 -357.375968) (xy 125.161548 -357.375968)
			(xy 125.188817 -357.376398) (xy 125.2428 -357.384166) (xy 125.295128 -357.399536) (xy 125.344736 -357.422197)
			(xy 125.390614 -357.451687) (xy 125.431829 -357.487405) (xy 125.467542 -357.528624) (xy 125.497026 -357.574506)
			(xy 125.51968 -357.624117) (xy 125.535045 -357.676447) (xy 125.542806 -357.730431) (xy 125.542806 -357.784969)
			(xy 127.025631 -357.784969) (xy 127.025631 -357.730431) (xy 127.033393 -357.676447) (xy 127.048759 -357.624118)
			(xy 127.071415 -357.574508) (xy 127.100901 -357.528628) (xy 127.136617 -357.487411) (xy 127.177834 -357.451696)
			(xy 127.223715 -357.422211) (xy 127.273326 -357.399556) (xy 127.325655 -357.384191) (xy 127.379639 -357.376431)
			(xy 127.406908 -357.375968) (xy 128.270508 -357.375968) (xy 128.297779 -357.376395) (xy 128.351766 -357.384158)
			(xy 128.404099 -357.399525) (xy 128.453712 -357.422184) (xy 128.499595 -357.451672) (xy 128.540815 -357.48739)
			(xy 128.576532 -357.528611) (xy 128.60602 -357.574495) (xy 128.628677 -357.624109) (xy 128.644043 -357.676442)
			(xy 128.651806 -357.730429) (xy 128.651806 -357.784966) (xy 130.134654 -357.784966) (xy 130.134654 -357.730434)
			(xy 130.142414 -357.676458) (xy 130.157777 -357.624135) (xy 130.180429 -357.574531) (xy 130.20991 -357.528655)
			(xy 130.245619 -357.487441) (xy 130.286829 -357.451729) (xy 130.332703 -357.422244) (xy 130.382305 -357.399588)
			(xy 130.434626 -357.384221) (xy 130.488602 -357.376457) (xy 130.515868 -357.375968) (xy 131.379468 -357.375968)
			(xy 131.406743 -357.376369) (xy 131.460737 -357.384128) (xy 131.513078 -357.399493) (xy 131.562699 -357.422151)
			(xy 131.60859 -357.45164) (xy 131.649817 -357.48736) (xy 131.685541 -357.528584) (xy 131.715034 -357.574473)
			(xy 131.737696 -357.624092) (xy 131.753065 -357.676431) (xy 131.760828 -357.730425) (xy 131.760828 -357.78497)
			(xy 133.243531 -357.78497) (xy 133.243532 -357.73043) (xy 133.251294 -357.676445) (xy 133.26666 -357.624114)
			(xy 133.289318 -357.574503) (xy 133.318806 -357.528621) (xy 133.354524 -357.487404) (xy 133.395744 -357.451689)
			(xy 133.441627 -357.422205) (xy 133.49124 -357.39955) (xy 133.543572 -357.384188) (xy 133.597558 -357.37643)
			(xy 133.624828 -357.375968) (xy 134.488428 -357.375968) (xy 134.515698 -357.376396) (xy 134.569683 -357.384162)
			(xy 134.622013 -357.399531) (xy 134.671624 -357.42219) (xy 134.717505 -357.451679) (xy 134.758722 -357.487397)
			(xy 134.794437 -357.528618) (xy 134.823923 -357.574501) (xy 134.846579 -357.624113) (xy 134.861944 -357.676444)
			(xy 134.869706 -357.73043) (xy 134.869706 -357.784967) (xy 136.352554 -357.784967) (xy 136.352554 -357.730433)
			(xy 136.360315 -357.676455) (xy 136.375679 -357.624131) (xy 136.398332 -357.574525) (xy 136.427815 -357.528648)
			(xy 136.463526 -357.487434) (xy 136.504739 -357.451722) (xy 136.550615 -357.422238) (xy 136.600219 -357.399583)
			(xy 136.652543 -357.384218) (xy 136.706521 -357.376455) (xy 136.733788 -357.375968) (xy 137.597388 -357.375968)
			(xy 137.624662 -357.376371) (xy 137.678654 -357.384132) (xy 137.730992 -357.399499) (xy 137.780611 -357.422157)
			(xy 137.8265 -357.451647) (xy 137.867724 -357.487367) (xy 137.903446 -357.528591) (xy 137.932937 -357.574479)
			(xy 137.955597 -357.624096) (xy 137.970965 -357.676434) (xy 137.978728 -357.730426) (xy 137.978728 -357.784971)
			(xy 139.461432 -357.784971) (xy 139.461432 -357.730429) (xy 139.469194 -357.676442) (xy 139.484562 -357.62411)
			(xy 139.507221 -357.574497) (xy 139.536711 -357.528615) (xy 139.572431 -357.487397) (xy 139.613653 -357.451682)
			(xy 139.659539 -357.422198) (xy 139.709155 -357.399545) (xy 139.761489 -357.384184) (xy 139.815477 -357.376428)
			(xy 139.842748 -357.375968) (xy 140.706348 -357.375968) (xy 140.733617 -357.376398) (xy 140.7876 -357.384166)
			(xy 140.839928 -357.399536) (xy 140.889536 -357.422197) (xy 140.935414 -357.451687) (xy 140.976629 -357.487405)
			(xy 141.012342 -357.528624) (xy 141.041826 -357.574506) (xy 141.06448 -357.624117) (xy 141.079845 -357.676447)
			(xy 141.087606 -357.730431) (xy 141.087606 -357.784969) (xy 142.570431 -357.784969) (xy 142.570431 -357.730431)
			(xy 142.578193 -357.676447) (xy 142.593559 -357.624118) (xy 142.616215 -357.574508) (xy 142.645701 -357.528628)
			(xy 142.681417 -357.487411) (xy 142.722634 -357.451696) (xy 142.768515 -357.422211) (xy 142.818126 -357.399556)
			(xy 142.870455 -357.384191) (xy 142.924439 -357.376431) (xy 142.951708 -357.375968) (xy 143.815308 -357.375968)
			(xy 143.842579 -357.376395) (xy 143.896566 -357.384158) (xy 143.948899 -357.399525) (xy 143.998512 -357.422184)
			(xy 144.044395 -357.451672) (xy 144.085615 -357.48739) (xy 144.121332 -357.528611) (xy 144.15082 -357.574495)
			(xy 144.173477 -357.624109) (xy 144.188843 -357.676442) (xy 144.196606 -357.730429) (xy 144.196606 -357.784965)
			(xy 158.695954 -357.784965) (xy 158.695954 -357.730435) (xy 158.703714 -357.67646) (xy 158.719076 -357.624138)
			(xy 158.741727 -357.574535) (xy 158.771206 -357.52866) (xy 158.806913 -357.487447) (xy 158.848122 -357.451735)
			(xy 158.893993 -357.42225) (xy 158.943593 -357.399593) (xy 158.995913 -357.384224) (xy 159.049887 -357.376458)
			(xy 159.077152 -357.375968) (xy 159.940752 -357.375968) (xy 159.968027 -357.376368) (xy 160.022024 -357.384125)
			(xy 160.074366 -357.399489) (xy 160.123989 -357.422145) (xy 160.169883 -357.451634) (xy 160.211112 -357.487354)
			(xy 160.246837 -357.528579) (xy 160.276332 -357.574468) (xy 160.298994 -357.624089) (xy 160.314364 -357.676429)
			(xy 160.322128 -357.730425) (xy 160.322128 -357.784969) (xy 161.804831 -357.784969) (xy 161.804831 -357.730431)
			(xy 161.812593 -357.676447) (xy 161.827959 -357.624117) (xy 161.850616 -357.574507) (xy 161.880102 -357.528627)
			(xy 161.915818 -357.487409) (xy 161.957036 -357.451695) (xy 162.002918 -357.42221) (xy 162.052529 -357.399555)
			(xy 162.104859 -357.384191) (xy 162.158843 -357.376431) (xy 162.186112 -357.375968) (xy 163.049712 -357.375968)
			(xy 163.076983 -357.376395) (xy 163.130969 -357.384159) (xy 163.183302 -357.399527) (xy 163.232914 -357.422185)
			(xy 163.278797 -357.451674) (xy 163.320017 -357.487392) (xy 163.355733 -357.528612) (xy 163.385221 -357.574496)
			(xy 163.407878 -357.62411) (xy 163.423244 -357.676442) (xy 163.431006 -357.730429) (xy 163.431006 -357.784966)
			(xy 164.913854 -357.784966) (xy 164.913854 -357.730434) (xy 164.921615 -357.676457) (xy 164.936977 -357.624134)
			(xy 164.95963 -357.57453) (xy 164.989111 -357.528654) (xy 165.02482 -357.48744) (xy 165.066031 -357.451727)
			(xy 165.111905 -357.422243) (xy 165.161508 -357.399587) (xy 165.21383 -357.384221) (xy 165.267806 -357.376456)
			(xy 165.295072 -357.375968) (xy 166.158672 -357.375968) (xy 166.185946 -357.37637) (xy 166.239941 -357.384129)
			(xy 166.292281 -357.399494) (xy 166.341901 -357.422152) (xy 166.387792 -357.451641) (xy 166.429019 -357.487361)
			(xy 166.464742 -357.528585) (xy 166.494235 -357.574474) (xy 166.516896 -357.624093) (xy 166.532265 -357.676432)
			(xy 166.540028 -357.730426) (xy 166.540028 -357.78497) (xy 168.022732 -357.78497) (xy 168.022732 -357.73043)
			(xy 168.030494 -357.676444) (xy 168.045861 -357.624113) (xy 168.068519 -357.574502) (xy 168.098007 -357.52862)
			(xy 168.133725 -357.487402) (xy 168.174946 -357.451688) (xy 168.22083 -357.422203) (xy 168.270443 -357.399549)
			(xy 168.322776 -357.384187) (xy 168.376762 -357.376429) (xy 168.404032 -357.375968) (xy 169.267632 -357.375968)
			(xy 169.294902 -357.376397) (xy 169.348886 -357.384163) (xy 169.401216 -357.399532) (xy 169.450826 -357.422192)
			(xy 169.496707 -357.451681) (xy 169.537924 -357.487399) (xy 169.573638 -357.528619) (xy 169.603124 -357.574502)
			(xy 169.625779 -357.624114) (xy 169.641144 -357.676445) (xy 169.648906 -357.73043) (xy 169.648906 -357.784967)
			(xy 171.131754 -357.784967) (xy 171.131754 -357.730433) (xy 171.139515 -357.676454) (xy 171.154879 -357.62413)
			(xy 171.177533 -357.574524) (xy 171.207016 -357.528647) (xy 171.242727 -357.487433) (xy 171.283941 -357.45172)
			(xy 171.329817 -357.422237) (xy 171.379422 -357.399582) (xy 171.431747 -357.384217) (xy 171.485725 -357.376455)
			(xy 171.512992 -357.375968) (xy 172.376592 -357.375968) (xy 172.403866 -357.376371) (xy 172.457857 -357.384133)
			(xy 172.510195 -357.3995) (xy 172.559813 -357.422159) (xy 172.605702 -357.451648) (xy 172.646926 -357.487368)
			(xy 172.682647 -357.528592) (xy 172.712138 -357.57448) (xy 172.734798 -357.624097) (xy 172.750165 -357.676435)
			(xy 172.757928 -357.730426) (xy 172.757928 -357.784965) (xy 174.240754 -357.784965) (xy 174.240754 -357.730435)
			(xy 174.248514 -357.67646) (xy 174.263876 -357.624138) (xy 174.286527 -357.574535) (xy 174.316006 -357.52866)
			(xy 174.351713 -357.487447) (xy 174.392922 -357.451735) (xy 174.438793 -357.42225) (xy 174.488393 -357.399593)
			(xy 174.540713 -357.384224) (xy 174.594687 -357.376458) (xy 174.621952 -357.375968) (xy 175.485552 -357.375968)
			(xy 175.512827 -357.376368) (xy 175.566824 -357.384125) (xy 175.619166 -357.399489) (xy 175.668789 -357.422145)
			(xy 175.714683 -357.451634) (xy 175.755912 -357.487354) (xy 175.791637 -357.528579) (xy 175.821132 -357.574468)
			(xy 175.843794 -357.624089) (xy 175.859164 -357.676429) (xy 175.866928 -357.730425) (xy 175.866928 -357.784969)
			(xy 177.349631 -357.784969) (xy 177.349631 -357.730431) (xy 177.357393 -357.676447) (xy 177.372759 -357.624117)
			(xy 177.395416 -357.574507) (xy 177.424902 -357.528627) (xy 177.460618 -357.487409) (xy 177.501836 -357.451695)
			(xy 177.547718 -357.42221) (xy 177.597329 -357.399555) (xy 177.649659 -357.384191) (xy 177.703643 -357.376431)
			(xy 177.730912 -357.375968) (xy 178.594512 -357.375968) (xy 178.621783 -357.376395) (xy 178.675769 -357.384159)
			(xy 178.728102 -357.399527) (xy 178.777714 -357.422185) (xy 178.823597 -357.451674) (xy 178.864817 -357.487392)
			(xy 178.900533 -357.528612) (xy 178.930021 -357.574496) (xy 178.952678 -357.62411) (xy 178.968044 -357.676442)
			(xy 178.975806 -357.730429) (xy 178.975806 -357.784966) (xy 180.458654 -357.784966) (xy 180.458654 -357.730434)
			(xy 180.466415 -357.676457) (xy 180.481777 -357.624134) (xy 180.50443 -357.57453) (xy 180.533911 -357.528654)
			(xy 180.56962 -357.48744) (xy 180.610831 -357.451727) (xy 180.656705 -357.422243) (xy 180.706308 -357.399587)
			(xy 180.75863 -357.384221) (xy 180.812606 -357.376456) (xy 180.839872 -357.375968) (xy 181.703472 -357.375968)
			(xy 181.730746 -357.37637) (xy 181.784741 -357.384129) (xy 181.837081 -357.399494) (xy 181.886701 -357.422152)
			(xy 181.932592 -357.451641) (xy 181.973819 -357.487361) (xy 182.009542 -357.528585) (xy 182.039035 -357.574474)
			(xy 182.061696 -357.624093) (xy 182.077065 -357.676432) (xy 182.084828 -357.730426) (xy 182.084828 -357.761176)
			(xy 183.567456 -357.761176) (xy 183.567456 -357.706624) (xy 183.57522 -357.652628) (xy 183.590589 -357.600287)
			(xy 183.613252 -357.550665) (xy 183.642746 -357.504775) (xy 183.678471 -357.463549) (xy 183.7197 -357.427827)
			(xy 183.765593 -357.398337) (xy 183.815217 -357.375678) (xy 183.867559 -357.360313) (xy 183.921556 -357.352553)
			(xy 183.948832 -357.352092) (xy 184.812432 -357.352092) (xy 184.839697 -357.352672) (xy 184.89367 -357.360437)
			(xy 184.94599 -357.375803) (xy 184.99559 -357.398458) (xy 185.041461 -357.427942) (xy 185.08267 -357.463653)
			(xy 185.118378 -357.504864) (xy 185.147857 -357.550738) (xy 185.170508 -357.60034) (xy 185.18587 -357.652661)
			(xy 185.19363 -357.706635) (xy 185.19363 -357.761165) (xy 185.193629 -357.761172) (xy 186.676479 -357.761172)
			(xy 186.676479 -357.706628) (xy 186.684241 -357.652638) (xy 186.699608 -357.600303) (xy 186.722266 -357.550688)
			(xy 186.751755 -357.504801) (xy 186.787473 -357.463579) (xy 186.828695 -357.42786) (xy 186.87458 -357.39837)
			(xy 186.924196 -357.37571) (xy 186.97653 -357.360343) (xy 187.03052 -357.352579) (xy 187.057792 -357.352092)
			(xy 187.921392 -357.352092) (xy 187.94866 -357.352647) (xy 188.002641 -357.360407) (xy 188.054969 -357.375771)
			(xy 188.104577 -357.398425) (xy 188.150456 -357.427909) (xy 188.191672 -357.463622) (xy 188.227386 -357.504838)
			(xy 188.256871 -357.550716) (xy 188.279526 -357.600324) (xy 188.294891 -357.652651) (xy 188.302653 -357.706632)
			(xy 188.302653 -357.761168) (xy 188.294891 -357.815149) (xy 188.279526 -357.867476) (xy 188.256871 -357.917084)
			(xy 188.227386 -357.962962) (xy 188.223925 -357.966956) (xy 245.50903 -357.966956) (xy 245.50903 -357.88226)
			(xy 245.517081 -357.797946) (xy 245.53311 -357.71478) (xy 245.556971 -357.633513) (xy 245.58845 -357.554883)
			(xy 245.627261 -357.479602) (xy 245.673051 -357.40835) (xy 245.725407 -357.341774) (xy 245.783855 -357.280476)
			(xy 245.847865 -357.225011) (xy 245.916857 -357.175882) (xy 245.990207 -357.133533) (xy 246.06725 -357.098349)
			(xy 246.147289 -357.070647) (xy 246.229598 -357.050679) (xy 246.313433 -357.038626) (xy 246.398034 -357.034596)
			(xy 246.482635 -357.038626) (xy 246.56647 -357.050679) (xy 246.648779 -357.070647) (xy 246.728818 -357.098349)
			(xy 246.805861 -357.133533) (xy 246.879211 -357.175882) (xy 246.948203 -357.225011) (xy 247.012213 -357.280476)
			(xy 247.070661 -357.341774) (xy 247.123017 -357.40835) (xy 247.168807 -357.479602) (xy 247.207618 -357.554883)
			(xy 247.239097 -357.633513) (xy 247.262958 -357.71478) (xy 247.276485 -357.784966) (xy 270.624854 -357.784966)
			(xy 270.624854 -357.730435) (xy 270.632614 -357.676458) (xy 270.647977 -357.624136) (xy 270.670628 -357.574532)
			(xy 270.700108 -357.528657) (xy 270.735817 -357.487443) (xy 270.777026 -357.451731) (xy 270.822899 -357.422246)
			(xy 270.8725 -357.39959) (xy 270.924821 -357.384222) (xy 270.978797 -357.376457) (xy 271.006062 -357.375968)
			(xy 271.869662 -357.375968) (xy 271.896937 -357.376369) (xy 271.950932 -357.384127) (xy 272.003273 -357.399491)
			(xy 272.052895 -357.422149) (xy 272.098787 -357.451638) (xy 272.140015 -357.487358) (xy 272.17574 -357.528582)
			(xy 272.205233 -357.574471) (xy 272.227895 -357.624091) (xy 272.243265 -357.676431) (xy 272.251028 -357.730425)
			(xy 272.251028 -357.78497) (xy 273.733731 -357.78497) (xy 273.733731 -357.73043) (xy 273.741494 -357.676446)
			(xy 273.75686 -357.624115) (xy 273.779517 -357.574505) (xy 273.809005 -357.528623) (xy 273.844722 -357.487406)
			(xy 273.885941 -357.451691) (xy 273.931824 -357.422207) (xy 273.981436 -357.399552) (xy 274.033767 -357.384189)
			(xy 274.087752 -357.37643) (xy 274.115022 -357.375968) (xy 274.978622 -357.375968) (xy 275.005892 -357.376396)
			(xy 275.059878 -357.384161) (xy 275.112209 -357.399529) (xy 275.16182 -357.422189) (xy 275.207702 -357.451677)
			(xy 275.24892 -357.487395) (xy 275.284636 -357.528616) (xy 275.314122 -357.574499) (xy 275.336778 -357.624112)
			(xy 275.352144 -357.676444) (xy 275.359906 -357.730429) (xy 275.359906 -357.784966) (xy 276.842754 -357.784966)
			(xy 276.842754 -357.730434) (xy 276.850515 -357.676456) (xy 276.865878 -357.624132) (xy 276.888531 -357.574527)
			(xy 276.918013 -357.52865) (xy 276.953724 -357.487436) (xy 276.994936 -357.451724) (xy 277.040811 -357.42224)
			(xy 277.090415 -357.399584) (xy 277.142738 -357.384219) (xy 277.196716 -357.376456) (xy 277.223982 -357.375968)
			(xy 278.087582 -357.375968) (xy 278.114856 -357.37637) (xy 278.168849 -357.384131) (xy 278.221188 -357.399497)
			(xy 278.270807 -357.422155) (xy 278.316697 -357.451645) (xy 278.357922 -357.487365) (xy 278.393644 -357.528589)
			(xy 278.423136 -357.574477) (xy 278.445797 -357.624095) (xy 278.461165 -357.676433) (xy 278.468928 -357.730426)
			(xy 278.468928 -357.784971) (xy 279.951632 -357.784971) (xy 279.951632 -357.730429) (xy 279.959394 -357.676443)
			(xy 279.974761 -357.624111) (xy 279.99742 -357.574499) (xy 280.026909 -357.528617) (xy 280.062629 -357.487399)
			(xy 280.103851 -357.451684) (xy 280.149736 -357.4222) (xy 280.19935 -357.399547) (xy 280.251684 -357.384185)
			(xy 280.305671 -357.376429) (xy 280.332942 -357.375968) (xy 281.196542 -357.375968) (xy 281.223812 -357.376397)
			(xy 281.277795 -357.384165) (xy 281.330123 -357.399535) (xy 281.379732 -357.422195) (xy 281.425611 -357.451684)
			(xy 281.466827 -357.487402) (xy 281.502541 -357.528622) (xy 281.532025 -357.574505) (xy 281.55468 -357.624116)
			(xy 281.570044 -357.676446) (xy 281.577806 -357.73043) (xy 281.577806 -357.784969) (xy 283.060631 -357.784969)
			(xy 283.060631 -357.730431) (xy 283.068393 -357.676448) (xy 283.083758 -357.62412) (xy 283.106414 -357.57451)
			(xy 283.1359 -357.52863) (xy 283.171614 -357.487413) (xy 283.212832 -357.451698) (xy 283.258712 -357.422213)
			(xy 283.308321 -357.399557) (xy 283.36065 -357.384193) (xy 283.414633 -357.376431) (xy 283.441902 -357.375968)
			(xy 284.305502 -357.375968) (xy 284.332773 -357.376395) (xy 284.386761 -357.384157) (xy 284.439094 -357.399524)
			(xy 284.488708 -357.422182) (xy 284.534593 -357.45167) (xy 284.575813 -357.487388) (xy 284.611531 -357.528609)
			(xy 284.641019 -357.574493) (xy 284.663677 -357.624107) (xy 284.679043 -357.676441) (xy 284.686806 -357.730429)
			(xy 284.686806 -357.784966) (xy 286.169654 -357.784966) (xy 286.169654 -357.730435) (xy 286.177414 -357.676458)
			(xy 286.192777 -357.624136) (xy 286.215428 -357.574532) (xy 286.244908 -357.528657) (xy 286.280617 -357.487443)
			(xy 286.321826 -357.451731) (xy 286.367699 -357.422246) (xy 286.4173 -357.39959) (xy 286.469621 -357.384222)
			(xy 286.523597 -357.376457) (xy 286.550862 -357.375968) (xy 287.414462 -357.375968) (xy 287.441737 -357.376369)
			(xy 287.495732 -357.384127) (xy 287.548073 -357.399491) (xy 287.597695 -357.422149) (xy 287.643587 -357.451638)
			(xy 287.684815 -357.487358) (xy 287.72054 -357.528582) (xy 287.750033 -357.574471) (xy 287.772695 -357.624091)
			(xy 287.788065 -357.676431) (xy 287.795828 -357.730425) (xy 287.795828 -357.78497) (xy 289.278531 -357.78497)
			(xy 289.278531 -357.73043) (xy 289.286294 -357.676446) (xy 289.30166 -357.624115) (xy 289.324317 -357.574505)
			(xy 289.353805 -357.528623) (xy 289.389522 -357.487406) (xy 289.430741 -357.451691) (xy 289.476624 -357.422207)
			(xy 289.526236 -357.399552) (xy 289.578567 -357.384189) (xy 289.632552 -357.37643) (xy 289.659822 -357.375968)
			(xy 290.523422 -357.375968) (xy 290.550692 -357.376396) (xy 290.604678 -357.384161) (xy 290.657009 -357.399529)
			(xy 290.70662 -357.422189) (xy 290.752502 -357.451677) (xy 290.79372 -357.487395) (xy 290.829436 -357.528616)
			(xy 290.858922 -357.574499) (xy 290.881578 -357.624112) (xy 290.896944 -357.676444) (xy 290.904706 -357.730429)
			(xy 290.904706 -357.784966) (xy 292.387554 -357.784966) (xy 292.387554 -357.730434) (xy 292.395315 -357.676456)
			(xy 292.410678 -357.624132) (xy 292.433331 -357.574527) (xy 292.462813 -357.52865) (xy 292.498524 -357.487436)
			(xy 292.539736 -357.451724) (xy 292.585611 -357.42224) (xy 292.635215 -357.399584) (xy 292.687538 -357.384219)
			(xy 292.741516 -357.376456) (xy 292.768782 -357.375968) (xy 293.632382 -357.375968) (xy 293.659656 -357.37637)
			(xy 293.713649 -357.384131) (xy 293.765988 -357.399497) (xy 293.815607 -357.422155) (xy 293.861497 -357.451645)
			(xy 293.902722 -357.487365) (xy 293.938444 -357.528589) (xy 293.967936 -357.574477) (xy 293.990597 -357.624095)
			(xy 294.005965 -357.676433) (xy 294.013728 -357.730426) (xy 294.013728 -357.784971) (xy 295.496432 -357.784971)
			(xy 295.496432 -357.730429) (xy 295.504194 -357.676443) (xy 295.519561 -357.624111) (xy 295.54222 -357.574499)
			(xy 295.571709 -357.528617) (xy 295.607429 -357.487399) (xy 295.648651 -357.451684) (xy 295.694536 -357.4222)
			(xy 295.74415 -357.399547) (xy 295.796484 -357.384185) (xy 295.850471 -357.376429) (xy 295.877742 -357.375968)
			(xy 296.741342 -357.375968) (xy 296.768612 -357.376397) (xy 296.822595 -357.384165) (xy 296.874923 -357.399535)
			(xy 296.924532 -357.422195) (xy 296.970411 -357.451684) (xy 297.011627 -357.487402) (xy 297.047341 -357.528622)
			(xy 297.076825 -357.574505) (xy 297.09948 -357.624116) (xy 297.114844 -357.676446) (xy 297.122606 -357.73043)
			(xy 297.122606 -357.784969) (xy 298.605431 -357.784969) (xy 298.605431 -357.730431) (xy 298.613193 -357.676448)
			(xy 298.628558 -357.62412) (xy 298.651214 -357.57451) (xy 298.6807 -357.52863) (xy 298.716414 -357.487413)
			(xy 298.757632 -357.451698) (xy 298.803512 -357.422213) (xy 298.853121 -357.399557) (xy 298.90545 -357.384193)
			(xy 298.959433 -357.376431) (xy 298.986702 -357.375968) (xy 299.850302 -357.375968) (xy 299.877573 -357.376395)
			(xy 299.931561 -357.384157) (xy 299.983894 -357.399524) (xy 300.033508 -357.422182) (xy 300.079393 -357.45167)
			(xy 300.120613 -357.487388) (xy 300.156331 -357.528609) (xy 300.185819 -357.574493) (xy 300.208477 -357.624107)
			(xy 300.223843 -357.676441) (xy 300.231606 -357.730429) (xy 300.231606 -357.784966) (xy 315.230554 -357.784966)
			(xy 315.230554 -357.730434) (xy 315.238314 -357.676458) (xy 315.253677 -357.624136) (xy 315.276328 -357.574532)
			(xy 315.305809 -357.528656) (xy 315.341517 -357.487443) (xy 315.382727 -357.45173) (xy 315.4286 -357.422246)
			(xy 315.478202 -357.399589) (xy 315.530523 -357.384222) (xy 315.584498 -357.376457) (xy 315.611764 -357.375968)
			(xy 316.475364 -357.375968) (xy 316.502639 -357.376369) (xy 316.556634 -357.384128) (xy 316.608975 -357.399492)
			(xy 316.658597 -357.422149) (xy 316.704488 -357.451638) (xy 316.745716 -357.487359) (xy 316.78144 -357.528583)
			(xy 316.810933 -357.574472) (xy 316.833595 -357.624091) (xy 316.848965 -357.676431) (xy 316.856728 -357.730425)
			(xy 316.856728 -357.78497) (xy 318.339431 -357.78497) (xy 318.339431 -357.73043) (xy 318.347194 -357.676445)
			(xy 318.36256 -357.624115) (xy 318.385217 -357.574504) (xy 318.414705 -357.528623) (xy 318.450422 -357.487405)
			(xy 318.491642 -357.451691) (xy 318.537525 -357.422206) (xy 318.587137 -357.399552) (xy 318.639469 -357.384189)
			(xy 318.693454 -357.37643) (xy 318.720724 -357.375968) (xy 319.584324 -357.375968) (xy 319.611594 -357.376396)
			(xy 319.66558 -357.384161) (xy 319.71791 -357.39953) (xy 319.767521 -357.422189) (xy 319.813403 -357.451678)
			(xy 319.854621 -357.487396) (xy 319.890336 -357.528616) (xy 319.919822 -357.5745) (xy 319.942479 -357.624112)
			(xy 319.957844 -357.676444) (xy 319.965606 -357.73043) (xy 319.965606 -357.784967) (xy 321.448454 -357.784967)
			(xy 321.448454 -357.730434) (xy 321.456215 -357.676456) (xy 321.471578 -357.624131) (xy 321.494232 -357.574526)
			(xy 321.523714 -357.52865) (xy 321.559424 -357.487436) (xy 321.600637 -357.451723) (xy 321.646512 -357.422239)
			(xy 321.696116 -357.399584) (xy 321.74844 -357.384218) (xy 321.802418 -357.376455) (xy 321.829684 -357.375968)
			(xy 322.693284 -357.375968) (xy 322.720558 -357.37637) (xy 322.774551 -357.384131) (xy 322.826889 -357.399497)
			(xy 322.876508 -357.422156) (xy 322.922398 -357.451645) (xy 322.963623 -357.487366) (xy 322.999345 -357.528589)
			(xy 323.028836 -357.574477) (xy 323.051497 -357.624096) (xy 323.066865 -357.676434) (xy 323.074628 -357.730426)
			(xy 323.074628 -357.784971) (xy 324.557332 -357.784971) (xy 324.557332 -357.730429) (xy 324.565094 -357.676443)
			(xy 324.580461 -357.624111) (xy 324.603121 -357.574498) (xy 324.63261 -357.528616) (xy 324.668329 -357.487398)
			(xy 324.709551 -357.451684) (xy 324.755437 -357.422199) (xy 324.805052 -357.399546) (xy 324.857386 -357.384185)
			(xy 324.911373 -357.376428) (xy 324.938644 -357.375968) (xy 325.802244 -357.375968) (xy 325.829513 -357.376398)
			(xy 325.883497 -357.384165) (xy 325.935825 -357.399535) (xy 325.985433 -357.422196) (xy 326.031312 -357.451685)
			(xy 326.072528 -357.487403) (xy 326.108241 -357.528623) (xy 326.137725 -357.574505) (xy 326.16038 -357.624116)
			(xy 326.175744 -357.676447) (xy 326.183506 -357.73043) (xy 326.183506 -357.784969) (xy 327.666331 -357.784969)
			(xy 327.666331 -357.730431) (xy 327.674093 -357.676448) (xy 327.689458 -357.624119) (xy 327.712114 -357.57451)
			(xy 327.7416 -357.528629) (xy 327.777315 -357.487412) (xy 327.818533 -357.451698) (xy 327.864413 -357.422212)
			(xy 327.914023 -357.399557) (xy 327.966352 -357.384192) (xy 328.020335 -357.376431) (xy 328.047604 -357.375968)
			(xy 328.911204 -357.375968) (xy 328.938475 -357.376395) (xy 328.992463 -357.384158) (xy 329.044796 -357.399524)
			(xy 329.094409 -357.422183) (xy 329.140293 -357.451671) (xy 329.181514 -357.487389) (xy 329.217231 -357.52861)
			(xy 329.246719 -357.574494) (xy 329.269377 -357.624108) (xy 329.284743 -357.676441) (xy 329.292506 -357.730429)
			(xy 329.292506 -357.784966) (xy 330.775354 -357.784966) (xy 330.775354 -357.730434) (xy 330.783114 -357.676458)
			(xy 330.798477 -357.624136) (xy 330.821128 -357.574532) (xy 330.850609 -357.528656) (xy 330.886317 -357.487443)
			(xy 330.927527 -357.45173) (xy 330.9734 -357.422246) (xy 331.023002 -357.399589) (xy 331.075323 -357.384222)
			(xy 331.129298 -357.376457) (xy 331.156564 -357.375968) (xy 332.020164 -357.375968) (xy 332.047439 -357.376369)
			(xy 332.101434 -357.384128) (xy 332.153775 -357.399492) (xy 332.203397 -357.422149) (xy 332.249288 -357.451638)
			(xy 332.290516 -357.487359) (xy 332.32624 -357.528583) (xy 332.355733 -357.574472) (xy 332.378395 -357.624091)
			(xy 332.393765 -357.676431) (xy 332.401528 -357.730425) (xy 332.401528 -357.78497) (xy 333.884231 -357.78497)
			(xy 333.884231 -357.73043) (xy 333.891994 -357.676445) (xy 333.90736 -357.624115) (xy 333.930017 -357.574504)
			(xy 333.959505 -357.528623) (xy 333.995222 -357.487405) (xy 334.036442 -357.451691) (xy 334.082325 -357.422206)
			(xy 334.131937 -357.399552) (xy 334.184269 -357.384189) (xy 334.238254 -357.37643) (xy 334.265524 -357.375968)
			(xy 335.129124 -357.375968) (xy 335.156394 -357.376396) (xy 335.21038 -357.384161) (xy 335.26271 -357.39953)
			(xy 335.312321 -357.422189) (xy 335.358203 -357.451678) (xy 335.399421 -357.487396) (xy 335.435136 -357.528616)
			(xy 335.464622 -357.5745) (xy 335.487279 -357.624112) (xy 335.502644 -357.676444) (xy 335.510406 -357.73043)
			(xy 335.510406 -357.784967) (xy 336.993254 -357.784967) (xy 336.993254 -357.730434) (xy 337.001015 -357.676456)
			(xy 337.016378 -357.624131) (xy 337.039032 -357.574526) (xy 337.068514 -357.52865) (xy 337.104224 -357.487436)
			(xy 337.145437 -357.451723) (xy 337.191312 -357.422239) (xy 337.240916 -357.399584) (xy 337.29324 -357.384218)
			(xy 337.347218 -357.376455) (xy 337.374484 -357.375968) (xy 338.238084 -357.375968) (xy 338.265358 -357.37637)
			(xy 338.319351 -357.384131) (xy 338.371689 -357.399497) (xy 338.421308 -357.422156) (xy 338.467198 -357.451645)
			(xy 338.508423 -357.487366) (xy 338.544145 -357.528589) (xy 338.573636 -357.574477) (xy 338.596297 -357.624096)
			(xy 338.611665 -357.676434) (xy 338.619428 -357.730426) (xy 338.619428 -357.784971) (xy 340.102132 -357.784971)
			(xy 340.102132 -357.730429) (xy 340.109894 -357.676443) (xy 340.125261 -357.624111) (xy 340.147921 -357.574498)
			(xy 340.17741 -357.528616) (xy 340.213129 -357.487398) (xy 340.254351 -357.451684) (xy 340.300237 -357.422199)
			(xy 340.349852 -357.399546) (xy 340.402186 -357.384185) (xy 340.456173 -357.376428) (xy 340.483444 -357.375968)
			(xy 341.347044 -357.375968) (xy 341.374313 -357.376398) (xy 341.428297 -357.384165) (xy 341.480625 -357.399535)
			(xy 341.530233 -357.422196) (xy 341.576112 -357.451685) (xy 341.617328 -357.487403) (xy 341.653041 -357.528623)
			(xy 341.682525 -357.574505) (xy 341.70518 -357.624116) (xy 341.720544 -357.676447) (xy 341.728306 -357.73043)
			(xy 341.728306 -357.784969) (xy 343.211131 -357.784969) (xy 343.211131 -357.730431) (xy 343.218893 -357.676448)
			(xy 343.234258 -357.624119) (xy 343.256914 -357.57451) (xy 343.2864 -357.528629) (xy 343.322115 -357.487412)
			(xy 343.363333 -357.451698) (xy 343.409213 -357.422212) (xy 343.458823 -357.399557) (xy 343.511152 -357.384192)
			(xy 343.565135 -357.376431) (xy 343.592404 -357.375968) (xy 344.456004 -357.375968) (xy 344.483275 -357.376395)
			(xy 344.537263 -357.384158) (xy 344.589596 -357.399524) (xy 344.639209 -357.422183) (xy 344.685093 -357.451671)
			(xy 344.726314 -357.487389) (xy 344.762031 -357.52861) (xy 344.791519 -357.574494) (xy 344.814177 -357.624108)
			(xy 344.829543 -357.676441) (xy 344.837306 -357.730429) (xy 344.837306 -357.784971) (xy 373.915632 -357.784971)
			(xy 373.915632 -357.730429) (xy 373.923394 -357.676443) (xy 373.938761 -357.624111) (xy 373.96142 -357.574499)
			(xy 373.990909 -357.528617) (xy 374.026628 -357.4874) (xy 374.06785 -357.451685) (xy 374.113735 -357.422201)
			(xy 374.163349 -357.399547) (xy 374.215682 -357.384186) (xy 374.269669 -357.376429) (xy 374.29694 -357.375968)
			(xy 375.16054 -357.375968) (xy 375.18781 -357.376397) (xy 375.241793 -357.384164) (xy 375.294122 -357.399534)
			(xy 375.343731 -357.422194) (xy 375.389611 -357.451684) (xy 375.430827 -357.487402) (xy 375.46654 -357.528622)
			(xy 375.496025 -357.574504) (xy 375.51868 -357.624116) (xy 375.534044 -357.676446) (xy 375.541806 -357.73043)
			(xy 375.541806 -357.784967) (xy 377.024654 -357.784967) (xy 377.024654 -357.730433) (xy 377.032415 -357.676453)
			(xy 377.04778 -357.624128) (xy 377.070434 -357.574522) (xy 377.099918 -357.528644) (xy 377.13563 -357.48743)
			(xy 377.176844 -357.451718) (xy 377.222722 -357.422234) (xy 377.272328 -357.39958) (xy 377.324653 -357.384215)
			(xy 377.378633 -357.376454) (xy 377.4059 -357.375968) (xy 378.2695 -357.375968) (xy 378.296772 -357.376395)
			(xy 378.350759 -357.384157) (xy 378.403093 -357.399523) (xy 378.452707 -357.422181) (xy 378.498592 -357.451669)
			(xy 378.539812 -357.487388) (xy 378.575531 -357.528608) (xy 378.605019 -357.574493) (xy 378.627677 -357.624107)
			(xy 378.643043 -357.676441) (xy 378.650805 -357.730428) (xy 378.650805 -357.784965) (xy 380.133654 -357.784965)
			(xy 380.133654 -357.730435) (xy 380.141414 -357.676459) (xy 380.156776 -357.624137) (xy 380.179428 -357.574533)
			(xy 380.208908 -357.528658) (xy 380.244616 -357.487444) (xy 380.285825 -357.451732) (xy 380.331698 -357.422247)
			(xy 380.381299 -357.39959) (xy 380.43362 -357.384223) (xy 380.487595 -357.376457) (xy 380.51486 -357.375968)
			(xy 381.37846 -357.375968) (xy 381.405735 -357.376369) (xy 381.45973 -357.384127) (xy 381.512072 -357.399491)
			(xy 381.561694 -357.422148) (xy 381.607586 -357.451637) (xy 381.648815 -357.487357) (xy 381.684539 -357.528582)
			(xy 381.714033 -357.574471) (xy 381.736695 -357.62409) (xy 381.752065 -357.67643) (xy 381.759828 -357.730425)
			(xy 381.759828 -357.78497) (xy 383.242531 -357.78497) (xy 383.242531 -357.73043) (xy 383.250294 -357.676446)
			(xy 383.26566 -357.624116) (xy 383.288317 -357.574505) (xy 383.317804 -357.528624) (xy 383.353521 -357.487407)
			(xy 383.39474 -357.451692) (xy 383.440623 -357.422207) (xy 383.490234 -357.399553) (xy 383.542565 -357.384189)
			(xy 383.59655 -357.37643) (xy 383.62382 -357.375968) (xy 384.48742 -357.375968) (xy 384.514691 -357.376396)
			(xy 384.568676 -357.38416) (xy 384.621007 -357.399529) (xy 384.670619 -357.422188) (xy 384.716501 -357.451677)
			(xy 384.75772 -357.487395) (xy 384.793435 -357.528615) (xy 384.822922 -357.574499) (xy 384.845578 -357.624111)
			(xy 384.860944 -357.676443) (xy 384.868706 -357.730429) (xy 384.868706 -357.784966) (xy 386.351554 -357.784966)
			(xy 386.351554 -357.730434) (xy 386.359315 -357.676456) (xy 386.374678 -357.624132) (xy 386.397331 -357.574527)
			(xy 386.426813 -357.528651) (xy 386.462523 -357.487437) (xy 386.503735 -357.451725) (xy 386.54961 -357.422241)
			(xy 386.599213 -357.399585) (xy 386.651537 -357.384219) (xy 386.705514 -357.376456) (xy 386.73278 -357.375968)
			(xy 387.59638 -357.375968) (xy 387.623654 -357.37637) (xy 387.677647 -357.384131) (xy 387.729987 -357.399496)
			(xy 387.779606 -357.422155) (xy 387.825496 -357.451644) (xy 387.866722 -357.487364) (xy 387.902444 -357.528588)
			(xy 387.931936 -357.574476) (xy 387.954597 -357.624095) (xy 387.969965 -357.676433) (xy 387.977728 -357.730426)
			(xy 387.977728 -357.784971) (xy 389.460432 -357.784971) (xy 389.460432 -357.730429) (xy 389.468194 -357.676443)
			(xy 389.483561 -357.624111) (xy 389.50622 -357.574499) (xy 389.535709 -357.528617) (xy 389.571428 -357.4874)
			(xy 389.61265 -357.451685) (xy 389.658535 -357.422201) (xy 389.708149 -357.399547) (xy 389.760482 -357.384186)
			(xy 389.814469 -357.376429) (xy 389.84174 -357.375968) (xy 390.70534 -357.375968) (xy 390.73261 -357.376397)
			(xy 390.786593 -357.384164) (xy 390.838922 -357.399534) (xy 390.888531 -357.422194) (xy 390.934411 -357.451684)
			(xy 390.975627 -357.487402) (xy 391.01134 -357.528622) (xy 391.040825 -357.574504) (xy 391.06348 -357.624116)
			(xy 391.078844 -357.676446) (xy 391.086606 -357.73043) (xy 391.086606 -357.784967) (xy 392.569454 -357.784967)
			(xy 392.569454 -357.730433) (xy 392.577215 -357.676453) (xy 392.59258 -357.624128) (xy 392.615234 -357.574522)
			(xy 392.644718 -357.528644) (xy 392.68043 -357.48743) (xy 392.721644 -357.451718) (xy 392.767522 -357.422234)
			(xy 392.817128 -357.39958) (xy 392.869453 -357.384215) (xy 392.923433 -357.376454) (xy 392.9507 -357.375968)
			(xy 393.8143 -357.375968) (xy 393.841572 -357.376395) (xy 393.895559 -357.384157) (xy 393.947893 -357.399523)
			(xy 393.997507 -357.422181) (xy 394.043392 -357.451669) (xy 394.084612 -357.487388) (xy 394.120331 -357.528608)
			(xy 394.149819 -357.574493) (xy 394.172477 -357.624107) (xy 394.187843 -357.676441) (xy 394.195605 -357.730428)
			(xy 394.195605 -357.784965) (xy 395.678454 -357.784965) (xy 395.678454 -357.730435) (xy 395.686214 -357.676459)
			(xy 395.701576 -357.624137) (xy 395.724228 -357.574533) (xy 395.753708 -357.528658) (xy 395.789416 -357.487444)
			(xy 395.830625 -357.451732) (xy 395.876498 -357.422247) (xy 395.926099 -357.39959) (xy 395.97842 -357.384223)
			(xy 396.032395 -357.376457) (xy 396.05966 -357.375968) (xy 396.92326 -357.375968) (xy 396.950535 -357.376369)
			(xy 397.00453 -357.384127) (xy 397.056872 -357.399491) (xy 397.106494 -357.422148) (xy 397.152386 -357.451637)
			(xy 397.193615 -357.487357) (xy 397.229339 -357.528582) (xy 397.258833 -357.574471) (xy 397.281495 -357.62409)
			(xy 397.296865 -357.67643) (xy 397.304628 -357.730425) (xy 397.304628 -357.78497) (xy 398.787331 -357.78497)
			(xy 398.787331 -357.73043) (xy 398.795094 -357.676446) (xy 398.81046 -357.624116) (xy 398.833117 -357.574505)
			(xy 398.862604 -357.528624) (xy 398.898321 -357.487407) (xy 398.93954 -357.451692) (xy 398.985423 -357.422207)
			(xy 399.035034 -357.399553) (xy 399.087365 -357.384189) (xy 399.14135 -357.37643) (xy 399.16862 -357.375968)
			(xy 400.03222 -357.375968) (xy 400.059491 -357.376396) (xy 400.113476 -357.38416) (xy 400.165807 -357.399529)
			(xy 400.215419 -357.422188) (xy 400.261301 -357.451677) (xy 400.30252 -357.487395) (xy 400.338235 -357.528615)
			(xy 400.367722 -357.574499) (xy 400.390378 -357.624111) (xy 400.405744 -357.676443) (xy 400.413506 -357.730429)
			(xy 400.413506 -357.784966) (xy 401.896354 -357.784966) (xy 401.896354 -357.730434) (xy 401.904115 -357.676456)
			(xy 401.919478 -357.624132) (xy 401.942131 -357.574527) (xy 401.971613 -357.528651) (xy 402.007323 -357.487437)
			(xy 402.048535 -357.451725) (xy 402.09441 -357.422241) (xy 402.144013 -357.399585) (xy 402.196337 -357.384219)
			(xy 402.250314 -357.376456) (xy 402.27758 -357.375968) (xy 403.14118 -357.375968) (xy 403.168454 -357.37637)
			(xy 403.222447 -357.384131) (xy 403.274787 -357.399496) (xy 403.324406 -357.422155) (xy 403.370296 -357.451644)
			(xy 403.411522 -357.487364) (xy 403.447244 -357.528588) (xy 403.476736 -357.574476) (xy 403.499397 -357.624095)
			(xy 403.514765 -357.676433) (xy 403.522528 -357.730426) (xy 403.522528 -357.784965) (xy 412.022854 -357.784965)
			(xy 412.022854 -357.730435) (xy 412.030614 -357.67646) (xy 412.045976 -357.624138) (xy 412.068627 -357.574535)
			(xy 412.098106 -357.52866) (xy 412.133813 -357.487447) (xy 412.175022 -357.451735) (xy 412.220893 -357.42225)
			(xy 412.270493 -357.399593) (xy 412.322813 -357.384224) (xy 412.376787 -357.376458) (xy 412.404052 -357.375968)
			(xy 413.267652 -357.375968) (xy 413.294927 -357.376368) (xy 413.348924 -357.384125) (xy 413.401266 -357.399489)
			(xy 413.450889 -357.422145) (xy 413.496783 -357.451634) (xy 413.538012 -357.487354) (xy 413.573737 -357.528579)
			(xy 413.603232 -357.574468) (xy 413.625894 -357.624089) (xy 413.641264 -357.676429) (xy 413.649028 -357.730425)
			(xy 413.649028 -357.784969) (xy 415.131731 -357.784969) (xy 415.131731 -357.730431) (xy 415.139493 -357.676447)
			(xy 415.154859 -357.624117) (xy 415.177516 -357.574507) (xy 415.207002 -357.528627) (xy 415.242718 -357.487409)
			(xy 415.283936 -357.451695) (xy 415.329818 -357.42221) (xy 415.379429 -357.399555) (xy 415.431759 -357.384191)
			(xy 415.485743 -357.376431) (xy 415.513012 -357.375968) (xy 416.376612 -357.375968) (xy 416.403883 -357.376395)
			(xy 416.457869 -357.384159) (xy 416.510202 -357.399527) (xy 416.559814 -357.422185) (xy 416.605697 -357.451674)
			(xy 416.646917 -357.487392) (xy 416.682633 -357.528612) (xy 416.712121 -357.574496) (xy 416.734778 -357.62411)
			(xy 416.750144 -357.676442) (xy 416.757906 -357.730429) (xy 416.757906 -357.784966) (xy 418.240754 -357.784966)
			(xy 418.240754 -357.730434) (xy 418.248515 -357.676457) (xy 418.263877 -357.624134) (xy 418.28653 -357.57453)
			(xy 418.316011 -357.528654) (xy 418.35172 -357.48744) (xy 418.392931 -357.451727) (xy 418.438805 -357.422243)
			(xy 418.488408 -357.399587) (xy 418.54073 -357.384221) (xy 418.594706 -357.376456) (xy 418.621972 -357.375968)
			(xy 419.485572 -357.375968) (xy 419.512846 -357.37637) (xy 419.566841 -357.384129) (xy 419.619181 -357.399494)
			(xy 419.668801 -357.422152) (xy 419.714692 -357.451641) (xy 419.755919 -357.487361) (xy 419.791642 -357.528585)
			(xy 419.821135 -357.574474) (xy 419.843796 -357.624093) (xy 419.859165 -357.676432) (xy 419.866928 -357.730426)
			(xy 419.866928 -357.78497) (xy 421.349632 -357.78497) (xy 421.349632 -357.73043) (xy 421.357394 -357.676444)
			(xy 421.372761 -357.624113) (xy 421.395419 -357.574502) (xy 421.424907 -357.52862) (xy 421.460625 -357.487402)
			(xy 421.501846 -357.451688) (xy 421.54773 -357.422203) (xy 421.597343 -357.399549) (xy 421.649676 -357.384187)
			(xy 421.703662 -357.376429) (xy 421.730932 -357.375968) (xy 422.594532 -357.375968) (xy 422.621802 -357.376397)
			(xy 422.675786 -357.384163) (xy 422.728116 -357.399532) (xy 422.777726 -357.422192) (xy 422.823607 -357.451681)
			(xy 422.864824 -357.487399) (xy 422.900538 -357.528619) (xy 422.930024 -357.574502) (xy 422.952679 -357.624114)
			(xy 422.968044 -357.676445) (xy 422.975806 -357.73043) (xy 422.975806 -357.784967) (xy 424.458654 -357.784967)
			(xy 424.458654 -357.730433) (xy 424.466415 -357.676454) (xy 424.481779 -357.62413) (xy 424.504433 -357.574524)
			(xy 424.533916 -357.528647) (xy 424.569627 -357.487433) (xy 424.610841 -357.45172) (xy 424.656717 -357.422237)
			(xy 424.706322 -357.399582) (xy 424.758647 -357.384217) (xy 424.812625 -357.376455) (xy 424.839892 -357.375968)
			(xy 425.703492 -357.375968) (xy 425.730766 -357.376371) (xy 425.784757 -357.384133) (xy 425.837095 -357.3995)
			(xy 425.886713 -357.422159) (xy 425.932602 -357.451648) (xy 425.973826 -357.487368) (xy 426.009547 -357.528592)
			(xy 426.039038 -357.57448) (xy 426.061698 -357.624097) (xy 426.077065 -357.676435) (xy 426.084828 -357.730426)
			(xy 426.084828 -357.784965) (xy 427.567654 -357.784965) (xy 427.567654 -357.730435) (xy 427.575414 -357.67646)
			(xy 427.590776 -357.624138) (xy 427.613427 -357.574535) (xy 427.642906 -357.52866) (xy 427.678613 -357.487447)
			(xy 427.719822 -357.451735) (xy 427.765693 -357.42225) (xy 427.815293 -357.399593) (xy 427.867613 -357.384224)
			(xy 427.921587 -357.376458) (xy 427.948852 -357.375968) (xy 428.812452 -357.375968) (xy 428.839727 -357.376368)
			(xy 428.893724 -357.384125) (xy 428.946066 -357.399489) (xy 428.995689 -357.422145) (xy 429.041583 -357.451634)
			(xy 429.082812 -357.487354) (xy 429.118537 -357.528579) (xy 429.148032 -357.574468) (xy 429.170694 -357.624089)
			(xy 429.186064 -357.676429) (xy 429.193828 -357.730425) (xy 429.193828 -357.784969) (xy 430.676531 -357.784969)
			(xy 430.676531 -357.730431) (xy 430.684293 -357.676447) (xy 430.699659 -357.624117) (xy 430.722316 -357.574507)
			(xy 430.751802 -357.528627) (xy 430.787518 -357.487409) (xy 430.828736 -357.451695) (xy 430.874618 -357.42221)
			(xy 430.924229 -357.399555) (xy 430.976559 -357.384191) (xy 431.030543 -357.376431) (xy 431.057812 -357.375968)
			(xy 431.921412 -357.375968) (xy 431.948683 -357.376395) (xy 432.002669 -357.384159) (xy 432.055002 -357.399527)
			(xy 432.104614 -357.422185) (xy 432.150497 -357.451674) (xy 432.191717 -357.487392) (xy 432.227433 -357.528612)
			(xy 432.256921 -357.574496) (xy 432.279578 -357.62411) (xy 432.294944 -357.676442) (xy 432.302706 -357.730429)
			(xy 432.302706 -357.784966) (xy 433.785554 -357.784966) (xy 433.785554 -357.730434) (xy 433.793315 -357.676457)
			(xy 433.808677 -357.624134) (xy 433.83133 -357.57453) (xy 433.860811 -357.528654) (xy 433.89652 -357.48744)
			(xy 433.937731 -357.451727) (xy 433.983605 -357.422243) (xy 434.033208 -357.399587) (xy 434.08553 -357.384221)
			(xy 434.139506 -357.376456) (xy 434.166772 -357.375968) (xy 435.030372 -357.375968) (xy 435.057646 -357.37637)
			(xy 435.111641 -357.384129) (xy 435.163981 -357.399494) (xy 435.213601 -357.422152) (xy 435.259492 -357.451641)
			(xy 435.300719 -357.487361) (xy 435.336442 -357.528585) (xy 435.365935 -357.574474) (xy 435.388596 -357.624093)
			(xy 435.403965 -357.676432) (xy 435.411728 -357.730426) (xy 435.411728 -357.78497) (xy 436.894432 -357.78497)
			(xy 436.894432 -357.73043) (xy 436.902194 -357.676444) (xy 436.917561 -357.624113) (xy 436.940219 -357.574502)
			(xy 436.969707 -357.52862) (xy 437.005425 -357.487402) (xy 437.046646 -357.451688) (xy 437.09253 -357.422203)
			(xy 437.142143 -357.399549) (xy 437.194476 -357.384187) (xy 437.248462 -357.376429) (xy 437.275732 -357.375968)
			(xy 438.139332 -357.375968) (xy 438.166602 -357.376397) (xy 438.220586 -357.384163) (xy 438.272916 -357.399532)
			(xy 438.322526 -357.422192) (xy 438.368407 -357.451681) (xy 438.409624 -357.487399) (xy 438.445338 -357.528619)
			(xy 438.474824 -357.574502) (xy 438.497479 -357.624114) (xy 438.512844 -357.676445) (xy 438.520606 -357.73043)
			(xy 438.520606 -357.784967) (xy 440.003454 -357.784967) (xy 440.003454 -357.730433) (xy 440.011215 -357.676454)
			(xy 440.026579 -357.62413) (xy 440.049233 -357.574524) (xy 440.078716 -357.528647) (xy 440.114427 -357.487433)
			(xy 440.155641 -357.45172) (xy 440.201517 -357.422237) (xy 440.251122 -357.399582) (xy 440.303447 -357.384217)
			(xy 440.357425 -357.376455) (xy 440.384692 -357.375968) (xy 441.248292 -357.375968) (xy 441.275566 -357.376371)
			(xy 441.329557 -357.384133) (xy 441.381895 -357.3995) (xy 441.431513 -357.422159) (xy 441.477402 -357.451648)
			(xy 441.518626 -357.487368) (xy 441.554347 -357.528592) (xy 441.583838 -357.57448) (xy 441.606498 -357.624097)
			(xy 441.621865 -357.676435) (xy 441.629628 -357.730426) (xy 441.629628 -357.784974) (xy 441.621865 -357.838965)
			(xy 441.606498 -357.891303) (xy 441.583838 -357.94092) (xy 441.554347 -357.986808) (xy 441.518626 -358.028032)
			(xy 441.477402 -358.063752) (xy 441.431513 -358.093241) (xy 441.381895 -358.1159) (xy 441.329557 -358.131267)
			(xy 441.275566 -358.139029) (xy 441.248292 -358.139492) (xy 440.384692 -358.139492) (xy 440.357425 -358.138945)
			(xy 440.303447 -358.131183) (xy 440.251122 -358.115818) (xy 440.201517 -358.093163) (xy 440.155641 -358.06368)
			(xy 440.114427 -358.027967) (xy 440.078716 -357.986753) (xy 440.049233 -357.940876) (xy 440.026579 -357.89127)
			(xy 440.011215 -357.838946) (xy 440.003454 -357.784967) (xy 438.520606 -357.784967) (xy 438.520606 -357.78497)
			(xy 438.512844 -357.838955) (xy 438.497479 -357.891286) (xy 438.474824 -357.940898) (xy 438.445338 -357.986781)
			(xy 438.409624 -358.028001) (xy 438.368407 -358.063719) (xy 438.322526 -358.093208) (xy 438.272916 -358.115868)
			(xy 438.220586 -358.131237) (xy 438.166602 -358.139003) (xy 438.139332 -358.139492) (xy 437.275732 -358.139492)
			(xy 437.248462 -358.138971) (xy 437.194476 -358.131213) (xy 437.142143 -358.115851) (xy 437.09253 -358.093197)
			(xy 437.046646 -358.063712) (xy 437.005425 -358.027998) (xy 436.969707 -357.98678) (xy 436.940219 -357.940898)
			(xy 436.917561 -357.891287) (xy 436.902194 -357.838956) (xy 436.894432 -357.78497) (xy 435.411728 -357.78497)
			(xy 435.411728 -357.784974) (xy 435.403965 -357.838968) (xy 435.388596 -357.891307) (xy 435.365935 -357.940926)
			(xy 435.336442 -357.986815) (xy 435.300719 -358.028039) (xy 435.259492 -358.063759) (xy 435.213601 -358.093248)
			(xy 435.163981 -358.115906) (xy 435.111641 -358.131271) (xy 435.057646 -358.13903) (xy 435.030372 -358.139492)
			(xy 434.166772 -358.139492) (xy 434.139506 -358.138944) (xy 434.08553 -358.131179) (xy 434.033208 -358.115813)
			(xy 433.983605 -358.093157) (xy 433.937731 -358.063673) (xy 433.89652 -358.02796) (xy 433.860811 -357.986746)
			(xy 433.83133 -357.94087) (xy 433.808677 -357.891266) (xy 433.793315 -357.838943) (xy 433.785554 -357.784966)
			(xy 432.302706 -357.784966) (xy 432.302706 -357.784971) (xy 432.294944 -357.838958) (xy 432.279578 -357.89129)
			(xy 432.256921 -357.940904) (xy 432.227433 -357.986788) (xy 432.191717 -358.028008) (xy 432.150497 -358.063726)
			(xy 432.104614 -358.093215) (xy 432.055002 -358.115873) (xy 432.002669 -358.131241) (xy 431.948683 -358.139005)
			(xy 431.921412 -358.139492) (xy 431.057812 -358.139492) (xy 431.030543 -358.138969) (xy 430.976559 -358.131209)
			(xy 430.924229 -358.115845) (xy 430.874618 -358.09319) (xy 430.828736 -358.063705) (xy 430.787518 -358.027991)
			(xy 430.751802 -357.986773) (xy 430.722316 -357.940893) (xy 430.699659 -357.891283) (xy 430.684293 -357.838953)
			(xy 430.676531 -357.784969) (xy 429.193828 -357.784969) (xy 429.193828 -357.784975) (xy 429.186064 -357.838971)
			(xy 429.170694 -357.891311) (xy 429.148032 -357.940932) (xy 429.118537 -357.986821) (xy 429.082812 -358.028046)
			(xy 429.041583 -358.063766) (xy 428.995689 -358.093255) (xy 428.946066 -358.115911) (xy 428.893724 -358.131275)
			(xy 428.839727 -358.139032) (xy 428.812452 -358.139492) (xy 427.948852 -358.139492) (xy 427.921587 -358.138942)
			(xy 427.867613 -358.131176) (xy 427.815293 -358.115807) (xy 427.765693 -358.09315) (xy 427.719822 -358.063665)
			(xy 427.678613 -358.027953) (xy 427.642906 -357.98674) (xy 427.613427 -357.940865) (xy 427.590776 -357.891262)
			(xy 427.575414 -357.83894) (xy 427.567654 -357.784965) (xy 426.084828 -357.784965) (xy 426.084828 -357.784974)
			(xy 426.077065 -357.838965) (xy 426.061698 -357.891303) (xy 426.039038 -357.94092) (xy 426.009547 -357.986808)
			(xy 425.973826 -358.028032) (xy 425.932602 -358.063752) (xy 425.886713 -358.093241) (xy 425.837095 -358.1159)
			(xy 425.784757 -358.131267) (xy 425.730766 -358.139029) (xy 425.703492 -358.139492) (xy 424.839892 -358.139492)
			(xy 424.812625 -358.138945) (xy 424.758647 -358.131183) (xy 424.706322 -358.115818) (xy 424.656717 -358.093163)
			(xy 424.610841 -358.06368) (xy 424.569627 -358.027967) (xy 424.533916 -357.986753) (xy 424.504433 -357.940876)
			(xy 424.481779 -357.89127) (xy 424.466415 -357.838946) (xy 424.458654 -357.784967) (xy 422.975806 -357.784967)
			(xy 422.975806 -357.78497) (xy 422.968044 -357.838955) (xy 422.952679 -357.891286) (xy 422.930024 -357.940898)
			(xy 422.900538 -357.986781) (xy 422.864824 -358.028001) (xy 422.823607 -358.063719) (xy 422.777726 -358.093208)
			(xy 422.728116 -358.115868) (xy 422.675786 -358.131237) (xy 422.621802 -358.139003) (xy 422.594532 -358.139492)
			(xy 421.730932 -358.139492) (xy 421.703662 -358.138971) (xy 421.649676 -358.131213) (xy 421.597343 -358.115851)
			(xy 421.54773 -358.093197) (xy 421.501846 -358.063712) (xy 421.460625 -358.027998) (xy 421.424907 -357.98678)
			(xy 421.395419 -357.940898) (xy 421.372761 -357.891287) (xy 421.357394 -357.838956) (xy 421.349632 -357.78497)
			(xy 419.866928 -357.78497) (xy 419.866928 -357.784974) (xy 419.859165 -357.838968) (xy 419.843796 -357.891307)
			(xy 419.821135 -357.940926) (xy 419.791642 -357.986815) (xy 419.755919 -358.028039) (xy 419.714692 -358.063759)
			(xy 419.668801 -358.093248) (xy 419.619181 -358.115906) (xy 419.566841 -358.131271) (xy 419.512846 -358.13903)
			(xy 419.485572 -358.139492) (xy 418.621972 -358.139492) (xy 418.594706 -358.138944) (xy 418.54073 -358.131179)
			(xy 418.488408 -358.115813) (xy 418.438805 -358.093157) (xy 418.392931 -358.063673) (xy 418.35172 -358.02796)
			(xy 418.316011 -357.986746) (xy 418.28653 -357.94087) (xy 418.263877 -357.891266) (xy 418.248515 -357.838943)
			(xy 418.240754 -357.784966) (xy 416.757906 -357.784966) (xy 416.757906 -357.784971) (xy 416.750144 -357.838958)
			(xy 416.734778 -357.89129) (xy 416.712121 -357.940904) (xy 416.682633 -357.986788) (xy 416.646917 -358.028008)
			(xy 416.605697 -358.063726) (xy 416.559814 -358.093215) (xy 416.510202 -358.115873) (xy 416.457869 -358.131241)
			(xy 416.403883 -358.139005) (xy 416.376612 -358.139492) (xy 415.513012 -358.139492) (xy 415.485743 -358.138969)
			(xy 415.431759 -358.131209) (xy 415.379429 -358.115845) (xy 415.329818 -358.09319) (xy 415.283936 -358.063705)
			(xy 415.242718 -358.027991) (xy 415.207002 -357.986773) (xy 415.177516 -357.940893) (xy 415.154859 -357.891283)
			(xy 415.139493 -357.838953) (xy 415.131731 -357.784969) (xy 413.649028 -357.784969) (xy 413.649028 -357.784975)
			(xy 413.641264 -357.838971) (xy 413.625894 -357.891311) (xy 413.603232 -357.940932) (xy 413.573737 -357.986821)
			(xy 413.538012 -358.028046) (xy 413.496783 -358.063766) (xy 413.450889 -358.093255) (xy 413.401266 -358.115911)
			(xy 413.348924 -358.131275) (xy 413.294927 -358.139032) (xy 413.267652 -358.139492) (xy 412.404052 -358.139492)
			(xy 412.376787 -358.138942) (xy 412.322813 -358.131176) (xy 412.270493 -358.115807) (xy 412.220893 -358.09315)
			(xy 412.175022 -358.063665) (xy 412.133813 -358.027953) (xy 412.098106 -357.98674) (xy 412.068627 -357.940865)
			(xy 412.045976 -357.891262) (xy 412.030614 -357.83894) (xy 412.022854 -357.784965) (xy 403.522528 -357.784965)
			(xy 403.522528 -357.784974) (xy 403.514765 -357.838967) (xy 403.499397 -357.891305) (xy 403.476736 -357.940924)
			(xy 403.447244 -357.986812) (xy 403.411522 -358.028036) (xy 403.370296 -358.063756) (xy 403.324406 -358.093245)
			(xy 403.274787 -358.115904) (xy 403.222447 -358.131269) (xy 403.168454 -358.13903) (xy 403.14118 -358.139492)
			(xy 402.27758 -358.139492) (xy 402.250314 -358.138944) (xy 402.196337 -358.131181) (xy 402.144013 -358.115815)
			(xy 402.09441 -358.093159) (xy 402.048535 -358.063675) (xy 402.007323 -358.027963) (xy 401.971613 -357.986749)
			(xy 401.942131 -357.940873) (xy 401.919478 -357.891268) (xy 401.904115 -357.838944) (xy 401.896354 -357.784966)
			(xy 400.413506 -357.784966) (xy 400.413506 -357.784971) (xy 400.405744 -357.838957) (xy 400.390378 -357.891289)
			(xy 400.367722 -357.940901) (xy 400.338235 -357.986785) (xy 400.30252 -358.028005) (xy 400.261301 -358.063723)
			(xy 400.215419 -358.093212) (xy 400.165807 -358.115871) (xy 400.113476 -358.13124) (xy 400.059491 -358.139004)
			(xy 400.03222 -358.139492) (xy 399.16862 -358.139492) (xy 399.14135 -358.13897) (xy 399.087365 -358.131211)
			(xy 399.035034 -358.115847) (xy 398.985423 -358.093193) (xy 398.93954 -358.063708) (xy 398.898321 -358.027993)
			(xy 398.862604 -357.986776) (xy 398.833117 -357.940895) (xy 398.81046 -357.891284) (xy 398.795094 -357.838954)
			(xy 398.787331 -357.78497) (xy 397.304628 -357.78497) (xy 397.304628 -357.784975) (xy 397.296865 -357.83897)
			(xy 397.281495 -357.89131) (xy 397.258833 -357.940929) (xy 397.229339 -357.986818) (xy 397.193615 -358.028043)
			(xy 397.152386 -358.063763) (xy 397.106494 -358.093252) (xy 397.056872 -358.115909) (xy 397.00453 -358.131273)
			(xy 396.950535 -358.139031) (xy 396.92326 -358.139492) (xy 396.05966 -358.139492) (xy 396.032395 -358.138943)
			(xy 395.97842 -358.131177) (xy 395.926099 -358.11581) (xy 395.876498 -358.093153) (xy 395.830625 -358.063668)
			(xy 395.789416 -358.027956) (xy 395.753708 -357.986742) (xy 395.724228 -357.940867) (xy 395.701576 -357.891263)
			(xy 395.686214 -357.838941) (xy 395.678454 -357.784965) (xy 394.195605 -357.784965) (xy 394.195605 -357.784972)
			(xy 394.187843 -357.838959) (xy 394.172477 -357.891293) (xy 394.149819 -357.940907) (xy 394.120331 -357.986792)
			(xy 394.084612 -358.028012) (xy 394.043392 -358.063731) (xy 393.997507 -358.093219) (xy 393.947893 -358.115877)
			(xy 393.895559 -358.131243) (xy 393.841572 -358.139005) (xy 393.8143 -358.139492) (xy 392.9507 -358.139492)
			(xy 392.923433 -358.138946) (xy 392.869453 -358.131185) (xy 392.817128 -358.11582) (xy 392.767522 -358.093166)
			(xy 392.721644 -358.063682) (xy 392.68043 -358.02797) (xy 392.644718 -357.986756) (xy 392.615234 -357.940878)
			(xy 392.59258 -357.891272) (xy 392.577215 -357.838947) (xy 392.569454 -357.784967) (xy 391.086606 -357.784967)
			(xy 391.086606 -357.78497) (xy 391.078844 -357.838954) (xy 391.06348 -357.891284) (xy 391.040825 -357.940896)
			(xy 391.01134 -357.986778) (xy 390.975627 -358.027998) (xy 390.934411 -358.063716) (xy 390.888531 -358.093206)
			(xy 390.838922 -358.115866) (xy 390.786593 -358.131236) (xy 390.73261 -358.139003) (xy 390.70534 -358.139492)
			(xy 389.84174 -358.139492) (xy 389.814469 -358.138971) (xy 389.760482 -358.131214) (xy 389.708149 -358.115853)
			(xy 389.658535 -358.093199) (xy 389.61265 -358.063715) (xy 389.571428 -358.028) (xy 389.535709 -357.986783)
			(xy 389.50622 -357.940901) (xy 389.483561 -357.891289) (xy 389.468194 -357.838957) (xy 389.460432 -357.784971)
			(xy 387.977728 -357.784971) (xy 387.977728 -357.784974) (xy 387.969965 -357.838967) (xy 387.954597 -357.891305)
			(xy 387.931936 -357.940924) (xy 387.902444 -357.986812) (xy 387.866722 -358.028036) (xy 387.825496 -358.063756)
			(xy 387.779606 -358.093245) (xy 387.729987 -358.115904) (xy 387.677647 -358.131269) (xy 387.623654 -358.13903)
			(xy 387.59638 -358.139492) (xy 386.73278 -358.139492) (xy 386.705514 -358.138944) (xy 386.651537 -358.131181)
			(xy 386.599213 -358.115815) (xy 386.54961 -358.093159) (xy 386.503735 -358.063675) (xy 386.462523 -358.027963)
			(xy 386.426813 -357.986749) (xy 386.397331 -357.940873) (xy 386.374678 -357.891268) (xy 386.359315 -357.838944)
			(xy 386.351554 -357.784966) (xy 384.868706 -357.784966) (xy 384.868706 -357.784971) (xy 384.860944 -357.838957)
			(xy 384.845578 -357.891289) (xy 384.822922 -357.940901) (xy 384.793435 -357.986785) (xy 384.75772 -358.028005)
			(xy 384.716501 -358.063723) (xy 384.670619 -358.093212) (xy 384.621007 -358.115871) (xy 384.568676 -358.13124)
			(xy 384.514691 -358.139004) (xy 384.48742 -358.139492) (xy 383.62382 -358.139492) (xy 383.59655 -358.13897)
			(xy 383.542565 -358.131211) (xy 383.490234 -358.115847) (xy 383.440623 -358.093193) (xy 383.39474 -358.063708)
			(xy 383.353521 -358.027993) (xy 383.317804 -357.986776) (xy 383.288317 -357.940895) (xy 383.26566 -357.891284)
			(xy 383.250294 -357.838954) (xy 383.242531 -357.78497) (xy 381.759828 -357.78497) (xy 381.759828 -357.784975)
			(xy 381.752065 -357.83897) (xy 381.736695 -357.89131) (xy 381.714033 -357.940929) (xy 381.684539 -357.986818)
			(xy 381.648815 -358.028043) (xy 381.607586 -358.063763) (xy 381.561694 -358.093252) (xy 381.512072 -358.115909)
			(xy 381.45973 -358.131273) (xy 381.405735 -358.139031) (xy 381.37846 -358.139492) (xy 380.51486 -358.139492)
			(xy 380.487595 -358.138943) (xy 380.43362 -358.131177) (xy 380.381299 -358.11581) (xy 380.331698 -358.093153)
			(xy 380.285825 -358.063668) (xy 380.244616 -358.027956) (xy 380.208908 -357.986742) (xy 380.179428 -357.940867)
			(xy 380.156776 -357.891263) (xy 380.141414 -357.838941) (xy 380.133654 -357.784965) (xy 378.650805 -357.784965)
			(xy 378.650805 -357.784972) (xy 378.643043 -357.838959) (xy 378.627677 -357.891293) (xy 378.605019 -357.940907)
			(xy 378.575531 -357.986792) (xy 378.539812 -358.028012) (xy 378.498592 -358.063731) (xy 378.452707 -358.093219)
			(xy 378.403093 -358.115877) (xy 378.350759 -358.131243) (xy 378.296772 -358.139005) (xy 378.2695 -358.139492)
			(xy 377.4059 -358.139492) (xy 377.378633 -358.138946) (xy 377.324653 -358.131185) (xy 377.272328 -358.11582)
			(xy 377.222722 -358.093166) (xy 377.176844 -358.063682) (xy 377.13563 -358.02797) (xy 377.099918 -357.986756)
			(xy 377.070434 -357.940878) (xy 377.04778 -357.891272) (xy 377.032415 -357.838947) (xy 377.024654 -357.784967)
			(xy 375.541806 -357.784967) (xy 375.541806 -357.78497) (xy 375.534044 -357.838954) (xy 375.51868 -357.891284)
			(xy 375.496025 -357.940896) (xy 375.46654 -357.986778) (xy 375.430827 -358.027998) (xy 375.389611 -358.063716)
			(xy 375.343731 -358.093206) (xy 375.294122 -358.115866) (xy 375.241793 -358.131236) (xy 375.18781 -358.139003)
			(xy 375.16054 -358.139492) (xy 374.29694 -358.139492) (xy 374.269669 -358.138971) (xy 374.215682 -358.131214)
			(xy 374.163349 -358.115853) (xy 374.113735 -358.093199) (xy 374.06785 -358.063715) (xy 374.026628 -358.028)
			(xy 373.990909 -357.986783) (xy 373.96142 -357.940901) (xy 373.938761 -357.891289) (xy 373.923394 -357.838957)
			(xy 373.915632 -357.784971) (xy 344.837306 -357.784971) (xy 344.829543 -357.838959) (xy 344.814177 -357.891292)
			(xy 344.791519 -357.940906) (xy 344.762031 -357.98679) (xy 344.726314 -358.028011) (xy 344.685093 -358.063729)
			(xy 344.639209 -358.093217) (xy 344.589596 -358.115876) (xy 344.537263 -358.131242) (xy 344.483275 -358.139005)
			(xy 344.456004 -358.139492) (xy 343.592404 -358.139492) (xy 343.565135 -358.138969) (xy 343.511152 -358.131208)
			(xy 343.458823 -358.115843) (xy 343.409213 -358.093188) (xy 343.363333 -358.063702) (xy 343.322115 -358.027988)
			(xy 343.2864 -357.986771) (xy 343.256914 -357.94089) (xy 343.234258 -357.891281) (xy 343.218893 -357.838952)
			(xy 343.211131 -357.784969) (xy 341.728306 -357.784969) (xy 341.728306 -357.78497) (xy 341.720544 -357.838953)
			(xy 341.70518 -357.891284) (xy 341.682525 -357.940895) (xy 341.653041 -357.986777) (xy 341.617328 -358.027997)
			(xy 341.576112 -358.063715) (xy 341.530233 -358.093204) (xy 341.480625 -358.115865) (xy 341.428297 -358.131235)
			(xy 341.374313 -358.139002) (xy 341.347044 -358.139492) (xy 340.483444 -358.139492) (xy 340.456173 -358.138972)
			(xy 340.402186 -358.131215) (xy 340.349852 -358.115854) (xy 340.300237 -358.093201) (xy 340.254351 -358.063716)
			(xy 340.213129 -358.028002) (xy 340.17741 -357.986784) (xy 340.147921 -357.940902) (xy 340.125261 -357.891289)
			(xy 340.109894 -357.838957) (xy 340.102132 -357.784971) (xy 338.619428 -357.784971) (xy 338.619428 -357.784974)
			(xy 338.611665 -357.838966) (xy 338.596297 -357.891304) (xy 338.573636 -357.940923) (xy 338.544145 -357.986811)
			(xy 338.508423 -358.028034) (xy 338.467198 -358.063755) (xy 338.421308 -358.093244) (xy 338.371689 -358.115903)
			(xy 338.319351 -358.131269) (xy 338.265358 -358.13903) (xy 338.238084 -358.139492) (xy 337.374484 -358.139492)
			(xy 337.347218 -358.138945) (xy 337.29324 -358.131182) (xy 337.240916 -358.115816) (xy 337.191312 -358.093161)
			(xy 337.145437 -358.063677) (xy 337.104224 -358.027964) (xy 337.068514 -357.98675) (xy 337.039032 -357.940874)
			(xy 337.016378 -357.891269) (xy 337.001015 -357.838944) (xy 336.993254 -357.784967) (xy 335.510406 -357.784967)
			(xy 335.510406 -357.78497) (xy 335.502644 -357.838956) (xy 335.487279 -357.891288) (xy 335.464622 -357.9409)
			(xy 335.435136 -357.986784) (xy 335.399421 -358.028004) (xy 335.358203 -358.063722) (xy 335.312321 -358.093211)
			(xy 335.26271 -358.11587) (xy 335.21038 -358.131239) (xy 335.156394 -358.139004) (xy 335.129124 -358.139492)
			(xy 334.265524 -358.139492) (xy 334.238254 -358.13897) (xy 334.184269 -358.131211) (xy 334.131937 -358.115848)
			(xy 334.082325 -358.093194) (xy 334.036442 -358.063709) (xy 333.995222 -358.027995) (xy 333.959505 -357.986777)
			(xy 333.930017 -357.940896) (xy 333.90736 -357.891285) (xy 333.891994 -357.838955) (xy 333.884231 -357.78497)
			(xy 332.401528 -357.78497) (xy 332.401528 -357.784975) (xy 332.393765 -357.838969) (xy 332.378395 -357.891309)
			(xy 332.355733 -357.940928) (xy 332.32624 -357.986817) (xy 332.290516 -358.028041) (xy 332.249288 -358.063762)
			(xy 332.203397 -358.093251) (xy 332.153775 -358.115908) (xy 332.101434 -358.131272) (xy 332.047439 -358.139031)
			(xy 332.020164 -358.139492) (xy 331.156564 -358.139492) (xy 331.129298 -358.138943) (xy 331.075323 -358.131178)
			(xy 331.023002 -358.115811) (xy 330.9734 -358.093154) (xy 330.927527 -358.06367) (xy 330.886317 -358.027957)
			(xy 330.850609 -357.986744) (xy 330.821128 -357.940868) (xy 330.798477 -357.891264) (xy 330.783114 -357.838942)
			(xy 330.775354 -357.784966) (xy 329.292506 -357.784966) (xy 329.292506 -357.784971) (xy 329.284743 -357.838959)
			(xy 329.269377 -357.891292) (xy 329.246719 -357.940906) (xy 329.217231 -357.98679) (xy 329.181514 -358.028011)
			(xy 329.140293 -358.063729) (xy 329.094409 -358.093217) (xy 329.044796 -358.115876) (xy 328.992463 -358.131242)
			(xy 328.938475 -358.139005) (xy 328.911204 -358.139492) (xy 328.047604 -358.139492) (xy 328.020335 -358.138969)
			(xy 327.966352 -358.131208) (xy 327.914023 -358.115843) (xy 327.864413 -358.093188) (xy 327.818533 -358.063702)
			(xy 327.777315 -358.027988) (xy 327.7416 -357.986771) (xy 327.712114 -357.94089) (xy 327.689458 -357.891281)
			(xy 327.674093 -357.838952) (xy 327.666331 -357.784969) (xy 326.183506 -357.784969) (xy 326.183506 -357.78497)
			(xy 326.175744 -357.838953) (xy 326.16038 -357.891284) (xy 326.137725 -357.940895) (xy 326.108241 -357.986777)
			(xy 326.072528 -358.027997) (xy 326.031312 -358.063715) (xy 325.985433 -358.093204) (xy 325.935825 -358.115865)
			(xy 325.883497 -358.131235) (xy 325.829513 -358.139002) (xy 325.802244 -358.139492) (xy 324.938644 -358.139492)
			(xy 324.911373 -358.138972) (xy 324.857386 -358.131215) (xy 324.805052 -358.115854) (xy 324.755437 -358.093201)
			(xy 324.709551 -358.063716) (xy 324.668329 -358.028002) (xy 324.63261 -357.986784) (xy 324.603121 -357.940902)
			(xy 324.580461 -357.891289) (xy 324.565094 -357.838957) (xy 324.557332 -357.784971) (xy 323.074628 -357.784971)
			(xy 323.074628 -357.784974) (xy 323.066865 -357.838966) (xy 323.051497 -357.891304) (xy 323.028836 -357.940923)
			(xy 322.999345 -357.986811) (xy 322.963623 -358.028034) (xy 322.922398 -358.063755) (xy 322.876508 -358.093244)
			(xy 322.826889 -358.115903) (xy 322.774551 -358.131269) (xy 322.720558 -358.13903) (xy 322.693284 -358.139492)
			(xy 321.829684 -358.139492) (xy 321.802418 -358.138945) (xy 321.74844 -358.131182) (xy 321.696116 -358.115816)
			(xy 321.646512 -358.093161) (xy 321.600637 -358.063677) (xy 321.559424 -358.027964) (xy 321.523714 -357.98675)
			(xy 321.494232 -357.940874) (xy 321.471578 -357.891269) (xy 321.456215 -357.838944) (xy 321.448454 -357.784967)
			(xy 319.965606 -357.784967) (xy 319.965606 -357.78497) (xy 319.957844 -357.838956) (xy 319.942479 -357.891288)
			(xy 319.919822 -357.9409) (xy 319.890336 -357.986784) (xy 319.854621 -358.028004) (xy 319.813403 -358.063722)
			(xy 319.767521 -358.093211) (xy 319.71791 -358.11587) (xy 319.66558 -358.131239) (xy 319.611594 -358.139004)
			(xy 319.584324 -358.139492) (xy 318.720724 -358.139492) (xy 318.693454 -358.13897) (xy 318.639469 -358.131211)
			(xy 318.587137 -358.115848) (xy 318.537525 -358.093194) (xy 318.491642 -358.063709) (xy 318.450422 -358.027995)
			(xy 318.414705 -357.986777) (xy 318.385217 -357.940896) (xy 318.36256 -357.891285) (xy 318.347194 -357.838955)
			(xy 318.339431 -357.78497) (xy 316.856728 -357.78497) (xy 316.856728 -357.784975) (xy 316.848965 -357.838969)
			(xy 316.833595 -357.891309) (xy 316.810933 -357.940928) (xy 316.78144 -357.986817) (xy 316.745716 -358.028041)
			(xy 316.704488 -358.063762) (xy 316.658597 -358.093251) (xy 316.608975 -358.115908) (xy 316.556634 -358.131272)
			(xy 316.502639 -358.139031) (xy 316.475364 -358.139492) (xy 315.611764 -358.139492) (xy 315.584498 -358.138943)
			(xy 315.530523 -358.131178) (xy 315.478202 -358.115811) (xy 315.4286 -358.093154) (xy 315.382727 -358.06367)
			(xy 315.341517 -358.027957) (xy 315.305809 -357.986744) (xy 315.276328 -357.940868) (xy 315.253677 -357.891264)
			(xy 315.238314 -357.838942) (xy 315.230554 -357.784966) (xy 300.231606 -357.784966) (xy 300.231606 -357.784971)
			(xy 300.223843 -357.838959) (xy 300.208477 -357.891293) (xy 300.185819 -357.940907) (xy 300.156331 -357.986791)
			(xy 300.120613 -358.028012) (xy 300.079393 -358.06373) (xy 300.033508 -358.093218) (xy 299.983894 -358.115876)
			(xy 299.931561 -358.131243) (xy 299.877573 -358.139005) (xy 299.850302 -358.139492) (xy 298.986702 -358.139492)
			(xy 298.959433 -358.138969) (xy 298.90545 -358.131207) (xy 298.853121 -358.115843) (xy 298.803512 -358.093187)
			(xy 298.757632 -358.063702) (xy 298.716414 -358.027987) (xy 298.6807 -357.98677) (xy 298.651214 -357.94089)
			(xy 298.628558 -357.89128) (xy 298.613193 -357.838952) (xy 298.605431 -357.784969) (xy 297.122606 -357.784969)
			(xy 297.122606 -357.78497) (xy 297.114844 -357.838954) (xy 297.09948 -357.891284) (xy 297.076825 -357.940895)
			(xy 297.047341 -357.986778) (xy 297.011627 -358.027998) (xy 296.970411 -358.063716) (xy 296.924532 -358.093205)
			(xy 296.874923 -358.115865) (xy 296.822595 -358.131235) (xy 296.768612 -358.139003) (xy 296.741342 -358.139492)
			(xy 295.877742 -358.139492) (xy 295.850471 -358.138971) (xy 295.796484 -358.131215) (xy 295.74415 -358.115853)
			(xy 295.694536 -358.0932) (xy 295.64865 -358.063716) (xy 295.607429 -358.028001) (xy 295.571709 -357.986783)
			(xy 295.54222 -357.940901) (xy 295.519561 -357.891289) (xy 295.504194 -357.838957) (xy 295.496432 -357.784971)
			(xy 294.013728 -357.784971) (xy 294.013728 -357.784974) (xy 294.005965 -357.838967) (xy 293.990597 -357.891305)
			(xy 293.967936 -357.940923) (xy 293.938444 -357.986811) (xy 293.902722 -358.028035) (xy 293.861497 -358.063755)
			(xy 293.815607 -358.093245) (xy 293.765988 -358.115903) (xy 293.713649 -358.131269) (xy 293.659656 -358.13903)
			(xy 293.632382 -358.139492) (xy 292.768782 -358.139492) (xy 292.741516 -358.138944) (xy 292.687538 -358.131181)
			(xy 292.635215 -358.115816) (xy 292.585611 -358.09316) (xy 292.539736 -358.063676) (xy 292.498524 -358.027964)
			(xy 292.462813 -357.98675) (xy 292.433331 -357.940873) (xy 292.410678 -357.891268) (xy 292.395315 -357.838944)
			(xy 292.387554 -357.784966) (xy 290.904706 -357.784966) (xy 290.904706 -357.784971) (xy 290.896944 -357.838956)
			(xy 290.881578 -357.891288) (xy 290.858922 -357.940901) (xy 290.829436 -357.986784) (xy 290.79372 -358.028005)
			(xy 290.752502 -358.063723) (xy 290.70662 -358.093211) (xy 290.657009 -358.115871) (xy 290.604678 -358.131239)
			(xy 290.550692 -358.139004) (xy 290.523422 -358.139492) (xy 289.659822 -358.139492) (xy 289.632552 -358.13897)
			(xy 289.578567 -358.131211) (xy 289.526236 -358.115848) (xy 289.476624 -358.093193) (xy 289.430741 -358.063709)
			(xy 289.389522 -358.027994) (xy 289.353805 -357.986777) (xy 289.324317 -357.940895) (xy 289.30166 -357.891285)
			(xy 289.286294 -357.838954) (xy 289.278531 -357.78497) (xy 287.795828 -357.78497) (xy 287.795828 -357.784975)
			(xy 287.788065 -357.838969) (xy 287.772695 -357.891309) (xy 287.750033 -357.940929) (xy 287.72054 -357.986818)
			(xy 287.684815 -358.028042) (xy 287.643587 -358.063762) (xy 287.597695 -358.093251) (xy 287.548073 -358.115908)
			(xy 287.495732 -358.131273) (xy 287.441737 -358.139031) (xy 287.414462 -358.139492) (xy 286.550862 -358.139492)
			(xy 286.523597 -358.138943) (xy 286.469621 -358.131178) (xy 286.4173 -358.11581) (xy 286.367699 -358.093154)
			(xy 286.321826 -358.063669) (xy 286.280617 -358.027957) (xy 286.244908 -357.986743) (xy 286.215428 -357.940868)
			(xy 286.192777 -357.891264) (xy 286.177414 -357.838942) (xy 286.169654 -357.784966) (xy 284.686806 -357.784966)
			(xy 284.686806 -357.784971) (xy 284.679043 -357.838959) (xy 284.663677 -357.891293) (xy 284.641019 -357.940907)
			(xy 284.611531 -357.986791) (xy 284.575813 -358.028012) (xy 284.534593 -358.06373) (xy 284.488708 -358.093218)
			(xy 284.439094 -358.115876) (xy 284.386761 -358.131243) (xy 284.332773 -358.139005) (xy 284.305502 -358.139492)
			(xy 283.441902 -358.139492) (xy 283.414633 -358.138969) (xy 283.36065 -358.131207) (xy 283.308321 -358.115843)
			(xy 283.258712 -358.093187) (xy 283.212832 -358.063702) (xy 283.171614 -358.027987) (xy 283.1359 -357.98677)
			(xy 283.106414 -357.94089) (xy 283.083758 -357.89128) (xy 283.068393 -357.838952) (xy 283.060631 -357.784969)
			(xy 281.577806 -357.784969) (xy 281.577806 -357.78497) (xy 281.570044 -357.838954) (xy 281.55468 -357.891284)
			(xy 281.532025 -357.940895) (xy 281.502541 -357.986778) (xy 281.466827 -358.027998) (xy 281.425611 -358.063716)
			(xy 281.379732 -358.093205) (xy 281.330123 -358.115865) (xy 281.277795 -358.131235) (xy 281.223812 -358.139003)
			(xy 281.196542 -358.139492) (xy 280.332942 -358.139492) (xy 280.305671 -358.138971) (xy 280.251684 -358.131215)
			(xy 280.19935 -358.115853) (xy 280.149736 -358.0932) (xy 280.10385 -358.063716) (xy 280.062629 -358.028001)
			(xy 280.026909 -357.986783) (xy 279.99742 -357.940901) (xy 279.974761 -357.891289) (xy 279.959394 -357.838957)
			(xy 279.951632 -357.784971) (xy 278.468928 -357.784971) (xy 278.468928 -357.784974) (xy 278.461165 -357.838967)
			(xy 278.445797 -357.891305) (xy 278.423136 -357.940923) (xy 278.393644 -357.986811) (xy 278.357922 -358.028035)
			(xy 278.316697 -358.063755) (xy 278.270807 -358.093245) (xy 278.221188 -358.115903) (xy 278.168849 -358.131269)
			(xy 278.114856 -358.13903) (xy 278.087582 -358.139492) (xy 277.223982 -358.139492) (xy 277.196716 -358.138944)
			(xy 277.142738 -358.131181) (xy 277.090415 -358.115816) (xy 277.040811 -358.09316) (xy 276.994936 -358.063676)
			(xy 276.953724 -358.027964) (xy 276.918013 -357.98675) (xy 276.888531 -357.940873) (xy 276.865878 -357.891268)
			(xy 276.850515 -357.838944) (xy 276.842754 -357.784966) (xy 275.359906 -357.784966) (xy 275.359906 -357.784971)
			(xy 275.352144 -357.838956) (xy 275.336778 -357.891288) (xy 275.314122 -357.940901) (xy 275.284636 -357.986784)
			(xy 275.24892 -358.028005) (xy 275.207702 -358.063723) (xy 275.16182 -358.093211) (xy 275.112209 -358.115871)
			(xy 275.059878 -358.131239) (xy 275.005892 -358.139004) (xy 274.978622 -358.139492) (xy 274.115022 -358.139492)
			(xy 274.087752 -358.13897) (xy 274.033767 -358.131211) (xy 273.981436 -358.115848) (xy 273.931824 -358.093193)
			(xy 273.885941 -358.063709) (xy 273.844722 -358.027994) (xy 273.809005 -357.986777) (xy 273.779517 -357.940895)
			(xy 273.75686 -357.891285) (xy 273.741494 -357.838954) (xy 273.733731 -357.78497) (xy 272.251028 -357.78497)
			(xy 272.251028 -357.784975) (xy 272.243265 -357.838969) (xy 272.227895 -357.891309) (xy 272.205233 -357.940929)
			(xy 272.17574 -357.986818) (xy 272.140015 -358.028042) (xy 272.098787 -358.063762) (xy 272.052895 -358.093251)
			(xy 272.003273 -358.115908) (xy 271.950932 -358.131273) (xy 271.896937 -358.139031) (xy 271.869662 -358.139492)
			(xy 271.006062 -358.139492) (xy 270.978797 -358.138943) (xy 270.924821 -358.131178) (xy 270.8725 -358.11581)
			(xy 270.822899 -358.093154) (xy 270.777026 -358.063669) (xy 270.735817 -358.027957) (xy 270.700108 -357.986743)
			(xy 270.670628 -357.940868) (xy 270.647977 -357.891264) (xy 270.632614 -357.838942) (xy 270.624854 -357.784966)
			(xy 247.276485 -357.784966) (xy 247.278987 -357.797946) (xy 247.287038 -357.88226) (xy 247.287542 -357.924608)
			(xy 247.287038 -357.966956) (xy 247.278987 -358.05127) (xy 247.262958 -358.134436) (xy 247.239097 -358.215703)
			(xy 247.207618 -358.294333) (xy 247.168807 -358.369614) (xy 247.123017 -358.440866) (xy 247.070661 -358.507442)
			(xy 247.012213 -358.56874) (xy 246.948203 -358.624205) (xy 246.879211 -358.673334) (xy 246.805861 -358.715683)
			(xy 246.728818 -358.750867) (xy 246.648779 -358.778569) (xy 246.56647 -358.798537) (xy 246.482635 -358.81059)
			(xy 246.398034 -358.814621) (xy 246.313433 -358.81059) (xy 246.229598 -358.798537) (xy 246.147289 -358.778569)
			(xy 246.06725 -358.750867) (xy 245.990207 -358.715683) (xy 245.916857 -358.673334) (xy 245.847865 -358.624205)
			(xy 245.783855 -358.56874) (xy 245.725407 -358.507442) (xy 245.673051 -358.440866) (xy 245.627261 -358.369614)
			(xy 245.58845 -358.294333) (xy 245.556971 -358.215703) (xy 245.53311 -358.134436) (xy 245.517081 -358.05127)
			(xy 245.50903 -357.966956) (xy 188.223925 -357.966956) (xy 188.191672 -358.004178) (xy 188.150456 -358.039891)
			(xy 188.104577 -358.069375) (xy 188.054969 -358.092029) (xy 188.002641 -358.107393) (xy 187.94866 -358.115153)
			(xy 187.921392 -358.115616) (xy 187.057792 -358.115616) (xy 187.03052 -358.115221) (xy 186.97653 -358.107457)
			(xy 186.924196 -358.092089) (xy 186.87458 -358.06943) (xy 186.828695 -358.03994) (xy 186.787473 -358.004221)
			(xy 186.751755 -357.962999) (xy 186.722266 -357.917112) (xy 186.699608 -357.867497) (xy 186.684241 -357.815162)
			(xy 186.676479 -357.761172) (xy 185.193629 -357.761172) (xy 185.18587 -357.815139) (xy 185.170508 -357.86746)
			(xy 185.147857 -357.917062) (xy 185.118378 -357.962936) (xy 185.08267 -358.004147) (xy 185.041461 -358.039858)
			(xy 184.99559 -358.069342) (xy 184.94599 -358.091997) (xy 184.89367 -358.107363) (xy 184.839697 -358.115128)
			(xy 184.812432 -358.115616) (xy 183.948832 -358.115616) (xy 183.921556 -358.115247) (xy 183.867559 -358.107487)
			(xy 183.815217 -358.092122) (xy 183.765593 -358.069463) (xy 183.7197 -358.039973) (xy 183.678471 -358.004251)
			(xy 183.642746 -357.963025) (xy 183.613252 -357.917135) (xy 183.590589 -357.867513) (xy 183.57522 -357.815172)
			(xy 183.567456 -357.761176) (xy 182.084828 -357.761176) (xy 182.084828 -357.784974) (xy 182.077065 -357.838968)
			(xy 182.061696 -357.891307) (xy 182.039035 -357.940926) (xy 182.009542 -357.986815) (xy 181.973819 -358.028039)
			(xy 181.932592 -358.063759) (xy 181.886701 -358.093248) (xy 181.837081 -358.115906) (xy 181.784741 -358.131271)
			(xy 181.730746 -358.13903) (xy 181.703472 -358.139492) (xy 180.839872 -358.139492) (xy 180.812606 -358.138944)
			(xy 180.75863 -358.131179) (xy 180.706308 -358.115813) (xy 180.656705 -358.093157) (xy 180.610831 -358.063673)
			(xy 180.56962 -358.02796) (xy 180.533911 -357.986746) (xy 180.50443 -357.94087) (xy 180.481777 -357.891266)
			(xy 180.466415 -357.838943) (xy 180.458654 -357.784966) (xy 178.975806 -357.784966) (xy 178.975806 -357.784971)
			(xy 178.968044 -357.838958) (xy 178.952678 -357.89129) (xy 178.930021 -357.940904) (xy 178.900533 -357.986788)
			(xy 178.864817 -358.028008) (xy 178.823597 -358.063726) (xy 178.777714 -358.093215) (xy 178.728102 -358.115873)
			(xy 178.675769 -358.131241) (xy 178.621783 -358.139005) (xy 178.594512 -358.139492) (xy 177.730912 -358.139492)
			(xy 177.703643 -358.138969) (xy 177.649659 -358.131209) (xy 177.597329 -358.115845) (xy 177.547718 -358.09319)
			(xy 177.501836 -358.063705) (xy 177.460618 -358.027991) (xy 177.424902 -357.986773) (xy 177.395416 -357.940893)
			(xy 177.372759 -357.891283) (xy 177.357393 -357.838953) (xy 177.349631 -357.784969) (xy 175.866928 -357.784969)
			(xy 175.866928 -357.784975) (xy 175.859164 -357.838971) (xy 175.843794 -357.891311) (xy 175.821132 -357.940932)
			(xy 175.791637 -357.986821) (xy 175.755912 -358.028046) (xy 175.714683 -358.063766) (xy 175.668789 -358.093255)
			(xy 175.619166 -358.115911) (xy 175.566824 -358.131275) (xy 175.512827 -358.139032) (xy 175.485552 -358.139492)
			(xy 174.621952 -358.139492) (xy 174.594687 -358.138942) (xy 174.540713 -358.131176) (xy 174.488393 -358.115807)
			(xy 174.438793 -358.09315) (xy 174.392922 -358.063665) (xy 174.351713 -358.027953) (xy 174.316006 -357.98674)
			(xy 174.286527 -357.940865) (xy 174.263876 -357.891262) (xy 174.248514 -357.83894) (xy 174.240754 -357.784965)
			(xy 172.757928 -357.784965) (xy 172.757928 -357.784974) (xy 172.750165 -357.838965) (xy 172.734798 -357.891303)
			(xy 172.712138 -357.94092) (xy 172.682647 -357.986808) (xy 172.646926 -358.028032) (xy 172.605702 -358.063752)
			(xy 172.559813 -358.093241) (xy 172.510195 -358.1159) (xy 172.457857 -358.131267) (xy 172.403866 -358.139029)
			(xy 172.376592 -358.139492) (xy 171.512992 -358.139492) (xy 171.485725 -358.138945) (xy 171.431747 -358.131183)
			(xy 171.379422 -358.115818) (xy 171.329817 -358.093163) (xy 171.283941 -358.06368) (xy 171.242727 -358.027967)
			(xy 171.207016 -357.986753) (xy 171.177533 -357.940876) (xy 171.154879 -357.89127) (xy 171.139515 -357.838946)
			(xy 171.131754 -357.784967) (xy 169.648906 -357.784967) (xy 169.648906 -357.78497) (xy 169.641144 -357.838955)
			(xy 169.625779 -357.891286) (xy 169.603124 -357.940898) (xy 169.573638 -357.986781) (xy 169.537924 -358.028001)
			(xy 169.496707 -358.063719) (xy 169.450826 -358.093208) (xy 169.401216 -358.115868) (xy 169.348886 -358.131237)
			(xy 169.294902 -358.139003) (xy 169.267632 -358.139492) (xy 168.404032 -358.139492) (xy 168.376762 -358.138971)
			(xy 168.322776 -358.131213) (xy 168.270443 -358.115851) (xy 168.22083 -358.093197) (xy 168.174946 -358.063712)
			(xy 168.133725 -358.027998) (xy 168.098007 -357.98678) (xy 168.068519 -357.940898) (xy 168.045861 -357.891287)
			(xy 168.030494 -357.838956) (xy 168.022732 -357.78497) (xy 166.540028 -357.78497) (xy 166.540028 -357.784974)
			(xy 166.532265 -357.838968) (xy 166.516896 -357.891307) (xy 166.494235 -357.940926) (xy 166.464742 -357.986815)
			(xy 166.429019 -358.028039) (xy 166.387792 -358.063759) (xy 166.341901 -358.093248) (xy 166.292281 -358.115906)
			(xy 166.239941 -358.131271) (xy 166.185946 -358.13903) (xy 166.158672 -358.139492) (xy 165.295072 -358.139492)
			(xy 165.267806 -358.138944) (xy 165.21383 -358.131179) (xy 165.161508 -358.115813) (xy 165.111905 -358.093157)
			(xy 165.066031 -358.063673) (xy 165.02482 -358.02796) (xy 164.989111 -357.986746) (xy 164.95963 -357.94087)
			(xy 164.936977 -357.891266) (xy 164.921615 -357.838943) (xy 164.913854 -357.784966) (xy 163.431006 -357.784966)
			(xy 163.431006 -357.784971) (xy 163.423244 -357.838958) (xy 163.407878 -357.89129) (xy 163.385221 -357.940904)
			(xy 163.355733 -357.986788) (xy 163.320017 -358.028008) (xy 163.278797 -358.063726) (xy 163.232914 -358.093215)
			(xy 163.183302 -358.115873) (xy 163.130969 -358.131241) (xy 163.076983 -358.139005) (xy 163.049712 -358.139492)
			(xy 162.186112 -358.139492) (xy 162.158843 -358.138969) (xy 162.104859 -358.131209) (xy 162.052529 -358.115845)
			(xy 162.002918 -358.09319) (xy 161.957036 -358.063705) (xy 161.915818 -358.027991) (xy 161.880102 -357.986773)
			(xy 161.850616 -357.940893) (xy 161.827959 -357.891283) (xy 161.812593 -357.838953) (xy 161.804831 -357.784969)
			(xy 160.322128 -357.784969) (xy 160.322128 -357.784975) (xy 160.314364 -357.838971) (xy 160.298994 -357.891311)
			(xy 160.276332 -357.940932) (xy 160.246837 -357.986821) (xy 160.211112 -358.028046) (xy 160.169883 -358.063766)
			(xy 160.123989 -358.093255) (xy 160.074366 -358.115911) (xy 160.022024 -358.131275) (xy 159.968027 -358.139032)
			(xy 159.940752 -358.139492) (xy 159.077152 -358.139492) (xy 159.049887 -358.138942) (xy 158.995913 -358.131176)
			(xy 158.943593 -358.115807) (xy 158.893993 -358.09315) (xy 158.848122 -358.063665) (xy 158.806913 -358.027953)
			(xy 158.771206 -357.98674) (xy 158.741727 -357.940865) (xy 158.719076 -357.891262) (xy 158.703714 -357.83894)
			(xy 158.695954 -357.784965) (xy 144.196606 -357.784965) (xy 144.196606 -357.784971) (xy 144.188843 -357.838958)
			(xy 144.173477 -357.891291) (xy 144.15082 -357.940905) (xy 144.121332 -357.986789) (xy 144.085615 -358.02801)
			(xy 144.044395 -358.063728) (xy 143.998512 -358.093216) (xy 143.948899 -358.115875) (xy 143.896566 -358.131242)
			(xy 143.842579 -358.139005) (xy 143.815308 -358.139492) (xy 142.951708 -358.139492) (xy 142.924439 -358.138969)
			(xy 142.870455 -358.131209) (xy 142.818126 -358.115844) (xy 142.768515 -358.093189) (xy 142.722634 -358.063704)
			(xy 142.681417 -358.027989) (xy 142.645701 -357.986772) (xy 142.616215 -357.940892) (xy 142.593559 -357.891282)
			(xy 142.578193 -357.838953) (xy 142.570431 -357.784969) (xy 141.087606 -357.784969) (xy 141.079845 -357.838953)
			(xy 141.06448 -357.891283) (xy 141.041826 -357.940894) (xy 141.012342 -357.986776) (xy 140.976629 -358.027995)
			(xy 140.935414 -358.063713) (xy 140.889536 -358.093203) (xy 140.839928 -358.115864) (xy 140.7876 -358.131234)
			(xy 140.733617 -358.139002) (xy 140.706348 -358.139492) (xy 139.842748 -358.139492) (xy 139.815477 -358.138972)
			(xy 139.761489 -358.131216) (xy 139.709155 -358.115855) (xy 139.659539 -358.093202) (xy 139.613653 -358.063718)
			(xy 139.572431 -358.028003) (xy 139.536711 -357.986785) (xy 139.507221 -357.940903) (xy 139.484562 -357.89129)
			(xy 139.469194 -357.838958) (xy 139.461432 -357.784971) (xy 137.978728 -357.784971) (xy 137.978728 -357.784974)
			(xy 137.970965 -357.838966) (xy 137.955597 -357.891304) (xy 137.932937 -357.940921) (xy 137.903446 -357.986809)
			(xy 137.867724 -358.028033) (xy 137.8265 -358.063753) (xy 137.780611 -358.093243) (xy 137.730992 -358.115901)
			(xy 137.678654 -358.131268) (xy 137.624662 -358.139029) (xy 137.597388 -358.139492) (xy 136.733788 -358.139492)
			(xy 136.706521 -358.138945) (xy 136.652543 -358.131182) (xy 136.600219 -358.115817) (xy 136.550615 -358.093162)
			(xy 136.504739 -358.063678) (xy 136.463526 -358.027966) (xy 136.427815 -357.986752) (xy 136.398332 -357.940875)
			(xy 136.375679 -357.891269) (xy 136.360315 -357.838945) (xy 136.352554 -357.784967) (xy 134.869706 -357.784967)
			(xy 134.869706 -357.78497) (xy 134.861944 -357.838956) (xy 134.846579 -357.891287) (xy 134.823923 -357.940899)
			(xy 134.794437 -357.986782) (xy 134.758722 -358.028003) (xy 134.717505 -358.063721) (xy 134.671624 -358.09321)
			(xy 134.622013 -358.115869) (xy 134.569683 -358.131238) (xy 134.515698 -358.139004) (xy 134.488428 -358.139492)
			(xy 133.624828 -358.139492) (xy 133.597558 -358.13897) (xy 133.543572 -358.131212) (xy 133.49124 -358.11585)
			(xy 133.441627 -358.093195) (xy 133.395744 -358.063711) (xy 133.354524 -358.027996) (xy 133.318806 -357.986779)
			(xy 133.289318 -357.940897) (xy 133.26666 -357.891286) (xy 133.251294 -357.838955) (xy 133.243531 -357.78497)
			(xy 131.760828 -357.78497) (xy 131.760828 -357.784975) (xy 131.753065 -357.838969) (xy 131.737696 -357.891308)
			(xy 131.715034 -357.940927) (xy 131.685541 -357.986816) (xy 131.649817 -358.02804) (xy 131.60859 -358.06376)
			(xy 131.562699 -358.093249) (xy 131.513078 -358.115907) (xy 131.460737 -358.131272) (xy 131.406743 -358.139031)
			(xy 131.379468 -358.139492) (xy 130.515868 -358.139492) (xy 130.488602 -358.138943) (xy 130.434626 -358.131179)
			(xy 130.382305 -358.115812) (xy 130.332703 -358.093156) (xy 130.286829 -358.063671) (xy 130.245619 -358.027959)
			(xy 130.20991 -357.986745) (xy 130.180429 -357.940869) (xy 130.157777 -357.891265) (xy 130.142414 -357.838942)
			(xy 130.134654 -357.784966) (xy 128.651806 -357.784966) (xy 128.651806 -357.784971) (xy 128.644043 -357.838958)
			(xy 128.628677 -357.891291) (xy 128.60602 -357.940905) (xy 128.576532 -357.986789) (xy 128.540815 -358.02801)
			(xy 128.499595 -358.063728) (xy 128.453712 -358.093216) (xy 128.404099 -358.115875) (xy 128.351766 -358.131242)
			(xy 128.297779 -358.139005) (xy 128.270508 -358.139492) (xy 127.406908 -358.139492) (xy 127.379639 -358.138969)
			(xy 127.325655 -358.131209) (xy 127.273326 -358.115844) (xy 127.223715 -358.093189) (xy 127.177834 -358.063704)
			(xy 127.136617 -358.027989) (xy 127.100901 -357.986772) (xy 127.071415 -357.940892) (xy 127.048759 -357.891282)
			(xy 127.033393 -357.838953) (xy 127.025631 -357.784969) (xy 125.542806 -357.784969) (xy 125.535045 -357.838953)
			(xy 125.51968 -357.891283) (xy 125.497026 -357.940894) (xy 125.467542 -357.986776) (xy 125.431829 -358.027995)
			(xy 125.390614 -358.063713) (xy 125.344736 -358.093203) (xy 125.295128 -358.115864) (xy 125.2428 -358.131234)
			(xy 125.188817 -358.139002) (xy 125.161548 -358.139492) (xy 124.297948 -358.139492) (xy 124.270677 -358.138972)
			(xy 124.216689 -358.131216) (xy 124.164355 -358.115855) (xy 124.114739 -358.093202) (xy 124.068853 -358.063718)
			(xy 124.027631 -358.028003) (xy 123.991911 -357.986785) (xy 123.962421 -357.940903) (xy 123.939762 -357.89129)
			(xy 123.924394 -357.838958) (xy 123.916632 -357.784971) (xy 122.433928 -357.784971) (xy 122.433928 -357.784974)
			(xy 122.426165 -357.838966) (xy 122.410797 -357.891304) (xy 122.388137 -357.940921) (xy 122.358646 -357.986809)
			(xy 122.322924 -358.028033) (xy 122.2817 -358.063753) (xy 122.235811 -358.093243) (xy 122.186192 -358.115901)
			(xy 122.133854 -358.131268) (xy 122.079862 -358.139029) (xy 122.052588 -358.139492) (xy 121.188988 -358.139492)
			(xy 121.161721 -358.138945) (xy 121.107743 -358.131182) (xy 121.055419 -358.115817) (xy 121.005815 -358.093162)
			(xy 120.959939 -358.063678) (xy 120.918726 -358.027966) (xy 120.883015 -357.986752) (xy 120.853532 -357.940875)
			(xy 120.830879 -357.891269) (xy 120.815515 -357.838945) (xy 120.807754 -357.784967) (xy 119.324906 -357.784967)
			(xy 119.324906 -357.78497) (xy 119.317144 -357.838956) (xy 119.301779 -357.891287) (xy 119.279123 -357.940899)
			(xy 119.249637 -357.986782) (xy 119.213922 -358.028003) (xy 119.172705 -358.063721) (xy 119.126824 -358.09321)
			(xy 119.077213 -358.115869) (xy 119.024883 -358.131238) (xy 118.970898 -358.139004) (xy 118.943628 -358.139492)
			(xy 118.080028 -358.139492) (xy 118.052758 -358.13897) (xy 117.998772 -358.131212) (xy 117.94644 -358.11585)
			(xy 117.896827 -358.093195) (xy 117.850944 -358.063711) (xy 117.809724 -358.027996) (xy 117.774006 -357.986779)
			(xy 117.744518 -357.940897) (xy 117.72186 -357.891286) (xy 117.706494 -357.838955) (xy 117.698731 -357.78497)
			(xy 116.216028 -357.78497) (xy 116.216028 -357.784975) (xy 116.208265 -357.838969) (xy 116.192896 -357.891308)
			(xy 116.170234 -357.940927) (xy 116.140741 -357.986816) (xy 116.105017 -358.02804) (xy 116.06379 -358.06376)
			(xy 116.017899 -358.093249) (xy 115.968278 -358.115907) (xy 115.915937 -358.131272) (xy 115.861943 -358.139031)
			(xy 115.834668 -358.139492) (xy 114.971068 -358.139492) (xy 114.943802 -358.138943) (xy 114.889826 -358.131179)
			(xy 114.837505 -358.115812) (xy 114.787903 -358.093156) (xy 114.742029 -358.063671) (xy 114.700819 -358.027959)
			(xy 114.66511 -357.986745) (xy 114.635629 -357.940869) (xy 114.612977 -357.891265) (xy 114.597614 -357.838942)
			(xy 114.589854 -357.784966) (xy 93.706706 -357.784966) (xy 93.706706 -357.78497) (xy 93.698944 -357.838954)
			(xy 93.68358 -357.891284) (xy 93.660925 -357.940895) (xy 93.631441 -357.986778) (xy 93.595727 -358.027998)
			(xy 93.554511 -358.063716) (xy 93.508632 -358.093205) (xy 93.459023 -358.115865) (xy 93.406695 -358.131235)
			(xy 93.352712 -358.139003) (xy 93.325442 -358.139492) (xy 92.461842 -358.139492) (xy 92.434571 -358.138971)
			(xy 92.380584 -358.131215) (xy 92.32825 -358.115853) (xy 92.278636 -358.0932) (xy 92.23275 -358.063716)
			(xy 92.191529 -358.028001) (xy 92.155809 -357.986783) (xy 92.12632 -357.940901) (xy 92.103661 -357.891289)
			(xy 92.088294 -357.838957) (xy 92.080532 -357.784971) (xy 90.597828 -357.784971) (xy 90.597828 -357.784974)
			(xy 90.590065 -357.838967) (xy 90.574697 -357.891305) (xy 90.552036 -357.940923) (xy 90.522544 -357.986811)
			(xy 90.486822 -358.028035) (xy 90.445597 -358.063755) (xy 90.399707 -358.093245) (xy 90.350088 -358.115903)
			(xy 90.297749 -358.131269) (xy 90.243756 -358.13903) (xy 90.216482 -358.139492) (xy 89.352882 -358.139492)
			(xy 89.325616 -358.138944) (xy 89.271638 -358.131181) (xy 89.219315 -358.115816) (xy 89.169711 -358.09316)
			(xy 89.123836 -358.063676) (xy 89.082624 -358.027964) (xy 89.046913 -357.98675) (xy 89.017431 -357.940873)
			(xy 88.994778 -357.891268) (xy 88.979415 -357.838944) (xy 88.971654 -357.784966) (xy 87.488806 -357.784966)
			(xy 87.488806 -357.784971) (xy 87.481044 -357.838956) (xy 87.465678 -357.891288) (xy 87.443022 -357.940901)
			(xy 87.413536 -357.986784) (xy 87.37782 -358.028005) (xy 87.336602 -358.063723) (xy 87.29072 -358.093211)
			(xy 87.241109 -358.115871) (xy 87.188778 -358.131239) (xy 87.134792 -358.139004) (xy 87.107522 -358.139492)
			(xy 86.243922 -358.139492) (xy 86.216652 -358.13897) (xy 86.162667 -358.131211) (xy 86.110336 -358.115848)
			(xy 86.060724 -358.093193) (xy 86.014841 -358.063709) (xy 85.973622 -358.027994) (xy 85.937905 -357.986777)
			(xy 85.908417 -357.940895) (xy 85.88576 -357.891285) (xy 85.870394 -357.838954) (xy 85.862631 -357.78497)
			(xy 84.379928 -357.78497) (xy 84.379928 -357.784975) (xy 84.372165 -357.838969) (xy 84.356795 -357.891309)
			(xy 84.334133 -357.940929) (xy 84.30464 -357.986818) (xy 84.268915 -358.028042) (xy 84.227687 -358.063762)
			(xy 84.181795 -358.093251) (xy 84.132173 -358.115908) (xy 84.079832 -358.131273) (xy 84.025837 -358.139031)
			(xy 83.998562 -358.139492) (xy 83.134962 -358.139492) (xy 83.107697 -358.138943) (xy 83.053721 -358.131178)
			(xy 83.0014 -358.11581) (xy 82.951799 -358.093154) (xy 82.905926 -358.063669) (xy 82.864717 -358.027957)
			(xy 82.829008 -357.986743) (xy 82.799528 -357.940868) (xy 82.776877 -357.891264) (xy 82.761514 -357.838942)
			(xy 82.753754 -357.784966) (xy 81.270906 -357.784966) (xy 81.270906 -357.784971) (xy 81.263143 -357.838959)
			(xy 81.247777 -357.891293) (xy 81.225119 -357.940907) (xy 81.195631 -357.986791) (xy 81.159913 -358.028012)
			(xy 81.118693 -358.06373) (xy 81.072808 -358.093218) (xy 81.023194 -358.115876) (xy 80.970861 -358.131243)
			(xy 80.916873 -358.139005) (xy 80.889602 -358.139492) (xy 80.026002 -358.139492) (xy 79.998733 -358.138969)
			(xy 79.94475 -358.131207) (xy 79.892421 -358.115843) (xy 79.842812 -358.093187) (xy 79.796932 -358.063702)
			(xy 79.755714 -358.027987) (xy 79.72 -357.98677) (xy 79.690514 -357.94089) (xy 79.667858 -357.89128)
			(xy 79.652493 -357.838952) (xy 79.644731 -357.784969) (xy 78.161906 -357.784969) (xy 78.161906 -357.78497)
			(xy 78.154144 -357.838954) (xy 78.13878 -357.891284) (xy 78.116125 -357.940895) (xy 78.086641 -357.986778)
			(xy 78.050927 -358.027998) (xy 78.009711 -358.063716) (xy 77.963832 -358.093205) (xy 77.914223 -358.115865)
			(xy 77.861895 -358.131235) (xy 77.807912 -358.139003) (xy 77.780642 -358.139492) (xy 76.917042 -358.139492)
			(xy 76.889771 -358.138971) (xy 76.835784 -358.131215) (xy 76.78345 -358.115853) (xy 76.733836 -358.0932)
			(xy 76.68795 -358.063716) (xy 76.646729 -358.028001) (xy 76.611009 -357.986783) (xy 76.58152 -357.940901)
			(xy 76.558861 -357.891289) (xy 76.543494 -357.838957) (xy 76.535732 -357.784971) (xy 75.053028 -357.784971)
			(xy 75.053028 -357.784974) (xy 75.045265 -357.838967) (xy 75.029897 -357.891305) (xy 75.007236 -357.940923)
			(xy 74.977744 -357.986811) (xy 74.942022 -358.028035) (xy 74.900797 -358.063755) (xy 74.854907 -358.093245)
			(xy 74.805288 -358.115903) (xy 74.752949 -358.131269) (xy 74.698956 -358.13903) (xy 74.671682 -358.139492)
			(xy 73.808082 -358.139492) (xy 73.780816 -358.138944) (xy 73.726838 -358.131181) (xy 73.674515 -358.115816)
			(xy 73.624911 -358.09316) (xy 73.579036 -358.063676) (xy 73.537824 -358.027964) (xy 73.502113 -357.98675)
			(xy 73.472631 -357.940873) (xy 73.449978 -357.891268) (xy 73.434615 -357.838944) (xy 73.426854 -357.784966)
			(xy 71.944006 -357.784966) (xy 71.944006 -357.784971) (xy 71.936244 -357.838956) (xy 71.920878 -357.891288)
			(xy 71.898222 -357.940901) (xy 71.868736 -357.986784) (xy 71.83302 -358.028005) (xy 71.791802 -358.063723)
			(xy 71.74592 -358.093211) (xy 71.696309 -358.115871) (xy 71.643978 -358.131239) (xy 71.589992 -358.139004)
			(xy 71.562722 -358.139492) (xy 70.699122 -358.139492) (xy 70.671852 -358.13897) (xy 70.617867 -358.131211)
			(xy 70.565536 -358.115848) (xy 70.515924 -358.093193) (xy 70.470041 -358.063709) (xy 70.428822 -358.027994)
			(xy 70.393105 -357.986777) (xy 70.363617 -357.940895) (xy 70.34096 -357.891285) (xy 70.325594 -357.838954)
			(xy 70.317831 -357.78497) (xy 68.835128 -357.78497) (xy 68.835128 -357.784975) (xy 68.827365 -357.838969)
			(xy 68.811995 -357.891309) (xy 68.789333 -357.940929) (xy 68.75984 -357.986818) (xy 68.724115 -358.028042)
			(xy 68.682887 -358.063762) (xy 68.636995 -358.093251) (xy 68.587373 -358.115908) (xy 68.535032 -358.131273)
			(xy 68.481037 -358.139031) (xy 68.453762 -358.139492) (xy 67.590162 -358.139492) (xy 67.562897 -358.138943)
			(xy 67.508921 -358.131178) (xy 67.4566 -358.11581) (xy 67.406999 -358.093154) (xy 67.361126 -358.063669)
			(xy 67.319917 -358.027957) (xy 67.284208 -357.986743) (xy 67.254728 -357.940868) (xy 67.232077 -357.891264)
			(xy 67.216714 -357.838942) (xy 67.208954 -357.784966) (xy 65.726106 -357.784966) (xy 65.726106 -357.784971)
			(xy 65.718343 -357.838959) (xy 65.702977 -357.891293) (xy 65.680319 -357.940907) (xy 65.650831 -357.986791)
			(xy 65.615113 -358.028012) (xy 65.573893 -358.06373) (xy 65.528008 -358.093218) (xy 65.478394 -358.115876)
			(xy 65.426061 -358.131243) (xy 65.372073 -358.139005) (xy 65.344802 -358.139492) (xy 64.481202 -358.139492)
			(xy 64.453933 -358.138969) (xy 64.39995 -358.131207) (xy 64.347621 -358.115843) (xy 64.298012 -358.093187)
			(xy 64.252132 -358.063702) (xy 64.210914 -358.027987) (xy 64.1752 -357.98677) (xy 64.145714 -357.94089)
			(xy 64.123058 -357.89128) (xy 64.107693 -357.838952) (xy 64.099931 -357.784969) (xy 51.666906 -357.784969)
			(xy 51.659145 -357.838953) (xy 51.64378 -357.891283) (xy 51.621126 -357.940894) (xy 51.591642 -357.986776)
			(xy 51.555929 -358.027995) (xy 51.514714 -358.063713) (xy 51.468836 -358.093203) (xy 51.419228 -358.115864)
			(xy 51.3669 -358.131234) (xy 51.312917 -358.139002) (xy 51.285648 -358.139492) (xy 50.422048 -358.139492)
			(xy 50.394777 -358.138972) (xy 50.340789 -358.131216) (xy 50.288455 -358.115855) (xy 50.238839 -358.093202)
			(xy 50.192953 -358.063718) (xy 50.151731 -358.028003) (xy 50.116011 -357.986785) (xy 50.086521 -357.940903)
			(xy 50.063862 -357.89129) (xy 50.048494 -357.838958) (xy 50.040732 -357.784971) (xy 48.558028 -357.784971)
			(xy 48.558028 -357.784974) (xy 48.550265 -357.838966) (xy 48.534897 -357.891304) (xy 48.512237 -357.940921)
			(xy 48.482746 -357.986809) (xy 48.447024 -358.028033) (xy 48.4058 -358.063753) (xy 48.359911 -358.093243)
			(xy 48.310292 -358.115901) (xy 48.257954 -358.131268) (xy 48.203962 -358.139029) (xy 48.176688 -358.139492)
			(xy 47.313088 -358.139492) (xy 47.285821 -358.138945) (xy 47.231843 -358.131182) (xy 47.179519 -358.115817)
			(xy 47.129915 -358.093162) (xy 47.084039 -358.063678) (xy 47.042826 -358.027966) (xy 47.007115 -357.986752)
			(xy 46.977632 -357.940875) (xy 46.954979 -357.891269) (xy 46.939615 -357.838945) (xy 46.931854 -357.784967)
			(xy 45.449006 -357.784967) (xy 45.449006 -357.78497) (xy 45.441244 -357.838956) (xy 45.425879 -357.891287)
			(xy 45.403223 -357.940899) (xy 45.373737 -357.986782) (xy 45.338022 -358.028003) (xy 45.296805 -358.063721)
			(xy 45.250924 -358.09321) (xy 45.201313 -358.115869) (xy 45.148983 -358.131238) (xy 45.094998 -358.139004)
			(xy 45.067728 -358.139492) (xy 44.204128 -358.139492) (xy 44.176858 -358.13897) (xy 44.122872 -358.131212)
			(xy 44.07054 -358.11585) (xy 44.020927 -358.093195) (xy 43.975044 -358.063711) (xy 43.933824 -358.027996)
			(xy 43.898106 -357.986779) (xy 43.868618 -357.940897) (xy 43.84596 -357.891286) (xy 43.830594 -357.838955)
			(xy 43.822831 -357.78497) (xy 42.340128 -357.78497) (xy 42.340128 -357.784975) (xy 42.332365 -357.838969)
			(xy 42.316996 -357.891308) (xy 42.294334 -357.940927) (xy 42.264841 -357.986816) (xy 42.229117 -358.02804)
			(xy 42.18789 -358.06376) (xy 42.141999 -358.093249) (xy 42.092378 -358.115907) (xy 42.040037 -358.131272)
			(xy 41.986043 -358.139031) (xy 41.958768 -358.139492) (xy 41.095168 -358.139492) (xy 41.067902 -358.138943)
			(xy 41.013926 -358.131179) (xy 40.961605 -358.115812) (xy 40.912003 -358.093156) (xy 40.866129 -358.063671)
			(xy 40.824919 -358.027959) (xy 40.78921 -357.986745) (xy 40.759729 -357.940869) (xy 40.737077 -357.891265)
			(xy 40.721714 -357.838942) (xy 40.713954 -357.784966) (xy 39.231106 -357.784966) (xy 39.231106 -357.784971)
			(xy 39.223343 -357.838958) (xy 39.207977 -357.891291) (xy 39.18532 -357.940905) (xy 39.155832 -357.986789)
			(xy 39.120115 -358.02801) (xy 39.078895 -358.063728) (xy 39.033012 -358.093216) (xy 38.983399 -358.115875)
			(xy 38.931066 -358.131242) (xy 38.877079 -358.139005) (xy 38.849808 -358.139492) (xy 37.986208 -358.139492)
			(xy 37.958939 -358.138969) (xy 37.904955 -358.131209) (xy 37.852626 -358.115844) (xy 37.803015 -358.093189)
			(xy 37.757134 -358.063704) (xy 37.715917 -358.027989) (xy 37.680201 -357.986772) (xy 37.650715 -357.940892)
			(xy 37.628059 -357.891282) (xy 37.612693 -357.838953) (xy 37.604931 -357.784969) (xy 36.122106 -357.784969)
			(xy 36.114345 -357.838953) (xy 36.09898 -357.891283) (xy 36.076326 -357.940894) (xy 36.046842 -357.986776)
			(xy 36.011129 -358.027995) (xy 35.969914 -358.063713) (xy 35.924036 -358.093203) (xy 35.874428 -358.115864)
			(xy 35.8221 -358.131234) (xy 35.768117 -358.139002) (xy 35.740848 -358.139492) (xy 34.877248 -358.139492)
			(xy 34.849977 -358.138972) (xy 34.795989 -358.131216) (xy 34.743655 -358.115855) (xy 34.694039 -358.093202)
			(xy 34.648153 -358.063718) (xy 34.606931 -358.028003) (xy 34.571211 -357.986785) (xy 34.541721 -357.940903)
			(xy 34.519062 -357.89129) (xy 34.503694 -357.838958) (xy 34.495932 -357.784971) (xy 33.013228 -357.784971)
			(xy 33.013228 -357.784974) (xy 33.005465 -357.838966) (xy 32.990097 -357.891304) (xy 32.967437 -357.940921)
			(xy 32.937946 -357.986809) (xy 32.902224 -358.028033) (xy 32.861 -358.063753) (xy 32.815111 -358.093243)
			(xy 32.765492 -358.115901) (xy 32.713154 -358.131268) (xy 32.659162 -358.139029) (xy 32.631888 -358.139492)
			(xy 31.768288 -358.139492) (xy 31.741021 -358.138945) (xy 31.687043 -358.131182) (xy 31.634719 -358.115817)
			(xy 31.585115 -358.093162) (xy 31.539239 -358.063678) (xy 31.498026 -358.027966) (xy 31.462315 -357.986752)
			(xy 31.432832 -357.940875) (xy 31.410179 -357.891269) (xy 31.394815 -357.838945) (xy 31.387054 -357.784967)
			(xy 29.904206 -357.784967) (xy 29.904206 -357.78497) (xy 29.896444 -357.838956) (xy 29.881079 -357.891287)
			(xy 29.858423 -357.940899) (xy 29.828937 -357.986782) (xy 29.793222 -358.028003) (xy 29.752005 -358.063721)
			(xy 29.706124 -358.09321) (xy 29.656513 -358.115869) (xy 29.604183 -358.131238) (xy 29.550198 -358.139004)
			(xy 29.522928 -358.139492) (xy 28.659328 -358.139492) (xy 28.632058 -358.13897) (xy 28.578072 -358.131212)
			(xy 28.52574 -358.11585) (xy 28.476127 -358.093195) (xy 28.430244 -358.063711) (xy 28.389024 -358.027996)
			(xy 28.353306 -357.986779) (xy 28.323818 -357.940897) (xy 28.30116 -357.891286) (xy 28.285794 -357.838955)
			(xy 28.278031 -357.78497) (xy 26.795328 -357.78497) (xy 26.795328 -357.784975) (xy 26.787565 -357.838969)
			(xy 26.772196 -357.891308) (xy 26.749534 -357.940927) (xy 26.720041 -357.986816) (xy 26.684317 -358.02804)
			(xy 26.64309 -358.06376) (xy 26.597199 -358.093249) (xy 26.547578 -358.115907) (xy 26.495237 -358.131272)
			(xy 26.441243 -358.139031) (xy 26.413968 -358.139492) (xy 25.550368 -358.139492) (xy 25.523102 -358.138943)
			(xy 25.469126 -358.131179) (xy 25.416805 -358.115812) (xy 25.367203 -358.093156) (xy 25.321329 -358.063671)
			(xy 25.280119 -358.027959) (xy 25.24441 -357.986745) (xy 25.214929 -357.940869) (xy 25.192277 -357.891265)
			(xy 25.176914 -357.838942) (xy 25.169154 -357.784966) (xy 23.686306 -357.784966) (xy 23.686306 -357.784971)
			(xy 23.678543 -357.838958) (xy 23.663177 -357.891291) (xy 23.64052 -357.940905) (xy 23.611032 -357.986789)
			(xy 23.575315 -358.02801) (xy 23.534095 -358.063728) (xy 23.488212 -358.093216) (xy 23.438599 -358.115875)
			(xy 23.386266 -358.131242) (xy 23.332279 -358.139005) (xy 23.305008 -358.139492) (xy 22.441408 -358.139492)
			(xy 22.414139 -358.138969) (xy 22.360155 -358.131209) (xy 22.307826 -358.115844) (xy 22.258215 -358.093189)
			(xy 22.212334 -358.063704) (xy 22.171117 -358.027989) (xy 22.135401 -357.986772) (xy 22.105915 -357.940892)
			(xy 22.083259 -357.891282) (xy 22.067893 -357.838953) (xy 22.060131 -357.784969) (xy 0.508 -357.784969)
			(xy 0.508 -360.017783) (xy 101.774757 -360.017783) (xy 101.774757 -359.957817) (xy 101.782584 -359.898365)
			(xy 101.798104 -359.840443) (xy 101.821052 -359.785042) (xy 101.851035 -359.733111) (xy 101.88754 -359.685538)
			(xy 101.929942 -359.643136) (xy 101.977516 -359.606632) (xy 102.029448 -359.57665) (xy 102.084849 -359.553703)
			(xy 102.142771 -359.538183) (xy 102.202223 -359.530357) (xy 102.232206 -359.529888) (xy 103.095806 -359.529888)
			(xy 103.125793 -359.530279) (xy 103.185255 -359.538108) (xy 103.243186 -359.553631) (xy 103.298595 -359.576583)
			(xy 103.350534 -359.60657) (xy 103.398115 -359.643081) (xy 103.440523 -359.68549) (xy 103.477033 -359.733071)
			(xy 103.50702 -359.785011) (xy 103.529971 -359.84042) (xy 103.545494 -359.898351) (xy 103.553322 -359.957813)
			(xy 103.553322 -360.017787) (xy 103.545494 -360.077249) (xy 103.529971 -360.13518) (xy 103.50702 -360.190589)
			(xy 103.477033 -360.242529) (xy 103.440523 -360.29011) (xy 103.398115 -360.332519) (xy 103.350534 -360.36903)
			(xy 103.298595 -360.399017) (xy 103.243186 -360.421969) (xy 103.185255 -360.437492) (xy 103.125793 -360.445321)
			(xy 103.095806 -360.445812) (xy 102.232206 -360.445812) (xy 102.202223 -360.445243) (xy 102.142771 -360.437417)
			(xy 102.084849 -360.421897) (xy 102.029448 -360.39895) (xy 101.977516 -360.368968) (xy 101.929942 -360.332464)
			(xy 101.88754 -360.290062) (xy 101.851035 -360.242489) (xy 101.821052 -360.190558) (xy 101.798104 -360.135157)
			(xy 101.782584 -360.077235) (xy 101.774757 -360.017783) (xy 0.508 -360.017783) (xy 0.508 -363.334808)
			(xy 54.890416 -363.334808) (xy 54.890416 -362.471208) (xy 54.890906 -362.441224) (xy 54.898734 -362.381768)
			(xy 54.914255 -362.323843) (xy 54.937204 -362.268439) (xy 54.967188 -362.216505) (xy 55.003694 -362.168929)
			(xy 55.046099 -362.126524) (xy 55.093675 -362.090018) (xy 55.145609 -362.060034) (xy 55.201013 -362.037085)
			(xy 55.258938 -362.021564) (xy 55.318394 -362.013736) (xy 55.378362 -362.013736) (xy 55.437818 -362.021564)
			(xy 55.495743 -362.037085) (xy 55.551147 -362.060034) (xy 55.603081 -362.090018) (xy 55.650657 -362.126524)
			(xy 55.693062 -362.168929) (xy 55.729568 -362.216505) (xy 55.759552 -362.268439) (xy 55.782501 -362.323843)
			(xy 55.798022 -362.381768) (xy 55.80585 -362.441224) (xy 55.80634 -362.471208) (xy 55.80634 -363.334808)
			(xy 55.80585 -363.364792) (xy 55.798022 -363.424248) (xy 55.782501 -363.482173) (xy 55.759552 -363.537577)
			(xy 55.729568 -363.589511) (xy 55.693062 -363.637087) (xy 55.650657 -363.679492) (xy 55.603081 -363.715998)
			(xy 55.551147 -363.745982) (xy 55.495743 -363.768931) (xy 55.437818 -363.784452) (xy 55.378362 -363.79228)
			(xy 55.318394 -363.79228) (xy 55.258938 -363.784452) (xy 55.201013 -363.768931) (xy 55.145609 -363.745982)
			(xy 55.093675 -363.715998) (xy 55.046099 -363.679492) (xy 55.003694 -363.637087) (xy 54.967188 -363.589511)
			(xy 54.937204 -363.537577) (xy 54.914255 -363.482173) (xy 54.898734 -363.424248) (xy 54.890906 -363.364792)
			(xy 54.890416 -363.334808) (xy 0.508 -363.334808) (xy 0.508 -365.797384) (xy 54.438294 -365.797384)
			(xy 54.438294 -365.737416) (xy 54.446121 -365.67796) (xy 54.461641 -365.620034) (xy 54.484589 -365.564629)
			(xy 54.514571 -365.512694) (xy 54.551076 -365.465115) (xy 54.593478 -365.422709) (xy 54.641052 -365.386199)
			(xy 54.692984 -365.356211) (xy 54.748387 -365.333257) (xy 54.806311 -365.317731) (xy 54.865766 -365.309897)
			(xy 54.89575 -365.309404) (xy 55.75935 -365.309404) (xy 55.789336 -365.309938) (xy 55.848794 -365.31776)
			(xy 55.906723 -365.333276) (xy 55.962131 -365.356222) (xy 56.01407 -365.386203) (xy 56.06165 -365.422708)
			(xy 56.104059 -365.465112) (xy 56.140569 -365.512689) (xy 56.170556 -365.564624) (xy 56.193508 -365.620029)
			(xy 56.20903 -365.677957) (xy 56.216859 -365.737414) (xy 56.216859 -365.797386) (xy 56.20903 -365.856843)
			(xy 56.193508 -365.914771) (xy 56.170556 -365.970176) (xy 56.140569 -366.022112) (xy 56.104059 -366.069688)
			(xy 56.06165 -366.112092) (xy 56.01407 -366.148597) (xy 55.962131 -366.178578) (xy 55.906723 -366.201524)
			(xy 55.848794 -366.21704) (xy 55.789336 -366.224862) (xy 55.75935 -366.225328) (xy 54.89575 -366.225328)
			(xy 54.865766 -366.224903) (xy 54.806311 -366.217069) (xy 54.748386 -366.201543) (xy 54.692984 -366.178589)
			(xy 54.641052 -366.148601) (xy 54.593478 -366.112091) (xy 54.551076 -366.069685) (xy 54.514571 -366.022106)
			(xy 54.484589 -365.970171) (xy 54.461641 -365.914766) (xy 54.446121 -365.85684) (xy 54.438294 -365.797384)
			(xy 0.508 -365.797384) (xy 0.508 -368.516662) (xy 53.966364 -368.516662) (xy 53.966364 -367.653062)
			(xy 53.96685 -367.625793) (xy 53.974612 -367.571809) (xy 53.989977 -367.519479) (xy 54.012634 -367.469869)
			(xy 54.04212 -367.423988) (xy 54.077835 -367.382771) (xy 54.119052 -367.347056) (xy 54.164933 -367.31757)
			(xy 54.214543 -367.294913) (xy 54.266873 -367.279548) (xy 54.320857 -367.271786) (xy 54.375395 -367.271786)
			(xy 54.429379 -367.279548) (xy 54.481709 -367.294913) (xy 54.531319 -367.31757) (xy 54.5772 -367.347056)
			(xy 54.618417 -367.382771) (xy 54.654132 -367.423988) (xy 54.683618 -367.469869) (xy 54.706275 -367.519479)
			(xy 54.72164 -367.571809) (xy 54.729402 -367.625793) (xy 54.729888 -367.653062) (xy 54.729888 -368.516662)
			(xy 57.339484 -368.516662) (xy 57.339484 -367.653062) (xy 57.33997 -367.625793) (xy 57.347732 -367.571809)
			(xy 57.363097 -367.519479) (xy 57.385754 -367.469869) (xy 57.41524 -367.423988) (xy 57.450955 -367.382771)
			(xy 57.492172 -367.347056) (xy 57.538053 -367.31757) (xy 57.587663 -367.294913) (xy 57.639993 -367.279548)
			(xy 57.693977 -367.271786) (xy 57.748515 -367.271786) (xy 57.802499 -367.279548) (xy 57.854829 -367.294913)
			(xy 57.904439 -367.31757) (xy 57.95032 -367.347056) (xy 57.991537 -367.382771) (xy 58.027252 -367.423988)
			(xy 58.056738 -367.469869) (xy 58.079395 -367.519479) (xy 58.09476 -367.571809) (xy 58.102522 -367.625793)
			(xy 58.103008 -367.653062) (xy 58.103008 -368.516662) (xy 58.102522 -368.543931) (xy 58.09476 -368.597915)
			(xy 58.079395 -368.650245) (xy 58.056738 -368.699855) (xy 58.027252 -368.745736) (xy 57.991537 -368.786953)
			(xy 57.95032 -368.822668) (xy 57.904439 -368.852154) (xy 57.854829 -368.874811) (xy 57.802499 -368.890176)
			(xy 57.748515 -368.897938) (xy 57.693977 -368.897938) (xy 57.639993 -368.890176) (xy 57.587663 -368.874811)
			(xy 57.538053 -368.852154) (xy 57.492172 -368.822668) (xy 57.450955 -368.786953) (xy 57.41524 -368.745736)
			(xy 57.385754 -368.699855) (xy 57.363097 -368.650245) (xy 57.347732 -368.597915) (xy 57.33997 -368.543931)
			(xy 57.339484 -368.516662) (xy 54.729888 -368.516662) (xy 54.729402 -368.543931) (xy 54.72164 -368.597915)
			(xy 54.706275 -368.650245) (xy 54.683618 -368.699855) (xy 54.654132 -368.745736) (xy 54.618417 -368.786953)
			(xy 54.5772 -368.822668) (xy 54.531319 -368.852154) (xy 54.481709 -368.874811) (xy 54.429379 -368.890176)
			(xy 54.375395 -368.897938) (xy 54.320857 -368.897938) (xy 54.266873 -368.890176) (xy 54.214543 -368.874811)
			(xy 54.164933 -368.852154) (xy 54.119052 -368.822668) (xy 54.077835 -368.786953) (xy 54.04212 -368.745736)
			(xy 54.012634 -368.699855) (xy 53.989977 -368.650245) (xy 53.974612 -368.597915) (xy 53.96685 -368.543931)
			(xy 53.966364 -368.516662) (xy 0.508 -368.516662) (xy 0.508 -370.523703) (xy 27.348898 -370.523703)
			(xy 27.348899 -370.456279) (xy 27.356975 -370.38934) (xy 27.373012 -370.323851) (xy 27.396776 -370.260753)
			(xy 27.427927 -370.200957) (xy 27.466016 -370.145322) (xy 27.48788 -370.119656) (xy 27.493675 -370.11251)
			(xy 27.500191 -370.09532) (xy 27.50058 -370.086128) (xy 27.50058 -369.928902) (xy 27.501029 -369.918771)
			(xy 27.508764 -369.900042) (xy 27.523062 -369.885684) (xy 27.541759 -369.877872) (xy 27.551888 -369.87734)
			(xy 28.268168 -369.87734) (xy 28.278293 -369.877743) (xy 28.297004 -369.885488) (xy 28.311321 -369.899809)
			(xy 28.31906 -369.918522) (xy 28.319476 -369.928648) (xy 28.319476 -370.086128) (xy 28.319878 -370.095316)
			(xy 28.326398 -370.1125) (xy 28.332176 -370.119656) (xy 28.354029 -370.145331) (xy 28.39212 -370.200963)
			(xy 28.423272 -370.260758) (xy 28.447038 -370.323854) (xy 28.463075 -370.389342) (xy 28.471152 -370.456279)
			(xy 28.471153 -370.523644) (xy 31.749193 -370.523644) (xy 31.749194 -370.456338) (xy 31.75724 -370.389514)
			(xy 31.773215 -370.324131) (xy 31.79689 -370.261126) (xy 31.827927 -370.201402) (xy 31.865879 -370.145816)
			(xy 31.887668 -370.120164) (xy 31.893471 -370.113023) (xy 31.89998 -370.095829) (xy 31.900368 -370.086636)
			(xy 31.900368 -369.928902) (xy 31.900766 -369.918727) (xy 31.908556 -369.899926) (xy 31.92295 -369.88554)
			(xy 31.941755 -369.877761) (xy 31.95193 -369.87734) (xy 32.66821 -369.87734) (xy 32.678369 -369.877825)
			(xy 32.697138 -369.885603) (xy 32.711503 -369.899972) (xy 32.719277 -369.918743) (xy 32.719772 -369.928902)
			(xy 32.719772 -370.086636) (xy 32.720171 -370.095824) (xy 32.726693 -370.113008) (xy 32.732472 -370.120164)
			(xy 32.754248 -370.145826) (xy 32.792196 -370.201411) (xy 32.823229 -370.261134) (xy 32.846902 -370.324137)
			(xy 32.862876 -370.389518) (xy 32.870921 -370.456339) (xy 32.870922 -370.523643) (xy 32.870915 -370.523703)
			(xy 36.148986 -370.523703) (xy 36.148987 -370.456279) (xy 36.157063 -370.389341) (xy 36.173099 -370.323851)
			(xy 36.196863 -370.260754) (xy 36.228013 -370.200957) (xy 36.266101 -370.145322) (xy 36.287964 -370.119656)
			(xy 36.29377 -370.112518) (xy 36.300277 -370.095322) (xy 36.300664 -370.086128) (xy 36.300664 -369.928902)
			(xy 36.301129 -369.918772) (xy 36.308861 -369.900047) (xy 36.323154 -369.88569) (xy 36.341845 -369.877875)
			(xy 36.351972 -369.87734) (xy 37.068252 -369.87734) (xy 37.078408 -369.877762) (xy 37.097167 -369.885549)
			(xy 37.111494 -369.899947) (xy 37.119188 -369.918744) (xy 37.11956 -369.928902) (xy 37.11956 -370.086128)
			(xy 37.119966 -370.095315) (xy 37.126483 -370.112499) (xy 37.13226 -370.119656) (xy 37.154114 -370.14533)
			(xy 37.192205 -370.200963) (xy 37.223359 -370.260757) (xy 37.247125 -370.323853) (xy 37.263163 -370.389341)
			(xy 37.27124 -370.456279) (xy 37.271241 -370.523703) (xy 37.271241 -370.523704) (xy 40.548752 -370.523704)
			(xy 40.548753 -370.456278) (xy 40.556831 -370.389338) (xy 40.572869 -370.323848) (xy 40.596637 -370.26075)
			(xy 40.627792 -370.200954) (xy 40.665885 -370.14532) (xy 40.687752 -370.119656) (xy 40.693556 -370.112516)
			(xy 40.700065 -370.095321) (xy 40.700452 -370.086128) (xy 40.700452 -369.928902) (xy 40.700929 -369.918774)
			(xy 40.708658 -369.900051) (xy 40.722947 -369.885694) (xy 40.741634 -369.877877) (xy 40.75176 -369.87734)
			(xy 41.46804 -369.87734) (xy 41.478202 -369.87769) (xy 41.496963 -369.885506) (xy 41.511286 -369.899925)
			(xy 41.518977 -369.918738) (xy 41.519348 -369.928902) (xy 41.519348 -370.086128) (xy 41.519756 -370.095315)
			(xy 41.526273 -370.112499) (xy 41.532048 -370.119656) (xy 41.553902 -370.14533) (xy 41.591994 -370.200962)
			(xy 41.623149 -370.260757) (xy 41.646916 -370.323852) (xy 41.662954 -370.389341) (xy 41.671031 -370.456279)
			(xy 41.671032 -370.523644) (xy 44.949071 -370.523644) (xy 44.949073 -370.456338) (xy 44.957118 -370.389515)
			(xy 44.973092 -370.324132) (xy 44.996766 -370.261127) (xy 45.027801 -370.201403) (xy 45.065751 -370.145816)
			(xy 45.08754 -370.120164) (xy 45.093339 -370.113021) (xy 45.099851 -370.095829) (xy 45.10024 -370.086636)
			(xy 45.10024 -369.928902) (xy 45.100665 -369.91873) (xy 45.10845 -369.899935) (xy 45.122835 -369.88555)
			(xy 45.14163 -369.877765) (xy 45.151802 -369.87734) (xy 45.868082 -369.87734) (xy 45.878253 -369.877778)
			(xy 45.897047 -369.885558) (xy 45.911433 -369.899939) (xy 45.919218 -369.918731) (xy 45.919644 -369.928902)
			(xy 45.919644 -370.086636) (xy 45.92005 -370.095823) (xy 45.926568 -370.113007) (xy 45.932344 -370.120164)
			(xy 45.95412 -370.145826) (xy 45.992071 -370.20141) (xy 46.023105 -370.261132) (xy 46.046779 -370.324136)
			(xy 46.062754 -370.389517) (xy 46.070799 -370.456339) (xy 46.0708 -370.523643) (xy 46.062757 -370.590465)
			(xy 46.046785 -370.655847) (xy 46.023113 -370.718851) (xy 45.99208 -370.778574) (xy 45.954131 -370.83416)
			(xy 45.932344 -370.859812) (xy 45.926553 -370.866961) (xy 45.920036 -370.884149) (xy 45.919644 -370.89334)
			(xy 45.919644 -371.386862) (xy 45.920085 -371.396046) (xy 45.926578 -371.41323) (xy 45.932344 -371.42039)
			(xy 45.954146 -371.44603) (xy 45.992096 -371.501618) (xy 46.023129 -371.561343) (xy 46.046568 -371.623726)
			(xy 47.14919 -371.623726) (xy 47.149193 -371.556417) (xy 47.157242 -371.489591) (xy 47.17322 -371.424206)
			(xy 47.1969 -371.3612) (xy 47.22794 -371.301475) (xy 47.265897 -371.24589) (xy 47.287688 -371.220238)
			(xy 47.293492 -371.213098) (xy 47.300003 -371.195904) (xy 47.300388 -371.18671) (xy 47.300388 -371.028722)
			(xy 47.300783 -371.018546) (xy 47.30857 -370.999742) (xy 47.322966 -370.985355) (xy 47.341773 -370.977578)
			(xy 47.35195 -370.97716) (xy 48.06823 -370.97716) (xy 48.078392 -370.977609) (xy 48.097167 -370.985398)
			(xy 48.111532 -370.999777) (xy 48.119301 -371.018559) (xy 48.119792 -371.028722) (xy 48.119792 -371.18671)
			(xy 48.120199 -371.195898) (xy 48.126715 -371.213082) (xy 48.132492 -371.220238) (xy 48.154241 -371.245921)
			(xy 48.192189 -371.301504) (xy 48.196948 -371.310662) (xy 53.966364 -371.310662) (xy 53.966364 -370.447062)
			(xy 53.96685 -370.419793) (xy 53.974612 -370.365809) (xy 53.989977 -370.313479) (xy 54.012634 -370.263869)
			(xy 54.04212 -370.217988) (xy 54.077835 -370.176771) (xy 54.119052 -370.141056) (xy 54.164933 -370.11157)
			(xy 54.214543 -370.088913) (xy 54.266873 -370.073548) (xy 54.320857 -370.065786) (xy 54.375395 -370.065786)
			(xy 54.429379 -370.073548) (xy 54.481709 -370.088913) (xy 54.531319 -370.11157) (xy 54.5772 -370.141056)
			(xy 54.618417 -370.176771) (xy 54.654132 -370.217988) (xy 54.683618 -370.263869) (xy 54.706275 -370.313479)
			(xy 54.72164 -370.365809) (xy 54.729402 -370.419793) (xy 54.729888 -370.447062) (xy 54.729888 -371.310662)
			(xy 57.339484 -371.310662) (xy 57.339484 -370.447062) (xy 57.33997 -370.419793) (xy 57.347732 -370.365809)
			(xy 57.363097 -370.313479) (xy 57.385754 -370.263869) (xy 57.41524 -370.217988) (xy 57.450955 -370.176771)
			(xy 57.492172 -370.141056) (xy 57.538053 -370.11157) (xy 57.587663 -370.088913) (xy 57.639993 -370.073548)
			(xy 57.693977 -370.065786) (xy 57.748515 -370.065786) (xy 57.802499 -370.073548) (xy 57.854829 -370.088913)
			(xy 57.904439 -370.11157) (xy 57.95032 -370.141056) (xy 57.991537 -370.176771) (xy 58.027252 -370.217988)
			(xy 58.056738 -370.263869) (xy 58.079395 -370.313479) (xy 58.09476 -370.365809) (xy 58.102522 -370.419793)
			(xy 58.103008 -370.447062) (xy 58.103008 -370.523703) (xy 71.348807 -370.523703) (xy 71.348808 -370.456279)
			(xy 71.356885 -370.38934) (xy 71.372921 -370.32385) (xy 71.396686 -370.260753) (xy 71.427838 -370.200956)
			(xy 71.465928 -370.145321) (xy 71.487792 -370.119656) (xy 71.493589 -370.112511) (xy 71.500104 -370.09532)
			(xy 71.500492 -370.086128) (xy 71.500492 -369.928902) (xy 71.501027 -369.918781) (xy 71.508745 -369.900069)
			(xy 71.523016 -369.885715) (xy 71.541682 -369.877887) (xy 71.5518 -369.87734) (xy 72.26808 -369.87734)
			(xy 72.278238 -369.877739) (xy 72.296998 -369.885535) (xy 72.311323 -369.89994) (xy 72.319016 -369.918742)
			(xy 72.319388 -369.928902) (xy 72.319388 -370.086128) (xy 72.319787 -370.095316) (xy 72.326309 -370.1125)
			(xy 72.332088 -370.119656) (xy 72.353941 -370.145331) (xy 72.39203 -370.200964) (xy 72.423182 -370.260758)
			(xy 72.446948 -370.323854) (xy 72.462984 -370.389342) (xy 72.471061 -370.45628) (xy 72.471063 -370.523644)
			(xy 75.749102 -370.523644) (xy 75.749103 -370.456338) (xy 75.757149 -370.389513) (xy 75.773125 -370.32413)
			(xy 75.796801 -370.261125) (xy 75.827837 -370.201401) (xy 75.86579 -370.145816) (xy 75.88758 -370.120164)
			(xy 75.893372 -370.113015) (xy 75.89989 -370.095828) (xy 75.90028 -370.086636) (xy 75.90028 -369.928902)
			(xy 75.900666 -369.918725) (xy 75.908459 -369.899923) (xy 75.922856 -369.885536) (xy 75.941665 -369.877759)
			(xy 75.951842 -369.87734) (xy 76.668122 -369.87734) (xy 76.678281 -369.877815) (xy 76.697052 -369.885597)
			(xy 76.711416 -369.899969) (xy 76.71919 -369.918742) (xy 76.719684 -369.928902) (xy 76.719684 -370.086636)
			(xy 76.72008 -370.095825) (xy 76.726604 -370.113009) (xy 76.732384 -370.120164) (xy 76.754159 -370.145826)
			(xy 76.792107 -370.201412) (xy 76.82314 -370.261134) (xy 76.846812 -370.324137) (xy 76.862785 -370.389518)
			(xy 76.87083 -370.456339) (xy 76.870831 -370.523643) (xy 76.870824 -370.523703) (xy 80.148895 -370.523703)
			(xy 80.148896 -370.456279) (xy 80.156972 -370.38934) (xy 80.173008 -370.323851) (xy 80.196773 -370.260754)
			(xy 80.227924 -370.200957) (xy 80.266012 -370.145322) (xy 80.287876 -370.119656) (xy 80.293671 -370.112509)
			(xy 80.300187 -370.09532) (xy 80.300576 -370.086128) (xy 80.300576 -369.928902) (xy 80.301029 -369.918771)
			(xy 80.308763 -369.900043) (xy 80.32306 -369.885685) (xy 80.341755 -369.877873) (xy 80.351884 -369.87734)
			(xy 81.068164 -369.87734) (xy 81.078289 -369.877747) (xy 81.096999 -369.88549) (xy 81.111316 -369.899811)
			(xy 81.119056 -369.918523) (xy 81.119472 -369.928648) (xy 81.119472 -370.086128) (xy 81.119875 -370.095316)
			(xy 81.126394 -370.1125) (xy 81.132172 -370.119656) (xy 81.154025 -370.14533) (xy 81.192116 -370.200963)
			(xy 81.223269 -370.260758) (xy 81.247035 -370.323853) (xy 81.263072 -370.389342) (xy 81.271149 -370.456279)
			(xy 81.27115 -370.523703) (xy 84.548686 -370.523703) (xy 84.548687 -370.456279) (xy 84.556763 -370.389341)
			(xy 84.572799 -370.323851) (xy 84.596563 -370.260754) (xy 84.627713 -370.200957) (xy 84.665801 -370.145322)
			(xy 84.687664 -370.119656) (xy 84.69347 -370.112518) (xy 84.699977 -370.095322) (xy 84.700364 -370.086128)
			(xy 84.700364 -369.928902) (xy 84.700829 -369.918772) (xy 84.708561 -369.900047) (xy 84.722854 -369.88569)
			(xy 84.741545 -369.877875) (xy 84.751672 -369.87734) (xy 85.467952 -369.87734) (xy 85.478076 -369.877756)
			(xy 85.496787 -369.885496) (xy 85.511104 -369.899813) (xy 85.518844 -369.918524) (xy 85.51926 -369.928648)
			(xy 85.51926 -370.086128) (xy 85.519666 -370.095315) (xy 85.526183 -370.112499) (xy 85.53196 -370.119656)
			(xy 85.553814 -370.14533) (xy 85.591905 -370.200963) (xy 85.623059 -370.260757) (xy 85.646825 -370.323853)
			(xy 85.662863 -370.389341) (xy 85.67094 -370.456279) (xy 85.670941 -370.523644) (xy 115.349244 -370.523644)
			(xy 115.349245 -370.456338) (xy 115.35729 -370.389516) (xy 115.373263 -370.324133) (xy 115.396936 -370.261128)
			(xy 115.427969 -370.201404) (xy 115.465917 -370.145817) (xy 115.487704 -370.120164) (xy 115.493499 -370.113018)
			(xy 115.500014 -370.095828) (xy 115.500404 -370.086636) (xy 115.500404 -369.928902) (xy 115.500934 -369.918749)
			(xy 115.508702 -369.899986) (xy 115.523056 -369.885622) (xy 115.541813 -369.877841) (xy 115.551966 -369.87734)
			(xy 116.268246 -369.87734) (xy 116.278407 -369.877796) (xy 116.297177 -369.885586) (xy 116.311541 -369.899963)
			(xy 116.319314 -369.918741) (xy 116.319808 -369.928902) (xy 116.319808 -370.086636) (xy 116.320199 -370.095825)
			(xy 116.326726 -370.11301) (xy 116.332508 -370.120164) (xy 116.354286 -370.145825) (xy 116.392238 -370.201409)
			(xy 116.423275 -370.261131) (xy 116.446951 -370.324134) (xy 116.462926 -370.389516) (xy 116.470972 -370.456338)
			(xy 116.470973 -370.523644) (xy 116.470966 -370.523703) (xy 119.749013 -370.523703) (xy 119.749014 -370.456279)
			(xy 119.757091 -370.38934) (xy 119.773128 -370.32385) (xy 119.796893 -370.260752) (xy 119.828045 -370.200956)
			(xy 119.866135 -370.145321) (xy 119.888 -370.119656) (xy 119.893798 -370.112512) (xy 119.900312 -370.09532)
			(xy 119.9007 -370.086128) (xy 119.9007 -369.928902) (xy 119.901227 -369.91878) (xy 119.908947 -369.900067)
			(xy 119.92322 -369.885712) (xy 119.941889 -369.877886) (xy 119.952008 -369.87734) (xy 120.668288 -369.87734)
			(xy 120.678446 -369.877732) (xy 120.697206 -369.885531) (xy 120.711531 -369.899938) (xy 120.719224 -369.918741)
			(xy 120.719596 -369.928902) (xy 120.719596 -370.086128) (xy 120.719993 -370.095317) (xy 120.726516 -370.112501)
			(xy 120.732296 -370.119656) (xy 120.754148 -370.145331) (xy 120.792238 -370.200964) (xy 120.823389 -370.260759)
			(xy 120.847154 -370.323854) (xy 120.863191 -370.389342) (xy 120.871267 -370.45628) (xy 120.871269 -370.523644)
			(xy 124.149308 -370.523644) (xy 124.149309 -370.456338) (xy 124.157355 -370.389513) (xy 124.173331 -370.32413)
			(xy 124.197007 -370.261125) (xy 124.228045 -370.201401) (xy 124.265998 -370.145816) (xy 124.287788 -370.120164)
			(xy 124.293581 -370.113016) (xy 124.300098 -370.095828) (xy 124.300488 -370.086636) (xy 124.300488 -369.928902)
			(xy 124.300867 -369.918724) (xy 124.30866 -369.89992) (xy 124.32306 -369.885533) (xy 124.341872 -369.877757)
			(xy 124.35205 -369.87734) (xy 125.06833 -369.87734) (xy 125.07849 -369.877809) (xy 125.09726 -369.885593)
			(xy 125.111625 -369.899967) (xy 125.119398 -369.918742) (xy 125.119892 -369.928902) (xy 125.119892 -370.086636)
			(xy 125.120286 -370.095825) (xy 125.126811 -370.113009) (xy 125.132592 -370.120164) (xy 125.154367 -370.145826)
			(xy 125.192314 -370.201412) (xy 125.223346 -370.261134) (xy 125.247018 -370.324138) (xy 125.262991 -370.389518)
			(xy 125.271036 -370.456339) (xy 125.271037 -370.523643) (xy 125.271037 -370.523644) (xy 128.549099 -370.523644)
			(xy 128.5491 -370.456338) (xy 128.557146 -370.389514) (xy 128.573121 -370.32413) (xy 128.596797 -370.261125)
			(xy 128.627834 -370.201402) (xy 128.665787 -370.145816) (xy 128.687576 -370.120164) (xy 128.693368 -370.113015)
			(xy 128.699886 -370.095828) (xy 128.700276 -370.086636) (xy 128.700276 -369.928902) (xy 128.700666 -369.918726)
			(xy 128.708458 -369.899924) (xy 128.722854 -369.885538) (xy 128.741661 -369.877759) (xy 128.751838 -369.87734)
			(xy 129.468118 -369.87734) (xy 129.478277 -369.877818) (xy 129.497047 -369.885599) (xy 129.511412 -369.89997)
			(xy 129.519185 -369.918743) (xy 129.51968 -369.928902) (xy 129.51968 -370.086636) (xy 129.520077 -370.095824)
			(xy 129.5266 -370.113008) (xy 129.53238 -370.120164) (xy 129.554155 -370.145826) (xy 129.592103 -370.201412)
			(xy 129.623136 -370.261134) (xy 129.646809 -370.324137) (xy 129.662782 -370.389518) (xy 129.670827 -370.456339)
			(xy 129.670828 -370.523643) (xy 129.670828 -370.523644) (xy 159.349153 -370.523644) (xy 159.349154 -370.456338)
			(xy 159.357199 -370.389515) (xy 159.373173 -370.324133) (xy 159.396846 -370.261128) (xy 159.427879 -370.201404)
			(xy 159.465828 -370.145816) (xy 159.487616 -370.120164) (xy 159.493412 -370.113019) (xy 159.499927 -370.095828)
			(xy 159.500316 -370.086636) (xy 159.500316 -369.928902) (xy 159.500835 -369.918747) (xy 159.508604 -369.899982)
			(xy 159.522962 -369.885618) (xy 159.541723 -369.877839) (xy 159.551878 -369.87734) (xy 160.268158 -369.87734)
			(xy 160.278327 -369.877798) (xy 160.297121 -369.88557) (xy 160.311508 -369.899945) (xy 160.319294 -369.918733)
			(xy 160.31972 -369.928902) (xy 160.31972 -370.086636) (xy 160.320109 -370.095826) (xy 160.326637 -370.11301)
			(xy 160.33242 -370.120164) (xy 160.354197 -370.145825) (xy 160.392149 -370.20141) (xy 160.423185 -370.261131)
			(xy 160.44686 -370.324135) (xy 160.462835 -370.389516) (xy 160.470881 -370.456339) (xy 160.470882 -370.523643)
			(xy 160.470875 -370.523703) (xy 163.748922 -370.523703) (xy 163.748923 -370.456279) (xy 163.757 -370.389339)
			(xy 163.773037 -370.323849) (xy 163.796803 -370.260752) (xy 163.827956 -370.200955) (xy 163.866047 -370.145321)
			(xy 163.887912 -370.119656) (xy 163.893711 -370.112513) (xy 163.900224 -370.095321) (xy 163.900612 -370.086128)
			(xy 163.900612 -369.928902) (xy 163.901127 -369.918779) (xy 163.908849 -369.900063) (xy 163.923126 -369.885708)
			(xy 163.9418 -369.877884) (xy 163.95192 -369.87734) (xy 164.6682 -369.87734) (xy 164.678359 -369.877722)
			(xy 164.697119 -369.885526) (xy 164.711444 -369.899935) (xy 164.719136 -369.918741) (xy 164.719508 -369.928902)
			(xy 164.719508 -370.086128) (xy 164.719903 -370.095317) (xy 164.726427 -370.112501) (xy 164.732208 -370.119656)
			(xy 164.75406 -370.145331) (xy 164.792148 -370.200964) (xy 164.823299 -370.260759) (xy 164.847064 -370.323855)
			(xy 164.8631 -370.389343) (xy 164.871176 -370.45628) (xy 164.871178 -370.523644) (xy 168.149241 -370.523644)
			(xy 168.149242 -370.456338) (xy 168.157287 -370.389516) (xy 168.17326 -370.324133) (xy 168.196933 -370.261128)
			(xy 168.227965 -370.201404) (xy 168.265913 -370.145817) (xy 168.2877 -370.120164) (xy 168.293494 -370.113017)
			(xy 168.30001 -370.095828) (xy 168.3004 -370.086636) (xy 168.3004 -369.928902) (xy 168.300934 -369.918749)
			(xy 168.308701 -369.899987) (xy 168.323054 -369.885623) (xy 168.341809 -369.877842) (xy 168.351962 -369.87734)
			(xy 169.068242 -369.87734) (xy 169.078403 -369.877799) (xy 169.097173 -369.885588) (xy 169.111537 -369.899964)
			(xy 169.11931 -369.918741) (xy 169.119804 -369.928902) (xy 169.119804 -370.086636) (xy 169.120196 -370.095825)
			(xy 169.126722 -370.113009) (xy 169.132504 -370.120164) (xy 169.154279 -370.145826) (xy 169.192225 -370.201412)
			(xy 169.223256 -370.261135) (xy 169.246928 -370.324138) (xy 169.2629 -370.389519) (xy 169.270945 -370.456339)
			(xy 169.270946 -370.523643) (xy 169.270946 -370.523644) (xy 172.549008 -370.523644) (xy 172.549009 -370.456338)
			(xy 172.557055 -370.389513) (xy 172.573031 -370.32413) (xy 172.596707 -370.261125) (xy 172.627745 -370.201401)
			(xy 172.665698 -370.145816) (xy 172.687488 -370.120164) (xy 172.693281 -370.113016) (xy 172.699798 -370.095828)
			(xy 172.700188 -370.086636) (xy 172.700188 -369.928902) (xy 172.700567 -369.918724) (xy 172.70836 -369.89992)
			(xy 172.72276 -369.885533) (xy 172.741572 -369.877757) (xy 172.75175 -369.87734) (xy 173.46803 -369.87734)
			(xy 173.47819 -369.877809) (xy 173.49696 -369.885593) (xy 173.511325 -369.899967) (xy 173.519098 -369.918742)
			(xy 173.519592 -369.928902) (xy 173.519592 -370.086636) (xy 173.519986 -370.095825) (xy 173.526511 -370.113009)
			(xy 173.532292 -370.120164) (xy 173.554067 -370.145826) (xy 173.592014 -370.201412) (xy 173.623046 -370.261134)
			(xy 173.646718 -370.324138) (xy 173.662691 -370.389518) (xy 173.670736 -370.456339) (xy 173.670737 -370.523643)
			(xy 173.662694 -370.590464) (xy 173.646724 -370.655845) (xy 173.623054 -370.718849) (xy 173.592023 -370.778573)
			(xy 173.554078 -370.834159) (xy 173.532292 -370.859812) (xy 173.526507 -370.866965) (xy 173.519986 -370.88415)
			(xy 173.519592 -370.89334) (xy 173.519592 -370.901722) (xy 204.470508 -370.901722) (xy 204.470508 -367.316004)
			(xy 204.470934 -367.305935) (xy 204.478654 -367.287337) (xy 204.485494 -367.279936) (xy 204.682344 -367.083086)
			(xy 204.689733 -367.076232) (xy 204.708341 -367.068521) (xy 204.718412 -367.0681) (xy 208.051146 -367.0681)
			(xy 208.061216 -367.068527) (xy 208.079815 -367.076244) (xy 208.087214 -367.083086) (xy 208.263998 -367.25987)
			(xy 208.270817 -367.267287) (xy 208.278549 -367.285873) (xy 208.278984 -367.295938) (xy 208.278984 -370.103908)
			(xy 208.279552 -370.116248) (xy 208.288818 -370.13912) (xy 208.297018 -370.148358) (xy 208.297526 -370.148866)
			(xy 208.34985 -370.20119) (xy 208.35903 -370.209654) (xy 208.382078 -370.219214) (xy 208.394554 -370.219732)
			(xy 208.738724 -370.219732) (xy 208.748796 -370.220137) (xy 208.767394 -370.227871) (xy 208.774792 -370.234718)
			(xy 209.51444 -370.974366) (xy 209.523615 -370.982837) (xy 209.546667 -370.99239) (xy 209.559144 -370.992908)
			(xy 210.018376 -370.992908) (xy 210.028444 -370.993344) (xy 210.047042 -371.001057) (xy 210.054444 -371.007894)
			(xy 210.21421 -371.16766) (xy 210.221026 -371.175079) (xy 210.228759 -371.193664) (xy 210.229196 -371.203728)
			(xy 210.229196 -371.61724) (xy 210.229798 -371.629697) (xy 210.239356 -371.652707) (xy 210.247738 -371.661944)
			(xy 210.379056 -371.793262) (xy 210.379564 -371.79377) (xy 210.388781 -371.802003) (xy 210.411665 -371.811276)
			(xy 210.424014 -371.811804) (xy 216.605104 -371.811804) (xy 216.617445 -371.811237) (xy 216.640316 -371.801971)
			(xy 216.649554 -371.79377) (xy 216.650062 -371.793262) (xy 217.67927 -370.764054) (xy 217.679778 -370.763546)
			(xy 217.688008 -370.754327) (xy 217.697282 -370.731444) (xy 217.697812 -370.719096) (xy 217.697812 -367.36528)
			(xy 217.698224 -367.355209) (xy 217.705954 -367.336611) (xy 217.712798 -367.329212) (xy 217.96883 -367.073434)
			(xy 217.97623 -367.066593) (xy 217.994829 -367.058873) (xy 218.004898 -367.058448) (xy 221.295214 -367.058448)
			(xy 221.305259 -367.058823) (xy 221.323856 -367.066407) (xy 221.331282 -367.07318) (xy 221.508066 -367.249964)
			(xy 221.514878 -367.257386) (xy 221.522615 -367.275968) (xy 221.523052 -367.286032) (xy 221.523052 -370.745258)
			(xy 221.523577 -370.757603) (xy 221.532871 -370.780476) (xy 221.541086 -370.789708) (xy 221.541594 -370.790216)
			(xy 221.701614 -370.950236) (xy 221.708464 -370.957628) (xy 221.716177 -370.976233) (xy 221.7166 -370.986304)
			(xy 221.7166 -373.574564) (xy 221.71724 -373.587017) (xy 221.726771 -373.610028) (xy 221.735142 -373.619268)
			(xy 223.603312 -375.487438) (xy 223.6125 -375.495892) (xy 223.635542 -375.505456) (xy 223.648016 -375.50598)
			(xy 225.569526 -375.50598) (xy 225.581983 -375.505377) (xy 225.604994 -375.49582) (xy 225.61423 -375.487438)
			(xy 226.890326 -374.211342) (xy 226.890834 -374.210834) (xy 226.899064 -374.201614) (xy 226.90834 -374.178732)
			(xy 226.908868 -374.166384) (xy 226.908868 -372.704106) (xy 226.909279 -372.694035) (xy 226.917008 -372.675436)
			(xy 226.923854 -372.668038) (xy 228.193346 -371.3988) (xy 228.201796 -371.389609) (xy 228.211362 -371.366569)
			(xy 228.211888 -371.354096) (xy 228.211888 -370.983256) (xy 228.212267 -370.973181) (xy 228.220018 -370.954582)
			(xy 228.226874 -370.947188) (xy 228.380798 -370.793264) (xy 228.389257 -370.78408) (xy 228.398819 -370.761035)
			(xy 228.39934 -370.74856) (xy 228.39934 -367.292382) (xy 228.399715 -367.282337) (xy 228.4073 -367.263741)
			(xy 228.414072 -367.256314) (xy 228.600508 -367.069878) (xy 228.607909 -367.063039) (xy 228.626508 -367.055319)
			(xy 228.636576 -367.054892) (xy 231.959912 -367.054892) (xy 231.969985 -367.055287) (xy 231.988584 -367.063026)
			(xy 231.99598 -367.069878) (xy 232.182416 -367.256314) (xy 232.1891 -367.263803) (xy 232.196697 -367.282356)
			(xy 232.197148 -367.292382) (xy 232.197148 -370.755164) (xy 232.197775 -370.767618) (xy 232.207314 -370.79063)
			(xy 232.21569 -370.799868) (xy 232.35031 -370.934234) (xy 232.357159 -370.941627) (xy 232.364873 -370.960232)
			(xy 232.365296 -370.970302) (xy 232.365296 -371.212364) (xy 232.365833 -371.224708) (xy 232.37512 -371.247579)
			(xy 232.38333 -371.256814) (xy 232.383838 -371.257322) (xy 233.100118 -371.973602) (xy 233.106954 -371.981005)
			(xy 233.114675 -371.999602) (xy 233.115104 -372.00967) (xy 233.115104 -375.498868) (xy 233.115741 -375.511321)
			(xy 233.125274 -375.534332) (xy 233.133646 -375.543572) (xy 233.841798 -376.251724) (xy 235.85424 -376.251724)
			(xy 235.85424 -368.653314) (xy 235.854662 -368.643244) (xy 235.862384 -368.624646) (xy 235.869226 -368.617246)
			(xy 236.22889 -368.257582) (xy 236.236297 -368.250752) (xy 236.254891 -368.243027) (xy 236.264958 -368.242596)
			(xy 242.047014 -368.242596) (xy 242.057087 -368.242989) (xy 242.075686 -368.25073) (xy 242.083082 -368.257582)
			(xy 242.35029 -368.52479) (xy 242.357117 -368.532201) (xy 242.364845 -368.550792) (xy 242.365276 -368.560858)
			(xy 242.365276 -376.144028) (xy 242.364736 -376.155236) (xy 242.355238 -376.175537) (xy 242.346988 -376.183144)
			(xy 242.273836 -376.244104) (xy 242.269772 -376.247914) (xy 241.986816 -376.53087) (xy 241.986562 -376.531124)
			(xy 241.978942 -376.540522) (xy 241.91849 -376.631454) (xy 241.910997 -376.641545) (xy 241.888878 -376.653411)
			(xy 241.876326 -376.65406) (xy 236.25683 -376.65406) (xy 236.246761 -376.653629) (xy 236.228163 -376.645913)
			(xy 236.220762 -376.639074) (xy 235.869226 -376.287792) (xy 235.862394 -376.280386) (xy 235.854669 -376.261791)
			(xy 235.85424 -376.251724) (xy 233.841798 -376.251724) (xy 234.964478 -377.374404) (xy 242.49126 -377.374404)
			(xy 242.49126 -368.547142) (xy 242.491691 -368.537073) (xy 242.499406 -368.518474) (xy 242.506246 -368.511074)
			(xy 242.759738 -368.257582) (xy 242.767129 -368.25073) (xy 242.785735 -368.243018) (xy 242.795806 -368.242596)
			(xy 265.583924 -368.242596) (xy 265.593998 -368.242984) (xy 265.612597 -368.250728) (xy 265.619992 -368.257582)
			(xy 266.105894 -368.743484) (xy 266.112719 -368.750896) (xy 266.120448 -368.769486) (xy 266.12088 -368.779552)
			(xy 266.12088 -370.523704) (xy 286.928752 -370.523704) (xy 286.928753 -370.456278) (xy 286.936831 -370.389338)
			(xy 286.952869 -370.323848) (xy 286.976637 -370.26075) (xy 287.007792 -370.200954) (xy 287.045885 -370.14532)
			(xy 287.067752 -370.119656) (xy 287.073556 -370.112516) (xy 287.080065 -370.095321) (xy 287.080452 -370.086128)
			(xy 287.080452 -369.928902) (xy 287.080929 -369.918774) (xy 287.088658 -369.900051) (xy 287.102947 -369.885694)
			(xy 287.121634 -369.877877) (xy 287.13176 -369.87734) (xy 287.84804 -369.87734) (xy 287.85817 -369.877684)
			(xy 287.876882 -369.885453) (xy 287.891196 -369.899792) (xy 287.898933 -369.918517) (xy 287.899348 -369.928648)
			(xy 287.899348 -370.086128) (xy 287.899756 -370.095315) (xy 287.906273 -370.112499) (xy 287.912048 -370.119656)
			(xy 287.933902 -370.14533) (xy 287.971994 -370.200962) (xy 288.003149 -370.260757) (xy 288.026916 -370.323852)
			(xy 288.042954 -370.389341) (xy 288.051031 -370.456279) (xy 288.051032 -370.523644) (xy 291.329071 -370.523644)
			(xy 291.329073 -370.456338) (xy 291.337118 -370.389515) (xy 291.353092 -370.324132) (xy 291.376766 -370.261127)
			(xy 291.407801 -370.201403) (xy 291.445751 -370.145816) (xy 291.46754 -370.120164) (xy 291.473339 -370.113021)
			(xy 291.479851 -370.095829) (xy 291.48024 -370.086636) (xy 291.48024 -369.928902) (xy 291.480665 -369.91873)
			(xy 291.48845 -369.899935) (xy 291.502835 -369.88555) (xy 291.52163 -369.877765) (xy 291.531802 -369.87734)
			(xy 292.248082 -369.87734) (xy 292.258253 -369.877778) (xy 292.277047 -369.885558) (xy 292.291433 -369.899939)
			(xy 292.299218 -369.918731) (xy 292.299644 -369.928902) (xy 292.299644 -370.086636) (xy 292.30005 -370.095823)
			(xy 292.306568 -370.113007) (xy 292.312344 -370.120164) (xy 292.33412 -370.145826) (xy 292.372071 -370.20141)
			(xy 292.403105 -370.261132) (xy 292.426779 -370.324136) (xy 292.442754 -370.389517) (xy 292.450799 -370.456339)
			(xy 292.4508 -370.523643) (xy 292.450793 -370.523704) (xy 295.72884 -370.523704) (xy 295.728841 -370.456278)
			(xy 295.736918 -370.389339) (xy 295.752956 -370.323848) (xy 295.776723 -370.260751) (xy 295.807878 -370.200955)
			(xy 295.84597 -370.145321) (xy 295.867836 -370.119656) (xy 295.873638 -370.112515) (xy 295.880149 -370.095321)
			(xy 295.880536 -370.086128) (xy 295.880536 -369.928902) (xy 295.881028 -369.918776) (xy 295.888755 -369.900056)
			(xy 295.903039 -369.885699) (xy 295.92172 -369.877879) (xy 295.931844 -369.87734) (xy 296.648124 -369.87734)
			(xy 296.658285 -369.877703) (xy 296.677045 -369.885514) (xy 296.691369 -369.899929) (xy 296.699061 -369.918739)
			(xy 296.699432 -369.928902) (xy 296.699432 -370.086128) (xy 296.699844 -370.095315) (xy 296.706358 -370.112498)
			(xy 296.712132 -370.119656) (xy 296.733983 -370.145332) (xy 296.77207 -370.200965) (xy 296.803219 -370.26076)
			(xy 296.826983 -370.323856) (xy 296.843018 -370.389343) (xy 296.851095 -370.45628) (xy 296.851096 -370.523702)
			(xy 296.851096 -370.523704) (xy 300.128631 -370.523704) (xy 300.128632 -370.456278) (xy 300.136709 -370.389339)
			(xy 300.152747 -370.323849) (xy 300.176513 -370.260751) (xy 300.207667 -370.200955) (xy 300.245758 -370.145321)
			(xy 300.267624 -370.119656) (xy 300.273425 -370.112514) (xy 300.279936 -370.095321) (xy 300.280324 -370.086128)
			(xy 300.280324 -369.928902) (xy 300.280828 -369.918777) (xy 300.288552 -369.900059) (xy 300.302833 -369.885704)
			(xy 300.32151 -369.877882) (xy 300.331632 -369.87734) (xy 301.047912 -369.87734) (xy 301.058072 -369.877712)
			(xy 301.076832 -369.885519) (xy 301.091157 -369.899932) (xy 301.098849 -369.91874) (xy 301.09922 -369.928902)
			(xy 301.09922 -370.086128) (xy 301.099612 -370.095317) (xy 301.106138 -370.112502) (xy 301.11192 -370.119656)
			(xy 301.133771 -370.145331) (xy 301.171859 -370.200965) (xy 301.203009 -370.26076) (xy 301.226773 -370.323855)
			(xy 301.242809 -370.389343) (xy 301.250886 -370.45628) (xy 301.250887 -370.523644) (xy 330.92919 -370.523644)
			(xy 330.929191 -370.456338) (xy 330.937237 -370.389514) (xy 330.953212 -370.324131) (xy 330.976887 -370.261126)
			(xy 331.007923 -370.201402) (xy 331.045875 -370.145816) (xy 331.067664 -370.120164) (xy 331.073466 -370.113023)
			(xy 331.079976 -370.095829) (xy 331.080364 -370.086636) (xy 331.080364 -369.928902) (xy 331.080766 -369.918727)
			(xy 331.088555 -369.899928) (xy 331.102948 -369.885542) (xy 331.121751 -369.877761) (xy 331.131926 -369.87734)
			(xy 331.848206 -369.87734) (xy 331.858364 -369.877829) (xy 331.877134 -369.885605) (xy 331.891499 -369.899973)
			(xy 331.899273 -369.918744) (xy 331.899768 -369.928902) (xy 331.899768 -370.086636) (xy 331.900168 -370.095824)
			(xy 331.90669 -370.113008) (xy 331.912468 -370.120164) (xy 331.934244 -370.145826) (xy 331.972193 -370.201411)
			(xy 332.003226 -370.261133) (xy 332.026899 -370.324137) (xy 332.042873 -370.389518) (xy 332.050918 -370.456339)
			(xy 332.050919 -370.523643) (xy 332.050912 -370.523703) (xy 335.328983 -370.523703) (xy 335.328984 -370.456279)
			(xy 335.33706 -370.389341) (xy 335.353096 -370.323852) (xy 335.376859 -370.260754) (xy 335.408009 -370.200957)
			(xy 335.446097 -370.145322) (xy 335.46796 -370.119656) (xy 335.473765 -370.112517) (xy 335.480273 -370.095322)
			(xy 335.48066 -370.086128) (xy 335.48066 -369.928902) (xy 335.481129 -369.918773) (xy 335.48886 -369.900048)
			(xy 335.503152 -369.885691) (xy 335.521841 -369.877875) (xy 335.531968 -369.87734) (xy 336.248248 -369.87734)
			(xy 336.25841 -369.877683) (xy 336.277171 -369.885502) (xy 336.291494 -369.899923) (xy 336.299185 -369.918737)
			(xy 336.299556 -369.928902) (xy 336.299556 -370.086128) (xy 336.299963 -370.095315) (xy 336.30648 -370.112499)
			(xy 336.312256 -370.119656) (xy 336.33411 -370.14533) (xy 336.372202 -370.200962) (xy 336.403355 -370.260757)
			(xy 336.427122 -370.323853) (xy 336.44316 -370.389341) (xy 336.451237 -370.456279) (xy 336.451238 -370.523644)
			(xy 339.729277 -370.523644) (xy 339.729279 -370.456338) (xy 339.737324 -370.389514) (xy 339.753299 -370.324131)
			(xy 339.776973 -370.261126) (xy 339.808008 -370.201402) (xy 339.845959 -370.145816) (xy 339.867748 -370.120164)
			(xy 339.873548 -370.113022) (xy 339.880059 -370.095829) (xy 339.880448 -370.086636) (xy 339.880448 -369.928902)
			(xy 339.880866 -369.918729) (xy 339.888652 -369.899933) (xy 339.903039 -369.885547) (xy 339.921837 -369.877764)
			(xy 339.93201 -369.87734) (xy 340.64829 -369.87734) (xy 340.658461 -369.877772) (xy 340.677256 -369.885554)
			(xy 340.691641 -369.899937) (xy 340.699426 -369.918731) (xy 340.699852 -369.928902) (xy 340.699852 -370.086636)
			(xy 340.700256 -370.095824) (xy 340.706775 -370.113007) (xy 340.712552 -370.120164) (xy 340.734328 -370.145826)
			(xy 340.772278 -370.201411) (xy 340.803312 -370.261133) (xy 340.826986 -370.324136) (xy 340.84296 -370.389517)
			(xy 340.851005 -370.456339) (xy 340.851006 -370.523643) (xy 340.851006 -370.523644) (xy 344.129068 -370.523644)
			(xy 344.129069 -370.456338) (xy 344.137115 -370.389515) (xy 344.153089 -370.324132) (xy 344.176763 -370.261127)
			(xy 344.207797 -370.201403) (xy 344.245748 -370.145816) (xy 344.267536 -370.120164) (xy 344.273335 -370.113021)
			(xy 344.279847 -370.095829) (xy 344.280236 -370.086636) (xy 344.280236 -369.928902) (xy 344.280735 -369.918745)
			(xy 344.288508 -369.899976) (xy 344.302873 -369.885611) (xy 344.321641 -369.877836) (xy 344.331798 -369.87734)
			(xy 345.048078 -369.87734) (xy 345.058248 -369.877782) (xy 345.077043 -369.88556) (xy 345.091429 -369.89994)
			(xy 345.099214 -369.918732) (xy 345.09964 -369.928902) (xy 345.09964 -370.086636) (xy 345.100046 -370.095823)
			(xy 345.106564 -370.113007) (xy 345.11234 -370.120164) (xy 345.134116 -370.145826) (xy 345.172067 -370.20141)
			(xy 345.203102 -370.261132) (xy 345.226776 -370.324136) (xy 345.242751 -370.389517) (xy 345.250796 -370.456339)
			(xy 345.250797 -370.523643) (xy 345.250797 -370.523644) (xy 374.929099 -370.523644) (xy 374.9291 -370.456338)
			(xy 374.937146 -370.389514) (xy 374.953121 -370.32413) (xy 374.976797 -370.261125) (xy 375.007834 -370.201402)
			(xy 375.045787 -370.145816) (xy 375.067576 -370.120164) (xy 375.073368 -370.113015) (xy 375.079886 -370.095828)
			(xy 375.080276 -370.086636) (xy 375.080276 -369.928902) (xy 375.080666 -369.918726) (xy 375.088458 -369.899924)
			(xy 375.102854 -369.885538) (xy 375.121661 -369.877759) (xy 375.131838 -369.87734) (xy 375.848118 -369.87734)
			(xy 375.858277 -369.877818) (xy 375.877047 -369.885599) (xy 375.891412 -369.89997) (xy 375.899185 -369.918743)
			(xy 375.89968 -369.928902) (xy 375.89968 -370.086636) (xy 375.900077 -370.095824) (xy 375.9066 -370.113008)
			(xy 375.91238 -370.120164) (xy 375.934155 -370.145826) (xy 375.972103 -370.201412) (xy 376.003136 -370.261134)
			(xy 376.026809 -370.324137) (xy 376.042782 -370.389518) (xy 376.050827 -370.456339) (xy 376.050828 -370.523643)
			(xy 376.050821 -370.523703) (xy 379.328892 -370.523703) (xy 379.328893 -370.456279) (xy 379.336969 -370.38934)
			(xy 379.353005 -370.323851) (xy 379.376769 -370.260754) (xy 379.40792 -370.200957) (xy 379.446008 -370.145322)
			(xy 379.467872 -370.119656) (xy 379.473678 -370.112518) (xy 379.480185 -370.095322) (xy 379.480572 -370.086128)
			(xy 379.480572 -369.928902) (xy 379.481029 -369.918772) (xy 379.488762 -369.900044) (xy 379.503058 -369.885687)
			(xy 379.521752 -369.877873) (xy 379.53188 -369.87734) (xy 380.24816 -369.87734) (xy 380.258316 -369.877755)
			(xy 380.277076 -369.885545) (xy 380.291402 -369.899945) (xy 380.299096 -369.918743) (xy 380.299468 -369.928902)
			(xy 380.299468 -370.086128) (xy 380.299872 -370.095316) (xy 380.306391 -370.1125) (xy 380.312168 -370.119656)
			(xy 380.334021 -370.14533) (xy 380.372112 -370.200963) (xy 380.403265 -370.260758) (xy 380.427032 -370.323853)
			(xy 380.443069 -370.389342) (xy 380.451146 -370.456279) (xy 380.451147 -370.523644) (xy 383.729187 -370.523644)
			(xy 383.729188 -370.456338) (xy 383.737234 -370.389514) (xy 383.753209 -370.324131) (xy 383.776884 -370.261126)
			(xy 383.807919 -370.201402) (xy 383.845871 -370.145816) (xy 383.86766 -370.120164) (xy 383.873462 -370.113023)
			(xy 383.879972 -370.095829) (xy 383.88036 -370.086636) (xy 383.88036 -369.928902) (xy 383.880766 -369.918728)
			(xy 383.888554 -369.899929) (xy 383.902946 -369.885543) (xy 383.921748 -369.877762) (xy 383.931922 -369.87734)
			(xy 384.648202 -369.87734) (xy 384.65836 -369.877832) (xy 384.67713 -369.885607) (xy 384.691495 -369.899974)
			(xy 384.699269 -369.918744) (xy 384.699764 -369.928902) (xy 384.699764 -370.086636) (xy 384.700165 -370.095824)
			(xy 384.706686 -370.113008) (xy 384.712464 -370.120164) (xy 384.73424 -370.145826) (xy 384.772189 -370.201411)
			(xy 384.803222 -370.261133) (xy 384.826895 -370.324137) (xy 384.842869 -370.389518) (xy 384.850914 -370.456339)
			(xy 384.850915 -370.523643) (xy 384.850915 -370.523644) (xy 388.128977 -370.523644) (xy 388.128979 -370.456338)
			(xy 388.137024 -370.389514) (xy 388.152999 -370.324131) (xy 388.176673 -370.261126) (xy 388.207708 -370.201402)
			(xy 388.245659 -370.145816) (xy 388.267448 -370.120164) (xy 388.273248 -370.113022) (xy 388.279759 -370.095829)
			(xy 388.280148 -370.086636) (xy 388.280148 -369.928902) (xy 388.280566 -369.918729) (xy 388.288352 -369.899933)
			(xy 388.302739 -369.885547) (xy 388.321537 -369.877764) (xy 388.33171 -369.87734) (xy 389.04799 -369.87734)
			(xy 389.058161 -369.877772) (xy 389.076956 -369.885554) (xy 389.091341 -369.899937) (xy 389.099126 -369.918731)
			(xy 389.099552 -369.928902) (xy 389.099552 -370.086636) (xy 389.099956 -370.095824) (xy 389.106475 -370.113007)
			(xy 389.112252 -370.120164) (xy 389.134028 -370.145826) (xy 389.171978 -370.201411) (xy 389.203012 -370.261133)
			(xy 389.226686 -370.324136) (xy 389.24266 -370.389517) (xy 389.250705 -370.456339) (xy 389.250706 -370.523643)
			(xy 389.250706 -370.523644) (xy 418.929008 -370.523644) (xy 418.929009 -370.456338) (xy 418.937055 -370.389513)
			(xy 418.953031 -370.32413) (xy 418.976707 -370.261125) (xy 419.007745 -370.201401) (xy 419.045698 -370.145816)
			(xy 419.067488 -370.120164) (xy 419.073281 -370.113016) (xy 419.079798 -370.095828) (xy 419.080188 -370.086636)
			(xy 419.080188 -369.928902) (xy 419.080567 -369.918724) (xy 419.08836 -369.89992) (xy 419.10276 -369.885533)
			(xy 419.121572 -369.877757) (xy 419.13175 -369.87734) (xy 419.84803 -369.87734) (xy 419.85819 -369.877809)
			(xy 419.87696 -369.885593) (xy 419.891325 -369.899967) (xy 419.899098 -369.918742) (xy 419.899592 -369.928902)
			(xy 419.899592 -370.086636) (xy 419.899986 -370.095825) (xy 419.906511 -370.113009) (xy 419.912292 -370.120164)
			(xy 419.934067 -370.145826) (xy 419.972014 -370.201412) (xy 420.003046 -370.261134) (xy 420.026718 -370.324138)
			(xy 420.042691 -370.389518) (xy 420.050736 -370.456339) (xy 420.050737 -370.523643) (xy 420.05073 -370.523703)
			(xy 423.328801 -370.523703) (xy 423.328802 -370.456279) (xy 423.336878 -370.38934) (xy 423.352915 -370.323851)
			(xy 423.37668 -370.260753) (xy 423.407831 -370.200957) (xy 423.44592 -370.145322) (xy 423.467784 -370.119656)
			(xy 423.47358 -370.11251) (xy 423.480095 -370.09532) (xy 423.480484 -370.086128) (xy 423.480484 -369.928902)
			(xy 423.48093 -369.91877) (xy 423.488665 -369.900041) (xy 423.502964 -369.885683) (xy 423.521662 -369.877871)
			(xy 423.531792 -369.87734) (xy 424.248072 -369.87734) (xy 424.258198 -369.87774) (xy 424.276908 -369.885486)
			(xy 424.291225 -369.899808) (xy 424.298964 -369.918522) (xy 424.29938 -369.928648) (xy 424.29938 -370.086128)
			(xy 424.299781 -370.095316) (xy 424.306302 -370.1125) (xy 424.31208 -370.119656) (xy 424.333933 -370.145331)
			(xy 424.372023 -370.200963) (xy 424.403176 -370.260758) (xy 424.426941 -370.323854) (xy 424.442978 -370.389342)
			(xy 424.451055 -370.456279) (xy 424.451056 -370.523644) (xy 427.729096 -370.523644) (xy 427.729097 -370.456338)
			(xy 427.737143 -370.389514) (xy 427.753118 -370.32413) (xy 427.776794 -370.261125) (xy 427.80783 -370.201402)
			(xy 427.845783 -370.145816) (xy 427.867572 -370.120164) (xy 427.873375 -370.113024) (xy 427.879884 -370.095829)
			(xy 427.880272 -370.086636) (xy 427.880272 -369.928902) (xy 427.880666 -369.918726) (xy 427.888457 -369.899925)
			(xy 427.902852 -369.885539) (xy 427.921658 -369.87776) (xy 427.931834 -369.87734) (xy 428.648114 -369.87734)
			(xy 428.658273 -369.877822) (xy 428.677043 -369.885602) (xy 428.691407 -369.899971) (xy 428.699181 -369.918743)
			(xy 428.699676 -369.928902) (xy 428.699676 -370.086636) (xy 428.700074 -370.095824) (xy 428.706597 -370.113008)
			(xy 428.712376 -370.120164) (xy 428.734152 -370.145826) (xy 428.7721 -370.201411) (xy 428.803133 -370.261134)
			(xy 428.826806 -370.324137) (xy 428.842779 -370.389518) (xy 428.850824 -370.456339) (xy 428.850825 -370.523643)
			(xy 428.850825 -370.523644) (xy 432.128887 -370.523644) (xy 432.128888 -370.456338) (xy 432.136934 -370.389514)
			(xy 432.152909 -370.324131) (xy 432.176584 -370.261126) (xy 432.207619 -370.201402) (xy 432.245571 -370.145816)
			(xy 432.26736 -370.120164) (xy 432.273162 -370.113023) (xy 432.279672 -370.095829) (xy 432.28006 -370.086636)
			(xy 432.28006 -369.928902) (xy 432.280466 -369.918728) (xy 432.288254 -369.899929) (xy 432.302646 -369.885543)
			(xy 432.321448 -369.877762) (xy 432.331622 -369.87734) (xy 433.047902 -369.87734) (xy 433.05806 -369.877832)
			(xy 433.07683 -369.885607) (xy 433.091195 -369.899974) (xy 433.098969 -369.918744) (xy 433.099464 -369.928902)
			(xy 433.099464 -370.086636) (xy 433.099865 -370.095824) (xy 433.106386 -370.113008) (xy 433.112164 -370.120164)
			(xy 433.13394 -370.145826) (xy 433.171889 -370.201411) (xy 433.202922 -370.261133) (xy 433.226595 -370.324137)
			(xy 433.242569 -370.389518) (xy 433.250614 -370.456339) (xy 433.250615 -370.523643) (xy 433.242572 -370.590465)
			(xy 433.226601 -370.655846) (xy 433.20293 -370.71885) (xy 433.171898 -370.778573) (xy 433.133951 -370.83416)
			(xy 433.112164 -370.859812) (xy 433.106375 -370.866963) (xy 433.099857 -370.884149) (xy 433.099464 -370.89334)
			(xy 433.099464 -371.386862) (xy 433.099901 -371.396046) (xy 433.106397 -371.41323) (xy 433.112164 -371.42039)
			(xy 433.133966 -371.446031) (xy 433.171914 -371.501619) (xy 433.202946 -371.561344) (xy 433.226383 -371.623725)
			(xy 434.329029 -371.623725) (xy 434.329032 -371.556418) (xy 434.33708 -371.489593) (xy 434.353056 -371.424209)
			(xy 434.376732 -371.361203) (xy 434.407768 -371.301478) (xy 434.445719 -371.245891) (xy 434.467508 -371.220238)
			(xy 434.473314 -371.2131) (xy 434.479823 -371.195904) (xy 434.480208 -371.18671) (xy 434.480208 -371.028722)
			(xy 434.48075 -371.018569) (xy 434.488512 -370.999806) (xy 434.502863 -370.985441) (xy 434.521618 -370.977661)
			(xy 434.53177 -370.97716) (xy 435.24805 -370.97716) (xy 435.258221 -370.977605) (xy 435.277019 -370.985378)
			(xy 435.291406 -370.999758) (xy 435.299189 -371.018551) (xy 435.299612 -371.028722) (xy 435.299612 -371.18671)
			(xy 435.300015 -371.195898) (xy 435.306533 -371.213082) (xy 435.312312 -371.220238) (xy 435.334064 -371.24592)
			(xy 435.372017 -371.301501) (xy 435.403055 -371.36122) (xy 435.426732 -371.424221) (xy 435.442709 -371.4896)
			(xy 435.450757 -371.55642) (xy 435.45076 -371.623723) (xy 435.442719 -371.690544) (xy 435.426749 -371.755924)
			(xy 435.403078 -371.818928) (xy 435.372046 -371.87865) (xy 435.334099 -371.934235) (xy 435.312312 -371.959886)
			(xy 435.306498 -371.967019) (xy 435.299993 -371.984219) (xy 435.299612 -371.993414) (xy 435.299612 -372.486682)
			(xy 435.300028 -372.495869) (xy 435.306537 -372.513053) (xy 435.312312 -372.52021) (xy 435.334135 -372.545834)
			(xy 435.372086 -372.601423) (xy 435.40312 -372.66115) (xy 435.426793 -372.724159) (xy 435.442765 -372.789545)
			(xy 435.450807 -372.856371) (xy 435.450804 -372.92368) (xy 435.442756 -372.990506) (xy 435.426778 -373.05589)
			(xy 435.403099 -373.118896) (xy 435.372059 -373.178621) (xy 435.334103 -373.234206) (xy 435.312312 -373.259858)
			(xy 435.30651 -373.266999) (xy 435.299998 -373.284193) (xy 435.299612 -373.293386) (xy 435.299612 -373.451374)
			(xy 435.299213 -373.46155) (xy 435.291428 -373.480354) (xy 435.277034 -373.494741) (xy 435.258226 -373.502518)
			(xy 435.24805 -373.502936) (xy 434.53177 -373.502936) (xy 434.521607 -373.502491) (xy 434.502832 -373.494701)
			(xy 434.488467 -373.480321) (xy 434.480698 -373.461537) (xy 434.480208 -373.451374) (xy 434.480208 -373.293386)
			(xy 434.479803 -373.284198) (xy 434.473286 -373.267014) (xy 434.467508 -373.259858) (xy 434.445755 -373.234178)
			(xy 434.407807 -373.178595) (xy 434.376774 -373.118875) (xy 434.3531 -373.055874) (xy 434.337126 -372.990495)
			(xy 434.32908 -372.923676) (xy 434.329077 -372.856375) (xy 434.337117 -372.789555) (xy 434.353085 -372.724175)
			(xy 434.376753 -372.661172) (xy 434.40778 -372.601449) (xy 434.445723 -372.545863) (xy 434.467508 -372.52021)
			(xy 434.473326 -372.51308) (xy 434.479828 -372.495878) (xy 434.480208 -372.486682) (xy 434.480208 -371.993414)
			(xy 434.479789 -371.984228) (xy 434.473281 -371.967043) (xy 434.467508 -371.959886) (xy 434.445684 -371.934264)
			(xy 434.407738 -371.878673) (xy 434.376708 -371.818945) (xy 434.353039 -371.755936) (xy 434.33707 -371.690551)
			(xy 434.329029 -371.623725) (xy 433.226383 -371.623725) (xy 433.226618 -371.62435) (xy 433.24259 -371.689734)
			(xy 433.250633 -371.756557) (xy 433.250632 -371.823864) (xy 433.242586 -371.890687) (xy 433.226612 -371.95607)
			(xy 433.202938 -372.019075) (xy 433.171903 -372.078799) (xy 433.133953 -372.134386) (xy 433.112164 -372.160038)
			(xy 433.106364 -372.167181) (xy 433.099852 -372.184373) (xy 433.099464 -372.193566) (xy 433.099464 -372.351554)
			(xy 433.098999 -372.361722) (xy 433.091229 -372.380516) (xy 433.076856 -372.394902) (xy 433.05807 -372.402689)
			(xy 433.047902 -372.403116) (xy 432.331622 -372.403116) (xy 432.321446 -372.402717) (xy 432.302643 -372.394931)
			(xy 432.288256 -372.380537) (xy 432.280478 -372.36173) (xy 432.28006 -372.351554) (xy 432.28006 -372.193566)
			(xy 432.279653 -372.184379) (xy 432.273135 -372.167195) (xy 432.26736 -372.160038) (xy 432.245586 -372.134375)
			(xy 432.207635 -372.07879) (xy 432.1766 -372.019069) (xy 432.152925 -371.956065) (xy 432.136951 -371.890684)
			(xy 432.128905 -371.823863) (xy 432.128904 -371.756558) (xy 432.136947 -371.689736) (xy 432.152919 -371.624355)
			(xy 432.176591 -371.561351) (xy 432.207624 -371.501628) (xy 432.245573 -371.446042) (xy 432.26736 -371.42039)
			(xy 432.273151 -371.413241) (xy 432.279667 -371.396053) (xy 432.28006 -371.386862) (xy 432.28006 -370.89334)
			(xy 432.279617 -370.884157) (xy 432.273125 -370.866972) (xy 432.26736 -370.859812) (xy 432.24556 -370.83417)
			(xy 432.20761 -370.778582) (xy 432.176576 -370.718858) (xy 432.152903 -370.655852) (xy 432.136931 -370.590468)
			(xy 432.128887 -370.523644) (xy 428.850825 -370.523644) (xy 428.842782 -370.590464) (xy 428.826811 -370.655846)
			(xy 428.80314 -370.71885) (xy 428.772109 -370.778573) (xy 428.734163 -370.83416) (xy 428.712376 -370.859812)
			(xy 428.706589 -370.866964) (xy 428.700069 -370.884149) (xy 428.699676 -370.89334) (xy 428.699676 -371.386862)
			(xy 428.70011 -371.396047) (xy 428.706608 -371.413231) (xy 428.712376 -371.42039) (xy 428.734177 -371.446031)
			(xy 428.772125 -371.501619) (xy 428.803156 -371.561345) (xy 428.826615 -371.623785) (xy 429.928709 -371.623785)
			(xy 429.928713 -371.556358) (xy 429.936793 -371.489417) (xy 429.952833 -371.423925) (xy 429.976602 -371.360827)
			(xy 430.007759 -371.30103) (xy 430.045853 -371.245395) (xy 430.06772 -371.21973) (xy 430.073531 -371.212595)
			(xy 430.080036 -371.195397) (xy 430.08042 -371.186202) (xy 430.08042 -371.028722) (xy 430.080944 -371.018599)
			(xy 430.088661 -370.999882) (xy 430.102935 -370.985526) (xy 430.121608 -370.977702) (xy 430.131728 -370.97716)
			(xy 430.848008 -370.97716) (xy 430.858158 -370.977614) (xy 430.876902 -370.985405) (xy 430.891224 -370.999791)
			(xy 430.898931 -371.018571) (xy 430.899316 -371.028722) (xy 430.899316 -371.186202) (xy 430.899722 -371.19539)
			(xy 430.906238 -371.212574) (xy 430.912016 -371.21973) (xy 430.933842 -371.245426) (xy 430.971931 -371.301057)
			(xy 431.003082 -371.360849) (xy 431.026848 -371.423942) (xy 431.042886 -371.489427) (xy 431.050964 -371.556361)
			(xy 431.050968 -371.623782) (xy 431.042896 -371.690717) (xy 431.026865 -371.756204) (xy 431.003106 -371.819299)
			(xy 430.97196 -371.879094) (xy 430.933877 -371.934729) (xy 430.912016 -371.960394) (xy 430.906241 -371.967555)
			(xy 430.899713 -371.984733) (xy 430.899316 -371.993922) (xy 430.899316 -372.486174) (xy 430.899735 -372.49536)
			(xy 430.906242 -372.512545) (xy 430.912016 -372.519702) (xy 430.933913 -372.54534) (xy 430.971999 -372.600979)
			(xy 431.003148 -372.660779) (xy 431.026909 -372.723879) (xy 431.042942 -372.789371) (xy 431.051015 -372.856313)
			(xy 431.051012 -372.923739) (xy 431.042933 -372.990679) (xy 431.026894 -373.05617) (xy 431.003127 -373.119268)
			(xy 430.971973 -373.179065) (xy 430.933881 -373.2347) (xy 430.912016 -373.260366) (xy 430.906211 -373.267505)
			(xy 430.899701 -373.2847) (xy 430.899316 -373.293894) (xy 430.899316 -373.451374) (xy 430.898851 -373.461504)
			(xy 430.891124 -373.480233) (xy 430.87683 -373.494592) (xy 430.858136 -373.502405) (xy 430.848008 -373.502936)
			(xy 430.131728 -373.502936) (xy 430.12158 -373.502456) (xy 430.102835 -373.494677) (xy 430.088512 -373.480298)
			(xy 430.080805 -373.461523) (xy 430.08042 -373.451374) (xy 430.08042 -373.293894) (xy 430.080008 -373.284707)
			(xy 430.073495 -373.267523) (xy 430.06772 -373.260366) (xy 430.045889 -373.234674) (xy 430.007798 -373.179043)
			(xy 429.976644 -373.119251) (xy 429.952877 -373.056158) (xy 429.936839 -372.990672) (xy 429.92876 -372.923736)
			(xy 429.928757 -372.856315) (xy 429.93683 -372.789379) (xy 429.952862 -372.723891) (xy 429.976624 -372.660796)
			(xy 430.007771 -372.601) (xy 430.045857 -372.545367) (xy 430.06772 -372.519702) (xy 430.073501 -372.512546)
			(xy 430.080024 -372.495364) (xy 430.08042 -372.486174) (xy 430.08042 -371.993922) (xy 430.079995 -371.984737)
			(xy 430.073491 -371.967552) (xy 430.06772 -371.960394) (xy 430.045818 -371.93476) (xy 430.007729 -371.879121)
			(xy 429.976579 -371.819321) (xy 429.952816 -371.75622) (xy 429.936783 -371.690727) (xy 429.928709 -371.623785)
			(xy 428.826615 -371.623785) (xy 428.826828 -371.624351) (xy 428.842799 -371.689734) (xy 428.850842 -371.756558)
			(xy 428.850841 -371.823863) (xy 428.842795 -371.890687) (xy 428.826821 -371.95607) (xy 428.803148 -372.019075)
			(xy 428.772114 -372.078799) (xy 428.734164 -372.134386) (xy 428.712376 -372.160038) (xy 428.706578 -372.167182)
			(xy 428.700065 -372.184374) (xy 428.699676 -372.193566) (xy 428.699676 -372.351554) (xy 428.699199 -372.361721)
			(xy 428.691432 -372.380512) (xy 428.677062 -372.394898) (xy 428.65828 -372.402687) (xy 428.648114 -372.403116)
			(xy 427.931834 -372.403116) (xy 427.921659 -372.402707) (xy 427.902856 -372.394925) (xy 427.888469 -372.380534)
			(xy 427.880691 -372.361729) (xy 427.880272 -372.351554) (xy 427.880272 -372.193566) (xy 427.879884 -372.184376)
			(xy 427.873356 -372.167192) (xy 427.867572 -372.160038) (xy 427.845797 -372.134375) (xy 427.807846 -372.078791)
			(xy 427.77681 -372.019069) (xy 427.753135 -371.956066) (xy 427.73716 -371.890685) (xy 427.729114 -371.823863)
			(xy 427.729113 -371.756558) (xy 427.737156 -371.689736) (xy 427.753129 -371.624354) (xy 427.776801 -371.56135)
			(xy 427.807835 -371.501627) (xy 427.845784 -371.446042) (xy 427.867572 -371.42039) (xy 427.873364 -371.413242)
			(xy 427.879879 -371.396053) (xy 427.880272 -371.386862) (xy 427.880272 -370.89334) (xy 427.879849 -370.884154)
			(xy 427.873345 -370.866969) (xy 427.867572 -370.859812) (xy 427.845772 -370.83417) (xy 427.807821 -370.778583)
			(xy 427.776786 -370.718858) (xy 427.753113 -370.655852) (xy 427.73714 -370.590468) (xy 427.729096 -370.523644)
			(xy 424.451056 -370.523644) (xy 424.451056 -370.523703) (xy 424.442981 -370.59064) (xy 424.426947 -370.656129)
			(xy 424.403183 -370.719225) (xy 424.372033 -370.779021) (xy 424.333944 -370.834655) (xy 424.31208 -370.86032)
			(xy 424.30629 -370.86747) (xy 424.299772 -370.884657) (xy 424.29938 -370.893848) (xy 424.29938 -371.386354)
			(xy 424.299817 -371.395538) (xy 424.306312 -371.412723) (xy 424.31208 -371.419882) (xy 424.333958 -371.445536)
			(xy 424.372048 -371.501171) (xy 424.403199 -371.560969) (xy 424.426835 -371.623725) (xy 425.528941 -371.623725)
			(xy 425.528945 -371.556418) (xy 425.536992 -371.489593) (xy 425.552969 -371.424208) (xy 425.576645 -371.361202)
			(xy 425.607682 -371.301478) (xy 425.645634 -371.24589) (xy 425.667424 -371.220238) (xy 425.673232 -371.213101)
			(xy 425.679739 -371.195904) (xy 425.680124 -371.18671) (xy 425.680124 -371.028722) (xy 425.680582 -371.018554)
			(xy 425.688357 -370.999762) (xy 425.702732 -370.985377) (xy 425.721518 -370.977589) (xy 425.731686 -370.97716)
			(xy 426.447966 -370.97716) (xy 426.458138 -370.977592) (xy 426.476936 -370.98537) (xy 426.491323 -370.999754)
			(xy 426.499105 -371.01855) (xy 426.499528 -371.028722) (xy 426.499528 -371.18671) (xy 426.499927 -371.195898)
			(xy 426.506448 -371.213083) (xy 426.512228 -371.220238) (xy 426.533979 -371.24592) (xy 426.571931 -371.301502)
			(xy 426.602968 -371.361221) (xy 426.626645 -371.424221) (xy 426.642621 -371.4896) (xy 426.650669 -371.55642)
			(xy 426.650672 -371.623723) (xy 426.642631 -371.690543) (xy 426.626661 -371.755924) (xy 426.602991 -371.818927)
			(xy 426.571961 -371.878649) (xy 426.534014 -371.934234) (xy 426.512228 -371.959886) (xy 426.506404 -371.967011)
			(xy 426.499908 -371.984217) (xy 426.499528 -371.993414) (xy 426.499528 -372.486682) (xy 426.49994 -372.495869)
			(xy 426.506452 -372.513054) (xy 426.512228 -372.52021) (xy 426.53405 -372.545834) (xy 426.572 -372.601424)
			(xy 426.603034 -372.661151) (xy 426.626706 -372.724159) (xy 426.642678 -372.789545) (xy 426.65072 -372.856371)
			(xy 426.650717 -372.92368) (xy 426.642669 -372.990505) (xy 426.626691 -373.05589) (xy 426.603013 -373.118896)
			(xy 426.571974 -373.17862) (xy 426.534019 -373.234206) (xy 426.512228 -373.259858) (xy 426.506416 -373.266992)
			(xy 426.499912 -373.284191) (xy 426.499528 -373.293386) (xy 426.499528 -373.451374) (xy 426.499114 -373.461548)
			(xy 426.491331 -373.480349) (xy 426.476942 -373.494736) (xy 426.45814 -373.502515) (xy 426.447966 -373.502936)
			(xy 425.731686 -373.502936) (xy 425.72151 -373.502547) (xy 425.70271 -373.494752) (xy 425.688325 -373.480356)
			(xy 425.680545 -373.46155) (xy 425.680124 -373.451374) (xy 425.680124 -373.293386) (xy 425.679715 -373.284199)
			(xy 425.6732 -373.267015) (xy 425.667424 -373.259858) (xy 425.64567 -373.234178) (xy 425.607722 -373.178595)
			(xy 425.576688 -373.118875) (xy 425.553014 -373.055874) (xy 425.537039 -372.990496) (xy 425.528992 -372.923677)
			(xy 425.528989 -372.856375) (xy 425.53703 -372.789555) (xy 425.552999 -372.724174) (xy 425.576667 -372.661171)
			(xy 425.607695 -372.601449) (xy 425.645639 -372.545863) (xy 425.667424 -372.52021) (xy 425.673244 -372.513082)
			(xy 425.679744 -372.495878) (xy 425.680124 -372.486682) (xy 425.680124 -371.993414) (xy 425.679702 -371.984228)
			(xy 425.673196 -371.967044) (xy 425.667424 -371.959886) (xy 425.645599 -371.934264) (xy 425.607653 -371.878673)
			(xy 425.576622 -371.818945) (xy 425.552952 -371.755937) (xy 425.536982 -371.690551) (xy 425.528941 -371.623725)
			(xy 424.426835 -371.623725) (xy 424.426964 -371.624067) (xy 424.442999 -371.689558) (xy 424.451074 -371.756498)
			(xy 424.451072 -371.823923) (xy 424.442995 -371.890863) (xy 424.426957 -371.956353) (xy 424.403191 -372.01945)
			(xy 424.372037 -372.079247) (xy 424.333946 -372.134881) (xy 424.31208 -372.160546) (xy 424.306279 -372.167688)
			(xy 424.299768 -372.184881) (xy 424.29938 -372.194074) (xy 424.29938 -372.351554) (xy 424.298836 -372.361675)
			(xy 424.291127 -372.380392) (xy 424.276858 -372.394749) (xy 424.25819 -372.402573) (xy 424.248072 -372.403116)
			(xy 423.531792 -372.403116) (xy 423.521685 -372.402622) (xy 423.50301 -372.394884) (xy 423.488716 -372.38059)
			(xy 423.480978 -372.361915) (xy 423.480484 -372.351808) (xy 423.480484 -372.194074) (xy 423.48009 -372.184885)
			(xy 423.473565 -372.167701) (xy 423.467784 -372.160546) (xy 423.445934 -372.134869) (xy 423.407846 -372.079236)
			(xy 423.376696 -372.019441) (xy 423.352932 -371.956346) (xy 423.336896 -371.890858) (xy 423.328819 -371.823922)
			(xy 423.328818 -371.756499) (xy 423.336892 -371.689562) (xy 423.352925 -371.624074) (xy 423.376687 -371.560978)
			(xy 423.407835 -371.501182) (xy 423.445921 -371.445547) (xy 423.467784 -371.419882) (xy 423.473569 -371.412728)
			(xy 423.480091 -371.395544) (xy 423.480484 -371.386354) (xy 423.480484 -370.893848) (xy 423.480055 -370.884663)
			(xy 423.473555 -370.867478) (xy 423.467784 -370.86032) (xy 423.445909 -370.834664) (xy 423.407821 -370.779028)
			(xy 423.376672 -370.71923) (xy 423.352909 -370.656132) (xy 423.336875 -370.590642) (xy 423.328801 -370.523703)
			(xy 420.05073 -370.523703) (xy 420.042694 -370.590464) (xy 420.026724 -370.655845) (xy 420.003054 -370.718849)
			(xy 419.972023 -370.778573) (xy 419.934078 -370.834159) (xy 419.912292 -370.859812) (xy 419.906507 -370.866965)
			(xy 419.899986 -370.88415) (xy 419.899592 -370.89334) (xy 419.899592 -371.386862) (xy 419.900022 -371.396047)
			(xy 419.906522 -371.413231) (xy 419.912292 -371.42039) (xy 419.934093 -371.446031) (xy 419.972039 -371.50162)
			(xy 420.00307 -371.561345) (xy 420.026528 -371.623785) (xy 421.128621 -371.623785) (xy 421.128625 -371.556358)
			(xy 421.136705 -371.489416) (xy 421.152746 -371.423925) (xy 421.176516 -371.360826) (xy 421.207673 -371.301029)
			(xy 421.245769 -371.245395) (xy 421.267636 -371.21973) (xy 421.273449 -371.212597) (xy 421.279953 -371.195397)
			(xy 421.280336 -371.186202) (xy 421.280336 -371.028722) (xy 421.280844 -371.018597) (xy 421.288564 -370.999877)
			(xy 421.302844 -370.98552) (xy 421.321522 -370.9777) (xy 421.331644 -370.97716) (xy 422.047924 -370.97716)
			(xy 422.058029 -370.977664) (xy 422.076701 -370.985402) (xy 422.090993 -370.999693) (xy 422.098734 -371.018363)
			(xy 422.099232 -371.028468) (xy 422.099232 -371.186202) (xy 422.099656 -371.195387) (xy 422.106162 -371.212571)
			(xy 422.111932 -371.21973) (xy 422.133758 -371.245427) (xy 422.171845 -371.301057) (xy 422.202996 -371.36085)
			(xy 422.226761 -371.423942) (xy 422.242798 -371.489427) (xy 422.250876 -371.556361) (xy 422.25088 -371.623781)
			(xy 422.242808 -371.690717) (xy 422.226778 -371.756203) (xy 422.203019 -371.819298) (xy 422.171875 -371.879094)
			(xy 422.133793 -371.934728) (xy 422.111932 -371.960394) (xy 422.106147 -371.967547) (xy 422.099627 -371.984732)
			(xy 422.099232 -371.993922) (xy 422.099232 -372.486174) (xy 422.09967 -372.495358) (xy 422.106166 -372.512542)
			(xy 422.111932 -372.519702) (xy 422.133828 -372.54534) (xy 422.171914 -372.600979) (xy 422.203061 -372.66078)
			(xy 422.226822 -372.72388) (xy 422.242854 -372.789372) (xy 422.250927 -372.856313) (xy 422.250924 -372.923738)
			(xy 422.242845 -372.990678) (xy 422.226807 -373.056169) (xy 422.20304 -373.119267) (xy 422.171888 -373.179064)
			(xy 422.133797 -373.2347) (xy 422.111932 -373.260366) (xy 422.106117 -373.267498) (xy 422.099615 -373.284699)
			(xy 422.099232 -373.293894) (xy 422.099232 -373.451374) (xy 422.098751 -373.461503) (xy 422.091027 -373.480228)
			(xy 422.076738 -373.494587) (xy 422.05805 -373.502402) (xy 422.047924 -373.502936) (xy 421.331644 -373.502936)
			(xy 421.321529 -373.502449) (xy 421.302833 -373.494722) (xy 421.288519 -373.480427) (xy 421.280765 -373.461743)
			(xy 421.280336 -373.451628) (xy 421.280336 -373.293894) (xy 421.279921 -373.284708) (xy 421.27341 -373.267524)
			(xy 421.267636 -373.260366) (xy 421.245804 -373.234674) (xy 421.207712 -373.179044) (xy 421.176558 -373.119252)
			(xy 421.15279 -373.056158) (xy 421.136751 -372.990672) (xy 421.128672 -372.923736) (xy 421.128669 -372.856315)
			(xy 421.136742 -372.789378) (xy 421.152775 -372.72389) (xy 421.176537 -372.660795) (xy 421.207686 -372.601)
			(xy 421.245773 -372.545367) (xy 421.267636 -372.519702) (xy 421.273419 -372.512547) (xy 421.279941 -372.495364)
			(xy 421.280336 -372.486174) (xy 421.280336 -371.993922) (xy 421.279907 -371.984737) (xy 421.273406 -371.967553)
			(xy 421.267636 -371.960394) (xy 421.245733 -371.93476) (xy 421.207643 -371.879122) (xy 421.176492 -371.819322)
			(xy 421.152729 -371.756221) (xy 421.136695 -371.690727) (xy 421.128621 -371.623785) (xy 420.026528 -371.623785)
			(xy 420.026741 -371.624351) (xy 420.042712 -371.689734) (xy 420.050754 -371.756558) (xy 420.050753 -371.823863)
			(xy 420.042708 -371.890686) (xy 420.026734 -371.956069) (xy 420.003061 -372.019074) (xy 419.972028 -372.078798)
			(xy 419.93408 -372.134385) (xy 419.912292 -372.160038) (xy 419.906496 -372.167183) (xy 419.899981 -372.184374)
			(xy 419.899592 -372.193566) (xy 419.899592 -372.351554) (xy 419.899099 -372.361719) (xy 419.891335 -372.380507)
			(xy 419.876971 -372.394892) (xy 419.858194 -372.402684) (xy 419.84803 -372.403116) (xy 419.13175 -372.403116)
			(xy 419.121576 -372.402694) (xy 419.102773 -372.394917) (xy 419.088385 -372.38053) (xy 419.080607 -372.361728)
			(xy 419.080188 -372.351554) (xy 419.080188 -372.193566) (xy 419.079797 -372.184377) (xy 419.07327 -372.167192)
			(xy 419.067488 -372.160038) (xy 419.045713 -372.134375) (xy 419.00776 -372.078791) (xy 418.976724 -372.01907)
			(xy 418.953048 -371.956067) (xy 418.937072 -371.890685) (xy 418.929026 -371.823863) (xy 418.929025 -371.756558)
			(xy 418.937069 -371.689736) (xy 418.953042 -371.624354) (xy 418.976715 -371.561349) (xy 419.007749 -371.501627)
			(xy 419.0457 -371.446041) (xy 419.067488 -371.42039) (xy 419.07327 -371.413234) (xy 419.079794 -371.396052)
			(xy 419.080188 -371.386862) (xy 419.080188 -370.89334) (xy 419.079761 -370.884154) (xy 419.07326 -370.86697)
			(xy 419.067488 -370.859812) (xy 419.045687 -370.83417) (xy 419.007735 -370.778583) (xy 418.9767 -370.718859)
			(xy 418.953026 -370.655853) (xy 418.937052 -370.590469) (xy 418.929008 -370.523644) (xy 389.250706 -370.523644)
			(xy 389.242663 -370.590465) (xy 389.226691 -370.655847) (xy 389.203019 -370.718851) (xy 389.171987 -370.778574)
			(xy 389.134039 -370.83416) (xy 389.112252 -370.859812) (xy 389.106462 -370.866962) (xy 389.099945 -370.884149)
			(xy 389.099552 -370.89334) (xy 389.099552 -371.386862) (xy 389.099991 -371.396046) (xy 389.106486 -371.41323)
			(xy 389.112252 -371.42039) (xy 389.134054 -371.446031) (xy 389.172003 -371.501618) (xy 389.203036 -371.561344)
			(xy 389.226474 -371.623725) (xy 390.32912 -371.623725) (xy 390.329123 -371.556418) (xy 390.337171 -371.489593)
			(xy 390.353146 -371.42421) (xy 390.376822 -371.361204) (xy 390.407857 -371.301479) (xy 390.445807 -371.245891)
			(xy 390.467596 -371.220238) (xy 390.473401 -371.213099) (xy 390.479911 -371.195904) (xy 390.480296 -371.18671)
			(xy 390.480296 -371.028722) (xy 390.48085 -371.018571) (xy 390.48861 -370.99981) (xy 390.502956 -370.985446)
			(xy 390.521707 -370.977663) (xy 390.531858 -370.97716) (xy 391.248138 -370.97716) (xy 391.258301 -370.977603)
			(xy 391.277075 -370.985394) (xy 391.29144 -370.999775) (xy 391.299209 -371.018558) (xy 391.2997 -371.028722)
			(xy 391.2997 -371.18671) (xy 391.300106 -371.195898) (xy 391.306623 -371.213082) (xy 391.3124 -371.220238)
			(xy 391.334149 -371.245921) (xy 391.372097 -371.301504) (xy 391.403129 -371.361224) (xy 391.426803 -371.424224)
			(xy 391.442777 -371.489602) (xy 391.450824 -371.556421) (xy 391.450827 -371.623722) (xy 391.442787 -371.690541)
			(xy 391.42682 -371.755921) (xy 391.403153 -371.818924) (xy 391.372126 -371.878647) (xy 391.334184 -371.934233)
			(xy 391.3124 -371.959886) (xy 391.306584 -371.967018) (xy 391.300081 -371.984219) (xy 391.2997 -371.993414)
			(xy 391.2997 -372.486682) (xy 391.300119 -372.495868) (xy 391.306627 -372.513053) (xy 391.3124 -372.52021)
			(xy 391.33422 -372.545835) (xy 391.372165 -372.601426) (xy 391.403195 -372.661154) (xy 391.426864 -372.724162)
			(xy 391.442833 -372.789547) (xy 391.450874 -372.856372) (xy 391.450871 -372.923679) (xy 391.442824 -372.990503)
			(xy 391.426849 -373.055887) (xy 391.403174 -373.118893) (xy 391.372139 -373.178617) (xy 391.334189 -373.234205)
			(xy 391.3124 -373.259858) (xy 391.306596 -373.266998) (xy 391.300086 -373.284193) (xy 391.2997 -373.293386)
			(xy 391.2997 -373.451374) (xy 391.299146 -373.461525) (xy 391.291388 -373.480287) (xy 391.277041 -373.494652)
			(xy 391.258289 -373.502434) (xy 391.248138 -373.502936) (xy 390.531858 -373.502936) (xy 390.521694 -373.5025)
			(xy 390.502919 -373.494707) (xy 390.488555 -373.480324) (xy 390.480786 -373.461538) (xy 390.480296 -373.451374)
			(xy 390.480296 -373.293386) (xy 390.479893 -373.284198) (xy 390.473374 -373.267014) (xy 390.467596 -373.259858)
			(xy 390.445843 -373.234178) (xy 390.407896 -373.178594) (xy 390.376864 -373.118874) (xy 390.353191 -373.055874)
			(xy 390.337217 -372.990495) (xy 390.329171 -372.923676) (xy 390.329167 -372.856375) (xy 390.337208 -372.789555)
			(xy 390.353176 -372.724175) (xy 390.376843 -372.661173) (xy 390.40787 -372.60145) (xy 390.445812 -372.545863)
			(xy 390.467596 -372.52021) (xy 390.473413 -372.513079) (xy 390.479916 -372.495878) (xy 390.480296 -372.486682)
			(xy 390.480296 -371.993414) (xy 390.47988 -371.984227) (xy 390.47337 -371.967043) (xy 390.467596 -371.959886)
			(xy 390.445772 -371.934264) (xy 390.407827 -371.878672) (xy 390.376798 -371.818944) (xy 390.353129 -371.755936)
			(xy 390.33716 -371.69055) (xy 390.32912 -371.623725) (xy 389.226474 -371.623725) (xy 389.226709 -371.62435)
			(xy 389.242681 -371.689733) (xy 389.250724 -371.756557) (xy 389.250723 -371.823864) (xy 389.242677 -371.890687)
			(xy 389.226702 -371.956071) (xy 389.203028 -372.019076) (xy 389.171992 -372.0788) (xy 389.134041 -372.134386)
			(xy 389.112252 -372.160038) (xy 389.106451 -372.16718) (xy 389.09994 -372.184373) (xy 389.099552 -372.193566)
			(xy 389.099552 -372.351554) (xy 389.099098 -372.361724) (xy 389.091327 -372.380519) (xy 389.07695 -372.394906)
			(xy 389.05816 -372.402691) (xy 389.04799 -372.403116) (xy 388.33171 -372.403116) (xy 388.321533 -372.402727)
			(xy 388.30273 -372.394937) (xy 388.288343 -372.38054) (xy 388.280566 -372.361731) (xy 388.280148 -372.351554)
			(xy 388.280148 -372.193566) (xy 388.279743 -372.184378) (xy 388.273225 -372.167195) (xy 388.267448 -372.160038)
			(xy 388.245674 -372.134375) (xy 388.207724 -372.07879) (xy 388.17669 -372.019068) (xy 388.153016 -371.956065)
			(xy 388.137042 -371.890684) (xy 388.128996 -371.823863) (xy 388.128995 -371.756558) (xy 388.137038 -371.689737)
			(xy 388.15301 -371.624355) (xy 388.176681 -371.561351) (xy 388.207713 -371.501628) (xy 388.245661 -371.446042)
			(xy 388.267448 -371.42039) (xy 388.273237 -371.41324) (xy 388.279755 -371.396053) (xy 388.280148 -371.386862)
			(xy 388.280148 -370.89334) (xy 388.279708 -370.884156) (xy 388.273214 -370.866972) (xy 388.267448 -370.859812)
			(xy 388.245648 -370.83417) (xy 388.207699 -370.778582) (xy 388.176666 -370.718857) (xy 388.152993 -370.655851)
			(xy 388.137021 -370.590468) (xy 388.128977 -370.523644) (xy 384.850915 -370.523644) (xy 384.842872 -370.590465)
			(xy 384.826901 -370.655846) (xy 384.80323 -370.71885) (xy 384.772198 -370.778573) (xy 384.734251 -370.83416)
			(xy 384.712464 -370.859812) (xy 384.706675 -370.866963) (xy 384.700157 -370.884149) (xy 384.699764 -370.89334)
			(xy 384.699764 -371.386862) (xy 384.700201 -371.396046) (xy 384.706697 -371.41323) (xy 384.712464 -371.42039)
			(xy 384.734266 -371.446031) (xy 384.772214 -371.501619) (xy 384.803246 -371.561344) (xy 384.826706 -371.623785)
			(xy 385.9288 -371.623785) (xy 385.928804 -371.556358) (xy 385.936884 -371.489417) (xy 385.952923 -371.423926)
			(xy 385.976692 -371.360827) (xy 386.007848 -371.30103) (xy 386.045941 -371.245395) (xy 386.067808 -371.21973)
			(xy 386.073618 -371.212594) (xy 386.080124 -371.195396) (xy 386.080508 -371.186202) (xy 386.080508 -371.028722)
			(xy 386.081044 -371.018601) (xy 386.088758 -370.999886) (xy 386.103029 -370.98553) (xy 386.121698 -370.977704)
			(xy 386.131816 -370.97716) (xy 386.848096 -370.97716) (xy 386.858245 -370.977624) (xy 386.876989 -370.985411)
			(xy 386.891311 -370.999794) (xy 386.899019 -371.018571) (xy 386.899404 -371.028722) (xy 386.899404 -371.186202)
			(xy 386.899812 -371.195389) (xy 386.906327 -371.212574) (xy 386.912104 -371.21973) (xy 386.93393 -371.245426)
			(xy 386.97202 -371.301056) (xy 387.003172 -371.360848) (xy 387.026938 -371.423941) (xy 387.042976 -371.489426)
			(xy 387.051055 -371.556361) (xy 387.051059 -371.623782) (xy 387.042987 -371.690717) (xy 387.026955 -371.756204)
			(xy 387.003196 -371.8193) (xy 386.972049 -371.879095) (xy 386.933966 -371.934729) (xy 386.912104 -371.960394)
			(xy 386.906328 -371.967554) (xy 386.899801 -371.984733) (xy 386.899404 -371.993922) (xy 386.899404 -372.486174)
			(xy 386.899826 -372.49536) (xy 386.906331 -372.512545) (xy 386.912104 -372.519702) (xy 386.934001 -372.54534)
			(xy 386.972089 -372.600978) (xy 387.003238 -372.660778) (xy 387.027 -372.723879) (xy 387.043033 -372.789371)
			(xy 387.051106 -372.856312) (xy 387.051103 -372.923739) (xy 387.043024 -372.990679) (xy 387.026985 -373.05617)
			(xy 387.003217 -373.119268) (xy 386.972062 -373.179066) (xy 386.93397 -373.234701) (xy 386.912104 -373.260366)
			(xy 386.906297 -373.267504) (xy 386.899789 -373.2847) (xy 386.899404 -373.293894) (xy 386.899404 -373.451374)
			(xy 386.898854 -373.461494) (xy 386.891142 -373.480206) (xy 386.876876 -373.494562) (xy 386.858212 -373.50239)
			(xy 386.848096 -373.502936) (xy 386.131816 -373.502936) (xy 386.121667 -373.502466) (xy 386.102922 -373.494683)
			(xy 386.0886 -373.480301) (xy 386.080893 -373.461524) (xy 386.080508 -373.451374) (xy 386.080508 -373.293894)
			(xy 386.080099 -373.284707) (xy 386.073584 -373.267523) (xy 386.067808 -373.260366) (xy 386.045977 -373.234673)
			(xy 386.007887 -373.179043) (xy 385.976734 -373.119251) (xy 385.952968 -373.056157) (xy 385.93693 -372.990671)
			(xy 385.928851 -372.923736) (xy 385.928848 -372.856315) (xy 385.936921 -372.789379) (xy 385.952953 -372.723892)
			(xy 385.976713 -372.660796) (xy 386.007861 -372.601001) (xy 386.045946 -372.545367) (xy 386.067808 -372.519702)
			(xy 386.073587 -372.512544) (xy 386.080112 -372.495363) (xy 386.080508 -372.486174) (xy 386.080508 -371.993922)
			(xy 386.080085 -371.984736) (xy 386.07358 -371.967552) (xy 386.067808 -371.960394) (xy 386.045906 -371.93476)
			(xy 386.007818 -371.879121) (xy 385.976669 -371.819321) (xy 385.952906 -371.75622) (xy 385.936873 -371.690727)
			(xy 385.9288 -371.623785) (xy 384.826706 -371.623785) (xy 384.826918 -371.62435) (xy 384.84289 -371.689734)
			(xy 384.850933 -371.756557) (xy 384.850932 -371.823864) (xy 384.842886 -371.890687) (xy 384.826912 -371.95607)
			(xy 384.803238 -372.019075) (xy 384.772203 -372.078799) (xy 384.734253 -372.134386) (xy 384.712464 -372.160038)
			(xy 384.706664 -372.167181) (xy 384.700152 -372.184373) (xy 384.699764 -372.193566) (xy 384.699764 -372.351554)
			(xy 384.699299 -372.361722) (xy 384.691529 -372.380516) (xy 384.677156 -372.394902) (xy 384.65837 -372.402689)
			(xy 384.648202 -372.403116) (xy 383.931922 -372.403116) (xy 383.921746 -372.402717) (xy 383.902943 -372.394931)
			(xy 383.888556 -372.380537) (xy 383.880778 -372.36173) (xy 383.88036 -372.351554) (xy 383.88036 -372.193566)
			(xy 383.879953 -372.184379) (xy 383.873435 -372.167195) (xy 383.86766 -372.160038) (xy 383.845886 -372.134375)
			(xy 383.807935 -372.07879) (xy 383.7769 -372.019069) (xy 383.753225 -371.956065) (xy 383.737251 -371.890684)
			(xy 383.729205 -371.823863) (xy 383.729204 -371.756558) (xy 383.737247 -371.689736) (xy 383.753219 -371.624355)
			(xy 383.776891 -371.561351) (xy 383.807924 -371.501628) (xy 383.845873 -371.446042) (xy 383.86766 -371.42039)
			(xy 383.873451 -371.413241) (xy 383.879967 -371.396053) (xy 383.88036 -371.386862) (xy 383.88036 -370.89334)
			(xy 383.879917 -370.884157) (xy 383.873425 -370.866972) (xy 383.86766 -370.859812) (xy 383.84586 -370.83417)
			(xy 383.80791 -370.778582) (xy 383.776876 -370.718858) (xy 383.753203 -370.655852) (xy 383.737231 -370.590468)
			(xy 383.729187 -370.523644) (xy 380.451147 -370.523644) (xy 380.451147 -370.523703) (xy 380.443072 -370.590641)
			(xy 380.427037 -370.656129) (xy 380.403273 -370.719226) (xy 380.372122 -370.779022) (xy 380.334032 -370.834655)
			(xy 380.312168 -370.86032) (xy 380.306376 -370.867469) (xy 380.299859 -370.884657) (xy 380.299468 -370.893848)
			(xy 380.299468 -371.386354) (xy 380.299908 -371.395538) (xy 380.306402 -371.412722) (xy 380.312168 -371.419882)
			(xy 380.334047 -371.445535) (xy 380.372137 -371.501171) (xy 380.403289 -371.560968) (xy 380.426925 -371.623725)
			(xy 381.529032 -371.623725) (xy 381.529035 -371.556418) (xy 381.537083 -371.489593) (xy 381.553059 -371.424209)
			(xy 381.576735 -371.361203) (xy 381.607771 -371.301478) (xy 381.645723 -371.245891) (xy 381.667512 -371.220238)
			(xy 381.673319 -371.2131) (xy 381.679827 -371.195904) (xy 381.680212 -371.18671) (xy 381.680212 -371.028722)
			(xy 381.680751 -371.018569) (xy 381.688513 -370.999805) (xy 381.702865 -370.98544) (xy 381.721621 -370.97766)
			(xy 381.731774 -370.97716) (xy 382.448054 -370.97716) (xy 382.458225 -370.977602) (xy 382.477023 -370.985376)
			(xy 382.491411 -370.999757) (xy 382.499193 -371.018551) (xy 382.499616 -371.028722) (xy 382.499616 -371.18671)
			(xy 382.500018 -371.195898) (xy 382.506537 -371.213083) (xy 382.512316 -371.220238) (xy 382.534068 -371.24592)
			(xy 382.572021 -371.301501) (xy 382.603058 -371.36122) (xy 382.626735 -371.424221) (xy 382.642712 -371.4896)
			(xy 382.65076 -371.55642) (xy 382.650763 -371.623723) (xy 382.642722 -371.690544) (xy 382.626752 -371.755924)
			(xy 382.603081 -371.818927) (xy 382.57205 -371.87865) (xy 382.534103 -371.934234) (xy 382.512316 -371.959886)
			(xy 382.506502 -371.967019) (xy 382.499997 -371.984219) (xy 382.499616 -371.993414) (xy 382.499616 -372.486682)
			(xy 382.500031 -372.495869) (xy 382.506541 -372.513053) (xy 382.512316 -372.52021) (xy 382.534138 -372.545834)
			(xy 382.572089 -372.601424) (xy 382.603123 -372.661151) (xy 382.626796 -372.724159) (xy 382.642768 -372.789545)
			(xy 382.65081 -372.856371) (xy 382.650807 -372.92368) (xy 382.642759 -372.990506) (xy 382.626781 -373.05589)
			(xy 382.603103 -373.118896) (xy 382.572063 -373.17862) (xy 382.534107 -373.234206) (xy 382.512316 -373.259858)
			(xy 382.506514 -373.267) (xy 382.500002 -373.284193) (xy 382.499616 -373.293386) (xy 382.499616 -373.451374)
			(xy 382.499214 -373.46155) (xy 382.491429 -373.480352) (xy 382.477036 -373.49474) (xy 382.45823 -373.502517)
			(xy 382.448054 -373.502936) (xy 381.731774 -373.502936) (xy 381.721611 -373.502487) (xy 381.702837 -373.4947)
			(xy 381.688471 -373.48032) (xy 381.680702 -373.461537) (xy 381.680212 -373.451374) (xy 381.680212 -373.293386)
			(xy 381.679806 -373.284198) (xy 381.673289 -373.267014) (xy 381.667512 -373.259858) (xy 381.645758 -373.234178)
			(xy 381.60781 -373.178595) (xy 381.576777 -373.118875) (xy 381.553104 -373.055874) (xy 381.537129 -372.990496)
			(xy 381.529083 -372.923676) (xy 381.52908 -372.856375) (xy 381.53712 -372.789555) (xy 381.553088 -372.724175)
			(xy 381.576756 -372.661172) (xy 381.607784 -372.601449) (xy 381.645727 -372.545862) (xy 381.667512 -372.52021)
			(xy 381.673331 -372.51308) (xy 381.679832 -372.495878) (xy 381.680212 -372.486682) (xy 381.680212 -371.993414)
			(xy 381.679792 -371.984228) (xy 381.673285 -371.967044) (xy 381.667512 -371.959886) (xy 381.645688 -371.934264)
			(xy 381.607742 -371.878673) (xy 381.576712 -371.818945) (xy 381.553042 -371.755936) (xy 381.537073 -371.690551)
			(xy 381.529032 -371.623725) (xy 380.426925 -371.623725) (xy 380.427054 -371.624067) (xy 380.443089 -371.689558)
			(xy 380.451165 -371.756498) (xy 380.451163 -371.823923) (xy 380.443086 -371.890863) (xy 380.427048 -371.956353)
			(xy 380.403281 -372.019451) (xy 380.372126 -372.079247) (xy 380.334034 -372.134881) (xy 380.312168 -372.160546)
			(xy 380.306365 -372.167687) (xy 380.299855 -372.184881) (xy 380.299468 -372.194074) (xy 380.299468 -372.351554)
			(xy 380.298936 -372.361677) (xy 380.291225 -372.380395) (xy 380.276952 -372.394753) (xy 380.25828 -372.402575)
			(xy 380.24816 -372.403116) (xy 379.53188 -372.403116) (xy 379.521727 -372.402695) (xy 379.502977 -372.394896)
			(xy 379.488655 -372.3805) (xy 379.480953 -372.36171) (xy 379.480572 -372.351554) (xy 379.480572 -372.194074)
			(xy 379.480181 -372.184885) (xy 379.473655 -372.1677) (xy 379.467872 -372.160546) (xy 379.446023 -372.134869)
			(xy 379.407935 -372.079235) (xy 379.376786 -372.019441) (xy 379.353022 -371.956345) (xy 379.336986 -371.890858)
			(xy 379.32891 -371.823922) (xy 379.328909 -371.7565) (xy 379.336983 -371.689563) (xy 379.353016 -371.624075)
			(xy 379.376777 -371.560979) (xy 379.407925 -371.501183) (xy 379.44601 -371.445548) (xy 379.467872 -371.419882)
			(xy 379.473667 -371.412736) (xy 379.480181 -371.395546) (xy 379.480572 -371.386354) (xy 379.480572 -370.893848)
			(xy 379.480145 -370.884663) (xy 379.473644 -370.867478) (xy 379.467872 -370.86032) (xy 379.445997 -370.834664)
			(xy 379.407911 -370.779027) (xy 379.376762 -370.71923) (xy 379.353 -370.656132) (xy 379.336966 -370.590642)
			(xy 379.328892 -370.523703) (xy 376.050821 -370.523703) (xy 376.042785 -370.590464) (xy 376.026814 -370.655846)
			(xy 376.003143 -370.71885) (xy 375.972113 -370.778573) (xy 375.934166 -370.83416) (xy 375.91238 -370.859812)
			(xy 375.906594 -370.866964) (xy 375.900073 -370.884149) (xy 375.89968 -370.89334) (xy 375.89968 -371.386862)
			(xy 375.900113 -371.396047) (xy 375.906611 -371.413231) (xy 375.91238 -371.42039) (xy 375.934181 -371.446031)
			(xy 375.972128 -371.50162) (xy 376.00316 -371.561345) (xy 376.026618 -371.623785) (xy 377.128712 -371.623785)
			(xy 377.128716 -371.556358) (xy 377.136796 -371.489417) (xy 377.152836 -371.423925) (xy 377.176606 -371.360827)
			(xy 377.207762 -371.301029) (xy 377.245857 -371.245395) (xy 377.267724 -371.21973) (xy 377.273536 -371.212596)
			(xy 377.28004 -371.195397) (xy 377.280424 -371.186202) (xy 377.280424 -371.028722) (xy 377.280944 -371.018599)
			(xy 377.288662 -370.999881) (xy 377.302938 -370.985524) (xy 377.321612 -370.977702) (xy 377.331732 -370.97716)
			(xy 378.048012 -370.97716) (xy 378.058162 -370.977611) (xy 378.076907 -370.985403) (xy 378.091229 -370.99979)
			(xy 378.098935 -371.01857) (xy 378.09932 -371.028722) (xy 378.09932 -371.186202) (xy 378.099725 -371.19539)
			(xy 378.106242 -371.212574) (xy 378.11202 -371.21973) (xy 378.133846 -371.245426) (xy 378.171934 -371.301057)
			(xy 378.203086 -371.360849) (xy 378.226851 -371.423942) (xy 378.242889 -371.489427) (xy 378.250967 -371.556361)
			(xy 378.250971 -371.623782) (xy 378.242899 -371.690717) (xy 378.226868 -371.756204) (xy 378.203109 -371.819299)
			(xy 378.171964 -371.879094) (xy 378.133881 -371.934728) (xy 378.11202 -371.960394) (xy 378.106246 -371.967555)
			(xy 378.099717 -371.984733) (xy 378.09932 -371.993922) (xy 378.09932 -372.486174) (xy 378.099738 -372.49536)
			(xy 378.106246 -372.512545) (xy 378.11202 -372.519702) (xy 378.133917 -372.54534) (xy 378.172003 -372.600979)
			(xy 378.203151 -372.660779) (xy 378.226913 -372.723879) (xy 378.242945 -372.789372) (xy 378.251018 -372.856313)
			(xy 378.251015 -372.923739) (xy 378.242936 -372.990679) (xy 378.226897 -373.056169) (xy 378.20313 -373.119268)
			(xy 378.171977 -373.179065) (xy 378.133885 -373.2347) (xy 378.11202 -373.260366) (xy 378.106215 -373.267506)
			(xy 378.099705 -373.2847) (xy 378.09932 -373.293894) (xy 378.09932 -373.451374) (xy 378.098851 -373.461504)
			(xy 378.091125 -373.480232) (xy 378.076832 -373.494591) (xy 378.05814 -373.502404) (xy 378.048012 -373.502936)
			(xy 377.331732 -373.502936) (xy 377.321584 -373.502453) (xy 377.30284 -373.494675) (xy 377.288516 -373.480297)
			(xy 377.280809 -373.461523) (xy 377.280424 -373.451374) (xy 377.280424 -373.293894) (xy 377.280012 -373.284707)
			(xy 377.273499 -373.267523) (xy 377.267724 -373.260366) (xy 377.245893 -373.234674) (xy 377.207801 -373.179044)
			(xy 377.176648 -373.119251) (xy 377.152881 -373.056158) (xy 377.136842 -372.990672) (xy 377.128763 -372.923736)
			(xy 377.12876 -372.856315) (xy 377.136833 -372.789378) (xy 377.152865 -372.723891) (xy 377.176627 -372.660795)
			(xy 377.207775 -372.601) (xy 377.245861 -372.545367) (xy 377.267724 -372.519702) (xy 377.273505 -372.512546)
			(xy 377.280028 -372.495364) (xy 377.280424 -372.486174) (xy 377.280424 -371.993922) (xy 377.279998 -371.984737)
			(xy 377.273495 -371.967552) (xy 377.267724 -371.960394) (xy 377.245822 -371.93476) (xy 377.207733 -371.879122)
			(xy 377.176582 -371.819321) (xy 377.152819 -371.75622) (xy 377.136786 -371.690727) (xy 377.128712 -371.623785)
			(xy 376.026618 -371.623785) (xy 376.026831 -371.624351) (xy 376.042802 -371.689734) (xy 376.050845 -371.756558)
			(xy 376.050844 -371.823863) (xy 376.042799 -371.890687) (xy 376.026825 -371.956069) (xy 376.003151 -372.019074)
			(xy 375.972117 -372.078799) (xy 375.934168 -372.134386) (xy 375.91238 -372.160038) (xy 375.906582 -372.167182)
			(xy 375.900069 -372.184374) (xy 375.89968 -372.193566) (xy 375.89968 -372.351554) (xy 375.899199 -372.36172)
			(xy 375.891432 -372.380511) (xy 375.877064 -372.394896) (xy 375.858284 -372.402686) (xy 375.848118 -372.403116)
			(xy 375.131838 -372.403116) (xy 375.121663 -372.402704) (xy 375.102861 -372.394923) (xy 375.088473 -372.380533)
			(xy 375.080695 -372.361729) (xy 375.080276 -372.351554) (xy 375.080276 -372.193566) (xy 375.079887 -372.184376)
			(xy 375.073359 -372.167192) (xy 375.067576 -372.160038) (xy 375.045801 -372.134375) (xy 375.007849 -372.078791)
			(xy 374.976813 -372.019069) (xy 374.953138 -371.956066) (xy 374.937163 -371.890685) (xy 374.929117 -371.823863)
			(xy 374.929116 -371.756558) (xy 374.937159 -371.689736) (xy 374.953132 -371.624354) (xy 374.976805 -371.56135)
			(xy 375.007838 -371.501627) (xy 375.045788 -371.446042) (xy 375.067576 -371.42039) (xy 375.073357 -371.413233)
			(xy 375.079882 -371.396052) (xy 375.080276 -371.386862) (xy 375.080276 -370.89334) (xy 375.079852 -370.884154)
			(xy 375.073349 -370.866969) (xy 375.067576 -370.859812) (xy 375.045775 -370.83417) (xy 375.007825 -370.778583)
			(xy 374.97679 -370.718858) (xy 374.953116 -370.655852) (xy 374.937143 -370.590469) (xy 374.929099 -370.523644)
			(xy 345.250797 -370.523644) (xy 345.242754 -370.590465) (xy 345.226782 -370.655847) (xy 345.203109 -370.718851)
			(xy 345.172076 -370.778574) (xy 345.134128 -370.83416) (xy 345.11234 -370.859812) (xy 345.106548 -370.86696)
			(xy 345.100032 -370.884149) (xy 345.09964 -370.89334) (xy 345.09964 -371.386862) (xy 345.100082 -371.396046)
			(xy 345.106575 -371.41323) (xy 345.11234 -371.42039) (xy 345.134142 -371.446031) (xy 345.172092 -371.501618)
			(xy 345.203126 -371.561343) (xy 345.226564 -371.623726) (xy 346.329187 -371.623726) (xy 346.32919 -371.556417)
			(xy 346.337239 -371.489591) (xy 346.353217 -371.424206) (xy 346.376896 -371.3612) (xy 346.407936 -371.301476)
			(xy 346.445893 -371.24589) (xy 346.467684 -371.220238) (xy 346.473488 -371.213098) (xy 346.479999 -371.195904)
			(xy 346.480384 -371.18671) (xy 346.480384 -371.028722) (xy 346.480783 -371.018546) (xy 346.488569 -370.999743)
			(xy 346.502963 -370.985356) (xy 346.52177 -370.977578) (xy 346.531946 -370.97716) (xy 347.248226 -370.97716)
			(xy 347.258388 -370.977612) (xy 347.277162 -370.9854) (xy 347.291527 -370.999778) (xy 347.299297 -371.018559)
			(xy 347.299788 -371.028722) (xy 347.299788 -371.18671) (xy 347.300196 -371.195897) (xy 347.306711 -371.213082)
			(xy 347.312488 -371.220238) (xy 347.334237 -371.245921) (xy 347.372185 -371.301504) (xy 347.403219 -371.361224)
			(xy 347.426893 -371.424224) (xy 347.442867 -371.489602) (xy 347.450914 -371.556421) (xy 347.450918 -371.623722)
			(xy 347.442878 -371.690542) (xy 347.426909 -371.755921) (xy 347.403242 -371.818924) (xy 347.372215 -371.878647)
			(xy 347.334272 -371.934233) (xy 347.312488 -371.959886) (xy 347.306671 -371.967017) (xy 347.300169 -371.984218)
			(xy 347.299788 -371.993414) (xy 347.299788 -372.486682) (xy 347.30021 -372.495868) (xy 347.306716 -372.513052)
			(xy 347.312488 -372.52021) (xy 347.334308 -372.545835) (xy 347.372254 -372.601426) (xy 347.403285 -372.661154)
			(xy 347.426954 -372.724162) (xy 347.442924 -372.789547) (xy 347.450965 -372.856372) (xy 347.450962 -372.923679)
			(xy 347.442915 -372.990504) (xy 347.426939 -373.055887) (xy 347.403264 -373.118893) (xy 347.372228 -373.178618)
			(xy 347.334277 -373.234205) (xy 347.312488 -373.259858) (xy 347.306683 -373.266997) (xy 347.300174 -373.284192)
			(xy 347.299788 -373.293386) (xy 347.299788 -373.451374) (xy 347.299246 -373.461527) (xy 347.291485 -373.480291)
			(xy 347.277134 -373.494656) (xy 347.258378 -373.502436) (xy 347.248226 -373.502936) (xy 346.531946 -373.502936)
			(xy 346.521774 -373.502498) (xy 346.502975 -373.494723) (xy 346.488588 -373.480341) (xy 346.480806 -373.461546)
			(xy 346.480384 -373.451374) (xy 346.480384 -373.293386) (xy 346.479984 -373.284198) (xy 346.473464 -373.267013)
			(xy 346.467684 -373.259858) (xy 346.445928 -373.234179) (xy 346.407976 -373.178597) (xy 346.376938 -373.118878)
			(xy 346.353262 -373.055877) (xy 346.337285 -372.990498) (xy 346.329237 -372.923677) (xy 346.329234 -372.856374)
			(xy 346.337276 -372.789553) (xy 346.353247 -372.724172) (xy 346.376917 -372.661169) (xy 346.407949 -372.601447)
			(xy 346.445897 -372.545862) (xy 346.467684 -372.52021) (xy 346.473499 -372.513078) (xy 346.480003 -372.495877)
			(xy 346.480384 -372.486682) (xy 346.480384 -371.993414) (xy 346.479971 -371.984227) (xy 346.47346 -371.967042)
			(xy 346.467684 -371.959886) (xy 346.445858 -371.934265) (xy 346.407907 -371.878675) (xy 346.376873 -371.818948)
			(xy 346.3532 -371.755939) (xy 346.337229 -371.690553) (xy 346.329187 -371.623726) (xy 345.226564 -371.623726)
			(xy 345.226798 -371.624349) (xy 345.242771 -371.689733) (xy 345.250814 -371.756557) (xy 345.250813 -371.823864)
			(xy 345.242767 -371.890688) (xy 345.226792 -371.956071) (xy 345.203117 -372.019076) (xy 345.172081 -372.0788)
			(xy 345.134129 -372.134386) (xy 345.11234 -372.160038) (xy 345.106537 -372.167179) (xy 345.100028 -372.184373)
			(xy 345.09964 -372.193566) (xy 345.09964 -372.351554) (xy 345.099198 -372.361725) (xy 345.091424 -372.380523)
			(xy 345.077043 -372.394911) (xy 345.058249 -372.402693) (xy 345.048078 -372.403116) (xy 344.331798 -372.403116)
			(xy 344.321621 -372.402737) (xy 344.302817 -372.394942) (xy 344.288431 -372.380543) (xy 344.280654 -372.361732)
			(xy 344.280236 -372.351554) (xy 344.280236 -372.193566) (xy 344.279834 -372.184378) (xy 344.273314 -372.167194)
			(xy 344.267536 -372.160038) (xy 344.245762 -372.134374) (xy 344.207813 -372.078789) (xy 344.17678 -372.019067)
			(xy 344.153106 -371.956064) (xy 344.137132 -371.890684) (xy 344.129087 -371.823862) (xy 344.129086 -371.756559)
			(xy 344.137129 -371.689737) (xy 344.1531 -371.624356) (xy 344.176771 -371.561352) (xy 344.207803 -371.501629)
			(xy 344.245749 -371.446042) (xy 344.267536 -371.42039) (xy 344.273324 -371.413239) (xy 344.279843 -371.396053)
			(xy 344.280236 -371.386862) (xy 344.280236 -370.89334) (xy 344.279798 -370.884156) (xy 344.273303 -370.866972)
			(xy 344.267536 -370.859812) (xy 344.245736 -370.83417) (xy 344.207788 -370.778582) (xy 344.176756 -370.718857)
			(xy 344.153084 -370.655851) (xy 344.137112 -370.590468) (xy 344.129068 -370.523644) (xy 340.851006 -370.523644)
			(xy 340.842963 -370.590465) (xy 340.826991 -370.655847) (xy 340.803319 -370.718851) (xy 340.772287 -370.778574)
			(xy 340.734339 -370.83416) (xy 340.712552 -370.859812) (xy 340.706762 -370.866962) (xy 340.700245 -370.884149)
			(xy 340.699852 -370.89334) (xy 340.699852 -371.386862) (xy 340.700291 -371.396046) (xy 340.706786 -371.41323)
			(xy 340.712552 -371.42039) (xy 340.734354 -371.446031) (xy 340.772303 -371.501618) (xy 340.803336 -371.561344)
			(xy 340.826797 -371.623785) (xy 341.928891 -371.623785) (xy 341.928895 -371.556358) (xy 341.936974 -371.489417)
			(xy 341.953014 -371.423926) (xy 341.976782 -371.360828) (xy 342.007937 -371.301031) (xy 342.04603 -371.245395)
			(xy 342.067896 -371.21973) (xy 342.073704 -371.212593) (xy 342.080212 -371.195396) (xy 342.080596 -371.186202)
			(xy 342.080596 -371.028722) (xy 342.081143 -371.018602) (xy 342.088856 -370.99989) (xy 342.103123 -370.985534)
			(xy 342.121787 -370.977706) (xy 342.131904 -370.97716) (xy 342.848184 -370.97716) (xy 342.858332 -370.977634)
			(xy 342.877076 -370.985417) (xy 342.891399 -370.999797) (xy 342.899106 -371.018572) (xy 342.899492 -371.028722)
			(xy 342.899492 -371.186202) (xy 342.899903 -371.195389) (xy 342.906416 -371.212573) (xy 342.912192 -371.21973)
			(xy 342.934019 -371.245426) (xy 342.972109 -371.301056) (xy 343.003262 -371.360848) (xy 343.027029 -371.423941)
			(xy 343.043067 -371.489426) (xy 343.051146 -371.556361) (xy 343.05115 -371.623782) (xy 343.043077 -371.690718)
			(xy 343.027046 -371.756205) (xy 343.003285 -371.8193) (xy 342.972139 -371.879095) (xy 342.934054 -371.934729)
			(xy 342.912192 -371.960394) (xy 342.906415 -371.967553) (xy 342.899889 -371.984733) (xy 342.899492 -371.993922)
			(xy 342.899492 -372.486174) (xy 342.899917 -372.49536) (xy 342.90642 -372.512544) (xy 342.912192 -372.519702)
			(xy 342.93409 -372.54534) (xy 342.972178 -372.600978) (xy 343.003328 -372.660778) (xy 343.02709 -372.723878)
			(xy 343.043124 -372.789371) (xy 343.051197 -372.856312) (xy 343.051194 -372.923739) (xy 343.043114 -372.99068)
			(xy 343.027075 -373.056171) (xy 343.003307 -373.119269) (xy 342.972152 -373.179066) (xy 342.934058 -373.234701)
			(xy 342.912192 -373.260366) (xy 342.906384 -373.267503) (xy 342.899876 -373.2847) (xy 342.899492 -373.293894)
			(xy 342.899492 -373.451374) (xy 342.898953 -373.461495) (xy 342.89124 -373.48021) (xy 342.87697 -373.494566)
			(xy 342.858302 -373.502392) (xy 342.848184 -373.502936) (xy 342.131904 -373.502936) (xy 342.121755 -373.502476)
			(xy 342.103009 -373.494688) (xy 342.088687 -373.480304) (xy 342.080981 -373.461525) (xy 342.080596 -373.451374)
			(xy 342.080596 -373.293894) (xy 342.080189 -373.284706) (xy 342.073673 -373.267522) (xy 342.067896 -373.260366)
			(xy 342.046066 -373.234673) (xy 342.007976 -373.179042) (xy 341.976824 -373.11925) (xy 341.953058 -373.056157)
			(xy 341.937021 -372.990671) (xy 341.928942 -372.923736) (xy 341.928939 -372.856315) (xy 341.937011 -372.789379)
			(xy 341.953043 -372.723892) (xy 341.976803 -372.660797) (xy 342.00795 -372.601001) (xy 342.046034 -372.545367)
			(xy 342.067896 -372.519702) (xy 342.073674 -372.512543) (xy 342.0802 -372.495363) (xy 342.080596 -372.486174)
			(xy 342.080596 -371.993922) (xy 342.080176 -371.984736) (xy 342.073669 -371.967551) (xy 342.067896 -371.960394)
			(xy 342.045995 -371.934759) (xy 342.007908 -371.87912) (xy 341.976759 -371.81932) (xy 341.952997 -371.756219)
			(xy 341.936964 -371.690726) (xy 341.928891 -371.623785) (xy 340.826797 -371.623785) (xy 340.827009 -371.62435)
			(xy 340.842981 -371.689733) (xy 340.851024 -371.756557) (xy 340.851023 -371.823864) (xy 340.842977 -371.890687)
			(xy 340.827002 -371.956071) (xy 340.803328 -372.019076) (xy 340.772292 -372.0788) (xy 340.734341 -372.134386)
			(xy 340.712552 -372.160038) (xy 340.706751 -372.16718) (xy 340.70024 -372.184373) (xy 340.699852 -372.193566)
			(xy 340.699852 -372.351554) (xy 340.699398 -372.361724) (xy 340.691627 -372.380519) (xy 340.67725 -372.394906)
			(xy 340.65846 -372.402691) (xy 340.64829 -372.403116) (xy 339.93201 -372.403116) (xy 339.921833 -372.402727)
			(xy 339.90303 -372.394937) (xy 339.888643 -372.38054) (xy 339.880866 -372.361731) (xy 339.880448 -372.351554)
			(xy 339.880448 -372.193566) (xy 339.880043 -372.184378) (xy 339.873525 -372.167195) (xy 339.867748 -372.160038)
			(xy 339.845974 -372.134375) (xy 339.808024 -372.07879) (xy 339.77699 -372.019068) (xy 339.753316 -371.956065)
			(xy 339.737342 -371.890684) (xy 339.729296 -371.823863) (xy 339.729295 -371.756558) (xy 339.737338 -371.689737)
			(xy 339.75331 -371.624355) (xy 339.776981 -371.561351) (xy 339.808013 -371.501628) (xy 339.845961 -371.446042)
			(xy 339.867748 -371.42039) (xy 339.873537 -371.41324) (xy 339.880055 -371.396053) (xy 339.880448 -371.386862)
			(xy 339.880448 -370.89334) (xy 339.880008 -370.884156) (xy 339.873514 -370.866972) (xy 339.867748 -370.859812)
			(xy 339.845948 -370.83417) (xy 339.807999 -370.778582) (xy 339.776966 -370.718857) (xy 339.753293 -370.655851)
			(xy 339.737321 -370.590468) (xy 339.729277 -370.523644) (xy 336.451238 -370.523644) (xy 336.451238 -370.523703)
			(xy 336.443163 -370.590641) (xy 336.427128 -370.65613) (xy 336.403363 -370.719227) (xy 336.372211 -370.779022)
			(xy 336.334121 -370.834656) (xy 336.312256 -370.86032) (xy 336.306463 -370.867467) (xy 336.299947 -370.884656)
			(xy 336.299556 -370.893848) (xy 336.299556 -371.386354) (xy 336.299998 -371.395538) (xy 336.306491 -371.412722)
			(xy 336.312256 -371.419882) (xy 336.334135 -371.445535) (xy 336.372226 -371.50117) (xy 336.403379 -371.560968)
			(xy 336.427016 -371.623725) (xy 337.529123 -371.623725) (xy 337.529126 -371.556418) (xy 337.537174 -371.489593)
			(xy 337.55315 -371.424209) (xy 337.576825 -371.361204) (xy 337.60786 -371.301479) (xy 337.645811 -371.245891)
			(xy 337.6676 -371.220238) (xy 337.673405 -371.213099) (xy 337.679915 -371.195904) (xy 337.6803 -371.18671)
			(xy 337.6803 -371.028722) (xy 337.68085 -371.01857) (xy 337.68861 -370.999809) (xy 337.702958 -370.985444)
			(xy 337.721711 -370.977662) (xy 337.731862 -370.97716) (xy 338.448142 -370.97716) (xy 338.458305 -370.9776)
			(xy 338.477079 -370.985392) (xy 338.491444 -370.999774) (xy 338.499213 -371.018558) (xy 338.499704 -371.028722)
			(xy 338.499704 -371.18671) (xy 338.500109 -371.195898) (xy 338.506626 -371.213082) (xy 338.512404 -371.220238)
			(xy 338.534153 -371.245921) (xy 338.5721 -371.301504) (xy 338.603133 -371.361224) (xy 338.626806 -371.424224)
			(xy 338.64278 -371.489602) (xy 338.650827 -371.556421) (xy 338.65083 -371.623722) (xy 338.64279 -371.690541)
			(xy 338.626823 -371.755921) (xy 338.603156 -371.818924) (xy 338.57213 -371.878646) (xy 338.534188 -371.934233)
			(xy 338.512404 -371.959886) (xy 338.506589 -371.967018) (xy 338.500085 -371.984219) (xy 338.499704 -371.993414)
			(xy 338.499704 -372.486682) (xy 338.500122 -372.495868) (xy 338.50663 -372.513053) (xy 338.512404 -372.52021)
			(xy 338.534224 -372.545835) (xy 338.572169 -372.601427) (xy 338.603198 -372.661154) (xy 338.626867 -372.724162)
			(xy 338.642836 -372.789547) (xy 338.650877 -372.856372) (xy 338.650874 -372.923679) (xy 338.642827 -372.990503)
			(xy 338.626852 -373.055887) (xy 338.603177 -373.118892) (xy 338.572142 -373.178617) (xy 338.534192 -373.234205)
			(xy 338.512404 -373.259858) (xy 338.506601 -373.266999) (xy 338.50009 -373.284193) (xy 338.499704 -373.293386)
			(xy 338.499704 -373.451374) (xy 338.499147 -373.461525) (xy 338.491388 -373.480286) (xy 338.477043 -373.49465)
			(xy 338.458292 -373.502433) (xy 338.448142 -373.502936) (xy 337.731862 -373.502936) (xy 337.721699 -373.502497)
			(xy 337.702924 -373.494705) (xy 337.688559 -373.480323) (xy 337.68079 -373.461538) (xy 337.6803 -373.451374)
			(xy 337.6803 -373.293386) (xy 337.679896 -373.284198) (xy 337.673378 -373.267014) (xy 337.6676 -373.259858)
			(xy 337.645847 -373.234178) (xy 337.6079 -373.178595) (xy 337.576867 -373.118874) (xy 337.553194 -373.055874)
			(xy 337.53722 -372.990495) (xy 337.529174 -372.923676) (xy 337.52917 -372.856375) (xy 337.537211 -372.789555)
			(xy 337.553179 -372.724175) (xy 337.576846 -372.661172) (xy 337.607873 -372.601449) (xy 337.645816 -372.545863)
			(xy 337.6676 -372.52021) (xy 337.673417 -372.513079) (xy 337.67992 -372.495878) (xy 337.6803 -372.486682)
			(xy 337.6803 -371.993414) (xy 337.679883 -371.984228) (xy 337.673374 -371.967043) (xy 337.6676 -371.959886)
			(xy 337.645776 -371.934264) (xy 337.607831 -371.878672) (xy 337.576802 -371.818944) (xy 337.553133 -371.755936)
			(xy 337.537163 -371.69055) (xy 337.529123 -371.623725) (xy 336.427016 -371.623725) (xy 336.427144 -371.624066)
			(xy 336.44318 -371.689557) (xy 336.451256 -371.756498) (xy 336.451254 -371.823923) (xy 336.443176 -371.890863)
			(xy 336.427138 -371.956354) (xy 336.40337 -372.019451) (xy 336.372216 -372.079248) (xy 336.334122 -372.134881)
			(xy 336.312256 -372.160546) (xy 336.306452 -372.167686) (xy 336.299943 -372.184881) (xy 336.299556 -372.194074)
			(xy 336.299556 -372.351554) (xy 336.299036 -372.361678) (xy 336.291322 -372.380399) (xy 336.277046 -372.394757)
			(xy 336.258369 -372.402577) (xy 336.248248 -372.403116) (xy 335.531968 -372.403116) (xy 335.521814 -372.402705)
			(xy 335.503064 -372.394902) (xy 335.488742 -372.380502) (xy 335.481041 -372.36171) (xy 335.48066 -372.351554)
			(xy 335.48066 -372.194074) (xy 335.480249 -372.184887) (xy 335.473734 -372.167704) (xy 335.46796 -372.160546)
			(xy 335.446111 -372.134869) (xy 335.408025 -372.079235) (xy 335.376876 -372.01944) (xy 335.353112 -371.956345)
			(xy 335.337077 -371.890858) (xy 335.329001 -371.823921) (xy 335.329 -371.7565) (xy 335.337073 -371.689563)
			(xy 335.353106 -371.624075) (xy 335.376867 -371.560979) (xy 335.408014 -371.501183) (xy 335.446098 -371.445548)
			(xy 335.46796 -371.419882) (xy 335.473754 -371.412735) (xy 335.480269 -371.395546) (xy 335.48066 -371.386354)
			(xy 335.48066 -370.893848) (xy 335.480214 -370.884665) (xy 335.473724 -370.867481) (xy 335.46796 -370.86032)
			(xy 335.446086 -370.834664) (xy 335.408 -370.779027) (xy 335.376852 -370.719229) (xy 335.35309 -370.656131)
			(xy 335.337057 -370.590642) (xy 335.328983 -370.523703) (xy 332.050912 -370.523703) (xy 332.042876 -370.590465)
			(xy 332.026905 -370.655846) (xy 332.003233 -370.71885) (xy 331.972202 -370.778573) (xy 331.934255 -370.83416)
			(xy 331.912468 -370.859812) (xy 331.90668 -370.866963) (xy 331.900161 -370.884149) (xy 331.899768 -370.89334)
			(xy 331.899768 -371.386862) (xy 331.900204 -371.396046) (xy 331.906701 -371.41323) (xy 331.912468 -371.42039)
			(xy 331.934269 -371.446031) (xy 331.972217 -371.501619) (xy 332.00325 -371.561344) (xy 332.026709 -371.623785)
			(xy 333.128803 -371.623785) (xy 333.128807 -371.556358) (xy 333.136887 -371.489417) (xy 333.152927 -371.423926)
			(xy 333.176696 -371.360827) (xy 333.207851 -371.30103) (xy 333.245945 -371.245395) (xy 333.267812 -371.21973)
			(xy 333.273622 -371.212594) (xy 333.280128 -371.195397) (xy 333.280512 -371.186202) (xy 333.280512 -371.028722)
			(xy 333.281044 -371.0186) (xy 333.288759 -370.999885) (xy 333.303031 -370.985529) (xy 333.321701 -370.977704)
			(xy 333.33182 -370.97716) (xy 334.0481 -370.97716) (xy 334.058249 -370.977621) (xy 334.076994 -370.985409)
			(xy 334.091316 -370.999793) (xy 334.099023 -371.018571) (xy 334.099408 -371.028722) (xy 334.099408 -371.186202)
			(xy 334.099815 -371.195389) (xy 334.106331 -371.212574) (xy 334.112108 -371.21973) (xy 334.133934 -371.245426)
			(xy 334.172024 -371.301056) (xy 334.203176 -371.360848) (xy 334.226942 -371.423941) (xy 334.242979 -371.489426)
			(xy 334.251058 -371.556361) (xy 334.251062 -371.623782) (xy 334.24299 -371.690717) (xy 334.226958 -371.756204)
			(xy 334.203199 -371.819299) (xy 334.172053 -371.879095) (xy 334.133969 -371.934729) (xy 334.112108 -371.960394)
			(xy 334.106332 -371.967554) (xy 334.099805 -371.984733) (xy 334.099408 -371.993922) (xy 334.099408 -372.486174)
			(xy 334.099829 -372.49536) (xy 334.106335 -372.512545) (xy 334.112108 -372.519702) (xy 334.134005 -372.54534)
			(xy 334.172092 -372.600978) (xy 334.203241 -372.660779) (xy 334.227003 -372.723879) (xy 334.243036 -372.789371)
			(xy 334.251109 -372.856312) (xy 334.251106 -372.923739) (xy 334.243027 -372.990679) (xy 334.226988 -373.05617)
			(xy 334.20322 -373.119268) (xy 334.172066 -373.179065) (xy 334.133974 -373.234701) (xy 334.112108 -373.260366)
			(xy 334.106302 -373.267504) (xy 334.099793 -373.2847) (xy 334.099408 -373.293894) (xy 334.099408 -373.451374)
			(xy 334.098854 -373.461493) (xy 334.091143 -373.480205) (xy 334.076878 -373.49456) (xy 334.058216 -373.502389)
			(xy 334.0481 -373.502936) (xy 333.33182 -373.502936) (xy 333.321672 -373.502463) (xy 333.302927 -373.494681)
			(xy 333.288604 -373.4803) (xy 333.280897 -373.461524) (xy 333.280512 -373.451374) (xy 333.280512 -373.293894)
			(xy 333.280102 -373.284707) (xy 333.273588 -373.267523) (xy 333.267812 -373.260366) (xy 333.245981 -373.234673)
			(xy 333.20789 -373.179043) (xy 333.176738 -373.119251) (xy 333.152971 -373.056157) (xy 333.136933 -372.990672)
			(xy 333.128854 -372.923736) (xy 333.128851 -372.856315) (xy 333.136924 -372.789379) (xy 333.152956 -372.723891)
			(xy 333.176717 -372.660796) (xy 333.207864 -372.601001) (xy 333.24595 -372.545367) (xy 333.267812 -372.519702)
			(xy 333.273592 -372.512545) (xy 333.280116 -372.495363) (xy 333.280512 -372.486174) (xy 333.280512 -371.993922)
			(xy 333.280088 -371.984736) (xy 333.273584 -371.967552) (xy 333.267812 -371.960394) (xy 333.24591 -371.93476)
			(xy 333.207822 -371.879121) (xy 333.176672 -371.819321) (xy 333.15291 -371.75622) (xy 333.136876 -371.690727)
			(xy 333.128803 -371.623785) (xy 332.026709 -371.623785) (xy 332.026921 -371.62435) (xy 332.042893 -371.689734)
			(xy 332.050936 -371.756558) (xy 332.050935 -371.823864) (xy 332.042889 -371.890687) (xy 332.026915 -371.95607)
			(xy 332.003241 -372.019075) (xy 331.972207 -372.078799) (xy 331.934256 -372.134386) (xy 331.912468 -372.160038)
			(xy 331.906669 -372.167181) (xy 331.900156 -372.184373) (xy 331.899768 -372.193566) (xy 331.899768 -372.351554)
			(xy 331.899299 -372.361722) (xy 331.89153 -372.380514) (xy 331.877158 -372.394901) (xy 331.858373 -372.402688)
			(xy 331.848206 -372.403116) (xy 331.131926 -372.403116) (xy 331.12175 -372.402714) (xy 331.102948 -372.394929)
			(xy 331.08856 -372.380536) (xy 331.080783 -372.36173) (xy 331.080364 -372.351554) (xy 331.080364 -372.193566)
			(xy 331.079956 -372.184379) (xy 331.073439 -372.167195) (xy 331.067664 -372.160038) (xy 331.045889 -372.134375)
			(xy 331.007939 -372.078791) (xy 330.976903 -372.019069) (xy 330.953229 -371.956066) (xy 330.937254 -371.890684)
			(xy 330.929208 -371.823863) (xy 330.929207 -371.756558) (xy 330.93725 -371.689736) (xy 330.953222 -371.624355)
			(xy 330.976895 -371.561351) (xy 331.007928 -371.501628) (xy 331.045876 -371.446042) (xy 331.067664 -371.42039)
			(xy 331.073455 -371.413241) (xy 331.079971 -371.396053) (xy 331.080364 -371.386862) (xy 331.080364 -370.89334)
			(xy 331.07992 -370.884157) (xy 331.073428 -370.866973) (xy 331.067664 -370.859812) (xy 331.045864 -370.83417)
			(xy 331.007914 -370.778582) (xy 330.97688 -370.718858) (xy 330.953206 -370.655852) (xy 330.937234 -370.590468)
			(xy 330.92919 -370.523644) (xy 301.250887 -370.523644) (xy 301.250887 -370.523702) (xy 301.242812 -370.590639)
			(xy 301.226779 -370.656127) (xy 301.203017 -370.719224) (xy 301.171869 -370.77902) (xy 301.133783 -370.834654)
			(xy 301.11192 -370.86032) (xy 301.106135 -370.867473) (xy 301.099613 -370.884658) (xy 301.09922 -370.893848)
			(xy 301.09922 -371.386354) (xy 301.099648 -371.395539) (xy 301.106149 -371.412724) (xy 301.11192 -371.419882)
			(xy 301.133797 -371.445536) (xy 301.171884 -371.501173) (xy 301.203033 -371.560971) (xy 301.226688 -371.623785)
			(xy 302.328773 -371.623785) (xy 302.328777 -371.556358) (xy 302.336856 -371.489418) (xy 302.352895 -371.423927)
			(xy 302.376662 -371.360829) (xy 302.407815 -371.301031) (xy 302.445907 -371.245396) (xy 302.467772 -371.21973)
			(xy 302.47359 -371.2126) (xy 302.48009 -371.195398) (xy 302.480472 -371.186202) (xy 302.480472 -371.028722)
			(xy 302.480945 -371.018593) (xy 302.488672 -370.999866) (xy 302.502963 -370.985508) (xy 302.521653 -370.977693)
			(xy 302.53178 -370.97716) (xy 303.24806 -370.97716) (xy 303.258207 -370.977654) (xy 303.27695 -370.985429)
			(xy 303.291274 -370.999803) (xy 303.298982 -371.018574) (xy 303.299368 -371.028722) (xy 303.299368 -371.186202)
			(xy 303.299784 -371.195388) (xy 303.306294 -371.212572) (xy 303.312068 -371.21973) (xy 303.333896 -371.245425)
			(xy 303.371988 -371.301055) (xy 303.403142 -371.360847) (xy 303.42691 -371.42394) (xy 303.442949 -371.489425)
			(xy 303.451028 -371.556361) (xy 303.451031 -371.623782) (xy 303.442959 -371.690718) (xy 303.426926 -371.756206)
			(xy 303.403165 -371.819301) (xy 303.372017 -371.879096) (xy 303.333931 -371.934729) (xy 303.312068 -371.960394)
			(xy 303.306287 -371.96755) (xy 303.299764 -371.984732) (xy 303.299368 -371.993922) (xy 303.299368 -372.486174)
			(xy 303.299798 -372.495359) (xy 303.306299 -372.512543) (xy 303.312068 -372.519702) (xy 303.333966 -372.545339)
			(xy 303.372056 -372.600977) (xy 303.403207 -372.660777) (xy 303.426971 -372.723877) (xy 303.443005 -372.78937)
			(xy 303.451079 -372.856312) (xy 303.451076 -372.923739) (xy 303.442996 -372.99068) (xy 303.426956 -373.056172)
			(xy 303.403186 -373.11927) (xy 303.37203 -373.179067) (xy 303.333935 -373.234701) (xy 303.312068 -373.260366)
			(xy 303.306257 -373.267501) (xy 303.299752 -373.284699) (xy 303.299368 -373.293894) (xy 303.299368 -373.451374)
			(xy 303.298853 -373.461498) (xy 303.291135 -373.480217) (xy 303.276857 -373.494574) (xy 303.258181 -373.502396)
			(xy 303.24806 -373.502936) (xy 302.53178 -373.502936) (xy 302.521629 -373.502496) (xy 302.502883 -373.4947)
			(xy 302.488562 -373.48031) (xy 302.480856 -373.461527) (xy 302.480472 -373.451374) (xy 302.480472 -373.293894)
			(xy 302.480071 -373.284706) (xy 302.473552 -373.267521) (xy 302.467772 -373.260366) (xy 302.445942 -373.234673)
			(xy 302.407855 -373.179042) (xy 302.376704 -373.119249) (xy 302.352939 -373.056156) (xy 302.336902 -372.99067)
			(xy 302.328824 -372.923736) (xy 302.328821 -372.856315) (xy 302.336893 -372.78938) (xy 302.352924 -372.723893)
			(xy 302.376683 -372.660798) (xy 302.407828 -372.601002) (xy 302.445911 -372.545368) (xy 302.467772 -372.519702)
			(xy 302.473559 -372.51255) (xy 302.480077 -372.495364) (xy 302.480472 -372.486174) (xy 302.480472 -371.993922)
			(xy 302.480058 -371.984735) (xy 302.473548 -371.96755) (xy 302.467772 -371.960394) (xy 302.445872 -371.934759)
			(xy 302.407786 -371.87912) (xy 302.376638 -371.819319) (xy 302.352878 -371.756218) (xy 302.336846 -371.690726)
			(xy 302.328773 -371.623785) (xy 301.226688 -371.623785) (xy 301.226795 -371.624069) (xy 301.242829 -371.689559)
			(xy 301.250904 -371.756498) (xy 301.250903 -371.823923) (xy 301.242826 -371.890862) (xy 301.226789 -371.956351)
			(xy 301.203024 -372.019449) (xy 301.171873 -372.079245) (xy 301.133784 -372.13488) (xy 301.11192 -372.160546)
			(xy 301.106124 -372.167692) (xy 301.099608 -372.184882) (xy 301.09922 -372.194074) (xy 301.09922 -372.351554)
			(xy 301.098734 -372.361683) (xy 301.091014 -372.38041) (xy 301.076727 -372.39477) (xy 301.058038 -372.402583)
			(xy 301.047912 -372.403116) (xy 300.331632 -372.403116) (xy 300.321482 -372.402653) (xy 300.302733 -372.394871)
			(xy 300.288409 -372.380487) (xy 300.280705 -372.361706) (xy 300.280324 -372.351554) (xy 300.280324 -372.194074)
			(xy 300.279921 -372.184886) (xy 300.273402 -372.167702) (xy 300.267624 -372.160546) (xy 300.245773 -372.13487)
			(xy 300.207682 -372.079237) (xy 300.17653 -372.019443) (xy 300.152764 -371.956347) (xy 300.136726 -371.890859)
			(xy 300.128649 -371.823922) (xy 300.128648 -371.756499) (xy 300.136723 -371.689561) (xy 300.152757 -371.624073)
			(xy 300.176521 -371.560976) (xy 300.207671 -371.501181) (xy 300.24576 -371.445547) (xy 300.267624 -371.419882)
			(xy 300.273413 -371.412732) (xy 300.279932 -371.395545) (xy 300.280324 -371.386354) (xy 300.280324 -370.893848)
			(xy 300.279885 -370.884664) (xy 300.273391 -370.86748) (xy 300.267624 -370.86032) (xy 300.245747 -370.834665)
			(xy 300.207657 -370.779029) (xy 300.176506 -370.719232) (xy 300.152741 -370.656134) (xy 300.136706 -370.590643)
			(xy 300.128631 -370.523704) (xy 296.851096 -370.523704) (xy 296.843021 -370.590639) (xy 296.826988 -370.656127)
			(xy 296.803227 -370.719223) (xy 296.772079 -370.779019) (xy 296.733994 -370.834654) (xy 296.712132 -370.86032)
			(xy 296.706336 -370.867465) (xy 296.699823 -370.884656) (xy 296.699432 -370.893848) (xy 296.699432 -371.386354)
			(xy 296.699879 -371.395537) (xy 296.706369 -371.412721) (xy 296.712132 -371.419882) (xy 296.734009 -371.445536)
			(xy 296.772095 -371.501173) (xy 296.803243 -371.560971) (xy 296.826876 -371.623726) (xy 297.92898 -371.623726)
			(xy 297.928984 -371.556417) (xy 297.937032 -371.489591) (xy 297.95301 -371.424206) (xy 297.976689 -371.3612)
			(xy 298.007729 -371.301476) (xy 298.045685 -371.245889) (xy 298.067476 -371.220238) (xy 298.073279 -371.213097)
			(xy 298.07979 -371.195903) (xy 298.080176 -371.18671) (xy 298.080176 -371.028722) (xy 298.080583 -371.018547)
			(xy 298.088368 -370.999746) (xy 298.102759 -370.985359) (xy 298.121563 -370.97758) (xy 298.131738 -370.97716)
			(xy 298.848018 -370.97716) (xy 298.858193 -370.97755) (xy 298.876993 -370.985345) (xy 298.891378 -370.999741)
			(xy 298.899158 -371.018546) (xy 298.89958 -371.028722) (xy 298.89958 -371.18671) (xy 298.89999 -371.195897)
			(xy 298.906504 -371.213081) (xy 298.91228 -371.220238) (xy 298.93403 -371.245921) (xy 298.971978 -371.301504)
			(xy 299.003012 -371.361223) (xy 299.026686 -371.424224) (xy 299.042661 -371.489602) (xy 299.050708 -371.556421)
			(xy 299.050711 -371.623722) (xy 299.042671 -371.690542) (xy 299.026703 -371.755922) (xy 299.003035 -371.818925)
			(xy 298.972008 -371.878647) (xy 298.934065 -371.934233) (xy 298.91228 -371.959886) (xy 298.906462 -371.967016)
			(xy 298.899961 -371.984218) (xy 298.89958 -371.993414) (xy 298.89958 -372.486682) (xy 298.900003 -372.495868)
			(xy 298.906508 -372.513052) (xy 298.91228 -372.52021) (xy 298.934101 -372.545835) (xy 298.972047 -372.601426)
			(xy 299.003078 -372.661153) (xy 299.026748 -372.724161) (xy 299.042718 -372.789547) (xy 299.050759 -372.856372)
			(xy 299.050756 -372.923679) (xy 299.042709 -372.990504) (xy 299.026733 -373.055888) (xy 299.003057 -373.118894)
			(xy 298.972021 -373.178618) (xy 298.934069 -373.234206) (xy 298.91228 -373.259858) (xy 298.906474 -373.266996)
			(xy 298.899966 -373.284192) (xy 298.89958 -373.293386) (xy 298.89958 -373.451374) (xy 298.899115 -373.461542)
			(xy 298.891342 -373.480332) (xy 298.876969 -373.494717) (xy 298.858185 -373.502506) (xy 298.848018 -373.502936)
			(xy 298.131738 -373.502936) (xy 298.121566 -373.502504) (xy 298.102767 -373.494727) (xy 298.08838 -373.480343)
			(xy 298.080598 -373.461546) (xy 298.080176 -373.451374) (xy 298.080176 -373.293386) (xy 298.079778 -373.284197)
			(xy 298.073256 -373.267013) (xy 298.067476 -373.259858) (xy 298.045721 -373.234179) (xy 298.007768 -373.178597)
			(xy 297.976732 -373.118878) (xy 297.953055 -373.055877) (xy 297.937079 -372.990497) (xy 297.929031 -372.923677)
			(xy 297.929028 -372.856374) (xy 297.93707 -372.789553) (xy 297.95304 -372.724172) (xy 297.976711 -372.661169)
			(xy 298.007742 -372.601447) (xy 298.045689 -372.545862) (xy 298.067476 -372.52021) (xy 298.073291 -372.513077)
			(xy 298.079795 -372.495877) (xy 298.080176 -372.486682) (xy 298.080176 -371.993414) (xy 298.079765 -371.984227)
			(xy 298.073252 -371.967042) (xy 298.067476 -371.959886) (xy 298.04565 -371.934265) (xy 298.007699 -371.878675)
			(xy 297.976666 -371.818948) (xy 297.952993 -371.755939) (xy 297.937022 -371.690552) (xy 297.92898 -371.623726)
			(xy 296.826876 -371.623726) (xy 296.827005 -371.624069) (xy 296.843039 -371.689559) (xy 296.851113 -371.756498)
			(xy 296.851112 -371.823923) (xy 296.843035 -371.890861) (xy 296.826999 -371.956351) (xy 296.803235 -372.019448)
			(xy 296.772084 -372.079245) (xy 296.733996 -372.13488) (xy 296.712132 -372.160546) (xy 296.706325 -372.167684)
			(xy 296.699819 -372.18488) (xy 296.699432 -372.194074) (xy 296.699432 -372.351554) (xy 296.698935 -372.361681)
			(xy 296.691217 -372.380407) (xy 296.676933 -372.394765) (xy 296.658249 -372.402581) (xy 296.648124 -372.403116)
			(xy 295.931844 -372.403116) (xy 295.921695 -372.402643) (xy 295.902946 -372.394865) (xy 295.888622 -372.380484)
			(xy 295.880918 -372.361705) (xy 295.880536 -372.351554) (xy 295.880536 -372.194074) (xy 295.88013 -372.184887)
			(xy 295.873613 -372.167703) (xy 295.867836 -372.160546) (xy 295.845985 -372.13487) (xy 295.807893 -372.079238)
			(xy 295.77674 -372.019444) (xy 295.752973 -371.956348) (xy 295.736936 -371.89086) (xy 295.728858 -371.823922)
			(xy 295.728857 -371.756499) (xy 295.736932 -371.689561) (xy 295.752967 -371.624072) (xy 295.776731 -371.560976)
			(xy 295.807882 -371.50118) (xy 295.845972 -371.445547) (xy 295.867836 -371.419882) (xy 295.873627 -371.412733)
			(xy 295.880144 -371.395545) (xy 295.880536 -371.386354) (xy 295.880536 -370.893848) (xy 295.880095 -370.884664)
			(xy 295.873602 -370.86748) (xy 295.867836 -370.86032) (xy 295.845959 -370.834665) (xy 295.807868 -370.77903)
			(xy 295.776716 -370.719233) (xy 295.752951 -370.656134) (xy 295.736915 -370.590644) (xy 295.72884 -370.523704)
			(xy 292.450793 -370.523704) (xy 292.442757 -370.590465) (xy 292.426785 -370.655847) (xy 292.403113 -370.718851)
			(xy 292.37208 -370.778574) (xy 292.334131 -370.83416) (xy 292.312344 -370.859812) (xy 292.306553 -370.866961)
			(xy 292.300036 -370.884149) (xy 292.299644 -370.89334) (xy 292.299644 -371.386862) (xy 292.300085 -371.396046)
			(xy 292.306578 -371.41323) (xy 292.312344 -371.42039) (xy 292.334146 -371.44603) (xy 292.372096 -371.501618)
			(xy 292.403129 -371.561343) (xy 292.42659 -371.623785) (xy 293.528685 -371.623785) (xy 293.528689 -371.556358)
			(xy 293.536768 -371.489418) (xy 293.552807 -371.423927) (xy 293.576575 -371.360828) (xy 293.60773 -371.301031)
			(xy 293.645822 -371.245395) (xy 293.667688 -371.21973) (xy 293.673495 -371.212592) (xy 293.680004 -371.195396)
			(xy 293.680388 -371.186202) (xy 293.680388 -371.028722) (xy 293.680943 -371.018603) (xy 293.688654 -370.999892)
			(xy 293.702919 -370.985537) (xy 293.72158 -370.977708) (xy 293.731696 -370.97716) (xy 294.447976 -370.97716)
			(xy 294.458078 -370.977704) (xy 294.476748 -370.985426) (xy 294.491043 -370.999705) (xy 294.498785 -371.018366)
			(xy 294.499284 -371.028468) (xy 294.499284 -371.186202) (xy 294.499697 -371.195389) (xy 294.506209 -371.212573)
			(xy 294.511984 -371.21973) (xy 294.533811 -371.245426) (xy 294.571902 -371.301056) (xy 294.603055 -371.360847)
			(xy 294.626822 -371.42394) (xy 294.642861 -371.489426) (xy 294.65094 -371.556361) (xy 294.650944 -371.623782)
			(xy 294.642871 -371.690718) (xy 294.626839 -371.756205) (xy 294.603079 -371.8193) (xy 294.571932 -371.879095)
			(xy 294.533846 -371.934729) (xy 294.511984 -371.960394) (xy 294.506206 -371.967552) (xy 294.499681 -371.984733)
			(xy 294.499284 -371.993922) (xy 294.499284 -372.486174) (xy 294.49971 -372.495359) (xy 294.506213 -372.512544)
			(xy 294.511984 -372.519702) (xy 294.533882 -372.545339) (xy 294.571971 -372.600978) (xy 294.603121 -372.660777)
			(xy 294.626884 -372.723878) (xy 294.642917 -372.789371) (xy 294.650991 -372.856312) (xy 294.650988 -372.923739)
			(xy 294.642908 -372.99068) (xy 294.626869 -373.056171) (xy 294.6031 -373.119269) (xy 294.571944 -373.179066)
			(xy 294.533851 -373.234701) (xy 294.511984 -373.260366) (xy 294.506175 -373.267502) (xy 294.499668 -373.2847)
			(xy 294.499284 -373.293894) (xy 294.499284 -373.451374) (xy 294.498753 -373.461496) (xy 294.491038 -373.480212)
			(xy 294.476766 -373.494569) (xy 294.458095 -373.502393) (xy 294.447976 -373.502936) (xy 293.731696 -373.502936)
			(xy 293.721591 -373.502419) (xy 293.70292 -373.494687) (xy 293.688627 -373.4804) (xy 293.680886 -373.461732)
			(xy 293.680388 -373.451628) (xy 293.680388 -373.293894) (xy 293.679983 -373.284706) (xy 293.673466 -373.267522)
			(xy 293.667688 -373.260366) (xy 293.645858 -373.234673) (xy 293.607769 -373.179042) (xy 293.576617 -373.11925)
			(xy 293.552852 -373.056156) (xy 293.536814 -372.990671) (xy 293.528736 -372.923736) (xy 293.528733 -372.856315)
			(xy 293.536805 -372.789379) (xy 293.552837 -372.723892) (xy 293.576597 -372.660797) (xy 293.607743 -372.601002)
			(xy 293.645826 -372.545367) (xy 293.667688 -372.519702) (xy 293.673465 -372.512543) (xy 293.679992 -372.495363)
			(xy 293.680388 -372.486174) (xy 293.680388 -371.993922) (xy 293.67997 -371.984736) (xy 293.673462 -371.967551)
			(xy 293.667688 -371.960394) (xy 293.645787 -371.934759) (xy 293.6077 -371.87912) (xy 293.576552 -371.81932)
			(xy 293.55279 -371.756219) (xy 293.536758 -371.690726) (xy 293.528685 -371.623785) (xy 292.42659 -371.623785)
			(xy 292.426802 -371.624349) (xy 292.442775 -371.689733) (xy 292.450818 -371.756557) (xy 292.450817 -371.823864)
			(xy 292.442771 -371.890688) (xy 292.426796 -371.956071) (xy 292.403121 -372.019076) (xy 292.372085 -372.0788)
			(xy 292.334133 -372.134386) (xy 292.312344 -372.160038) (xy 292.306542 -372.167179) (xy 292.300032 -372.184373)
			(xy 292.299644 -372.193566) (xy 292.299644 -372.351554) (xy 292.299198 -372.361725) (xy 292.291425 -372.380522)
			(xy 292.277046 -372.394909) (xy 292.258253 -372.402693) (xy 292.248082 -372.403116) (xy 291.531802 -372.403116)
			(xy 291.521625 -372.402733) (xy 291.502821 -372.394941) (xy 291.488435 -372.380542) (xy 291.480658 -372.361732)
			(xy 291.48024 -372.351554) (xy 291.48024 -372.193566) (xy 291.479837 -372.184378) (xy 291.473317 -372.167194)
			(xy 291.46754 -372.160038) (xy 291.445766 -372.134374) (xy 291.407817 -372.07879) (xy 291.376783 -372.019068)
			(xy 291.353109 -371.956065) (xy 291.337135 -371.890684) (xy 291.32909 -371.823862) (xy 291.329089 -371.756559)
			(xy 291.337132 -371.689737) (xy 291.353103 -371.624356) (xy 291.376774 -371.561352) (xy 291.407806 -371.501628)
			(xy 291.445753 -371.446042) (xy 291.46754 -371.42039) (xy 291.473328 -371.413239) (xy 291.479847 -371.396053)
			(xy 291.48024 -371.386862) (xy 291.48024 -370.89334) (xy 291.479801 -370.884156) (xy 291.473306 -370.866972)
			(xy 291.46754 -370.859812) (xy 291.44574 -370.83417) (xy 291.407792 -370.778582) (xy 291.376759 -370.718857)
			(xy 291.353087 -370.655851) (xy 291.337115 -370.590468) (xy 291.329071 -370.523644) (xy 288.051032 -370.523644)
			(xy 288.051032 -370.523703) (xy 288.042957 -370.590641) (xy 288.026921 -370.65613) (xy 288.003156 -370.719227)
			(xy 287.972004 -370.779022) (xy 287.933913 -370.834656) (xy 287.912048 -370.86032) (xy 287.906254 -370.867467)
			(xy 287.899739 -370.884656) (xy 287.899348 -370.893848) (xy 287.899348 -371.386354) (xy 287.899792 -371.395537)
			(xy 287.906284 -371.412721) (xy 287.912048 -371.419882) (xy 287.933928 -371.445535) (xy 287.972019 -371.50117)
			(xy 288.003172 -371.560967) (xy 288.02681 -371.623726) (xy 289.128893 -371.623726) (xy 289.128896 -371.556417)
			(xy 289.136945 -371.489591) (xy 289.152924 -371.424206) (xy 289.176603 -371.3612) (xy 289.207644 -371.301475)
			(xy 289.2456 -371.245889) (xy 289.267392 -371.220238) (xy 289.273196 -371.213098) (xy 289.279707 -371.195904)
			(xy 289.280092 -371.18671) (xy 289.280092 -371.028722) (xy 289.28065 -371.018571) (xy 289.288409 -370.999811)
			(xy 289.302754 -370.985447) (xy 289.321504 -370.977663) (xy 289.331654 -370.97716) (xy 290.047934 -370.97716)
			(xy 290.058097 -370.977606) (xy 290.076871 -370.985396) (xy 290.091236 -370.999776) (xy 290.099005 -371.018559)
			(xy 290.099496 -371.028722) (xy 290.099496 -371.18671) (xy 290.099902 -371.195898) (xy 290.106419 -371.213082)
			(xy 290.112196 -371.220238) (xy 290.133945 -371.245921) (xy 290.171893 -371.301504) (xy 290.202926 -371.361224)
			(xy 290.226599 -371.424224) (xy 290.242574 -371.489602) (xy 290.250621 -371.556421) (xy 290.250624 -371.623722)
			(xy 290.242584 -371.690542) (xy 290.226616 -371.755921) (xy 290.202949 -371.818924) (xy 290.171922 -371.878647)
			(xy 290.13398 -371.934233) (xy 290.112196 -371.959886) (xy 290.10638 -371.967017) (xy 290.099877 -371.984218)
			(xy 290.099496 -371.993414) (xy 290.099496 -372.486682) (xy 290.099916 -372.495868) (xy 290.106423 -372.513053)
			(xy 290.112196 -372.52021) (xy 290.134016 -372.545835) (xy 290.171962 -372.601426) (xy 290.202991 -372.661154)
			(xy 290.226661 -372.724162) (xy 290.24263 -372.789547) (xy 290.250671 -372.856372) (xy 290.250668 -372.923679)
			(xy 290.242621 -372.990503) (xy 290.226646 -373.055887) (xy 290.202971 -373.118893) (xy 290.171935 -373.178618)
			(xy 290.133985 -373.234205) (xy 290.112196 -373.259858) (xy 290.106392 -373.266998) (xy 290.099882 -373.284192)
			(xy 290.099496 -373.293386) (xy 290.099496 -373.451374) (xy 290.098946 -373.461526) (xy 290.091187 -373.480288)
			(xy 290.076838 -373.494653) (xy 290.058085 -373.502435) (xy 290.047934 -373.502936) (xy 289.331654 -373.502936)
			(xy 289.32149 -373.502504) (xy 289.302715 -373.494709) (xy 289.28835 -373.480325) (xy 289.280582 -373.461539)
			(xy 289.280092 -373.451374) (xy 289.280092 -373.293386) (xy 289.27969 -373.284198) (xy 289.273171 -373.267014)
			(xy 289.267392 -373.259858) (xy 289.245636 -373.234179) (xy 289.207683 -373.178598) (xy 289.176645 -373.118878)
			(xy 289.152968 -373.055877) (xy 289.136991 -372.990498) (xy 289.128943 -372.923677) (xy 289.12894 -372.856374)
			(xy 289.136982 -372.789553) (xy 289.152953 -372.724172) (xy 289.176624 -372.661168) (xy 289.207656 -372.601446)
			(xy 289.245605 -372.545861) (xy 289.267392 -372.52021) (xy 289.273208 -372.513079) (xy 289.279711 -372.495878)
			(xy 289.280092 -372.486682) (xy 289.280092 -371.993414) (xy 289.279677 -371.984227) (xy 289.273167 -371.967043)
			(xy 289.267392 -371.959886) (xy 289.245565 -371.934265) (xy 289.207614 -371.878676) (xy 289.17658 -371.818948)
			(xy 289.152907 -371.755939) (xy 289.136935 -371.690553) (xy 289.128893 -371.623726) (xy 288.02681 -371.623726)
			(xy 288.026938 -371.624066) (xy 288.042974 -371.689557) (xy 288.05105 -371.756498) (xy 288.051048 -371.823923)
			(xy 288.04297 -371.890864) (xy 288.026932 -371.956354) (xy 288.003164 -372.019452) (xy 287.972008 -372.079248)
			(xy 287.933915 -372.134882) (xy 287.912048 -372.160546) (xy 287.906243 -372.167685) (xy 287.899735 -372.18488)
			(xy 287.899348 -372.194074) (xy 287.899348 -372.351554) (xy 287.898835 -372.361679) (xy 287.89112 -372.380402)
			(xy 287.876842 -372.39476) (xy 287.858162 -372.402579) (xy 287.84804 -372.403116) (xy 287.13176 -372.403116)
			(xy 287.121651 -372.402648) (xy 287.102975 -372.3949) (xy 287.088682 -372.380598) (xy 287.080946 -372.361918)
			(xy 287.080452 -372.351808) (xy 287.080452 -372.194074) (xy 287.080043 -372.184887) (xy 287.073527 -372.167703)
			(xy 287.067752 -372.160546) (xy 287.0459 -372.13487) (xy 287.007807 -372.079238) (xy 286.976653 -372.019444)
			(xy 286.952886 -371.956349) (xy 286.936848 -371.89086) (xy 286.92877 -371.823922) (xy 286.928769 -371.756499)
			(xy 286.936844 -371.68956) (xy 286.95288 -371.624072) (xy 286.976645 -371.560975) (xy 287.007797 -371.50118)
			(xy 287.045887 -371.445546) (xy 287.067752 -371.419882) (xy 287.073545 -371.412735) (xy 287.08006 -371.395546)
			(xy 287.080452 -371.386354) (xy 287.080452 -370.893848) (xy 287.080007 -370.884665) (xy 287.073516 -370.867481)
			(xy 287.067752 -370.86032) (xy 287.045874 -370.834665) (xy 287.007783 -370.779031) (xy 286.97663 -370.719233)
			(xy 286.952864 -370.656135) (xy 286.936828 -370.590644) (xy 286.928752 -370.523704) (xy 266.12088 -370.523704)
			(xy 266.12088 -374.423882) (xy 286.928731 -374.423882) (xy 286.928735 -374.356454) (xy 286.936815 -374.289512)
			(xy 286.952857 -374.22402) (xy 286.976628 -374.160921) (xy 287.007787 -374.101124) (xy 287.045884 -374.04549)
			(xy 287.067752 -374.019826) (xy 287.073569 -374.012695) (xy 287.08007 -373.995494) (xy 287.080452 -373.986298)
			(xy 287.080452 -373.828818) (xy 287.080942 -373.818691) (xy 287.088666 -373.799968) (xy 287.102951 -373.785611)
			(xy 287.121636 -373.777793) (xy 287.13176 -373.777256) (xy 287.84804 -373.777256) (xy 287.858146 -373.777751)
			(xy 287.876817 -373.785494) (xy 287.891108 -373.799787) (xy 287.898849 -373.818458) (xy 287.899348 -373.828564)
			(xy 287.899348 -373.986298) (xy 287.899771 -373.995484) (xy 287.906277 -374.012667) (xy 287.912048 -374.019826)
			(xy 287.933873 -374.045524) (xy 287.971966 -374.101153) (xy 288.003121 -374.160944) (xy 288.02689 -374.224037)
			(xy 288.04293 -374.289522) (xy 288.05101 -374.356458) (xy 288.051014 -374.423823) (xy 291.32905 -374.423823)
			(xy 291.329054 -374.356514) (xy 291.337102 -374.289689) (xy 291.35308 -374.224304) (xy 291.376757 -374.161298)
			(xy 291.407796 -374.101573) (xy 291.44575 -374.045986) (xy 291.46754 -374.020334) (xy 291.473352 -374.0132)
			(xy 291.479857 -373.996001) (xy 291.48024 -373.986806) (xy 291.48024 -373.828818) (xy 291.480678 -373.818647)
			(xy 291.488458 -373.799853) (xy 291.502839 -373.785467) (xy 291.521631 -373.777682) (xy 291.531802 -373.777256)
			(xy 292.248082 -373.777256) (xy 292.258255 -373.777679) (xy 292.277053 -373.785461) (xy 292.291439 -373.799847)
			(xy 292.299221 -373.818645) (xy 292.299644 -373.828818) (xy 292.299644 -373.986806) (xy 292.300064 -373.995992)
			(xy 292.306572 -374.013176) (xy 292.312344 -374.020334) (xy 292.334091 -374.04602) (xy 292.372042 -374.101601)
			(xy 292.403078 -374.16132) (xy 292.426754 -374.22432) (xy 292.44273 -374.289698) (xy 292.450778 -374.356517)
			(xy 292.450782 -374.423819) (xy 292.450774 -374.423882) (xy 295.728819 -374.423882) (xy 295.728822 -374.356455)
			(xy 295.736903 -374.289513) (xy 295.752944 -374.224021) (xy 295.776715 -374.160922) (xy 295.807872 -374.101125)
			(xy 295.845968 -374.045491) (xy 295.867836 -374.019826) (xy 295.873651 -374.012694) (xy 295.880154 -373.995493)
			(xy 295.880536 -373.986298) (xy 295.880536 -373.828818) (xy 295.881041 -373.818693) (xy 295.888762 -373.799973)
			(xy 295.903043 -373.785616) (xy 295.921722 -373.777796) (xy 295.931844 -373.777256) (xy 296.648124 -373.777256)
			(xy 296.658274 -373.777701) (xy 296.677019 -373.785496) (xy 296.69134 -373.799885) (xy 296.699046 -373.818666)
			(xy 296.699432 -373.828818) (xy 296.699432 -373.986298) (xy 296.699858 -373.995483) (xy 296.706362 -374.012667)
			(xy 296.712132 -374.019826) (xy 296.733954 -374.045526) (xy 296.772041 -374.101156) (xy 296.803192 -374.160948)
			(xy 296.826957 -374.22404) (xy 296.842995 -374.289525) (xy 296.851073 -374.356459) (xy 296.851077 -374.423878)
			(xy 296.851077 -374.423882) (xy 300.12861 -374.423882) (xy 300.128613 -374.356455) (xy 300.136694 -374.289513)
			(xy 300.152734 -374.224021) (xy 300.176504 -374.160923) (xy 300.207661 -374.101126) (xy 300.245757 -374.045491)
			(xy 300.267624 -374.019826) (xy 300.273437 -374.012693) (xy 300.279941 -373.995493) (xy 300.280324 -373.986298)
			(xy 300.280324 -373.828818) (xy 300.280841 -373.818694) (xy 300.28856 -373.799977) (xy 300.302837 -373.78562)
			(xy 300.321511 -373.777798) (xy 300.331632 -373.777256) (xy 301.047912 -373.777256) (xy 301.058061 -373.777711)
			(xy 301.076806 -373.785502) (xy 301.091127 -373.799888) (xy 301.098834 -373.818667) (xy 301.09922 -373.828818)
			(xy 301.09922 -373.986298) (xy 301.099627 -373.995486) (xy 301.106142 -374.01267) (xy 301.11192 -374.019826)
			(xy 301.133742 -374.045526) (xy 301.171831 -374.101156) (xy 301.202982 -374.160947) (xy 301.226748 -374.22404)
			(xy 301.242785 -374.289524) (xy 301.250864 -374.356458) (xy 301.250868 -374.423823) (xy 330.929168 -374.423823)
			(xy 330.929172 -374.356514) (xy 330.937221 -374.289688) (xy 330.953199 -374.224303) (xy 330.976878 -374.161297)
			(xy 331.007917 -374.101572) (xy 331.045873 -374.045986) (xy 331.067664 -374.020334) (xy 331.073479 -374.013202)
			(xy 331.079981 -373.996001) (xy 331.080364 -373.986806) (xy 331.080364 -373.828818) (xy 331.080779 -373.818644)
			(xy 331.088563 -373.799845) (xy 331.102952 -373.785458) (xy 331.121752 -373.777677) (xy 331.131926 -373.777256)
			(xy 331.848206 -373.777256) (xy 331.85838 -373.777659) (xy 331.877178 -373.78545) (xy 331.891564 -373.799842)
			(xy 331.899345 -373.818644) (xy 331.899768 -373.828818) (xy 331.899768 -373.986806) (xy 331.900182 -373.995993)
			(xy 331.906694 -374.013177) (xy 331.912468 -374.020334) (xy 331.934214 -374.04602) (xy 331.972164 -374.101602)
			(xy 332.003198 -374.161321) (xy 332.026873 -374.224321) (xy 332.042849 -374.289699) (xy 332.050896 -374.356518)
			(xy 332.0509 -374.423819) (xy 332.050892 -374.423882) (xy 335.328961 -374.423882) (xy 335.328965 -374.356455)
			(xy 335.337045 -374.289515) (xy 335.353083 -374.224024) (xy 335.37685 -374.160926) (xy 335.408004 -374.101128)
			(xy 335.446095 -374.045492) (xy 335.46796 -374.019826) (xy 335.473778 -374.012696) (xy 335.480278 -373.995494)
			(xy 335.48066 -373.986298) (xy 335.48066 -373.828818) (xy 335.481142 -373.81869) (xy 335.488867 -373.799965)
			(xy 335.503156 -373.785608) (xy 335.521842 -373.777791) (xy 335.531968 -373.777256) (xy 336.248248 -373.777256)
			(xy 336.2584 -373.777682) (xy 336.277145 -373.785485) (xy 336.291465 -373.799879) (xy 336.299171 -373.818664)
			(xy 336.299556 -373.828818) (xy 336.299556 -373.986298) (xy 336.299977 -373.995484) (xy 336.306484 -374.012668)
			(xy 336.312256 -374.019826) (xy 336.33408 -374.045525) (xy 336.372173 -374.101153) (xy 336.403328 -374.160944)
			(xy 336.427097 -374.224037) (xy 336.443136 -374.289523) (xy 336.451216 -374.356458) (xy 336.45122 -374.423823)
			(xy 339.729256 -374.423823) (xy 339.72926 -374.356514) (xy 339.737309 -374.289689) (xy 339.753286 -374.224304)
			(xy 339.776964 -374.161298) (xy 339.808003 -374.101573) (xy 339.845957 -374.045986) (xy 339.867748 -374.020334)
			(xy 339.873561 -374.013201) (xy 339.880065 -373.996001) (xy 339.880448 -373.986806) (xy 339.880448 -373.828818)
			(xy 339.880879 -373.818646) (xy 339.88866 -373.79985) (xy 339.903043 -373.785464) (xy 339.921838 -373.77768)
			(xy 339.93201 -373.777256) (xy 340.64829 -373.777256) (xy 340.658463 -373.777672) (xy 340.677261 -373.785457)
			(xy 340.691647 -373.799846) (xy 340.699429 -373.818645) (xy 340.699852 -373.828818) (xy 340.699852 -373.986806)
			(xy 340.70027 -373.995992) (xy 340.706779 -374.013176) (xy 340.712552 -374.020334) (xy 340.734299 -374.04602)
			(xy 340.772249 -374.101601) (xy 340.803285 -374.16132) (xy 340.82696 -374.22432) (xy 340.842936 -374.289699)
			(xy 340.850984 -374.356517) (xy 340.850988 -374.423819) (xy 340.850988 -374.423823) (xy 344.129047 -374.423823)
			(xy 344.129051 -374.356514) (xy 344.137099 -374.289689) (xy 344.153077 -374.224304) (xy 344.176754 -374.161298)
			(xy 344.207792 -374.101573) (xy 344.245746 -374.045986) (xy 344.267536 -374.020334) (xy 344.273348 -374.0132)
			(xy 344.279852 -373.996001) (xy 344.280236 -373.986806) (xy 344.280236 -373.828818) (xy 344.280678 -373.818648)
			(xy 344.288457 -373.799854) (xy 344.302837 -373.785468) (xy 344.321628 -373.777682) (xy 344.331798 -373.777256)
			(xy 345.048078 -373.777256) (xy 345.05825 -373.777683) (xy 345.077048 -373.785464) (xy 345.091434 -373.799849)
			(xy 345.099217 -373.818646) (xy 345.09964 -373.828818) (xy 345.09964 -373.986806) (xy 345.100061 -373.995992)
			(xy 345.106569 -374.013175) (xy 345.11234 -374.020334) (xy 345.134087 -374.04602) (xy 345.172038 -374.101601)
			(xy 345.203075 -374.16132) (xy 345.226751 -374.22432) (xy 345.242727 -374.289698) (xy 345.250775 -374.356517)
			(xy 345.250779 -374.423819) (xy 345.250779 -374.423823) (xy 374.929078 -374.423823) (xy 374.929081 -374.356514)
			(xy 374.93713 -374.289688) (xy 374.953109 -374.224303) (xy 374.976788 -374.161296) (xy 375.007828 -374.101572)
			(xy 375.045784 -374.045985) (xy 375.067576 -374.020334) (xy 375.07338 -374.013194) (xy 375.079891 -373.996)
			(xy 375.080276 -373.986806) (xy 375.080276 -373.828818) (xy 375.080679 -373.818643) (xy 375.088465 -373.799841)
			(xy 375.102858 -373.785454) (xy 375.121663 -373.777675) (xy 375.131838 -373.777256) (xy 375.848118 -373.777256)
			(xy 375.858279 -373.777719) (xy 375.877052 -373.785503) (xy 375.891418 -373.799878) (xy 375.899188 -373.818656)
			(xy 375.89968 -373.828818) (xy 375.89968 -373.986806) (xy 375.900092 -373.995993) (xy 375.906605 -374.013177)
			(xy 375.91238 -374.020334) (xy 375.934126 -374.046021) (xy 375.972074 -374.101603) (xy 376.003108 -374.161322)
			(xy 376.026783 -374.224321) (xy 376.042758 -374.289699) (xy 376.050805 -374.356518) (xy 376.050809 -374.423819)
			(xy 376.050801 -374.423882) (xy 379.32887 -374.423882) (xy 379.328874 -374.356455) (xy 379.336954 -374.289515)
			(xy 379.352993 -374.224024) (xy 379.376761 -374.160925) (xy 379.407915 -374.101127) (xy 379.446007 -374.045492)
			(xy 379.467872 -374.019826) (xy 379.473691 -374.012697) (xy 379.48019 -373.995494) (xy 379.480572 -373.986298)
			(xy 379.480572 -373.828818) (xy 379.481042 -373.818688) (xy 379.48877 -373.799962) (xy 379.503062 -373.785604)
			(xy 379.521753 -373.777789) (xy 379.53188 -373.777256) (xy 380.24816 -373.777256) (xy 380.258306 -373.777754)
			(xy 380.277049 -373.785528) (xy 380.291372 -373.799901) (xy 380.299081 -373.818671) (xy 380.299468 -373.828818)
			(xy 380.299468 -373.986298) (xy 380.299886 -373.995484) (xy 380.306395 -374.012668) (xy 380.312168 -374.019826)
			(xy 380.333992 -374.045525) (xy 380.372084 -374.101154) (xy 380.403238 -374.160945) (xy 380.427006 -374.224038)
			(xy 380.443046 -374.289523) (xy 380.451125 -374.356458) (xy 380.451129 -374.423823) (xy 383.729165 -374.423823)
			(xy 383.729169 -374.356514) (xy 383.737218 -374.289688) (xy 383.753196 -374.224303) (xy 383.776874 -374.161297)
			(xy 383.807914 -374.101572) (xy 383.845869 -374.045986) (xy 383.86766 -374.020334) (xy 383.873474 -374.013202)
			(xy 383.879977 -373.996001) (xy 383.88036 -373.986806) (xy 383.88036 -373.828818) (xy 383.880779 -373.818645)
			(xy 383.888562 -373.799846) (xy 383.90295 -373.78546) (xy 383.921749 -373.777678) (xy 383.931922 -373.777256)
			(xy 384.648202 -373.777256) (xy 384.658376 -373.777663) (xy 384.677174 -373.785452) (xy 384.69156 -373.799843)
			(xy 384.699341 -373.818644) (xy 384.699764 -373.828818) (xy 384.699764 -373.986806) (xy 384.700179 -373.995992)
			(xy 384.70669 -374.013176) (xy 384.712464 -374.020334) (xy 384.73421 -374.04602) (xy 384.77216 -374.101602)
			(xy 384.803195 -374.161321) (xy 384.82687 -374.224321) (xy 384.842846 -374.289699) (xy 384.850893 -374.356518)
			(xy 384.850897 -374.423819) (xy 384.850897 -374.423823) (xy 388.128956 -374.423823) (xy 388.12896 -374.356514)
			(xy 388.137009 -374.289689) (xy 388.152986 -374.224304) (xy 388.176664 -374.161298) (xy 388.207703 -374.101573)
			(xy 388.245657 -374.045986) (xy 388.267448 -374.020334) (xy 388.273261 -374.013201) (xy 388.279765 -373.996001)
			(xy 388.280148 -373.986806) (xy 388.280148 -373.828818) (xy 388.280579 -373.818646) (xy 388.28836 -373.79985)
			(xy 388.302743 -373.785464) (xy 388.321538 -373.77768) (xy 388.33171 -373.777256) (xy 389.04799 -373.777256)
			(xy 389.058163 -373.777672) (xy 389.076961 -373.785457) (xy 389.091347 -373.799846) (xy 389.099129 -373.818645)
			(xy 389.099552 -373.828818) (xy 389.099552 -373.986806) (xy 389.09997 -373.995992) (xy 389.106479 -374.013176)
			(xy 389.112252 -374.020334) (xy 389.133999 -374.04602) (xy 389.171949 -374.101601) (xy 389.202985 -374.16132)
			(xy 389.22666 -374.22432) (xy 389.242636 -374.289699) (xy 389.250684 -374.356517) (xy 389.250688 -374.423819)
			(xy 389.250688 -374.423823) (xy 418.928987 -374.423823) (xy 418.928991 -374.356514) (xy 418.93704 -374.289688)
			(xy 418.953019 -374.224302) (xy 418.976698 -374.161296) (xy 419.007739 -374.101572) (xy 419.045696 -374.045986)
			(xy 419.067488 -374.020334) (xy 419.073294 -374.013195) (xy 419.079803 -373.996) (xy 419.080188 -373.986806)
			(xy 419.080188 -373.828818) (xy 419.08058 -373.818641) (xy 419.088368 -373.799837) (xy 419.102764 -373.78545)
			(xy 419.121573 -373.777673) (xy 419.13175 -373.777256) (xy 419.84803 -373.777256) (xy 419.858192 -373.777709)
			(xy 419.876965 -373.785497) (xy 419.89133 -373.799875) (xy 419.8991 -373.818656) (xy 419.899592 -373.828818)
			(xy 419.899592 -373.986806) (xy 419.900001 -373.995993) (xy 419.906516 -374.013177) (xy 419.912292 -374.020334)
			(xy 419.934038 -374.04602) (xy 419.971986 -374.101603) (xy 420.003019 -374.161322) (xy 420.026693 -374.224322)
			(xy 420.042668 -374.2897) (xy 420.050715 -374.356518) (xy 420.050719 -374.423819) (xy 420.050711 -374.423882)
			(xy 423.328779 -374.423882) (xy 423.328783 -374.356455) (xy 423.336863 -374.289514) (xy 423.352903 -374.224023)
			(xy 423.376671 -374.160925) (xy 423.407825 -374.101127) (xy 423.445918 -374.045492) (xy 423.467784 -374.019826)
			(xy 423.473593 -374.012689) (xy 423.480101 -373.995492) (xy 423.480484 -373.986298) (xy 423.480484 -373.828818)
			(xy 423.480942 -373.818687) (xy 423.488672 -373.799958) (xy 423.502968 -373.785599) (xy 423.521663 -373.777787)
			(xy 423.531792 -373.777256) (xy 424.248072 -373.777256) (xy 424.258174 -373.777807) (xy 424.276843 -373.785527)
			(xy 424.291137 -373.799803) (xy 424.298881 -373.818463) (xy 424.29938 -373.828564) (xy 424.29938 -373.986298)
			(xy 424.299795 -373.995485) (xy 424.306306 -374.012669) (xy 424.31208 -374.019826) (xy 424.333903 -374.045525)
			(xy 424.371995 -374.101154) (xy 424.403148 -374.160946) (xy 424.426916 -374.224038) (xy 424.442955 -374.289523)
			(xy 424.451034 -374.356458) (xy 424.451038 -374.423823) (xy 427.729074 -374.423823) (xy 427.729078 -374.356514)
			(xy 427.737127 -374.289688) (xy 427.753106 -374.224303) (xy 427.776784 -374.161296) (xy 427.807824 -374.101572)
			(xy 427.84578 -374.045986) (xy 427.867572 -374.020334) (xy 427.873388 -374.013203) (xy 427.879889 -373.996001)
			(xy 427.880272 -373.986806) (xy 427.880272 -373.828818) (xy 427.880679 -373.818643) (xy 427.888465 -373.799842)
			(xy 427.902856 -373.785456) (xy 427.921659 -373.777676) (xy 427.931834 -373.777256) (xy 428.648114 -373.777256)
			(xy 428.658289 -373.777653) (xy 428.677087 -373.785446) (xy 428.691472 -373.79984) (xy 428.699253 -373.818643)
			(xy 428.699676 -373.828818) (xy 428.699676 -373.986806) (xy 428.700088 -373.995993) (xy 428.706601 -374.013177)
			(xy 428.712376 -374.020334) (xy 428.734122 -374.04602) (xy 428.772071 -374.101602) (xy 428.803105 -374.161321)
			(xy 428.82678 -374.224321) (xy 428.842755 -374.289699) (xy 428.850802 -374.356518) (xy 428.850806 -374.423819)
			(xy 428.850806 -374.423823) (xy 432.128865 -374.423823) (xy 432.128869 -374.356514) (xy 432.136918 -374.289688)
			(xy 432.152896 -374.224303) (xy 432.176574 -374.161297) (xy 432.207614 -374.101572) (xy 432.245569 -374.045986)
			(xy 432.26736 -374.020334) (xy 432.273174 -374.013202) (xy 432.279677 -373.996001) (xy 432.28006 -373.986806)
			(xy 432.28006 -373.828818) (xy 432.280479 -373.818645) (xy 432.288262 -373.799846) (xy 432.30265 -373.78546)
			(xy 432.321449 -373.777678) (xy 432.331622 -373.777256) (xy 433.047902 -373.777256) (xy 433.058076 -373.777663)
			(xy 433.076874 -373.785452) (xy 433.09126 -373.799843) (xy 433.099041 -373.818644) (xy 433.099464 -373.828818)
			(xy 433.099464 -373.986806) (xy 433.099879 -373.995992) (xy 433.10639 -374.013176) (xy 433.112164 -374.020334)
			(xy 433.13391 -374.04602) (xy 433.17186 -374.101602) (xy 433.202895 -374.161321) (xy 433.22657 -374.224321)
			(xy 433.242546 -374.289699) (xy 433.250593 -374.356518) (xy 433.250597 -374.423819) (xy 433.242557 -374.490639)
			(xy 433.226589 -374.556019) (xy 433.202921 -374.619021) (xy 433.171892 -374.678744) (xy 433.133949 -374.73433)
			(xy 433.112164 -374.759982) (xy 433.106346 -374.767112) (xy 433.099845 -374.784314) (xy 433.099464 -374.79351)
			(xy 433.099464 -375.286778) (xy 433.099893 -375.295963) (xy 433.106394 -375.313147) (xy 433.112164 -375.320306)
			(xy 433.133981 -375.345934) (xy 433.171929 -375.401524) (xy 433.202961 -375.461251) (xy 433.226632 -375.524259)
			(xy 433.242603 -375.589644) (xy 433.250644 -375.656469) (xy 433.250642 -375.723776) (xy 433.242594 -375.790601)
			(xy 433.226618 -375.855985) (xy 433.202942 -375.91899) (xy 433.171906 -375.978715) (xy 433.133954 -376.034302)
			(xy 433.112164 -376.059954) (xy 433.106357 -376.067092) (xy 433.09985 -376.084288) (xy 433.099464 -376.093482)
			(xy 433.099464 -376.25147) (xy 433.099011 -376.261639) (xy 433.091237 -376.280433) (xy 433.07686 -376.294819)
			(xy 433.058071 -376.302605) (xy 433.047902 -376.303032) (xy 432.331622 -376.303032) (xy 432.321448 -376.302617)
			(xy 432.302648 -376.294834) (xy 432.288262 -376.280445) (xy 432.280481 -376.261644) (xy 432.28006 -376.25147)
			(xy 432.28006 -376.093482) (xy 432.279645 -376.084296) (xy 432.273133 -376.067112) (xy 432.26736 -376.059954)
			(xy 432.245601 -376.034278) (xy 432.20765 -375.978695) (xy 432.176614 -375.918975) (xy 432.152939 -375.855974)
			(xy 432.136963 -375.790594) (xy 432.128917 -375.723774) (xy 432.128914 -375.656471) (xy 432.136955 -375.58965)
			(xy 432.152926 -375.524269) (xy 432.176596 -375.461266) (xy 432.207627 -375.401543) (xy 432.245574 -375.345958)
			(xy 432.26736 -375.320306) (xy 432.273144 -375.313152) (xy 432.279664 -375.295968) (xy 432.28006 -375.286778)
			(xy 432.28006 -374.79351) (xy 432.279632 -374.784325) (xy 432.273129 -374.767141) (xy 432.26736 -374.759982)
			(xy 432.24553 -374.734364) (xy 432.207581 -374.678773) (xy 432.176549 -374.619045) (xy 432.152877 -374.556036)
			(xy 432.136907 -374.49065) (xy 432.128865 -374.423823) (xy 428.850806 -374.423823) (xy 428.842766 -374.490639)
			(xy 428.826798 -374.556018) (xy 428.803131 -374.619021) (xy 428.772103 -374.678743) (xy 428.73416 -374.734329)
			(xy 428.712376 -374.759982) (xy 428.706559 -374.767113) (xy 428.700057 -374.784314) (xy 428.699676 -374.79351)
			(xy 428.699676 -375.286778) (xy 428.700102 -375.295963) (xy 428.706605 -375.313148) (xy 428.712376 -375.320306)
			(xy 428.734193 -375.345934) (xy 428.77214 -375.401524) (xy 428.803171 -375.461251) (xy 428.826841 -375.524259)
			(xy 428.842812 -375.589644) (xy 428.850853 -375.656469) (xy 428.850851 -375.723776) (xy 428.842804 -375.790601)
			(xy 428.826828 -375.855984) (xy 428.803152 -375.91899) (xy 428.772117 -375.978714) (xy 428.734165 -376.034302)
			(xy 428.712376 -376.059954) (xy 428.706571 -376.067093) (xy 428.700062 -376.084288) (xy 428.699676 -376.093482)
			(xy 428.699676 -376.25147) (xy 428.699212 -376.261638) (xy 428.691439 -376.280429) (xy 428.677066 -376.294815)
			(xy 428.658282 -376.302603) (xy 428.648114 -376.303032) (xy 427.931834 -376.303032) (xy 427.921661 -376.302607)
			(xy 427.902861 -376.294828) (xy 427.888474 -376.280442) (xy 427.880693 -376.261643) (xy 427.880272 -376.25147)
			(xy 427.880272 -376.093482) (xy 427.879877 -376.084293) (xy 427.873353 -376.067109) (xy 427.867572 -376.059954)
			(xy 427.845813 -376.034278) (xy 427.807861 -375.978696) (xy 427.776825 -375.918976) (xy 427.753149 -375.855974)
			(xy 427.737173 -375.790595) (xy 427.729126 -375.723774) (xy 427.729123 -375.656471) (xy 427.737165 -375.58965)
			(xy 427.753135 -375.524269) (xy 427.776806 -375.461266) (xy 427.807838 -375.401543) (xy 427.845785 -375.345958)
			(xy 427.867572 -375.320306) (xy 427.873357 -375.313153) (xy 427.879877 -375.295968) (xy 427.880272 -375.286778)
			(xy 427.880272 -374.79351) (xy 427.879863 -374.784323) (xy 427.873349 -374.767138) (xy 427.867572 -374.759982)
			(xy 427.845742 -374.734364) (xy 427.807792 -374.678774) (xy 427.776759 -374.619046) (xy 427.753087 -374.556037)
			(xy 427.737116 -374.49065) (xy 427.729074 -374.423823) (xy 424.451038 -374.423823) (xy 424.451038 -374.423879)
			(xy 424.442966 -374.490815) (xy 424.426934 -374.556302) (xy 424.403174 -374.619397) (xy 424.372027 -374.679192)
			(xy 424.333942 -374.734825) (xy 424.31208 -374.76049) (xy 424.30626 -374.767619) (xy 424.29976 -374.784822)
			(xy 424.29938 -374.794018) (xy 424.29938 -375.28627) (xy 424.299809 -375.295455) (xy 424.30631 -375.312639)
			(xy 424.31208 -375.319798) (xy 424.333974 -375.345439) (xy 424.372063 -375.401076) (xy 424.403214 -375.460876)
			(xy 424.426977 -375.523976) (xy 424.443011 -375.589468) (xy 424.451085 -375.656409) (xy 424.451082 -375.723836)
			(xy 424.443003 -375.790776) (xy 424.426964 -375.856267) (xy 424.403195 -375.919366) (xy 424.37204 -375.979163)
			(xy 424.333946 -376.034797) (xy 424.31208 -376.060462) (xy 424.306272 -376.067599) (xy 424.299765 -376.084796)
			(xy 424.29938 -376.09399) (xy 424.29938 -376.25147) (xy 424.29885 -376.261592) (xy 424.291135 -376.280309)
			(xy 424.276863 -376.294666) (xy 424.258191 -376.30249) (xy 424.248072 -376.303032) (xy 423.531792 -376.303032)
			(xy 423.521687 -376.302522) (xy 423.503015 -376.294788) (xy 423.488721 -376.280499) (xy 423.480981 -376.261829)
			(xy 423.480484 -376.251724) (xy 423.480484 -376.09399) (xy 423.480082 -376.084802) (xy 423.473563 -376.067617)
			(xy 423.467784 -376.060462) (xy 423.44595 -376.034772) (xy 423.407862 -375.979141) (xy 423.37671 -375.919348)
			(xy 423.352945 -375.856254) (xy 423.336908 -375.790768) (xy 423.32883 -375.723833) (xy 423.328827 -375.656412)
			(xy 423.3369 -375.589476) (xy 423.352932 -375.523989) (xy 423.376692 -375.460893) (xy 423.407838 -375.401098)
			(xy 423.445922 -375.345463) (xy 423.467784 -375.319798) (xy 423.473562 -375.31264) (xy 423.480088 -375.295459)
			(xy 423.480484 -375.28627) (xy 423.480484 -374.794018) (xy 423.480069 -374.784831) (xy 423.473559 -374.767647)
			(xy 423.467784 -374.76049) (xy 423.445879 -374.734859) (xy 423.407793 -374.679219) (xy 423.376645 -374.619418)
			(xy 423.352884 -374.556317) (xy 423.336852 -374.490824) (xy 423.328779 -374.423882) (xy 420.050711 -374.423882)
			(xy 420.042679 -374.490638) (xy 420.026712 -374.556018) (xy 420.003045 -374.61902) (xy 419.972018 -374.678743)
			(xy 419.934076 -374.73433) (xy 419.912292 -374.759982) (xy 419.906477 -374.767114) (xy 419.899974 -374.784315)
			(xy 419.899592 -374.79351) (xy 419.899592 -375.286778) (xy 419.900015 -375.295964) (xy 419.90652 -375.313148)
			(xy 419.912292 -375.320306) (xy 419.934108 -375.345934) (xy 419.972054 -375.401525) (xy 420.003084 -375.461252)
			(xy 420.026754 -375.52426) (xy 420.042724 -375.589644) (xy 420.050765 -375.656469) (xy 420.050763 -375.723776)
			(xy 420.042716 -375.7906) (xy 420.026741 -375.855984) (xy 420.003066 -375.918989) (xy 419.972031 -375.978714)
			(xy 419.934081 -376.034301) (xy 419.912292 -376.059954) (xy 419.906489 -376.067095) (xy 419.899978 -376.084289)
			(xy 419.899592 -376.093482) (xy 419.899592 -376.25147) (xy 419.899043 -376.261622) (xy 419.891284 -376.280385)
			(xy 419.876935 -376.29475) (xy 419.858182 -376.302531) (xy 419.84803 -376.303032) (xy 419.13175 -376.303032)
			(xy 419.121578 -376.302595) (xy 419.102779 -376.29482) (xy 419.088391 -376.280438) (xy 419.080609 -376.261642)
			(xy 419.080188 -376.25147) (xy 419.080188 -376.093482) (xy 419.079789 -376.084294) (xy 419.073268 -376.067109)
			(xy 419.067488 -376.059954) (xy 419.045728 -376.034278) (xy 419.007775 -375.978696) (xy 418.976738 -375.918976)
			(xy 418.953061 -375.855975) (xy 418.937085 -375.790595) (xy 418.929038 -375.723774) (xy 418.929035 -375.656471)
			(xy 418.937077 -375.589649) (xy 418.953048 -375.524268) (xy 418.97672 -375.461265) (xy 419.007752 -375.401542)
			(xy 419.045701 -375.345957) (xy 419.067488 -375.320306) (xy 419.073263 -375.313145) (xy 419.079791 -375.295967)
			(xy 419.080188 -375.286778) (xy 419.080188 -374.79351) (xy 419.079776 -374.784323) (xy 419.073264 -374.767138)
			(xy 419.067488 -374.759982) (xy 419.045658 -374.734364) (xy 419.007707 -374.678774) (xy 418.976673 -374.619046)
			(xy 418.953 -374.556037) (xy 418.937029 -374.49065) (xy 418.928987 -374.423823) (xy 389.250688 -374.423823)
			(xy 389.242648 -374.490639) (xy 389.226679 -374.556019) (xy 389.203011 -374.619022) (xy 389.171982 -374.678744)
			(xy 389.134037 -374.73433) (xy 389.112252 -374.759982) (xy 389.106432 -374.76711) (xy 389.099933 -374.784314)
			(xy 389.099552 -374.79351) (xy 389.099552 -375.286778) (xy 389.099983 -375.295963) (xy 389.106483 -375.313147)
			(xy 389.112252 -375.320306) (xy 389.13407 -375.345934) (xy 389.172018 -375.401523) (xy 389.203051 -375.46125)
			(xy 389.226722 -375.524258) (xy 389.242693 -375.589643) (xy 389.250735 -375.656469) (xy 389.250732 -375.723776)
			(xy 389.242685 -375.790601) (xy 389.226709 -375.855985) (xy 389.203032 -375.918991) (xy 389.171995 -375.978715)
			(xy 389.134042 -376.034302) (xy 389.112252 -376.059954) (xy 389.106444 -376.067091) (xy 389.099937 -376.084288)
			(xy 389.099552 -376.093482) (xy 389.099552 -376.25147) (xy 389.099111 -376.261641) (xy 389.091334 -376.280437)
			(xy 389.076954 -376.294823) (xy 389.058161 -376.302607) (xy 389.04799 -376.303032) (xy 388.33171 -376.303032)
			(xy 388.321535 -376.302627) (xy 388.302735 -376.29484) (xy 388.288349 -376.280448) (xy 388.280569 -376.261645)
			(xy 388.280148 -376.25147) (xy 388.280148 -376.093482) (xy 388.279736 -376.084295) (xy 388.273222 -376.067111)
			(xy 388.267448 -376.059954) (xy 388.24569 -376.034278) (xy 388.207739 -375.978695) (xy 388.176704 -375.918975)
			(xy 388.153029 -375.855973) (xy 388.137054 -375.790594) (xy 388.129007 -375.723774) (xy 388.129005 -375.656471)
			(xy 388.137046 -375.58965) (xy 388.153016 -375.52427) (xy 388.176686 -375.461267) (xy 388.207716 -375.401544)
			(xy 388.245662 -375.345958) (xy 388.267448 -375.320306) (xy 388.273231 -375.313151) (xy 388.279752 -375.295968)
			(xy 388.280148 -375.286778) (xy 388.280148 -374.79351) (xy 388.279722 -374.784325) (xy 388.273218 -374.767141)
			(xy 388.267448 -374.759982) (xy 388.245619 -374.734364) (xy 388.20767 -374.678773) (xy 388.176638 -374.619045)
			(xy 388.152968 -374.556036) (xy 388.136997 -374.490649) (xy 388.128956 -374.423823) (xy 384.850897 -374.423823)
			(xy 384.842857 -374.490639) (xy 384.826889 -374.556019) (xy 384.803221 -374.619021) (xy 384.772192 -374.678744)
			(xy 384.734249 -374.73433) (xy 384.712464 -374.759982) (xy 384.706646 -374.767112) (xy 384.700145 -374.784314)
			(xy 384.699764 -374.79351) (xy 384.699764 -375.286778) (xy 384.700193 -375.295963) (xy 384.706694 -375.313147)
			(xy 384.712464 -375.320306) (xy 384.734281 -375.345934) (xy 384.772229 -375.401524) (xy 384.803261 -375.461251)
			(xy 384.826932 -375.524259) (xy 384.842903 -375.589644) (xy 384.850944 -375.656469) (xy 384.850942 -375.723776)
			(xy 384.842894 -375.790601) (xy 384.826918 -375.855985) (xy 384.803242 -375.91899) (xy 384.772206 -375.978715)
			(xy 384.734254 -376.034302) (xy 384.712464 -376.059954) (xy 384.706657 -376.067092) (xy 384.70015 -376.084288)
			(xy 384.699764 -376.093482) (xy 384.699764 -376.25147) (xy 384.699311 -376.261639) (xy 384.691537 -376.280433)
			(xy 384.67716 -376.294819) (xy 384.658371 -376.302605) (xy 384.648202 -376.303032) (xy 383.931922 -376.303032)
			(xy 383.921748 -376.302617) (xy 383.902948 -376.294834) (xy 383.888562 -376.280445) (xy 383.880781 -376.261644)
			(xy 383.88036 -376.25147) (xy 383.88036 -376.093482) (xy 383.879945 -376.084296) (xy 383.873433 -376.067112)
			(xy 383.86766 -376.059954) (xy 383.845901 -376.034278) (xy 383.80795 -375.978695) (xy 383.776914 -375.918975)
			(xy 383.753239 -375.855974) (xy 383.737263 -375.790594) (xy 383.729217 -375.723774) (xy 383.729214 -375.656471)
			(xy 383.737255 -375.58965) (xy 383.753226 -375.524269) (xy 383.776896 -375.461266) (xy 383.807927 -375.401543)
			(xy 383.845874 -375.345958) (xy 383.86766 -375.320306) (xy 383.873444 -375.313152) (xy 383.879964 -375.295968)
			(xy 383.88036 -375.286778) (xy 383.88036 -374.79351) (xy 383.879932 -374.784325) (xy 383.873429 -374.767141)
			(xy 383.86766 -374.759982) (xy 383.84583 -374.734364) (xy 383.807881 -374.678773) (xy 383.776849 -374.619045)
			(xy 383.753177 -374.556036) (xy 383.737207 -374.49065) (xy 383.729165 -374.423823) (xy 380.451129 -374.423823)
			(xy 380.451129 -374.423879) (xy 380.443057 -374.490815) (xy 380.427025 -374.556302) (xy 380.403264 -374.619397)
			(xy 380.372116 -374.679192) (xy 380.334031 -374.734825) (xy 380.312168 -374.76049) (xy 380.306347 -374.767617)
			(xy 380.299847 -374.784822) (xy 380.299468 -374.794018) (xy 380.299468 -375.28627) (xy 380.2999 -375.295455)
			(xy 380.306399 -375.312639) (xy 380.312168 -375.319798) (xy 380.334063 -375.345438) (xy 380.372152 -375.401076)
			(xy 380.403304 -375.460875) (xy 380.427068 -375.523975) (xy 380.443102 -375.589468) (xy 380.451176 -375.656409)
			(xy 380.451173 -375.723836) (xy 380.443094 -375.790777) (xy 380.427054 -375.856268) (xy 380.403285 -375.919366)
			(xy 380.372129 -375.979163) (xy 380.334035 -376.034797) (xy 380.312168 -376.060462) (xy 380.306358 -376.067598)
			(xy 380.299852 -376.084796) (xy 380.299468 -376.09399) (xy 380.299468 -376.25147) (xy 380.298949 -376.261594)
			(xy 380.291233 -376.280313) (xy 380.276956 -376.29467) (xy 380.258281 -376.302492) (xy 380.24816 -376.303032)
			(xy 379.53188 -376.303032) (xy 379.521729 -376.302596) (xy 379.502982 -376.294799) (xy 379.48866 -376.280408)
			(xy 379.480955 -376.261623) (xy 379.480572 -376.25147) (xy 379.480572 -376.09399) (xy 379.480173 -376.084802)
			(xy 379.473652 -376.067617) (xy 379.467872 -376.060462) (xy 379.446038 -376.034772) (xy 379.407951 -375.97914)
			(xy 379.3768 -375.919347) (xy 379.353036 -375.856254) (xy 379.336999 -375.790768) (xy 379.328921 -375.723833)
			(xy 379.328918 -375.656412) (xy 379.336991 -375.589476) (xy 379.353022 -375.523989) (xy 379.376782 -375.460894)
			(xy 379.407928 -375.401098) (xy 379.446011 -375.345464) (xy 379.467872 -375.319798) (xy 379.473661 -375.312648)
			(xy 379.480178 -375.295461) (xy 379.480572 -375.28627) (xy 379.480572 -374.794018) (xy 379.48016 -374.784831)
			(xy 379.473648 -374.767646) (xy 379.467872 -374.76049) (xy 379.445968 -374.734858) (xy 379.407882 -374.679218)
			(xy 379.376735 -374.619417) (xy 379.352974 -374.556316) (xy 379.336943 -374.490823) (xy 379.32887 -374.423882)
			(xy 376.050801 -374.423882) (xy 376.042769 -374.490638) (xy 376.026801 -374.556018) (xy 376.003134 -374.619021)
			(xy 375.972107 -374.678743) (xy 375.934164 -374.734329) (xy 375.91238 -374.759982) (xy 375.906564 -374.767113)
			(xy 375.900062 -374.784315) (xy 375.89968 -374.79351) (xy 375.89968 -375.286778) (xy 375.900105 -375.295963)
			(xy 375.906609 -375.313148) (xy 375.91238 -375.320306) (xy 375.934197 -375.345934) (xy 375.972143 -375.401524)
			(xy 376.003174 -375.461252) (xy 376.026845 -375.524259) (xy 376.042815 -375.589644) (xy 376.050856 -375.656469)
			(xy 376.050854 -375.723776) (xy 376.042807 -375.7906) (xy 376.026831 -375.855984) (xy 376.003156 -375.91899)
			(xy 375.97212 -375.978714) (xy 375.934169 -376.034302) (xy 375.91238 -376.059954) (xy 375.906576 -376.067094)
			(xy 375.900066 -376.084288) (xy 375.89968 -376.093482) (xy 375.89968 -376.25147) (xy 375.899212 -376.261637)
			(xy 375.89144 -376.280428) (xy 375.877068 -376.294813) (xy 375.858285 -376.302602) (xy 375.848118 -376.303032)
			(xy 375.131838 -376.303032) (xy 375.121665 -376.302604) (xy 375.102866 -376.294826) (xy 375.088478 -376.280441)
			(xy 375.080697 -376.261643) (xy 375.080276 -376.25147) (xy 375.080276 -376.093482) (xy 375.07988 -376.084293)
			(xy 375.073357 -376.067109) (xy 375.067576 -376.059954) (xy 375.045817 -376.034278) (xy 375.007865 -375.978696)
			(xy 374.976828 -375.918976) (xy 374.953152 -375.855974) (xy 374.937176 -375.790595) (xy 374.929129 -375.723774)
			(xy 374.929126 -375.656471) (xy 374.937168 -375.58965) (xy 374.953138 -375.524269) (xy 374.97681 -375.461265)
			(xy 375.007841 -375.401543) (xy 375.045789 -375.345958) (xy 375.067576 -375.320306) (xy 375.07335 -375.313144)
			(xy 375.079879 -375.295967) (xy 375.080276 -375.286778) (xy 375.080276 -374.79351) (xy 375.079866 -374.784323)
			(xy 375.073353 -374.767138) (xy 375.067576 -374.759982) (xy 375.045746 -374.734365) (xy 375.007796 -374.678774)
			(xy 374.976762 -374.619046) (xy 374.95309 -374.556037) (xy 374.937119 -374.49065) (xy 374.929078 -374.423823)
			(xy 345.250779 -374.423823) (xy 345.242739 -374.49064) (xy 345.226769 -374.55602) (xy 345.2031 -374.619022)
			(xy 345.172071 -374.678745) (xy 345.134126 -374.73433) (xy 345.11234 -374.759982) (xy 345.106519 -374.767109)
			(xy 345.10002 -374.784314) (xy 345.09964 -374.79351) (xy 345.09964 -375.286778) (xy 345.100074 -375.295962)
			(xy 345.106573 -375.313146) (xy 345.11234 -375.320306) (xy 345.134158 -375.345933) (xy 345.172107 -375.401523)
			(xy 345.203141 -375.46125) (xy 345.226813 -375.524258) (xy 345.242784 -375.589643) (xy 345.250826 -375.656469)
			(xy 345.250823 -375.723776) (xy 345.242776 -375.790602) (xy 345.226799 -375.855986) (xy 345.203122 -375.918992)
			(xy 345.172084 -375.978716) (xy 345.13413 -376.034302) (xy 345.11234 -376.059954) (xy 345.106531 -376.06709)
			(xy 345.100025 -376.084288) (xy 345.09964 -376.093482) (xy 345.09964 -376.25147) (xy 345.099211 -376.261642)
			(xy 345.091432 -376.280441) (xy 345.077047 -376.294827) (xy 345.05825 -376.302609) (xy 345.048078 -376.303032)
			(xy 344.331798 -376.303032) (xy 344.321623 -376.302637) (xy 344.302822 -376.294846) (xy 344.288436 -376.280451)
			(xy 344.280657 -376.261646) (xy 344.280236 -376.25147) (xy 344.280236 -376.093482) (xy 344.279826 -376.084295)
			(xy 344.273311 -376.067111) (xy 344.267536 -376.059954) (xy 344.245778 -376.034277) (xy 344.207829 -375.978694)
			(xy 344.176794 -375.918974) (xy 344.15312 -375.855973) (xy 344.137145 -375.790594) (xy 344.129098 -375.723774)
			(xy 344.129096 -375.656471) (xy 344.137137 -375.589651) (xy 344.153106 -375.52427) (xy 344.176776 -375.461267)
			(xy 344.207805 -375.401544) (xy 344.24575 -375.345958) (xy 344.267536 -375.320306) (xy 344.273317 -375.31315)
			(xy 344.27984 -375.295968) (xy 344.280236 -375.286778) (xy 344.280236 -374.79351) (xy 344.279813 -374.784324)
			(xy 344.273308 -374.76714) (xy 344.267536 -374.759982) (xy 344.245707 -374.734364) (xy 344.20776 -374.678772)
			(xy 344.176728 -374.619044) (xy 344.153058 -374.556035) (xy 344.137088 -374.490649) (xy 344.129047 -374.423823)
			(xy 340.850988 -374.423823) (xy 340.842948 -374.490639) (xy 340.826979 -374.556019) (xy 340.803311 -374.619022)
			(xy 340.772282 -374.678744) (xy 340.734337 -374.73433) (xy 340.712552 -374.759982) (xy 340.706732 -374.76711)
			(xy 340.700233 -374.784314) (xy 340.699852 -374.79351) (xy 340.699852 -375.286778) (xy 340.700283 -375.295963)
			(xy 340.706783 -375.313147) (xy 340.712552 -375.320306) (xy 340.73437 -375.345934) (xy 340.772318 -375.401523)
			(xy 340.803351 -375.46125) (xy 340.827022 -375.524258) (xy 340.842993 -375.589643) (xy 340.851035 -375.656469)
			(xy 340.851032 -375.723776) (xy 340.842985 -375.790601) (xy 340.827009 -375.855985) (xy 340.803332 -375.918991)
			(xy 340.772295 -375.978715) (xy 340.734342 -376.034302) (xy 340.712552 -376.059954) (xy 340.706744 -376.067091)
			(xy 340.700237 -376.084288) (xy 340.699852 -376.093482) (xy 340.699852 -376.25147) (xy 340.699411 -376.261641)
			(xy 340.691634 -376.280437) (xy 340.677254 -376.294823) (xy 340.658461 -376.302607) (xy 340.64829 -376.303032)
			(xy 339.93201 -376.303032) (xy 339.921835 -376.302627) (xy 339.903035 -376.29484) (xy 339.888649 -376.280448)
			(xy 339.880869 -376.261645) (xy 339.880448 -376.25147) (xy 339.880448 -376.093482) (xy 339.880036 -376.084295)
			(xy 339.873522 -376.067111) (xy 339.867748 -376.059954) (xy 339.84599 -376.034278) (xy 339.808039 -375.978695)
			(xy 339.777004 -375.918975) (xy 339.753329 -375.855973) (xy 339.737354 -375.790594) (xy 339.729307 -375.723774)
			(xy 339.729305 -375.656471) (xy 339.737346 -375.58965) (xy 339.753316 -375.52427) (xy 339.776986 -375.461267)
			(xy 339.808016 -375.401544) (xy 339.845962 -375.345958) (xy 339.867748 -375.320306) (xy 339.873531 -375.313151)
			(xy 339.880052 -375.295968) (xy 339.880448 -375.286778) (xy 339.880448 -374.79351) (xy 339.880022 -374.784325)
			(xy 339.873518 -374.767141) (xy 339.867748 -374.759982) (xy 339.845919 -374.734364) (xy 339.80797 -374.678773)
			(xy 339.776938 -374.619045) (xy 339.753268 -374.556036) (xy 339.737297 -374.490649) (xy 339.729256 -374.423823)
			(xy 336.45122 -374.423823) (xy 336.45122 -374.423879) (xy 336.443148 -374.490815) (xy 336.427115 -374.556303)
			(xy 336.403354 -374.619398) (xy 336.372206 -374.679193) (xy 336.334119 -374.734826) (xy 336.312256 -374.76049)
			(xy 336.306433 -374.767616) (xy 336.299935 -374.784821) (xy 336.299556 -374.794018) (xy 336.299556 -375.28627)
			(xy 336.29999 -375.295454) (xy 336.306488 -375.312639) (xy 336.312256 -375.319798) (xy 336.334151 -375.345438)
			(xy 336.372242 -375.401075) (xy 336.403394 -375.460875) (xy 336.427158 -375.523975) (xy 336.443193 -375.589467)
			(xy 336.451267 -375.656409) (xy 336.451264 -375.723836) (xy 336.443185 -375.790777) (xy 336.427145 -375.856268)
			(xy 336.403375 -375.919367) (xy 336.372218 -375.979163) (xy 336.334123 -376.034797) (xy 336.312256 -376.060462)
			(xy 336.306445 -376.067597) (xy 336.29994 -376.084795) (xy 336.299556 -376.09399) (xy 336.299556 -376.25147)
			(xy 336.299049 -376.261595) (xy 336.29133 -376.280317) (xy 336.27705 -376.294674) (xy 336.258371 -376.302494)
			(xy 336.248248 -376.303032) (xy 335.531968 -376.303032) (xy 335.521816 -376.302605) (xy 335.503069 -376.294805)
			(xy 335.488748 -376.280411) (xy 335.481043 -376.261624) (xy 335.48066 -376.25147) (xy 335.48066 -376.09399)
			(xy 335.480241 -376.084804) (xy 335.473732 -376.06762) (xy 335.46796 -376.060462) (xy 335.446127 -376.034772)
			(xy 335.40804 -375.97914) (xy 335.37689 -375.919347) (xy 335.353126 -375.856253) (xy 335.33709 -375.790768)
			(xy 335.329012 -375.723833) (xy 335.329009 -375.656412) (xy 335.337082 -375.589477) (xy 335.353113 -375.52399)
			(xy 335.376872 -375.460894) (xy 335.408017 -375.401099) (xy 335.446099 -375.345464) (xy 335.46796 -375.319798)
			(xy 335.473747 -375.312647) (xy 335.480266 -375.295461) (xy 335.48066 -375.28627) (xy 335.48066 -374.794018)
			(xy 335.480228 -374.784833) (xy 335.473728 -374.76765) (xy 335.46796 -374.76049) (xy 335.446056 -374.734858)
			(xy 335.407971 -374.679218) (xy 335.376825 -374.619417) (xy 335.353065 -374.556316) (xy 335.337033 -374.490823)
			(xy 335.328961 -374.423882) (xy 332.050892 -374.423882) (xy 332.04286 -374.490639) (xy 332.026892 -374.556019)
			(xy 332.003224 -374.619021) (xy 331.972196 -374.678744) (xy 331.934253 -374.73433) (xy 331.912468 -374.759982)
			(xy 331.90665 -374.767112) (xy 331.900149 -374.784314) (xy 331.899768 -374.79351) (xy 331.899768 -375.286778)
			(xy 331.900196 -375.295963) (xy 331.906698 -375.313147) (xy 331.912468 -375.320306) (xy 331.934285 -375.345934)
			(xy 331.972233 -375.401524) (xy 332.003264 -375.461251) (xy 332.026935 -375.524259) (xy 332.042906 -375.589644)
			(xy 332.050947 -375.656469) (xy 332.050945 -375.723776) (xy 332.042898 -375.790601) (xy 332.026922 -375.855985)
			(xy 332.003246 -375.91899) (xy 331.972209 -375.978715) (xy 331.934257 -376.034302) (xy 331.912468 -376.059954)
			(xy 331.906662 -376.067092) (xy 331.900154 -376.084288) (xy 331.899768 -376.093482) (xy 331.899768 -376.25147)
			(xy 331.899312 -376.261639) (xy 331.891538 -376.280432) (xy 331.877162 -376.294817) (xy 331.858375 -376.302604)
			(xy 331.848206 -376.303032) (xy 331.131926 -376.303032) (xy 331.121752 -376.302614) (xy 331.102953 -376.294832)
			(xy 331.088566 -376.280444) (xy 331.080785 -376.261644) (xy 331.080364 -376.25147) (xy 331.080364 -376.093482)
			(xy 331.079948 -376.084296) (xy 331.073437 -376.067112) (xy 331.067664 -376.059954) (xy 331.045905 -376.034278)
			(xy 331.007954 -375.978695) (xy 330.976918 -375.918975) (xy 330.953242 -375.855974) (xy 330.937266 -375.790594)
			(xy 330.92922 -375.723774) (xy 330.929217 -375.656471) (xy 330.937258 -375.58965) (xy 330.953229 -375.524269)
			(xy 330.976899 -375.461266) (xy 331.007931 -375.401543) (xy 331.045877 -375.345958) (xy 331.067664 -375.320306)
			(xy 331.073448 -375.313152) (xy 331.079969 -375.295968) (xy 331.080364 -375.286778) (xy 331.080364 -374.79351)
			(xy 331.079935 -374.784325) (xy 331.073433 -374.767141) (xy 331.067664 -374.759982) (xy 331.045834 -374.734364)
			(xy 331.007885 -374.678773) (xy 330.976852 -374.619045) (xy 330.95318 -374.556036) (xy 330.93721 -374.49065)
			(xy 330.929168 -374.423823) (xy 301.250868 -374.423823) (xy 301.250868 -374.423878) (xy 301.242797 -374.490814)
			(xy 301.226766 -374.5563) (xy 301.203008 -374.619395) (xy 301.171863 -374.67919) (xy 301.133781 -374.734824)
			(xy 301.11192 -374.76049) (xy 301.106105 -374.767622) (xy 301.099601 -374.784823) (xy 301.09922 -374.794018)
			(xy 301.09922 -375.28627) (xy 301.09964 -375.295456) (xy 301.106146 -375.312641) (xy 301.11192 -375.319798)
			(xy 301.133813 -375.345439) (xy 301.171899 -375.401078) (xy 301.203048 -375.460877) (xy 301.226809 -375.523977)
			(xy 301.242842 -375.589469) (xy 301.250915 -375.65641) (xy 301.250912 -375.723835) (xy 301.242834 -375.790775)
			(xy 301.226796 -375.856266) (xy 301.203029 -375.919364) (xy 301.171876 -375.979161) (xy 301.133785 -376.034796)
			(xy 301.11192 -376.060462) (xy 301.106117 -376.067603) (xy 301.099605 -376.084797) (xy 301.09922 -376.09399)
			(xy 301.09922 -376.25147) (xy 301.098748 -376.2616) (xy 301.091023 -376.280328) (xy 301.076731 -376.294687)
			(xy 301.058039 -376.3025) (xy 301.047912 -376.303032) (xy 300.331632 -376.303032) (xy 300.321484 -376.302553)
			(xy 300.302738 -376.294774) (xy 300.288415 -376.280395) (xy 300.280708 -376.26162) (xy 300.280324 -376.25147)
			(xy 300.280324 -376.09399) (xy 300.279913 -376.084803) (xy 300.2734 -376.067619) (xy 300.267624 -376.060462)
			(xy 300.245789 -376.034773) (xy 300.207697 -375.979142) (xy 300.176544 -375.91935) (xy 300.152777 -375.856256)
			(xy 300.136739 -375.790769) (xy 300.12866 -375.723833) (xy 300.128658 -375.656412) (xy 300.136731 -375.589475)
			(xy 300.152764 -375.523987) (xy 300.176526 -375.460892) (xy 300.207674 -375.401096) (xy 300.245761 -375.345463)
			(xy 300.267624 -375.319798) (xy 300.273407 -375.312643) (xy 300.279929 -375.29546) (xy 300.280324 -375.28627)
			(xy 300.280324 -374.794018) (xy 300.2799 -374.784832) (xy 300.273395 -374.767648) (xy 300.267624 -374.76049)
			(xy 300.245718 -374.734859) (xy 300.207629 -374.67922) (xy 300.176479 -374.61942) (xy 300.152716 -374.556318)
			(xy 300.136683 -374.490825) (xy 300.12861 -374.423882) (xy 296.851077 -374.423882) (xy 296.843006 -374.490813)
			(xy 296.826976 -374.556299) (xy 296.803218 -374.619394) (xy 296.772074 -374.67919) (xy 296.733992 -374.734824)
			(xy 296.712132 -374.76049) (xy 296.706306 -374.767614) (xy 296.699811 -374.784821) (xy 296.699432 -374.794018)
			(xy 296.699432 -375.28627) (xy 296.699872 -375.295454) (xy 296.706366 -375.312638) (xy 296.712132 -375.319798)
			(xy 296.734024 -375.345439) (xy 296.77211 -375.401078) (xy 296.803258 -375.460878) (xy 296.827019 -375.523978)
			(xy 296.843051 -375.589469) (xy 296.851124 -375.65641) (xy 296.851121 -375.723835) (xy 296.843043 -375.790775)
			(xy 296.827005 -375.856265) (xy 296.803239 -375.919363) (xy 296.772087 -375.979161) (xy 296.733997 -376.034796)
			(xy 296.712132 -376.060462) (xy 296.706318 -376.067595) (xy 296.699816 -376.084795) (xy 296.699432 -376.09399)
			(xy 296.699432 -376.25147) (xy 296.698948 -376.261598) (xy 296.691225 -376.280324) (xy 296.676937 -376.294683)
			(xy 296.65825 -376.302498) (xy 296.648124 -376.303032) (xy 295.931844 -376.303032) (xy 295.921697 -376.302543)
			(xy 295.902951 -376.294768) (xy 295.888628 -376.280392) (xy 295.880921 -376.261619) (xy 295.880536 -376.25147)
			(xy 295.880536 -376.09399) (xy 295.880123 -376.084803) (xy 295.87361 -376.067619) (xy 295.867836 -376.060462)
			(xy 295.846 -376.034773) (xy 295.807908 -375.979143) (xy 295.776754 -375.91935) (xy 295.752987 -375.856256)
			(xy 295.736948 -375.79077) (xy 295.728869 -375.723834) (xy 295.728867 -375.656412) (xy 295.73694 -375.589475)
			(xy 295.752973 -375.523987) (xy 295.776736 -375.460891) (xy 295.807885 -375.401096) (xy 295.845973 -375.345463)
			(xy 295.867836 -375.319798) (xy 295.873621 -375.312644) (xy 295.880142 -375.29546) (xy 295.880536 -375.28627)
			(xy 295.880536 -374.794018) (xy 295.880109 -374.784833) (xy 295.873606 -374.767649) (xy 295.867836 -374.76049)
			(xy 295.84593 -374.734859) (xy 295.80784 -374.679221) (xy 295.776689 -374.61942) (xy 295.752925 -374.556319)
			(xy 295.736892 -374.490825) (xy 295.728819 -374.423882) (xy 292.450774 -374.423882) (xy 292.442742 -374.490639)
			(xy 292.426773 -374.55602) (xy 292.403104 -374.619022) (xy 292.372075 -374.678745) (xy 292.33413 -374.73433)
			(xy 292.312344 -374.759982) (xy 292.306523 -374.76711) (xy 292.300025 -374.784314) (xy 292.299644 -374.79351)
			(xy 292.299644 -375.286778) (xy 292.300077 -375.295962) (xy 292.306576 -375.313146) (xy 292.312344 -375.320306)
			(xy 292.334162 -375.345934) (xy 292.372111 -375.401523) (xy 292.403144 -375.46125) (xy 292.426816 -375.524258)
			(xy 292.442787 -375.589643) (xy 292.450829 -375.656469) (xy 292.450826 -375.723776) (xy 292.442779 -375.790601)
			(xy 292.426802 -375.855985) (xy 292.403125 -375.918991) (xy 292.372088 -375.978716) (xy 292.334134 -376.034302)
			(xy 292.312344 -376.059954) (xy 292.306535 -376.06709) (xy 292.300029 -376.084288) (xy 292.299644 -376.093482)
			(xy 292.299644 -376.25147) (xy 292.299211 -376.261642) (xy 292.291433 -376.280439) (xy 292.277049 -376.294826)
			(xy 292.258254 -376.302609) (xy 292.248082 -376.303032) (xy 291.531802 -376.303032) (xy 291.521627 -376.302634)
			(xy 291.502826 -376.294844) (xy 291.48844 -376.28045) (xy 291.480661 -376.261645) (xy 291.48024 -376.25147)
			(xy 291.48024 -376.093482) (xy 291.47983 -376.084295) (xy 291.473315 -376.067111) (xy 291.46754 -376.059954)
			(xy 291.445782 -376.034277) (xy 291.407832 -375.978695) (xy 291.376798 -375.918974) (xy 291.353123 -375.855973)
			(xy 291.337148 -375.790594) (xy 291.329101 -375.723774) (xy 291.329099 -375.656471) (xy 291.33714 -375.589651)
			(xy 291.35311 -375.52427) (xy 291.376779 -375.461267) (xy 291.407809 -375.401544) (xy 291.445754 -375.345958)
			(xy 291.46754 -375.320306) (xy 291.473322 -375.31315) (xy 291.479844 -375.295968) (xy 291.48024 -375.286778)
			(xy 291.48024 -374.79351) (xy 291.479816 -374.784324) (xy 291.473311 -374.76714) (xy 291.46754 -374.759982)
			(xy 291.445711 -374.734364) (xy 291.407763 -374.678773) (xy 291.376732 -374.619044) (xy 291.353061 -374.556035)
			(xy 291.337091 -374.490649) (xy 291.32905 -374.423823) (xy 288.051014 -374.423823) (xy 288.051014 -374.423879)
			(xy 288.042941 -374.490816) (xy 288.026909 -374.556303) (xy 288.003147 -374.619398) (xy 287.971998 -374.679193)
			(xy 287.933911 -374.734826) (xy 287.912048 -374.76049) (xy 287.906224 -374.767616) (xy 287.899727 -374.784821)
			(xy 287.899348 -374.794018) (xy 287.899348 -375.28627) (xy 287.899784 -375.295454) (xy 287.906281 -375.312638)
			(xy 287.912048 -375.319798) (xy 287.933943 -375.345438) (xy 287.972035 -375.401075) (xy 288.003187 -375.460874)
			(xy 288.026952 -375.523974) (xy 288.042987 -375.589467) (xy 288.051061 -375.656409) (xy 288.051058 -375.723836)
			(xy 288.042978 -375.790777) (xy 288.026938 -375.856269) (xy 288.003168 -375.919367) (xy 287.972011 -375.979164)
			(xy 287.933916 -376.034798) (xy 287.912048 -376.060462) (xy 287.906236 -376.067596) (xy 287.899732 -376.084795)
			(xy 287.899348 -376.09399) (xy 287.899348 -376.25147) (xy 287.898849 -376.261596) (xy 287.891129 -376.280319)
			(xy 287.876846 -376.294677) (xy 287.858164 -376.302495) (xy 287.84804 -376.303032) (xy 287.13176 -376.303032)
			(xy 287.121653 -376.302548) (xy 287.10298 -376.294804) (xy 287.088687 -376.280507) (xy 287.080948 -376.261831)
			(xy 287.080452 -376.251724) (xy 287.080452 -376.09399) (xy 287.080035 -376.084804) (xy 287.073525 -376.06762)
			(xy 287.067752 -376.060462) (xy 287.045916 -376.034773) (xy 287.007823 -375.979143) (xy 286.976668 -375.919351)
			(xy 286.9529 -375.856257) (xy 286.93686 -375.79077) (xy 286.928781 -375.723834) (xy 286.928779 -375.656411)
			(xy 286.936852 -375.589474) (xy 286.952886 -375.523986) (xy 286.976649 -375.46089) (xy 287.007799 -375.401095)
			(xy 287.045888 -375.345462) (xy 287.067752 -375.319798) (xy 287.073538 -375.312646) (xy 287.080058 -375.29546)
			(xy 287.080452 -375.28627) (xy 287.080452 -374.794018) (xy 287.080022 -374.784833) (xy 287.073521 -374.767649)
			(xy 287.067752 -374.76049) (xy 287.045845 -374.73486) (xy 287.007754 -374.679221) (xy 286.976602 -374.619421)
			(xy 286.952838 -374.556319) (xy 286.936804 -374.490825) (xy 286.928731 -374.423882) (xy 266.12088 -374.423882)
			(xy 266.12088 -377.534932) (xy 266.120477 -377.545004) (xy 266.112741 -377.563602) (xy 266.105894 -377.571)
			(xy 265.757406 -377.919234) (xy 265.750002 -377.926069) (xy 265.731406 -377.933791) (xy 265.721338 -377.93422)
			(xy 243.05133 -377.93422) (xy 243.04126 -377.9338) (xy 243.022661 -377.926078) (xy 243.015262 -377.919234)
			(xy 242.506246 -377.410472) (xy 242.499408 -377.40307) (xy 242.491685 -377.384473) (xy 242.49126 -377.374404)
			(xy 234.964478 -377.374404) (xy 236.356885 -378.766811) (xy 269.68983 -378.766811) (xy 269.68983 -378.633249)
			(xy 269.697894 -378.499931) (xy 269.713994 -378.367343) (xy 269.738069 -378.235969) (xy 269.770032 -378.106288)
			(xy 269.809767 -377.978774) (xy 269.857129 -377.853891) (xy 269.911944 -377.732096) (xy 269.974014 -377.613833)
			(xy 270.04311 -377.499534) (xy 270.118982 -377.389614) (xy 270.201352 -377.284477) (xy 270.28992 -377.184504)
			(xy 270.384362 -377.090062) (xy 270.484335 -377.001494) (xy 270.589472 -376.919124) (xy 270.699392 -376.843252)
			(xy 270.813691 -376.774156) (xy 270.931954 -376.712086) (xy 271.053749 -376.657271) (xy 271.178632 -376.609909)
			(xy 271.306146 -376.570174) (xy 271.435827 -376.538211) (xy 271.567201 -376.514136) (xy 271.699789 -376.498036)
			(xy 271.833107 -376.489972) (xy 271.966669 -376.489972) (xy 272.099987 -376.498036) (xy 272.232575 -376.514136)
			(xy 272.363949 -376.538211) (xy 272.49363 -376.570174) (xy 272.621144 -376.609909) (xy 272.746027 -376.657271)
			(xy 272.867822 -376.712086) (xy 272.986085 -376.774156) (xy 273.068299 -376.823856) (xy 289.128922 -376.823856)
			(xy 289.128922 -376.75655) (xy 289.136967 -376.689727) (xy 289.152941 -376.624344) (xy 289.176615 -376.56134)
			(xy 289.207651 -376.501617) (xy 289.245603 -376.446031) (xy 289.267392 -376.42038) (xy 289.273179 -376.413228)
			(xy 289.2797 -376.396043) (xy 289.280092 -376.386852) (xy 289.280092 -375.893584) (xy 289.279691 -375.884396)
			(xy 289.273171 -375.867212) (xy 289.267392 -375.860056) (xy 289.245634 -375.834379) (xy 289.207681 -375.778797)
			(xy 289.176643 -375.719078) (xy 289.152966 -375.656076) (xy 289.13699 -375.590696) (xy 289.128942 -375.523876)
			(xy 289.128939 -375.456572) (xy 289.136981 -375.389751) (xy 289.152952 -375.32437) (xy 289.176624 -375.261367)
			(xy 289.207656 -375.201644) (xy 289.245605 -375.146059) (xy 289.267392 -375.120408) (xy 289.273167 -375.113247)
			(xy 289.279695 -375.096069) (xy 289.280092 -375.08688) (xy 289.280092 -374.928638) (xy 289.280664 -374.918488)
			(xy 289.288417 -374.899729) (xy 289.302758 -374.885364) (xy 289.321505 -374.87758) (xy 289.331654 -374.877076)
			(xy 290.047934 -374.877076) (xy 290.058113 -374.877437) (xy 290.076915 -374.88524) (xy 290.0913 -374.899645)
			(xy 290.099077 -374.918459) (xy 290.099496 -374.928638) (xy 290.099496 -375.08688) (xy 290.099917 -375.096066)
			(xy 290.106423 -375.11325) (xy 290.112196 -375.120408) (xy 290.134014 -375.146035) (xy 290.17196 -375.201626)
			(xy 290.20299 -375.261353) (xy 290.226659 -375.324361) (xy 290.242629 -375.389746) (xy 290.25067 -375.456571)
			(xy 290.250667 -375.523878) (xy 290.24262 -375.590702) (xy 290.226645 -375.656085) (xy 290.20297 -375.719091)
			(xy 290.171935 -375.778816) (xy 290.133985 -375.834403) (xy 290.112196 -375.860056) (xy 290.106393 -375.867196)
			(xy 290.099882 -375.884391) (xy 290.099496 -375.893584) (xy 290.099496 -376.386852) (xy 290.09993 -376.396037)
			(xy 290.106427 -376.413221) (xy 290.112196 -376.42038) (xy 290.133987 -376.446029) (xy 290.171933 -376.501617)
			(xy 290.202964 -376.561341) (xy 290.226635 -376.624346) (xy 290.242607 -376.689728) (xy 290.25065 -376.756551)
			(xy 290.25065 -376.823855) (xy 290.250643 -376.823915) (xy 293.528715 -376.823915) (xy 293.528715 -376.756491)
			(xy 293.53679 -376.689554) (xy 293.552824 -376.624065) (xy 293.576588 -376.560968) (xy 293.607737 -376.501172)
			(xy 293.645825 -376.445537) (xy 293.667688 -376.419872) (xy 293.673478 -376.412722) (xy 293.679997 -376.395535)
			(xy 293.680388 -376.386344) (xy 293.680388 -375.894092) (xy 293.679984 -375.884904) (xy 293.673466 -375.86772)
			(xy 293.667688 -375.860564) (xy 293.645856 -375.834873) (xy 293.607767 -375.779242) (xy 293.576616 -375.719449)
			(xy 293.55285 -375.656355) (xy 293.536813 -375.59087) (xy 293.528735 -375.523934) (xy 293.528732 -375.456514)
			(xy 293.536804 -375.389578) (xy 293.552836 -375.324091) (xy 293.576596 -375.260995) (xy 293.607742 -375.2012)
			(xy 293.645826 -375.145565) (xy 293.667688 -375.1199) (xy 293.673466 -375.112741) (xy 293.679992 -375.095561)
			(xy 293.680388 -375.086372) (xy 293.680388 -374.928638) (xy 293.680956 -374.91852) (xy 293.688662 -374.89981)
			(xy 293.702923 -374.885454) (xy 293.721582 -374.877624) (xy 293.731696 -374.877076) (xy 294.447976 -374.877076)
			(xy 294.458094 -374.877535) (xy 294.476793 -374.885271) (xy 294.491107 -374.899574) (xy 294.498857 -374.918266)
			(xy 294.499284 -374.928384) (xy 294.499284 -375.086372) (xy 294.499711 -375.095557) (xy 294.506214 -375.112742)
			(xy 294.511984 -375.1199) (xy 294.53388 -375.145539) (xy 294.571969 -375.201177) (xy 294.603119 -375.260977)
			(xy 294.626882 -375.324077) (xy 294.642916 -375.389569) (xy 294.650989 -375.456511) (xy 294.650986 -375.523937)
			(xy 294.642907 -375.590878) (xy 294.626868 -375.656369) (xy 294.603099 -375.719467) (xy 294.571944 -375.779264)
			(xy 294.53385 -375.834899) (xy 294.511984 -375.860564) (xy 294.506176 -375.867701) (xy 294.499669 -375.884898)
			(xy 294.499284 -375.894092) (xy 294.499284 -376.386344) (xy 294.499677 -376.395533) (xy 294.506203 -376.412717)
			(xy 294.511984 -376.419872) (xy 294.533852 -376.445534) (xy 294.571942 -376.501168) (xy 294.603094 -376.560965)
			(xy 294.626858 -376.624062) (xy 294.642894 -376.689552) (xy 294.65097 -376.756491) (xy 294.650969 -376.823856)
			(xy 297.92901 -376.823856) (xy 297.92901 -376.75655) (xy 297.937054 -376.689727) (xy 297.953028 -376.624345)
			(xy 297.976702 -376.56134) (xy 298.007737 -376.501617) (xy 298.045687 -376.446032) (xy 298.067476 -376.42038)
			(xy 298.073261 -376.413226) (xy 298.079783 -376.396042) (xy 298.080176 -376.386852) (xy 298.080176 -375.893584)
			(xy 298.079779 -375.884395) (xy 298.073257 -375.867211) (xy 298.067476 -375.860056) (xy 298.045719 -375.834378)
			(xy 298.007766 -375.778797) (xy 297.97673 -375.719077) (xy 297.953054 -375.656076) (xy 297.937077 -375.590696)
			(xy 297.92903 -375.523876) (xy 297.929027 -375.456572) (xy 297.937069 -375.389751) (xy 297.953039 -375.324371)
			(xy 297.97671 -375.261367) (xy 298.007742 -375.201645) (xy 298.045689 -375.14606) (xy 298.067476 -375.120408)
			(xy 298.073249 -375.113246) (xy 298.079778 -375.096068) (xy 298.080176 -375.08688) (xy 298.080176 -374.928638)
			(xy 298.080596 -374.918464) (xy 298.088376 -374.899663) (xy 298.102763 -374.885276) (xy 298.121564 -374.877496)
			(xy 298.131738 -374.877076) (xy 298.848018 -374.877076) (xy 298.858195 -374.87745) (xy 298.876998 -374.885248)
			(xy 298.891383 -374.899649) (xy 298.899161 -374.91846) (xy 298.89958 -374.928638) (xy 298.89958 -375.08688)
			(xy 298.900004 -375.096066) (xy 298.906509 -375.11325) (xy 298.91228 -375.120408) (xy 298.934099 -375.146035)
			(xy 298.972045 -375.201625) (xy 299.003076 -375.261352) (xy 299.026746 -375.32436) (xy 299.042716 -375.389745)
			(xy 299.050758 -375.45657) (xy 299.050755 -375.523878) (xy 299.042708 -375.590702) (xy 299.026732 -375.656086)
			(xy 299.003056 -375.719092) (xy 298.972021 -375.778816) (xy 298.934069 -375.834404) (xy 298.91228 -375.860056)
			(xy 298.906475 -375.867195) (xy 298.899966 -375.88439) (xy 298.89958 -375.893584) (xy 298.89958 -376.386852)
			(xy 298.900018 -376.396036) (xy 298.906513 -376.413221) (xy 298.91228 -376.42038) (xy 298.934071 -376.446029)
			(xy 298.972019 -376.501616) (xy 299.003051 -376.561341) (xy 299.026722 -376.624345) (xy 299.042695 -376.689728)
			(xy 299.050731 -376.756492) (xy 302.328802 -376.756492) (xy 302.336877 -376.689554) (xy 302.352912 -376.624066)
			(xy 302.376674 -376.560969) (xy 302.407823 -376.501173) (xy 302.445909 -376.445538) (xy 302.467772 -376.419872)
			(xy 302.473572 -376.412729) (xy 302.480082 -376.395537) (xy 302.480472 -376.386344) (xy 302.480472 -375.894092)
			(xy 302.480072 -375.884904) (xy 302.473552 -375.867719) (xy 302.467772 -375.860564) (xy 302.44594 -375.834872)
			(xy 302.407853 -375.779241) (xy 302.376702 -375.719448) (xy 302.352937 -375.656355) (xy 302.336901 -375.590869)
			(xy 302.328823 -375.523934) (xy 302.32882 -375.456514) (xy 302.336892 -375.389578) (xy 302.352923 -375.324091)
			(xy 302.376682 -375.260996) (xy 302.407828 -375.2012) (xy 302.445911 -375.145566) (xy 302.467772 -375.1199)
			(xy 302.47356 -375.112749) (xy 302.480078 -375.095563) (xy 302.480472 -375.086372) (xy 302.480472 -374.928638)
			(xy 302.480959 -374.91851) (xy 302.48868 -374.899784) (xy 302.502967 -374.885425) (xy 302.521654 -374.87761)
			(xy 302.53178 -374.877076) (xy 303.24806 -374.877076) (xy 303.258209 -374.877554) (xy 303.276955 -374.885332)
			(xy 303.291279 -374.899711) (xy 303.298985 -374.918488) (xy 303.299368 -374.928638) (xy 303.299368 -375.086372)
			(xy 303.299799 -375.095557) (xy 303.306299 -375.112741) (xy 303.312068 -375.1199) (xy 303.333965 -375.145539)
			(xy 303.372054 -375.201176) (xy 303.403205 -375.260976) (xy 303.426969 -375.324076) (xy 303.443004 -375.389569)
			(xy 303.451077 -375.456511) (xy 303.451074 -375.523937) (xy 303.442995 -375.590878) (xy 303.426955 -375.65637)
			(xy 303.403186 -375.719468) (xy 303.37203 -375.779265) (xy 303.333935 -375.834899) (xy 303.312068 -375.860564)
			(xy 303.306258 -375.867699) (xy 303.299752 -375.884898) (xy 303.299368 -375.894092) (xy 303.299368 -376.386344)
			(xy 303.299764 -376.395533) (xy 303.306288 -376.412716) (xy 303.312068 -376.419872) (xy 303.333937 -376.445533)
			(xy 303.372028 -376.501168) (xy 303.40318 -376.560964) (xy 303.426945 -376.624062) (xy 303.442982 -376.689551)
			(xy 303.451058 -376.756491) (xy 303.451057 -376.823915) (xy 333.128833 -376.823915) (xy 333.128833 -376.756491)
			(xy 333.136908 -376.689553) (xy 333.152944 -376.624064) (xy 333.176708 -376.560967) (xy 333.207859 -376.501171)
			(xy 333.245948 -376.445537) (xy 333.267812 -376.419872) (xy 333.273604 -376.412724) (xy 333.280121 -376.395536)
			(xy 333.280512 -376.386344) (xy 333.280512 -375.894092) (xy 333.280103 -375.884905) (xy 333.273588 -375.86772)
			(xy 333.267812 -375.860564) (xy 333.245979 -375.834873) (xy 333.207889 -375.779242) (xy 333.176736 -375.71945)
			(xy 333.152969 -375.656356) (xy 333.136931 -375.59087) (xy 333.128853 -375.523935) (xy 333.12885 -375.456513)
			(xy 333.136923 -375.389577) (xy 333.152955 -375.32409) (xy 333.176716 -375.260994) (xy 333.207864 -375.201199)
			(xy 333.24595 -375.145565) (xy 333.267812 -375.1199) (xy 333.273592 -375.112743) (xy 333.280116 -375.095562)
			(xy 333.280512 -375.086372) (xy 333.280512 -374.928638) (xy 333.281057 -374.918517) (xy 333.288767 -374.899802)
			(xy 333.303035 -374.885446) (xy 333.321702 -374.87762) (xy 333.33182 -374.877076) (xy 334.0481 -374.877076)
			(xy 334.058251 -374.877521) (xy 334.076999 -374.885312) (xy 334.091321 -374.899701) (xy 334.099025 -374.918485)
			(xy 334.099408 -374.928638) (xy 334.099408 -375.086372) (xy 334.09983 -375.095558) (xy 334.106335 -375.112743)
			(xy 334.112108 -375.1199) (xy 334.134003 -375.145539) (xy 334.17209 -375.201178) (xy 334.203239 -375.260978)
			(xy 334.227001 -375.324078) (xy 334.243034 -375.38957) (xy 334.251107 -375.456511) (xy 334.251105 -375.523937)
			(xy 334.243026 -375.590877) (xy 334.226987 -375.656368) (xy 334.20322 -375.719466) (xy 334.172066 -375.779263)
			(xy 334.133974 -375.834899) (xy 334.112108 -375.860564) (xy 334.106303 -375.867703) (xy 334.099793 -375.884898)
			(xy 334.099408 -375.894092) (xy 334.099408 -376.386344) (xy 334.099795 -376.395534) (xy 334.106324 -376.412718)
			(xy 334.112108 -376.419872) (xy 334.133976 -376.445534) (xy 334.172064 -376.501169) (xy 334.203214 -376.560966)
			(xy 334.226977 -376.624063) (xy 334.243012 -376.689553) (xy 334.251088 -376.756491) (xy 334.251087 -376.823855)
			(xy 337.529152 -376.823855) (xy 337.529152 -376.756551) (xy 337.537195 -376.689729) (xy 337.553167 -376.624348)
			(xy 337.576837 -376.561344) (xy 337.607868 -376.50162) (xy 337.645814 -376.446033) (xy 337.6676 -376.42038)
			(xy 337.673388 -376.413228) (xy 337.679908 -376.396043) (xy 337.6803 -376.386852) (xy 337.6803 -375.893584)
			(xy 337.679897 -375.884396) (xy 337.673378 -375.867212) (xy 337.6676 -375.860056) (xy 337.645845 -375.834377)
			(xy 337.607898 -375.778794) (xy 337.576865 -375.719074) (xy 337.553192 -375.656073) (xy 337.537218 -375.590694)
			(xy 337.529172 -375.523875) (xy 337.529169 -375.456573) (xy 337.53721 -375.389753) (xy 337.553178 -375.324373)
			(xy 337.576846 -375.26137) (xy 337.607873 -375.201647) (xy 337.645815 -375.146061) (xy 337.6676 -375.120408)
			(xy 337.673376 -375.113248) (xy 337.679903 -375.096069) (xy 337.6803 -375.08688) (xy 337.6803 -374.928638)
			(xy 337.680864 -374.918487) (xy 337.688619 -374.899726) (xy 337.702963 -374.885361) (xy 337.721712 -374.877579)
			(xy 337.731862 -374.877076) (xy 338.448142 -374.877076) (xy 338.458307 -374.8775) (xy 338.477085 -374.885295)
			(xy 338.49145 -374.899683) (xy 338.499216 -374.918472) (xy 338.499704 -374.928638) (xy 338.499704 -375.08688)
			(xy 338.500123 -375.096066) (xy 338.50663 -375.113251) (xy 338.512404 -375.120408) (xy 338.534222 -375.146035)
			(xy 338.572167 -375.201626) (xy 338.603196 -375.261353) (xy 338.626865 -375.324361) (xy 338.642835 -375.389746)
			(xy 338.650876 -375.456571) (xy 338.650873 -375.523877) (xy 338.642826 -375.590701) (xy 338.626851 -375.656085)
			(xy 338.603177 -375.719091) (xy 338.572142 -375.778815) (xy 338.534192 -375.834403) (xy 338.512404 -375.860056)
			(xy 338.506602 -375.867197) (xy 338.50009 -375.884391) (xy 338.499704 -375.893584) (xy 338.499704 -376.386852)
			(xy 338.500136 -376.396037) (xy 338.506634 -376.413222) (xy 338.512404 -376.42038) (xy 338.534194 -376.44603)
			(xy 338.57214 -376.501617) (xy 338.603171 -376.561342) (xy 338.626842 -376.624346) (xy 338.642813 -376.689729)
			(xy 338.650856 -376.756551) (xy 338.650856 -376.823855) (xy 338.650849 -376.823915) (xy 341.928921 -376.823915)
			(xy 341.928921 -376.756491) (xy 341.936996 -376.689553) (xy 341.953031 -376.624065) (xy 341.976794 -376.560968)
			(xy 342.007944 -376.501172) (xy 342.046032 -376.445537) (xy 342.067896 -376.419872) (xy 342.073686 -376.412722)
			(xy 342.080205 -376.395535) (xy 342.080596 -376.386344) (xy 342.080596 -375.894092) (xy 342.08019 -375.884904)
			(xy 342.073674 -375.86772) (xy 342.067896 -375.860564) (xy 342.046064 -375.834873) (xy 342.007974 -375.779242)
			(xy 341.976822 -375.719449) (xy 341.953057 -375.656356) (xy 341.937019 -375.59087) (xy 341.928941 -375.523935)
			(xy 341.928938 -375.456513) (xy 341.93701 -375.389577) (xy 341.953042 -375.32409) (xy 341.976803 -375.260995)
			(xy 342.007949 -375.201199) (xy 342.046034 -375.145565) (xy 342.067896 -375.1199) (xy 342.073675 -375.112742)
			(xy 342.0802 -375.095561) (xy 342.080596 -375.086372) (xy 342.080596 -374.928638) (xy 342.081157 -374.918519)
			(xy 342.088864 -374.899807) (xy 342.103127 -374.885451) (xy 342.121789 -374.877623) (xy 342.131904 -374.877076)
			(xy 342.848184 -374.877076) (xy 342.858334 -374.877534) (xy 342.877082 -374.88532) (xy 342.891405 -374.899705)
			(xy 342.899109 -374.918486) (xy 342.899492 -374.928638) (xy 342.899492 -375.086372) (xy 342.899917 -375.095558)
			(xy 342.906421 -375.112742) (xy 342.912192 -375.1199) (xy 342.934088 -375.145539) (xy 342.972176 -375.201177)
			(xy 343.003326 -375.260977) (xy 343.027088 -375.324077) (xy 343.043122 -375.38957) (xy 343.051195 -375.456511)
			(xy 343.051193 -375.523937) (xy 343.043113 -375.590878) (xy 343.027074 -375.656369) (xy 343.003306 -375.719467)
			(xy 342.972151 -375.779264) (xy 342.934058 -375.834899) (xy 342.912192 -375.860564) (xy 342.906385 -375.867702)
			(xy 342.899877 -375.884898) (xy 342.899492 -375.894092) (xy 342.899492 -376.386344) (xy 342.899883 -376.395533)
			(xy 342.90641 -376.412717) (xy 342.912192 -376.419872) (xy 342.93406 -376.445534) (xy 342.972149 -376.501169)
			(xy 343.0033 -376.560965) (xy 343.027065 -376.624063) (xy 343.0431 -376.689552) (xy 343.051176 -376.756491)
			(xy 343.051175 -376.823856) (xy 346.329216 -376.823856) (xy 346.329216 -376.75655) (xy 346.33726 -376.689727)
			(xy 346.353234 -376.624345) (xy 346.376909 -376.56134) (xy 346.407944 -376.501617) (xy 346.445895 -376.446032)
			(xy 346.467684 -376.42038) (xy 346.47347 -376.413227) (xy 346.479991 -376.396043) (xy 346.480384 -376.386852)
			(xy 346.480384 -375.893584) (xy 346.479985 -375.884396) (xy 346.473464 -375.867211) (xy 346.467684 -375.860056)
			(xy 346.445926 -375.834379) (xy 346.407974 -375.778797) (xy 346.376937 -375.719077) (xy 346.35326 -375.656076)
			(xy 346.337283 -375.590696) (xy 346.329236 -375.523876) (xy 346.329233 -375.456572) (xy 346.337275 -375.389751)
			(xy 346.353246 -375.32437) (xy 346.376917 -375.261367) (xy 346.407949 -375.201645) (xy 346.445897 -375.14606)
			(xy 346.467684 -375.120408) (xy 346.473458 -375.113247) (xy 346.479987 -375.096069) (xy 346.480384 -375.08688)
			(xy 346.480384 -374.928638) (xy 346.480796 -374.918463) (xy 346.488577 -374.899661) (xy 346.502967 -374.885273)
			(xy 346.521771 -374.877495) (xy 346.531946 -374.877076) (xy 347.248226 -374.877076) (xy 347.258404 -374.877443)
			(xy 347.277207 -374.885244) (xy 347.291592 -374.899647) (xy 347.299369 -374.918459) (xy 347.299788 -374.928638)
			(xy 347.299788 -375.08688) (xy 347.300211 -375.096066) (xy 347.306716 -375.11325) (xy 347.312488 -375.120408)
			(xy 347.334306 -375.146035) (xy 347.372252 -375.201625) (xy 347.403283 -375.261353) (xy 347.426953 -375.324361)
			(xy 347.442923 -375.389746) (xy 347.450964 -375.456571) (xy 347.450961 -375.523878) (xy 347.442914 -375.590702)
			(xy 347.426938 -375.656086) (xy 347.403263 -375.719091) (xy 347.372228 -375.778816) (xy 347.334277 -375.834403)
			(xy 347.312488 -375.860056) (xy 347.306684 -375.867196) (xy 347.300174 -375.88439) (xy 347.299788 -375.893584)
			(xy 347.299788 -376.386852) (xy 347.300224 -376.396036) (xy 347.30672 -376.413221) (xy 347.312488 -376.42038)
			(xy 347.334279 -376.446029) (xy 347.372226 -376.501617) (xy 347.403257 -376.561341) (xy 347.426929 -376.624346)
			(xy 347.442901 -376.689728) (xy 347.450944 -376.756551) (xy 347.450944 -376.823855) (xy 347.450937 -376.823915)
			(xy 377.128742 -376.823915) (xy 377.128742 -376.756491) (xy 377.136817 -376.689553) (xy 377.152853 -376.624064)
			(xy 377.176618 -376.560967) (xy 377.20777 -376.501171) (xy 377.245859 -376.445537) (xy 377.267724 -376.419872)
			(xy 377.273518 -376.412725) (xy 377.280033 -376.395536) (xy 377.280424 -376.386344) (xy 377.280424 -375.894092)
			(xy 377.280012 -375.884905) (xy 377.273499 -375.867721) (xy 377.267724 -375.860564) (xy 377.245891 -375.834873)
			(xy 377.207799 -375.779243) (xy 377.176646 -375.71945) (xy 377.152879 -375.656357) (xy 377.136841 -375.590871)
			(xy 377.128762 -375.523935) (xy 377.128759 -375.456513) (xy 377.136832 -375.389577) (xy 377.152865 -375.324089)
			(xy 377.176626 -375.260993) (xy 377.207775 -375.201198) (xy 377.245861 -375.145565) (xy 377.267724 -375.1199)
			(xy 377.273506 -375.112744) (xy 377.280029 -375.095562) (xy 377.280424 -375.086372) (xy 377.280424 -374.928638)
			(xy 377.280957 -374.918516) (xy 377.28867 -374.899799) (xy 377.302942 -374.885442) (xy 377.321613 -374.877618)
			(xy 377.331732 -374.877076) (xy 378.048012 -374.877076) (xy 378.058164 -374.877511) (xy 378.076912 -374.885306)
			(xy 378.091234 -374.899698) (xy 378.098938 -374.918484) (xy 378.09932 -374.928638) (xy 378.09932 -375.086372)
			(xy 378.099739 -375.095558) (xy 378.106246 -375.112743) (xy 378.11202 -375.1199) (xy 378.133915 -375.14554)
			(xy 378.172001 -375.201178) (xy 378.203149 -375.260978) (xy 378.226911 -375.324078) (xy 378.242943 -375.38957)
			(xy 378.251016 -375.456511) (xy 378.251014 -375.523937) (xy 378.242935 -375.590877) (xy 378.226897 -375.656368)
			(xy 378.20313 -375.719466) (xy 378.171976 -375.779263) (xy 378.133885 -375.834898) (xy 378.11202 -375.860564)
			(xy 378.106216 -375.867704) (xy 378.099705 -375.884898) (xy 378.09932 -375.894092) (xy 378.09932 -376.386344)
			(xy 378.099704 -376.395534) (xy 378.106235 -376.412718) (xy 378.11202 -376.419872) (xy 378.133887 -376.445534)
			(xy 378.171974 -376.50117) (xy 378.203124 -376.560967) (xy 378.226887 -376.624064) (xy 378.242922 -376.689553)
			(xy 378.250997 -376.756491) (xy 378.250997 -376.756551) (xy 381.529061 -376.756551) (xy 381.537105 -376.689729)
			(xy 381.553076 -376.624347) (xy 381.576747 -376.561343) (xy 381.607779 -376.501619) (xy 381.645725 -376.446032)
			(xy 381.667512 -376.42038) (xy 381.673301 -376.413229) (xy 381.67982 -376.396043) (xy 381.680212 -376.386852)
			(xy 381.680212 -375.893584) (xy 381.679807 -375.884396) (xy 381.67329 -375.867212) (xy 381.667512 -375.860056)
			(xy 381.645756 -375.834378) (xy 381.607808 -375.778794) (xy 381.576775 -375.719074) (xy 381.553102 -375.656073)
			(xy 381.537127 -375.590694) (xy 381.529081 -375.523875) (xy 381.529078 -375.456573) (xy 381.537119 -375.389753)
			(xy 381.553088 -375.324373) (xy 381.576756 -375.26137) (xy 381.607784 -375.201647) (xy 381.645727 -375.14606)
			(xy 381.667512 -375.120408) (xy 381.673289 -375.113249) (xy 381.679815 -375.096069) (xy 381.680212 -375.08688)
			(xy 381.680212 -374.928638) (xy 381.680694 -374.918472) (xy 381.688462 -374.899683) (xy 381.702829 -374.885298)
			(xy 381.721609 -374.877507) (xy 381.731774 -374.877076) (xy 382.448054 -374.877076) (xy 382.458227 -374.877502)
			(xy 382.477028 -374.885279) (xy 382.491416 -374.899665) (xy 382.499196 -374.918465) (xy 382.499616 -374.928638)
			(xy 382.499616 -375.08688) (xy 382.500032 -375.096067) (xy 382.506541 -375.113251) (xy 382.512316 -375.120408)
			(xy 382.534136 -375.146034) (xy 382.572087 -375.201623) (xy 382.603122 -375.26135) (xy 382.626795 -375.324358)
			(xy 382.642767 -375.389744) (xy 382.650809 -375.45657) (xy 382.650806 -375.523878) (xy 382.642758 -375.590704)
			(xy 382.62678 -375.656088) (xy 382.603102 -375.719094) (xy 382.572063 -375.778818) (xy 382.534107 -375.834404)
			(xy 382.512316 -375.860056) (xy 382.506515 -375.867198) (xy 382.500002 -375.884391) (xy 382.499616 -375.893584)
			(xy 382.499616 -376.386852) (xy 382.500045 -376.396037) (xy 382.506545 -376.413222) (xy 382.512316 -376.42038)
			(xy 382.534109 -376.446028) (xy 382.572061 -376.501614) (xy 382.603096 -376.561338) (xy 382.626771 -376.624343)
			(xy 382.642745 -376.689726) (xy 382.650789 -376.75655) (xy 382.650789 -376.823856) (xy 382.650782 -376.823915)
			(xy 385.92883 -376.823915) (xy 385.92883 -376.756491) (xy 385.936905 -376.689553) (xy 385.95294 -376.624064)
			(xy 385.976705 -376.560967) (xy 386.007855 -376.501171) (xy 386.045944 -376.445537) (xy 386.067808 -376.419872)
			(xy 386.0736 -376.412724) (xy 386.080117 -376.395535) (xy 386.080508 -376.386344) (xy 386.080508 -375.894092)
			(xy 386.0801 -375.884905) (xy 386.073584 -375.867721) (xy 386.067808 -375.860564) (xy 386.045975 -375.834873)
			(xy 386.007885 -375.779242) (xy 385.976732 -375.71945) (xy 385.952966 -375.656356) (xy 385.936928 -375.59087)
			(xy 385.92885 -375.523935) (xy 385.928847 -375.456513) (xy 385.93692 -375.389577) (xy 385.952952 -375.32409)
			(xy 385.976713 -375.260994) (xy 386.00786 -375.201199) (xy 386.045946 -375.145565) (xy 386.067808 -375.1199)
			(xy 386.073588 -375.112743) (xy 386.080112 -375.095562) (xy 386.080508 -375.086372) (xy 386.080508 -374.928638)
			(xy 386.081057 -374.918518) (xy 386.088766 -374.899804) (xy 386.103033 -374.885447) (xy 386.121699 -374.877621)
			(xy 386.131816 -374.877076) (xy 386.848096 -374.877076) (xy 386.858247 -374.877524) (xy 386.876995 -374.885314)
			(xy 386.891317 -374.899702) (xy 386.899021 -374.918485) (xy 386.899404 -374.928638) (xy 386.899404 -375.086372)
			(xy 386.899827 -375.095558) (xy 386.906332 -375.112742) (xy 386.912104 -375.1199) (xy 386.933999 -375.145539)
			(xy 386.972087 -375.201178) (xy 387.003236 -375.260978) (xy 387.026998 -375.324078) (xy 387.043031 -375.38957)
			(xy 387.051104 -375.456511) (xy 387.051102 -375.523937) (xy 387.043023 -375.590877) (xy 387.026984 -375.656368)
			(xy 387.003216 -375.719466) (xy 386.972062 -375.779264) (xy 386.93397 -375.834899) (xy 386.912104 -375.860564)
			(xy 386.906298 -375.867703) (xy 386.899789 -375.884898) (xy 386.899404 -375.894092) (xy 386.899404 -376.386344)
			(xy 386.899792 -376.395534) (xy 386.906321 -376.412718) (xy 386.912104 -376.419872) (xy 386.933972 -376.445534)
			(xy 386.97206 -376.501169) (xy 387.00321 -376.560966) (xy 387.026974 -376.624063) (xy 387.043009 -376.689552)
			(xy 387.051085 -376.756491) (xy 387.051084 -376.823855) (xy 390.329149 -376.823855) (xy 390.329149 -376.756551)
			(xy 390.337192 -376.689729) (xy 390.353163 -376.624348) (xy 390.376834 -376.561344) (xy 390.407864 -376.50162)
			(xy 390.44581 -376.446033) (xy 390.467596 -376.42038) (xy 390.473383 -376.413228) (xy 390.479904 -376.396043)
			(xy 390.480296 -376.386852) (xy 390.480296 -375.893584) (xy 390.479894 -375.884396) (xy 390.473375 -375.867212)
			(xy 390.467596 -375.860056) (xy 390.445841 -375.834377) (xy 390.407894 -375.778794) (xy 390.376862 -375.719073)
			(xy 390.353189 -375.656072) (xy 390.337215 -375.590694) (xy 390.329169 -375.523875) (xy 390.329166 -375.456573)
			(xy 390.337207 -375.389754) (xy 390.353175 -375.324374) (xy 390.376842 -375.261371) (xy 390.407869 -375.201648)
			(xy 390.445812 -375.146061) (xy 390.467596 -375.120408) (xy 390.473371 -375.113248) (xy 390.479899 -375.096069)
			(xy 390.480296 -375.08688) (xy 390.480296 -374.928638) (xy 390.480864 -374.918488) (xy 390.488618 -374.899728)
			(xy 390.502961 -374.885363) (xy 390.521709 -374.877579) (xy 390.531858 -374.877076) (xy 391.248138 -374.877076)
			(xy 391.258303 -374.877503) (xy 391.27708 -374.885297) (xy 391.291445 -374.899684) (xy 391.299212 -374.918472)
			(xy 391.2997 -374.928638) (xy 391.2997 -375.08688) (xy 391.30012 -375.096066) (xy 391.306627 -375.113251)
			(xy 391.3124 -375.120408) (xy 391.334218 -375.146035) (xy 391.372163 -375.201626) (xy 391.403193 -375.261353)
			(xy 391.426862 -375.324361) (xy 391.442832 -375.389746) (xy 391.450873 -375.456571) (xy 391.45087 -375.523877)
			(xy 391.442823 -375.590702) (xy 391.426848 -375.656085) (xy 391.403173 -375.719091) (xy 391.372139 -375.778816)
			(xy 391.334188 -375.834403) (xy 391.3124 -375.860056) (xy 391.306597 -375.867197) (xy 391.300086 -375.884391)
			(xy 391.2997 -375.893584) (xy 391.2997 -376.386852) (xy 391.300133 -376.396037) (xy 391.306631 -376.413221)
			(xy 391.3124 -376.42038) (xy 391.33419 -376.446029) (xy 391.372137 -376.501617) (xy 391.403168 -376.561342)
			(xy 391.426838 -376.624346) (xy 391.44281 -376.689728) (xy 391.450853 -376.756551) (xy 391.450853 -376.823855)
			(xy 391.450846 -376.823915) (xy 421.128651 -376.823915) (xy 421.128651 -376.756491) (xy 421.136727 -376.689552)
			(xy 421.152763 -376.624063) (xy 421.176528 -376.560966) (xy 421.20768 -376.50117) (xy 421.245771 -376.445537)
			(xy 421.267636 -376.419872) (xy 421.273432 -376.412726) (xy 421.279946 -376.395536) (xy 421.280336 -376.386344)
			(xy 421.280336 -375.894092) (xy 421.279922 -375.884905) (xy 421.27341 -375.867721) (xy 421.267636 -375.860564)
			(xy 421.245802 -375.834873) (xy 421.20771 -375.779243) (xy 421.176556 -375.719451) (xy 421.152788 -375.656357)
			(xy 421.13675 -375.590871) (xy 421.128671 -375.523935) (xy 421.128668 -375.456513) (xy 421.136741 -375.389576)
			(xy 421.152774 -375.324089) (xy 421.176536 -375.260993) (xy 421.207685 -375.201198) (xy 421.245773 -375.145565)
			(xy 421.267636 -375.1199) (xy 421.27342 -375.112746) (xy 421.279941 -375.095562) (xy 421.280336 -375.086372)
			(xy 421.280336 -374.928638) (xy 421.280858 -374.918514) (xy 421.288572 -374.899795) (xy 421.302848 -374.885437)
			(xy 421.321523 -374.877616) (xy 421.331644 -374.877076) (xy 422.047924 -374.877076) (xy 422.058031 -374.877565)
			(xy 422.076706 -374.885306) (xy 422.090999 -374.899601) (xy 422.098737 -374.918277) (xy 422.099232 -374.928384)
			(xy 422.099232 -375.086372) (xy 422.099671 -375.095556) (xy 422.106166 -375.11274) (xy 422.111932 -375.1199)
			(xy 422.133826 -375.14554) (xy 422.171912 -375.201179) (xy 422.203059 -375.260979) (xy 422.22682 -375.324079)
			(xy 422.242853 -375.389571) (xy 422.250926 -375.456511) (xy 422.250923 -375.523937) (xy 422.242844 -375.590877)
			(xy 422.226806 -375.656367) (xy 422.20304 -375.719465) (xy 422.171887 -375.779263) (xy 422.133797 -375.834898)
			(xy 422.111932 -375.860564) (xy 422.106117 -375.867696) (xy 422.099615 -375.884897) (xy 422.099232 -375.894092)
			(xy 422.099232 -376.386344) (xy 422.099636 -376.395532) (xy 422.106156 -376.412715) (xy 422.111932 -376.419872)
			(xy 422.133799 -376.445535) (xy 422.171885 -376.50117) (xy 422.203034 -376.560967) (xy 422.226797 -376.624064)
			(xy 422.242831 -376.689553) (xy 422.250906 -376.756491) (xy 422.250906 -376.756551) (xy 425.52897 -376.756551)
			(xy 425.537014 -376.689729) (xy 425.552986 -376.624347) (xy 425.576658 -376.561343) (xy 425.607689 -376.501619)
			(xy 425.645637 -376.446032) (xy 425.667424 -376.42038) (xy 425.673214 -376.413231) (xy 425.679732 -376.396043)
			(xy 425.680124 -376.386852) (xy 425.680124 -375.893584) (xy 425.679716 -375.884397) (xy 425.6732 -375.867213)
			(xy 425.667424 -375.860056) (xy 425.645668 -375.834378) (xy 425.60772 -375.778795) (xy 425.576686 -375.719074)
			(xy 425.553012 -375.656073) (xy 425.537037 -375.590695) (xy 425.528991 -375.523875) (xy 425.528988 -375.456573)
			(xy 425.537029 -375.389753) (xy 425.552998 -375.324373) (xy 425.576666 -375.26137) (xy 425.607695 -375.201647)
			(xy 425.645639 -375.146061) (xy 425.667424 -375.120408) (xy 425.673202 -375.11325) (xy 425.679727 -375.096069)
			(xy 425.680124 -375.08688) (xy 425.680124 -374.928638) (xy 425.680595 -374.918471) (xy 425.688365 -374.899679)
			(xy 425.702736 -374.885294) (xy 425.721519 -374.877505) (xy 425.731686 -374.877076) (xy 426.447966 -374.877076)
			(xy 426.45814 -374.877493) (xy 426.476941 -374.885274) (xy 426.491329 -374.899662) (xy 426.499108 -374.918464)
			(xy 426.499528 -374.928638) (xy 426.499528 -375.08688) (xy 426.499941 -375.096067) (xy 426.506452 -375.113252)
			(xy 426.512228 -375.120408) (xy 426.534048 -375.146034) (xy 426.571998 -375.201623) (xy 426.603032 -375.26135)
			(xy 426.626705 -375.324358) (xy 426.642676 -375.389744) (xy 426.650718 -375.45657) (xy 426.650716 -375.523878)
			(xy 426.642668 -375.590704) (xy 426.62669 -375.656088) (xy 426.603013 -375.719094) (xy 426.571974 -375.778818)
			(xy 426.534019 -375.834404) (xy 426.512228 -375.860056) (xy 426.506416 -375.86719) (xy 426.499913 -375.884389)
			(xy 426.499528 -375.893584) (xy 426.499528 -376.386852) (xy 426.499955 -376.396037) (xy 426.506456 -376.413222)
			(xy 426.512228 -376.42038) (xy 426.534021 -376.446029) (xy 426.571971 -376.501615) (xy 426.603006 -376.561338)
			(xy 426.62668 -376.624344) (xy 426.642654 -376.689727) (xy 426.650698 -376.75655) (xy 426.650698 -376.823856)
			(xy 426.650691 -376.823915) (xy 429.928739 -376.823915) (xy 429.928739 -376.756491) (xy 429.936814 -376.689553)
			(xy 429.95285 -376.624064) (xy 429.976615 -376.560967) (xy 430.007766 -376.501171) (xy 430.045856 -376.445537)
			(xy 430.06772 -376.419872) (xy 430.073513 -376.412725) (xy 430.080029 -376.395536) (xy 430.08042 -376.386344)
			(xy 430.08042 -375.894092) (xy 430.080009 -375.884905) (xy 430.073496 -375.867721) (xy 430.06772 -375.860564)
			(xy 430.045887 -375.834873) (xy 430.007796 -375.779243) (xy 429.976643 -375.71945) (xy 429.952876 -375.656357)
			(xy 429.936837 -375.590871) (xy 429.928759 -375.523935) (xy 429.928756 -375.456513) (xy 429.936829 -375.389577)
			(xy 429.952861 -375.324089) (xy 429.976623 -375.260994) (xy 430.007771 -375.201199) (xy 430.045857 -375.145565)
			(xy 430.06772 -375.1199) (xy 430.073501 -375.112744) (xy 430.080024 -375.095562) (xy 430.08042 -375.086372)
			(xy 430.08042 -374.928638) (xy 430.080957 -374.918516) (xy 430.088669 -374.8998) (xy 430.10294 -374.885443)
			(xy 430.121609 -374.877619) (xy 430.131728 -374.877076) (xy 430.848008 -374.877076) (xy 430.85816 -374.877515)
			(xy 430.876907 -374.885308) (xy 430.89123 -374.899699) (xy 430.898933 -374.918484) (xy 430.899316 -374.928638)
			(xy 430.899316 -375.086372) (xy 430.899736 -375.095558) (xy 430.906242 -375.112743) (xy 430.912016 -375.1199)
			(xy 430.933911 -375.14554) (xy 430.971998 -375.201178) (xy 431.003146 -375.260978) (xy 431.026908 -375.324078)
			(xy 431.04294 -375.38957) (xy 431.051013 -375.456511) (xy 431.051011 -375.523937) (xy 431.042932 -375.590877)
			(xy 431.026893 -375.656368) (xy 431.003126 -375.719466) (xy 430.971973 -375.779263) (xy 430.933881 -375.834898)
			(xy 430.912016 -375.860564) (xy 430.906212 -375.867704) (xy 430.899701 -375.884898) (xy 430.899316 -375.894092)
			(xy 430.899316 -376.386344) (xy 430.899701 -376.395534) (xy 430.906232 -376.412718) (xy 430.912016 -376.419872)
			(xy 430.933883 -376.445534) (xy 430.971971 -376.50117) (xy 431.003121 -376.560966) (xy 431.026884 -376.624064)
			(xy 431.042918 -376.689553) (xy 431.050994 -376.756491) (xy 431.050994 -376.756551) (xy 434.329058 -376.756551)
			(xy 434.337101 -376.689729) (xy 434.353073 -376.624348) (xy 434.376744 -376.561343) (xy 434.407775 -376.50162)
			(xy 434.445721 -376.446033) (xy 434.467508 -376.42038) (xy 434.473296 -376.413229) (xy 434.479816 -376.396043)
			(xy 434.480208 -376.386852) (xy 434.480208 -375.893584) (xy 434.479804 -375.884396) (xy 434.473286 -375.867212)
			(xy 434.467508 -375.860056) (xy 434.445753 -375.834378) (xy 434.407805 -375.778794) (xy 434.376772 -375.719074)
			(xy 434.353099 -375.656073) (xy 434.337124 -375.590694) (xy 434.329078 -375.523875) (xy 434.329075 -375.456573)
			(xy 434.337116 -375.389753) (xy 434.353084 -375.324373) (xy 434.376752 -375.26137) (xy 434.40778 -375.201647)
			(xy 434.445723 -375.146061) (xy 434.467508 -375.120408) (xy 434.473285 -375.113249) (xy 434.479811 -375.096069)
			(xy 434.480208 -375.08688) (xy 434.480208 -374.928638) (xy 434.480694 -374.918473) (xy 434.488461 -374.899684)
			(xy 434.502827 -374.885299) (xy 434.521605 -374.877508) (xy 434.53177 -374.877076) (xy 435.24805 -374.877076)
			(xy 435.258223 -374.877506) (xy 435.277024 -374.885281) (xy 435.291412 -374.899666) (xy 435.299192 -374.918465)
			(xy 435.299612 -374.928638) (xy 435.299612 -375.08688) (xy 435.300029 -375.096067) (xy 435.306538 -375.113251)
			(xy 435.312312 -375.120408) (xy 435.334133 -375.146034) (xy 435.372084 -375.201623) (xy 435.403118 -375.26135)
			(xy 435.426791 -375.324358) (xy 435.442764 -375.389744) (xy 435.450806 -375.45657) (xy 435.450803 -375.523878)
			(xy 435.442755 -375.590704) (xy 435.426777 -375.656088) (xy 435.403099 -375.719094) (xy 435.372059 -375.778819)
			(xy 435.334103 -375.834404) (xy 435.312312 -375.860056) (xy 435.306511 -375.867198) (xy 435.299998 -375.884391)
			(xy 435.299612 -375.893584) (xy 435.299612 -376.386852) (xy 435.300042 -376.396037) (xy 435.306542 -376.413222)
			(xy 435.312312 -376.42038) (xy 435.334105 -376.446028) (xy 435.372057 -376.501614) (xy 435.403093 -376.561338)
			(xy 435.426768 -376.624343) (xy 435.442742 -376.689726) (xy 435.450786 -376.75655) (xy 435.450786 -376.823856)
			(xy 435.442741 -376.89068) (xy 435.426766 -376.956063) (xy 435.40309 -377.019068) (xy 435.372054 -377.078791)
			(xy 435.334101 -377.134376) (xy 435.312312 -377.160028) (xy 435.306522 -377.167178) (xy 435.300003 -377.184365)
			(xy 435.299612 -377.193556) (xy 435.299612 -377.35129) (xy 435.299227 -377.361467) (xy 435.291436 -377.380271)
			(xy 435.277038 -377.394658) (xy 435.258228 -377.402435) (xy 435.24805 -377.402852) (xy 434.53177 -377.402852)
			(xy 434.521609 -377.402391) (xy 434.502837 -377.394605) (xy 434.488473 -377.380229) (xy 434.480701 -377.361451)
			(xy 434.480208 -377.35129) (xy 434.480208 -377.193556) (xy 434.479817 -377.184367) (xy 434.47329 -377.167183)
			(xy 434.467508 -377.160028) (xy 434.445725 -377.134372) (xy 434.407778 -377.078786) (xy 434.376746 -377.019062)
			(xy 434.353075 -376.956058) (xy 434.337103 -376.890677) (xy 434.329059 -376.823855) (xy 434.329058 -376.756551)
			(xy 431.050994 -376.756551) (xy 431.050993 -376.823915) (xy 431.042917 -376.890853) (xy 431.026882 -376.956342)
			(xy 431.003118 -377.019439) (xy 430.971968 -377.079236) (xy 430.93388 -377.13487) (xy 430.912016 -377.160536)
			(xy 430.906223 -377.167684) (xy 430.899706 -377.184872) (xy 430.899316 -377.194064) (xy 430.899316 -377.35129)
			(xy 430.898864 -377.361421) (xy 430.891131 -377.380151) (xy 430.876834 -377.394509) (xy 430.858137 -377.402321)
			(xy 430.848008 -377.402852) (xy 430.131728 -377.402852) (xy 430.121582 -377.402357) (xy 430.10284 -377.39458)
			(xy 430.088518 -377.380207) (xy 430.080808 -377.361437) (xy 430.08042 -377.35129) (xy 430.08042 -377.194064)
			(xy 430.080023 -377.184876) (xy 430.0735 -377.167692) (xy 430.06772 -377.160536) (xy 430.045859 -377.134868)
			(xy 430.007769 -377.079234) (xy 429.976617 -377.019439) (xy 429.952852 -376.956342) (xy 429.936815 -376.890853)
			(xy 429.928739 -376.823915) (xy 426.650691 -376.823915) (xy 426.642653 -376.890679) (xy 426.626679 -376.956062)
			(xy 426.603004 -377.019067) (xy 426.571968 -377.07879) (xy 426.534017 -377.134376) (xy 426.512228 -377.160028)
			(xy 426.506428 -377.167171) (xy 426.499918 -377.184363) (xy 426.499528 -377.193556) (xy 426.499528 -377.35129)
			(xy 426.499127 -377.361465) (xy 426.491339 -377.380266) (xy 426.476946 -377.394653) (xy 426.458141 -377.402432)
			(xy 426.447966 -377.402852) (xy 425.731686 -377.402852) (xy 425.721526 -377.402378) (xy 425.702755 -377.394597)
			(xy 425.68839 -377.380225) (xy 425.680618 -377.36145) (xy 425.680124 -377.35129) (xy 425.680124 -377.193556)
			(xy 425.67973 -377.184367) (xy 425.673204 -377.167183) (xy 425.667424 -377.160028) (xy 425.645641 -377.134372)
			(xy 425.607693 -377.078786) (xy 425.57666 -377.019063) (xy 425.552988 -376.956059) (xy 425.537015 -376.890677)
			(xy 425.528971 -376.823855) (xy 425.52897 -376.756551) (xy 422.250906 -376.756551) (xy 422.250905 -376.823915)
			(xy 422.24283 -376.890853) (xy 422.226795 -376.956342) (xy 422.203032 -377.019438) (xy 422.171882 -377.079235)
			(xy 422.133795 -377.13487) (xy 422.111932 -377.160536) (xy 422.106129 -377.167677) (xy 422.09962 -377.184871)
			(xy 422.099232 -377.194064) (xy 422.099232 -377.35129) (xy 422.098764 -377.36142) (xy 422.091035 -377.380146)
			(xy 422.076742 -377.394503) (xy 422.058051 -377.402318) (xy 422.047924 -377.402852) (xy 421.331644 -377.402852)
			(xy 421.321544 -377.40228) (xy 421.302877 -377.394567) (xy 421.288583 -377.380297) (xy 421.280837 -377.361643)
			(xy 421.280336 -377.351544) (xy 421.280336 -377.194064) (xy 421.279935 -377.184876) (xy 421.273414 -377.167692)
			(xy 421.267636 -377.160536) (xy 421.245775 -377.134868) (xy 421.207684 -377.079235) (xy 421.176531 -377.019439)
			(xy 421.152765 -376.956343) (xy 421.136728 -376.890854) (xy 421.128651 -376.823915) (xy 391.450846 -376.823915)
			(xy 391.442809 -376.890678) (xy 391.426837 -376.956059) (xy 391.403165 -377.019064) (xy 391.372134 -377.078788)
			(xy 391.334187 -377.134375) (xy 391.3124 -377.160028) (xy 391.306609 -377.167177) (xy 391.300091 -377.184365)
			(xy 391.2997 -377.193556) (xy 391.2997 -377.35129) (xy 391.299159 -377.361442) (xy 391.291395 -377.380204)
			(xy 391.277044 -377.394568) (xy 391.25829 -377.40235) (xy 391.248138 -377.402852) (xy 390.531858 -377.402852)
			(xy 390.521696 -377.402401) (xy 390.502924 -377.394611) (xy 390.48856 -377.380232) (xy 390.480789 -377.361452)
			(xy 390.480296 -377.35129) (xy 390.480296 -377.193556) (xy 390.479908 -377.184366) (xy 390.473379 -377.167182)
			(xy 390.467596 -377.160028) (xy 390.445814 -377.134372) (xy 390.407867 -377.078785) (xy 390.376836 -377.019062)
			(xy 390.353165 -376.956058) (xy 390.337193 -376.890676) (xy 390.329149 -376.823855) (xy 387.051084 -376.823855)
			(xy 387.051084 -376.823915) (xy 387.043008 -376.890853) (xy 387.026972 -376.956343) (xy 387.003208 -377.01944)
			(xy 386.972057 -377.079236) (xy 386.933968 -377.134871) (xy 386.912104 -377.160536) (xy 386.90631 -377.167683)
			(xy 386.899794 -377.184872) (xy 386.899404 -377.194064) (xy 386.899404 -377.35129) (xy 386.898867 -377.361411)
			(xy 386.89115 -377.380123) (xy 386.87688 -377.394478) (xy 386.858214 -377.402306) (xy 386.848096 -377.402852)
			(xy 386.131816 -377.402852) (xy 386.121669 -377.402366) (xy 386.102927 -377.394586) (xy 386.088605 -377.380209)
			(xy 386.080896 -377.361438) (xy 386.080508 -377.35129) (xy 386.080508 -377.194064) (xy 386.080114 -377.184875)
			(xy 386.073589 -377.167691) (xy 386.067808 -377.160536) (xy 386.045948 -377.134868) (xy 386.007858 -377.079234)
			(xy 385.976707 -377.019438) (xy 385.952942 -376.956342) (xy 385.936906 -376.890853) (xy 385.92883 -376.823915)
			(xy 382.650782 -376.823915) (xy 382.642744 -376.89068) (xy 382.626769 -376.956063) (xy 382.603094 -377.019068)
			(xy 382.572058 -377.078791) (xy 382.534105 -377.134376) (xy 382.512316 -377.160028) (xy 382.506527 -377.167179)
			(xy 382.500007 -377.184365) (xy 382.499616 -377.193556) (xy 382.499616 -377.35129) (xy 382.499227 -377.361467)
			(xy 382.491437 -377.38027) (xy 382.47704 -377.394657) (xy 382.458231 -377.402434) (xy 382.448054 -377.402852)
			(xy 381.731774 -377.402852) (xy 381.721613 -377.402388) (xy 381.702842 -377.394603) (xy 381.688477 -377.380228)
			(xy 381.680705 -377.361451) (xy 381.680212 -377.35129) (xy 381.680212 -377.193556) (xy 381.67982 -377.184367)
			(xy 381.673294 -377.167183) (xy 381.667512 -377.160028) (xy 381.645729 -377.134372) (xy 381.607782 -377.078786)
			(xy 381.57675 -377.019062) (xy 381.553078 -376.956058) (xy 381.537106 -376.890677) (xy 381.529062 -376.823855)
			(xy 381.529061 -376.756551) (xy 378.250997 -376.756551) (xy 378.250996 -376.823915) (xy 378.24292 -376.890853)
			(xy 378.226885 -376.956342) (xy 378.203121 -377.019439) (xy 378.171971 -377.079235) (xy 378.133884 -377.13487)
			(xy 378.11202 -377.160536) (xy 378.106228 -377.167685) (xy 378.09971 -377.184872) (xy 378.09932 -377.194064)
			(xy 378.09932 -377.35129) (xy 378.098864 -377.361421) (xy 378.091132 -377.38015) (xy 378.076836 -377.394508)
			(xy 378.058141 -377.40232) (xy 378.048012 -377.402852) (xy 377.331732 -377.402852) (xy 377.321586 -377.402353)
			(xy 377.302845 -377.394578) (xy 377.288522 -377.380206) (xy 377.280812 -377.361437) (xy 377.280424 -377.35129)
			(xy 377.280424 -377.194064) (xy 377.280026 -377.184876) (xy 377.273503 -377.167692) (xy 377.267724 -377.160536)
			(xy 377.245863 -377.134868) (xy 377.207773 -377.079234) (xy 377.17662 -377.019439) (xy 377.152855 -376.956342)
			(xy 377.136819 -376.890853) (xy 377.128742 -376.823915) (xy 347.450937 -376.823915) (xy 347.4429 -376.890678)
			(xy 347.426927 -376.95606) (xy 347.403255 -377.019065) (xy 347.372223 -377.078788) (xy 347.334275 -377.134376)
			(xy 347.312488 -377.160028) (xy 347.306696 -377.167176) (xy 347.300179 -377.184364) (xy 347.299788 -377.193556)
			(xy 347.299788 -377.35129) (xy 347.299259 -377.361444) (xy 347.291493 -377.380208) (xy 347.277138 -377.394573)
			(xy 347.25838 -377.402352) (xy 347.248226 -377.402852) (xy 346.531946 -377.402852) (xy 346.521776 -377.402398)
			(xy 346.502981 -377.394627) (xy 346.488594 -377.38025) (xy 346.480809 -377.36146) (xy 346.480384 -377.35129)
			(xy 346.480384 -377.193556) (xy 346.479999 -377.184366) (xy 346.473468 -377.167182) (xy 346.467684 -377.160028)
			(xy 346.445899 -377.134373) (xy 346.407947 -377.078788) (xy 346.376911 -377.019065) (xy 346.353236 -376.956061)
			(xy 346.337262 -376.890679) (xy 346.329216 -376.823856) (xy 343.051175 -376.823856) (xy 343.051175 -376.823915)
			(xy 343.043099 -376.890854) (xy 343.027063 -376.956343) (xy 343.003298 -377.01944) (xy 342.972146 -377.079236)
			(xy 342.934056 -377.134871) (xy 342.912192 -377.160536) (xy 342.906397 -377.167682) (xy 342.899882 -377.184872)
			(xy 342.899492 -377.194064) (xy 342.899492 -377.35129) (xy 342.898966 -377.361412) (xy 342.891248 -377.380127)
			(xy 342.876974 -377.394483) (xy 342.858303 -377.402308) (xy 342.848184 -377.402852) (xy 342.131904 -377.402852)
			(xy 342.121757 -377.402376) (xy 342.103014 -377.394592) (xy 342.088693 -377.380212) (xy 342.080984 -377.361439)
			(xy 342.080596 -377.35129) (xy 342.080596 -377.194064) (xy 342.080204 -377.184875) (xy 342.073678 -377.167691)
			(xy 342.067896 -377.160536) (xy 342.046036 -377.134867) (xy 342.007948 -377.079233) (xy 341.976797 -377.019438)
			(xy 341.953033 -376.956341) (xy 341.936997 -376.890852) (xy 341.928921 -376.823915) (xy 338.650849 -376.823915)
			(xy 338.642812 -376.890677) (xy 338.62684 -376.956059) (xy 338.603168 -377.019064) (xy 338.572137 -377.078788)
			(xy 338.534191 -377.134375) (xy 338.512404 -377.160028) (xy 338.506614 -377.167178) (xy 338.500095 -377.184365)
			(xy 338.499704 -377.193556) (xy 338.499704 -377.35129) (xy 338.49916 -377.361442) (xy 338.491396 -377.380203)
			(xy 338.477047 -377.394567) (xy 338.458293 -377.402349) (xy 338.448142 -377.402852) (xy 337.731862 -377.402852)
			(xy 337.721701 -377.402397) (xy 337.702929 -377.394609) (xy 337.688564 -377.380231) (xy 337.680793 -377.361452)
			(xy 337.6803 -377.35129) (xy 337.6803 -377.193556) (xy 337.679911 -377.184367) (xy 337.673383 -377.167182)
			(xy 337.6676 -377.160028) (xy 337.645817 -377.134372) (xy 337.607871 -377.078785) (xy 337.57684 -377.019062)
			(xy 337.553168 -376.956058) (xy 337.537196 -376.890677) (xy 337.529152 -376.823855) (xy 334.251087 -376.823855)
			(xy 334.251087 -376.823915) (xy 334.243011 -376.890853) (xy 334.226976 -376.956342) (xy 334.203211 -377.019439)
			(xy 334.172061 -377.079236) (xy 334.133972 -377.134871) (xy 334.112108 -377.160536) (xy 334.106315 -377.167684)
			(xy 334.099798 -377.184872) (xy 334.099408 -377.194064) (xy 334.099408 -377.35129) (xy 334.098867 -377.36141)
			(xy 334.091151 -377.380122) (xy 334.076882 -377.394477) (xy 334.058217 -377.402305) (xy 334.0481 -377.402852)
			(xy 333.33182 -377.402852) (xy 333.321674 -377.402363) (xy 333.302932 -377.394584) (xy 333.288609 -377.380209)
			(xy 333.2809 -377.361438) (xy 333.280512 -377.35129) (xy 333.280512 -377.194064) (xy 333.280117 -377.184875)
			(xy 333.273592 -377.167691) (xy 333.267812 -377.160536) (xy 333.245952 -377.134868) (xy 333.207862 -377.079234)
			(xy 333.17671 -377.019438) (xy 333.152945 -376.956342) (xy 333.136909 -376.890853) (xy 333.128833 -376.823915)
			(xy 303.451057 -376.823915) (xy 303.44298 -376.890854) (xy 303.426944 -376.956344) (xy 303.403178 -377.019441)
			(xy 303.372025 -377.079237) (xy 303.333933 -377.134871) (xy 303.312068 -377.160536) (xy 303.30627 -377.16768)
			(xy 303.299757 -377.184871) (xy 303.299368 -377.194064) (xy 303.299368 -377.35129) (xy 303.298865 -377.361415)
			(xy 303.291142 -377.380135) (xy 303.276861 -377.394491) (xy 303.258182 -377.402312) (xy 303.24806 -377.402852)
			(xy 302.53178 -377.402852) (xy 302.521631 -377.402396) (xy 302.502888 -377.394604) (xy 302.488567 -377.380218)
			(xy 302.480859 -377.361441) (xy 302.480472 -377.35129) (xy 302.480472 -377.194064) (xy 302.480085 -377.184874)
			(xy 302.473556 -377.16769) (xy 302.467772 -377.160536) (xy 302.445913 -377.134867) (xy 302.407826 -377.079232)
			(xy 302.376677 -377.019436) (xy 302.352913 -376.95634) (xy 302.336879 -376.890852) (xy 302.328803 -376.823914)
			(xy 302.328802 -376.756492) (xy 299.050731 -376.756492) (xy 299.050738 -376.756551) (xy 299.050738 -376.823856)
			(xy 299.042693 -376.890678) (xy 299.026721 -376.95606) (xy 299.003048 -377.019065) (xy 298.972016 -377.078789)
			(xy 298.934067 -377.134376) (xy 298.91228 -377.160028) (xy 298.906487 -377.167175) (xy 298.899971 -377.184364)
			(xy 298.89958 -377.193556) (xy 298.89958 -377.35129) (xy 298.899059 -377.361445) (xy 298.891291 -377.38021)
			(xy 298.876934 -377.394575) (xy 298.858173 -377.402353) (xy 298.848018 -377.402852) (xy 298.131738 -377.402852)
			(xy 298.121568 -377.402405) (xy 298.102772 -377.39463) (xy 298.088385 -377.380252) (xy 298.080601 -377.36146)
			(xy 298.080176 -377.35129) (xy 298.080176 -377.193556) (xy 298.079792 -377.184366) (xy 298.073261 -377.167182)
			(xy 298.067476 -377.160028) (xy 298.045691 -377.134373) (xy 298.00774 -377.078788) (xy 297.976704 -377.019065)
			(xy 297.95303 -376.956061) (xy 297.937055 -376.890679) (xy 297.92901 -376.823856) (xy 294.650969 -376.823856)
			(xy 294.650969 -376.823915) (xy 294.642893 -376.890854) (xy 294.626856 -376.956343) (xy 294.603091 -377.019441)
			(xy 294.571939 -377.079237) (xy 294.533849 -377.134871) (xy 294.511984 -377.160536) (xy 294.506188 -377.167681)
			(xy 294.499673 -377.184872) (xy 294.499284 -377.194064) (xy 294.499284 -377.35129) (xy 294.498766 -377.361413)
			(xy 294.491046 -377.38013) (xy 294.47677 -377.394485) (xy 294.458096 -377.402309) (xy 294.447976 -377.402852)
			(xy 293.731696 -377.402852) (xy 293.721593 -377.402319) (xy 293.702925 -377.39459) (xy 293.688632 -377.380308)
			(xy 293.680889 -377.361646) (xy 293.680388 -377.351544) (xy 293.680388 -377.194064) (xy 293.679998 -377.184875)
			(xy 293.673471 -377.16769) (xy 293.667688 -377.160536) (xy 293.645828 -377.134867) (xy 293.60774 -377.079233)
			(xy 293.57659 -377.019437) (xy 293.552826 -376.956341) (xy 293.536791 -376.890852) (xy 293.528715 -376.823915)
			(xy 290.250643 -376.823915) (xy 290.242606 -376.890678) (xy 290.226633 -376.95606) (xy 290.202962 -377.019064)
			(xy 290.17193 -377.078788) (xy 290.133983 -377.134375) (xy 290.112196 -377.160028) (xy 290.106405 -377.167177)
			(xy 290.099887 -377.184365) (xy 290.099496 -377.193556) (xy 290.099496 -377.35129) (xy 290.098959 -377.361443)
			(xy 290.091194 -377.380205) (xy 290.076842 -377.39457) (xy 290.058087 -377.402351) (xy 290.047934 -377.402852)
			(xy 289.331654 -377.402852) (xy 289.321492 -377.402404) (xy 289.30272 -377.394613) (xy 289.288356 -377.380233)
			(xy 289.280585 -377.361452) (xy 289.280092 -377.35129) (xy 289.280092 -377.193556) (xy 289.279705 -377.184366)
			(xy 289.273176 -377.167182) (xy 289.267392 -377.160028) (xy 289.245607 -377.134373) (xy 289.207654 -377.078788)
			(xy 289.176618 -377.019066) (xy 289.152942 -376.956061) (xy 289.136968 -376.890679) (xy 289.128922 -376.823856)
			(xy 273.068299 -376.823856) (xy 273.100384 -376.843252) (xy 273.210304 -376.919124) (xy 273.315441 -377.001494)
			(xy 273.415414 -377.090062) (xy 273.509856 -377.184504) (xy 273.598424 -377.284477) (xy 273.680794 -377.389614)
			(xy 273.756666 -377.499534) (xy 273.825762 -377.613833) (xy 273.887832 -377.732096) (xy 273.942647 -377.853891)
			(xy 273.990009 -377.978774) (xy 274.029744 -378.106288) (xy 274.061707 -378.235969) (xy 274.077801 -378.323794)
			(xy 286.928742 -378.323794) (xy 286.928744 -378.256367) (xy 286.936824 -378.189426) (xy 286.952863 -378.123935)
			(xy 286.976633 -378.060837) (xy 287.007789 -378.00104) (xy 287.045885 -377.945406) (xy 287.067752 -377.919742)
			(xy 287.073562 -377.912607) (xy 287.080067 -377.895408) (xy 287.080452 -377.886214) (xy 287.080452 -377.728734)
			(xy 287.080955 -377.718608) (xy 287.088674 -377.699885) (xy 287.102955 -377.685528) (xy 287.121637 -377.677709)
			(xy 287.13176 -377.677172) (xy 287.84804 -377.677172) (xy 287.858148 -377.677652) (xy 287.876822 -377.685397)
			(xy 287.891114 -377.699695) (xy 287.898852 -377.718372) (xy 287.899348 -377.72848) (xy 287.899348 -377.886214)
			(xy 287.899763 -377.8954) (xy 287.906275 -377.912584) (xy 287.912048 -377.919742) (xy 287.933888 -377.945427)
			(xy 287.971981 -378.001058) (xy 288.003136 -378.060851) (xy 288.026904 -378.123945) (xy 288.042943 -378.189432)
			(xy 288.051021 -378.256369) (xy 288.051024 -378.323734) (xy 291.329062 -378.323734) (xy 291.329064 -378.256427)
			(xy 291.337111 -378.189602) (xy 291.353086 -378.124219) (xy 291.376762 -378.061213) (xy 291.407799 -378.001489)
			(xy 291.445751 -377.945902) (xy 291.46754 -377.92025) (xy 291.473345 -377.913111) (xy 291.479854 -377.895916)
			(xy 291.48024 -377.886722) (xy 291.48024 -377.728734) (xy 291.480692 -377.718564) (xy 291.488466 -377.69977)
			(xy 291.502843 -377.685384) (xy 291.521633 -377.677598) (xy 291.531802 -377.677172) (xy 292.248082 -377.677172)
			(xy 292.258257 -377.677579) (xy 292.277058 -377.685365) (xy 292.291444 -377.699756) (xy 292.299224 -377.718559)
			(xy 292.299644 -377.728734) (xy 292.299644 -377.886722) (xy 292.300056 -377.895909) (xy 292.30657 -377.913092)
			(xy 292.312344 -377.92025) (xy 292.334107 -377.945923) (xy 292.372057 -378.001506) (xy 292.403093 -378.061227)
			(xy 292.426768 -378.124228) (xy 292.442743 -378.189608) (xy 292.450789 -378.256429) (xy 292.450792 -378.323732)
			(xy 292.450785 -378.323794) (xy 295.72883 -378.323794) (xy 295.728832 -378.256367) (xy 295.736911 -378.189427)
			(xy 295.752951 -378.123936) (xy 295.776719 -378.060837) (xy 295.807875 -378.001041) (xy 295.845969 -377.945407)
			(xy 295.867836 -377.919742) (xy 295.873644 -377.912605) (xy 295.880151 -377.895408) (xy 295.880536 -377.886214)
			(xy 295.880536 -377.728734) (xy 295.881055 -377.71861) (xy 295.88877 -377.69989) (xy 295.903047 -377.685533)
			(xy 295.921723 -377.677712) (xy 295.931844 -377.677172) (xy 296.648124 -377.677172) (xy 296.658276 -377.677601)
			(xy 296.677024 -377.6854) (xy 296.691345 -377.699793) (xy 296.699049 -377.71858) (xy 296.699432 -377.728734)
			(xy 296.699432 -377.886214) (xy 296.699851 -377.8954) (xy 296.70636 -377.912584) (xy 296.712132 -377.919742)
			(xy 296.733969 -377.945429) (xy 296.772057 -378.001061) (xy 296.803207 -378.060855) (xy 296.826971 -378.123949)
			(xy 296.843007 -378.189435) (xy 296.851085 -378.25637) (xy 296.851087 -378.323791) (xy 296.851087 -378.323794)
			(xy 300.128621 -378.323794) (xy 300.128623 -378.256367) (xy 300.136702 -378.189427) (xy 300.152741 -378.123936)
			(xy 300.176509 -378.060838) (xy 300.207664 -378.001041) (xy 300.245758 -377.945407) (xy 300.267624 -377.919742)
			(xy 300.27343 -377.912604) (xy 300.279938 -377.895408) (xy 300.280324 -377.886214) (xy 300.280324 -377.728734)
			(xy 300.280854 -377.718611) (xy 300.288568 -377.699894) (xy 300.302841 -377.685537) (xy 300.321512 -377.677714)
			(xy 300.331632 -377.677172) (xy 301.047912 -377.677172) (xy 301.058063 -377.677611) (xy 301.076811 -377.685405)
			(xy 301.091133 -377.699796) (xy 301.098837 -377.718581) (xy 301.09922 -377.728734) (xy 301.09922 -377.886214)
			(xy 301.099619 -377.895402) (xy 301.10614 -377.912587) (xy 301.11192 -377.919742) (xy 301.133758 -377.945429)
			(xy 301.171846 -378.001061) (xy 301.202997 -378.060854) (xy 301.226761 -378.123948) (xy 301.242798 -378.189434)
			(xy 301.250876 -378.25637) (xy 301.250878 -378.323734) (xy 330.92918 -378.323734) (xy 330.929182 -378.256427)
			(xy 330.937229 -378.189602) (xy 330.953206 -378.124218) (xy 330.976882 -378.061212) (xy 331.00792 -378.001488)
			(xy 331.045874 -377.945902) (xy 331.067664 -377.92025) (xy 331.073472 -377.913113) (xy 331.079978 -377.895916)
			(xy 331.080364 -377.886722) (xy 331.080364 -377.728734) (xy 331.080792 -377.718561) (xy 331.088571 -377.699763)
			(xy 331.102956 -377.685376) (xy 331.121753 -377.677594) (xy 331.131926 -377.677172) (xy 331.848206 -377.677172)
			(xy 331.858382 -377.67756) (xy 331.877184 -377.685353) (xy 331.891569 -377.69975) (xy 331.899348 -377.718557)
			(xy 331.899768 -377.728734) (xy 331.899768 -377.886722) (xy 331.900175 -377.895909) (xy 331.906692 -377.913093)
			(xy 331.912468 -377.92025) (xy 331.93423 -377.945923) (xy 331.972179 -378.001507) (xy 332.003213 -378.061228)
			(xy 332.026887 -378.124229) (xy 332.042861 -378.189609) (xy 332.050907 -378.256429) (xy 332.05091 -378.323732)
			(xy 332.050903 -378.323793) (xy 335.328973 -378.323793) (xy 335.328975 -378.256368) (xy 335.337053 -378.189429)
			(xy 335.35309 -378.123939) (xy 335.376855 -378.060841) (xy 335.408007 -378.001044) (xy 335.446096 -377.945408)
			(xy 335.46796 -377.919742) (xy 335.473771 -377.912607) (xy 335.480275 -377.895409) (xy 335.48066 -377.886214)
			(xy 335.48066 -377.728734) (xy 335.481155 -377.718607) (xy 335.488875 -377.699883) (xy 335.50316 -377.685525)
			(xy 335.521844 -377.677708) (xy 335.531968 -377.677172) (xy 336.248248 -377.677172) (xy 336.258402 -377.677582)
			(xy 336.27715 -377.685388) (xy 336.29147 -377.699787) (xy 336.299173 -377.718578) (xy 336.299556 -377.728734)
			(xy 336.299556 -377.886214) (xy 336.299969 -377.895401) (xy 336.306482 -377.912585) (xy 336.312256 -377.919742)
			(xy 336.334096 -377.945428) (xy 336.372188 -378.001058) (xy 336.403343 -378.060851) (xy 336.42711 -378.123945)
			(xy 336.443149 -378.189433) (xy 336.451227 -378.256369) (xy 336.45123 -378.323734) (xy 339.729268 -378.323734)
			(xy 339.72927 -378.256427) (xy 339.737317 -378.189602) (xy 339.753293 -378.124218) (xy 339.776969 -378.061213)
			(xy 339.808006 -378.001489) (xy 339.845958 -377.945902) (xy 339.867748 -377.92025) (xy 339.873554 -377.913112)
			(xy 339.880062 -377.895916) (xy 339.880448 -377.886722) (xy 339.880448 -377.728734) (xy 339.880892 -377.718563)
			(xy 339.888668 -377.699768) (xy 339.903047 -377.685381) (xy 339.92184 -377.677597) (xy 339.93201 -377.677172)
			(xy 340.64829 -377.677172) (xy 340.658465 -377.677573) (xy 340.677266 -377.685361) (xy 340.691653 -377.699754)
			(xy 340.699432 -377.718559) (xy 340.699852 -377.728734) (xy 340.699852 -377.886722) (xy 340.700262 -377.895909)
			(xy 340.706777 -377.913093) (xy 340.712552 -377.92025) (xy 340.734314 -377.945923) (xy 340.772264 -378.001506)
			(xy 340.803299 -378.061227) (xy 340.826974 -378.124229) (xy 340.842949 -378.189608) (xy 340.850995 -378.256429)
			(xy 340.850998 -378.323732) (xy 340.850998 -378.323734) (xy 344.129059 -378.323734) (xy 344.129061 -378.256427)
			(xy 344.137108 -378.189603) (xy 344.153083 -378.124219) (xy 344.176759 -378.061213) (xy 344.207795 -378.001489)
			(xy 344.245747 -377.945902) (xy 344.267536 -377.92025) (xy 344.273341 -377.913111) (xy 344.27985 -377.895916)
			(xy 344.280236 -377.886722) (xy 344.280236 -377.728734) (xy 344.280692 -377.718565) (xy 344.288465 -377.699771)
			(xy 344.302841 -377.685385) (xy 344.321629 -377.677599) (xy 344.331798 -377.677172) (xy 345.048078 -377.677172)
			(xy 345.058252 -377.677583) (xy 345.077053 -377.685367) (xy 345.09144 -377.699757) (xy 345.099219 -377.71856)
			(xy 345.09964 -377.728734) (xy 345.09964 -377.886722) (xy 345.100053 -377.895909) (xy 345.106566 -377.913092)
			(xy 345.11234 -377.92025) (xy 345.134103 -377.945923) (xy 345.172054 -378.001506) (xy 345.203089 -378.061226)
			(xy 345.226764 -378.124228) (xy 345.24274 -378.189608) (xy 345.250786 -378.256429) (xy 345.250789 -378.323732)
			(xy 345.250789 -378.323734) (xy 374.929089 -378.323734) (xy 374.929092 -378.256427) (xy 374.937139 -378.189602)
			(xy 374.953116 -378.124218) (xy 374.976793 -378.061212) (xy 375.007831 -378.001488) (xy 375.045786 -377.945902)
			(xy 375.067576 -377.92025) (xy 375.073374 -377.913105) (xy 375.079888 -377.895915) (xy 375.080276 -377.886722)
			(xy 375.080276 -377.728734) (xy 375.080693 -377.71856) (xy 375.088474 -377.699759) (xy 375.102862 -377.685371)
			(xy 375.121664 -377.677592) (xy 375.131838 -377.677172) (xy 375.848118 -377.677172) (xy 375.858295 -377.67755)
			(xy 375.877097 -377.685347) (xy 375.891482 -377.699747) (xy 375.89926 -377.718557) (xy 375.89968 -377.728734)
			(xy 375.89968 -377.886722) (xy 375.900084 -377.89591) (xy 375.906602 -377.913094) (xy 375.91238 -377.92025)
			(xy 375.934142 -377.945923) (xy 375.97209 -378.001507) (xy 376.003123 -378.061228) (xy 376.026797 -378.12423)
			(xy 376.042771 -378.189609) (xy 376.050817 -378.256429) (xy 376.050819 -378.323732) (xy 376.050812 -378.323793)
			(xy 379.328882 -378.323793) (xy 379.328884 -378.256368) (xy 379.336962 -378.189428) (xy 379.352999 -378.123938)
			(xy 379.376765 -378.06084) (xy 379.407917 -378.001043) (xy 379.446007 -377.945408) (xy 379.467872 -377.919742)
			(xy 379.473684 -377.912608) (xy 379.480188 -377.895409) (xy 379.480572 -377.886214) (xy 379.480572 -377.728734)
			(xy 379.481056 -377.718606) (xy 379.488778 -377.699879) (xy 379.503066 -377.685521) (xy 379.521754 -377.677706)
			(xy 379.53188 -377.677172) (xy 380.24816 -377.677172) (xy 380.258308 -377.677654) (xy 380.277054 -377.685431)
			(xy 380.291378 -377.699809) (xy 380.299084 -377.718584) (xy 380.299468 -377.728734) (xy 380.299468 -377.886214)
			(xy 380.299878 -377.895401) (xy 380.306393 -377.912585) (xy 380.312168 -377.919742) (xy 380.334008 -377.945428)
			(xy 380.372099 -378.001059) (xy 380.403253 -378.060852) (xy 380.42702 -378.123946) (xy 380.443058 -378.189433)
			(xy 380.451137 -378.256369) (xy 380.451139 -378.323734) (xy 383.729177 -378.323734) (xy 383.729179 -378.256427)
			(xy 383.737226 -378.189602) (xy 383.753202 -378.124218) (xy 383.776879 -378.061212) (xy 383.807917 -378.001488)
			(xy 383.84587 -377.945902) (xy 383.86766 -377.92025) (xy 383.873468 -377.913113) (xy 383.879974 -377.895916)
			(xy 383.88036 -377.886722) (xy 383.88036 -377.728734) (xy 383.880792 -377.718562) (xy 383.88857 -377.699764)
			(xy 383.902954 -377.685377) (xy 383.92175 -377.677595) (xy 383.931922 -377.677172) (xy 384.648202 -377.677172)
			(xy 384.658378 -377.677563) (xy 384.677179 -377.685355) (xy 384.691565 -377.699751) (xy 384.699344 -377.718558)
			(xy 384.699764 -377.728734) (xy 384.699764 -377.886722) (xy 384.700172 -377.895909) (xy 384.706688 -377.913093)
			(xy 384.712464 -377.92025) (xy 384.734226 -377.945923) (xy 384.772175 -378.001507) (xy 384.803209 -378.061228)
			(xy 384.826884 -378.124229) (xy 384.842858 -378.189609) (xy 384.850904 -378.256429) (xy 384.850907 -378.323732)
			(xy 384.850907 -378.323734) (xy 388.128968 -378.323734) (xy 388.12897 -378.256427) (xy 388.137017 -378.189602)
			(xy 388.152993 -378.124218) (xy 388.176669 -378.061213) (xy 388.207706 -378.001489) (xy 388.245658 -377.945902)
			(xy 388.267448 -377.92025) (xy 388.273254 -377.913112) (xy 388.279762 -377.895916) (xy 388.280148 -377.886722)
			(xy 388.280148 -377.728734) (xy 388.280592 -377.718563) (xy 388.288368 -377.699768) (xy 388.302747 -377.685381)
			(xy 388.32154 -377.677597) (xy 388.33171 -377.677172) (xy 389.04799 -377.677172) (xy 389.058165 -377.677573)
			(xy 389.076966 -377.685361) (xy 389.091353 -377.699754) (xy 389.099132 -377.718559) (xy 389.099552 -377.728734)
			(xy 389.099552 -377.886722) (xy 389.099962 -377.895909) (xy 389.106477 -377.913093) (xy 389.112252 -377.92025)
			(xy 389.134014 -377.945923) (xy 389.171964 -378.001506) (xy 389.202999 -378.061227) (xy 389.226674 -378.124229)
			(xy 389.242649 -378.189608) (xy 389.250695 -378.256429) (xy 389.250698 -378.323732) (xy 389.250698 -378.323734)
			(xy 418.928998 -378.323734) (xy 418.929001 -378.256426) (xy 418.937048 -378.189601) (xy 418.953025 -378.124217)
			(xy 418.976703 -378.061211) (xy 419.007742 -378.001487) (xy 419.045697 -377.945902) (xy 419.067488 -377.92025)
			(xy 419.073287 -377.913106) (xy 419.079801 -377.895915) (xy 419.080188 -377.886722) (xy 419.080188 -377.728734)
			(xy 419.080593 -377.718558) (xy 419.088376 -377.699755) (xy 419.102768 -377.685367) (xy 419.121574 -377.67759)
			(xy 419.13175 -377.677172) (xy 419.84803 -377.677172) (xy 419.858208 -377.67754) (xy 419.87701 -377.685341)
			(xy 419.891395 -377.699744) (xy 419.899173 -377.718556) (xy 419.899592 -377.728734) (xy 419.899592 -377.886722)
			(xy 419.899993 -377.89591) (xy 419.906513 -377.913094) (xy 419.912292 -377.92025) (xy 419.934053 -377.945924)
			(xy 419.972001 -378.001508) (xy 420.003034 -378.061229) (xy 420.026706 -378.12423) (xy 420.04268 -378.189609)
			(xy 420.050726 -378.256429) (xy 420.050728 -378.323732) (xy 420.050721 -378.323793) (xy 423.328791 -378.323793)
			(xy 423.328793 -378.256368) (xy 423.336871 -378.189428) (xy 423.352909 -378.123938) (xy 423.376675 -378.06084)
			(xy 423.407828 -378.001043) (xy 423.445919 -377.945408) (xy 423.467784 -377.919742) (xy 423.473586 -377.9126)
			(xy 423.480098 -377.895407) (xy 423.480484 -377.886214) (xy 423.480484 -377.728734) (xy 423.480956 -377.718604)
			(xy 423.488681 -377.699875) (xy 423.502972 -377.685516) (xy 423.521664 -377.677704) (xy 423.531792 -377.677172)
			(xy 424.248072 -377.677172) (xy 424.258189 -377.677638) (xy 424.276887 -377.685372) (xy 424.291201 -377.699673)
			(xy 424.298953 -377.718363) (xy 424.29938 -377.72848) (xy 424.29938 -377.886214) (xy 424.299788 -377.895401)
			(xy 424.306303 -377.912585) (xy 424.31208 -377.919742) (xy 424.333919 -377.945428) (xy 424.37201 -378.001059)
			(xy 424.403163 -378.060852) (xy 424.426929 -378.123946) (xy 424.442967 -378.189433) (xy 424.451046 -378.256369)
			(xy 424.451048 -378.323734) (xy 427.729086 -378.323734) (xy 427.729089 -378.256427) (xy 427.737136 -378.189602)
			(xy 427.753113 -378.124218) (xy 427.77679 -378.061212) (xy 427.807828 -378.001488) (xy 427.845782 -377.945902)
			(xy 427.867572 -377.92025) (xy 427.873381 -377.913114) (xy 427.879886 -377.895916) (xy 427.880272 -377.886722)
			(xy 427.880272 -377.728734) (xy 427.880693 -377.71856) (xy 427.888473 -377.69976) (xy 427.90286 -377.685373)
			(xy 427.92166 -377.677593) (xy 427.931834 -377.677172) (xy 428.648114 -377.677172) (xy 428.658291 -377.677553)
			(xy 428.677092 -377.685349) (xy 428.691478 -377.699748) (xy 428.699256 -377.718557) (xy 428.699676 -377.728734)
			(xy 428.699676 -377.886722) (xy 428.700081 -377.89591) (xy 428.706599 -377.913094) (xy 428.712376 -377.92025)
			(xy 428.734137 -377.945924) (xy 428.772086 -378.001507) (xy 428.80312 -378.061228) (xy 428.826793 -378.12423)
			(xy 428.842767 -378.189609) (xy 428.850813 -378.256429) (xy 428.850816 -378.323732) (xy 428.850816 -378.323734)
			(xy 432.128877 -378.323734) (xy 432.128879 -378.256427) (xy 432.136926 -378.189602) (xy 432.152902 -378.124218)
			(xy 432.176579 -378.061212) (xy 432.207617 -378.001488) (xy 432.24557 -377.945902) (xy 432.26736 -377.92025)
			(xy 432.273168 -377.913113) (xy 432.279674 -377.895916) (xy 432.28006 -377.886722) (xy 432.28006 -377.728734)
			(xy 432.280492 -377.718562) (xy 432.28827 -377.699764) (xy 432.302654 -377.685377) (xy 432.32145 -377.677595)
			(xy 432.331622 -377.677172) (xy 433.047902 -377.677172) (xy 433.058078 -377.677563) (xy 433.076879 -377.685355)
			(xy 433.091265 -377.699751) (xy 433.099044 -377.718558) (xy 433.099464 -377.728734) (xy 433.099464 -377.886722)
			(xy 433.099872 -377.895909) (xy 433.106388 -377.913093) (xy 433.112164 -377.92025) (xy 433.133926 -377.945923)
			(xy 433.171875 -378.001507) (xy 433.202909 -378.061228) (xy 433.226584 -378.124229) (xy 433.242558 -378.189609)
			(xy 433.250604 -378.256429) (xy 433.250607 -378.323732) (xy 433.242565 -378.390553) (xy 433.226595 -378.455933)
			(xy 433.202925 -378.518937) (xy 433.171895 -378.57866) (xy 433.13395 -378.634246) (xy 433.112164 -378.659898)
			(xy 433.106381 -378.667053) (xy 433.099859 -378.684236) (xy 433.099464 -378.693426) (xy 433.099464 -379.186694)
			(xy 433.099885 -379.19588) (xy 433.106392 -379.213064) (xy 433.112164 -379.220222) (xy 433.133997 -379.245837)
			(xy 433.171944 -379.301429) (xy 433.202975 -379.361158) (xy 433.226645 -379.424167) (xy 433.242615 -379.489554)
			(xy 433.250655 -379.55638) (xy 433.250651 -379.623689) (xy 433.242603 -379.690515) (xy 433.226625 -379.755899)
			(xy 433.202947 -379.818906) (xy 433.171909 -379.878631) (xy 433.133955 -379.934218) (xy 433.112164 -379.95987)
			(xy 433.106351 -379.967003) (xy 433.099847 -379.984203) (xy 433.099464 -379.993398) (xy 433.099464 -380.151386)
			(xy 433.099025 -380.161556) (xy 433.091245 -380.180351) (xy 433.076864 -380.194736) (xy 433.058072 -380.202522)
			(xy 433.047902 -380.202948) (xy 432.331622 -380.202948) (xy 432.32145 -380.202518) (xy 432.302653 -380.194737)
			(xy 432.288267 -380.180353) (xy 432.280484 -380.161558) (xy 432.28006 -380.151386) (xy 432.28006 -379.993398)
			(xy 432.279637 -379.984212) (xy 432.273131 -379.967029) (xy 432.26736 -379.95987) (xy 432.245617 -379.934181)
			(xy 432.207665 -379.8786) (xy 432.176629 -379.818882) (xy 432.152953 -379.755882) (xy 432.136976 -379.690504)
			(xy 432.128928 -379.623685) (xy 432.128924 -379.556384) (xy 432.136964 -379.489564) (xy 432.152932 -379.424184)
			(xy 432.176601 -379.361181) (xy 432.20763 -379.301459) (xy 432.245575 -379.245874) (xy 432.26736 -379.220222)
			(xy 432.27318 -379.213093) (xy 432.279679 -379.19589) (xy 432.28006 -379.186694) (xy 432.28006 -378.693426)
			(xy 432.279624 -378.684242) (xy 432.273127 -378.667058) (xy 432.26736 -378.659898) (xy 432.245546 -378.634267)
			(xy 432.207596 -378.578678) (xy 432.176563 -378.518952) (xy 432.152891 -378.455945) (xy 432.136919 -378.39056)
			(xy 432.128877 -378.323734) (xy 428.850816 -378.323734) (xy 428.842774 -378.390552) (xy 428.826805 -378.455933)
			(xy 428.803136 -378.518936) (xy 428.772106 -378.578659) (xy 428.734161 -378.634245) (xy 428.712376 -378.659898)
			(xy 428.706595 -378.667054) (xy 428.700072 -378.684236) (xy 428.699676 -378.693426) (xy 428.699676 -379.186694)
			(xy 428.700094 -379.19588) (xy 428.706603 -379.213064) (xy 428.712376 -379.220222) (xy 428.734209 -379.245837)
			(xy 428.772155 -379.301429) (xy 428.803185 -379.361158) (xy 428.826855 -379.424167) (xy 428.842824 -379.489554)
			(xy 428.850865 -379.55638) (xy 428.85086 -379.623689) (xy 428.842812 -379.690514) (xy 428.826835 -379.755899)
			(xy 428.803157 -379.818905) (xy 428.772119 -379.87863) (xy 428.734166 -379.934218) (xy 428.712376 -379.95987)
			(xy 428.706564 -379.967004) (xy 428.70006 -379.984203) (xy 428.699676 -379.993398) (xy 428.699676 -380.151386)
			(xy 428.699156 -380.161541) (xy 428.691388 -380.180307) (xy 428.677031 -380.194673) (xy 428.658269 -380.20245)
			(xy 428.648114 -380.202948) (xy 427.931834 -380.202948) (xy 427.921663 -380.202508) (xy 427.902866 -380.194731)
			(xy 427.88848 -380.180351) (xy 427.880696 -380.161557) (xy 427.880272 -380.151386) (xy 427.880272 -379.993398)
			(xy 427.879869 -379.98421) (xy 427.873351 -379.967025) (xy 427.867572 -379.95987) (xy 427.845829 -379.934181)
			(xy 427.807876 -379.878601) (xy 427.776839 -379.818882) (xy 427.753162 -379.755883) (xy 427.737185 -379.690505)
			(xy 427.729137 -379.623686) (xy 427.729133 -379.556384) (xy 427.737173 -379.489564) (xy 427.753142 -379.424183)
			(xy 427.776811 -379.361181) (xy 427.807841 -379.301459) (xy 427.845786 -379.245874) (xy 427.867572 -379.220222)
			(xy 427.873393 -379.213094) (xy 427.879891 -379.19589) (xy 427.880272 -379.186694) (xy 427.880272 -378.693426)
			(xy 427.879856 -378.684239) (xy 427.873347 -378.667055) (xy 427.867572 -378.659898) (xy 427.845758 -378.634267)
			(xy 427.807808 -378.578678) (xy 427.776774 -378.518952) (xy 427.753101 -378.455945) (xy 427.737129 -378.39056)
			(xy 427.729086 -378.323734) (xy 424.451048 -378.323734) (xy 424.451048 -378.323791) (xy 424.442974 -378.390728)
			(xy 424.426941 -378.456216) (xy 424.403179 -378.519312) (xy 424.37203 -378.579107) (xy 424.333943 -378.634741)
			(xy 424.31208 -378.660406) (xy 424.306296 -378.66756) (xy 424.299775 -378.684744) (xy 424.29938 -378.693934)
			(xy 424.29938 -379.186186) (xy 424.299802 -379.195372) (xy 424.306308 -379.212556) (xy 424.31208 -379.219714)
			(xy 424.33399 -379.245342) (xy 424.372079 -379.300981) (xy 424.403228 -379.360782) (xy 424.426991 -379.423884)
			(xy 424.443024 -379.489378) (xy 424.451096 -379.556321) (xy 424.451092 -379.623748) (xy 424.443011 -379.69069)
			(xy 424.42697 -379.756182) (xy 424.4032 -379.819281) (xy 424.372043 -379.879078) (xy 424.333947 -379.934713)
			(xy 424.31208 -379.960378) (xy 424.306266 -379.96751) (xy 424.299762 -379.984711) (xy 424.29938 -379.993906)
			(xy 424.29938 -380.151386) (xy 424.298863 -380.161509) (xy 424.291143 -380.180226) (xy 424.276866 -380.194583)
			(xy 424.258193 -380.202406) (xy 424.248072 -380.202948) (xy 423.531792 -380.202948) (xy 423.521689 -380.202422)
			(xy 423.50302 -380.194691) (xy 423.488727 -380.180407) (xy 423.480984 -380.161743) (xy 423.480484 -380.15164)
			(xy 423.480484 -379.993906) (xy 423.480075 -379.984719) (xy 423.473561 -379.967534) (xy 423.467784 -379.960378)
			(xy 423.445966 -379.934675) (xy 423.407877 -379.879046) (xy 423.376725 -379.819255) (xy 423.352959 -379.756163)
			(xy 423.336921 -379.690678) (xy 423.328841 -379.623744) (xy 423.328837 -379.556325) (xy 423.336908 -379.48939)
			(xy 423.352938 -379.423904) (xy 423.376697 -379.360809) (xy 423.407841 -379.301014) (xy 423.445923 -379.245379)
			(xy 423.467784 -379.219714) (xy 423.473598 -379.212581) (xy 423.480103 -379.195381) (xy 423.480484 -379.186186)
			(xy 423.480484 -378.693934) (xy 423.480061 -378.684748) (xy 423.473557 -378.667563) (xy 423.467784 -378.660406)
			(xy 423.445895 -378.634762) (xy 423.407808 -378.579124) (xy 423.376659 -378.519324) (xy 423.352897 -378.456225)
			(xy 423.336864 -378.390733) (xy 423.328791 -378.323793) (xy 420.050721 -378.323793) (xy 420.042687 -378.390552)
			(xy 420.026718 -378.455932) (xy 420.003049 -378.518936) (xy 419.972021 -378.578659) (xy 419.934077 -378.634245)
			(xy 419.912292 -378.659898) (xy 419.906513 -378.667056) (xy 419.899988 -378.684237) (xy 419.899592 -378.693426)
			(xy 419.899592 -379.186694) (xy 419.900007 -379.195881) (xy 419.906518 -379.213065) (xy 419.912292 -379.220222)
			(xy 419.934124 -379.245837) (xy 419.972069 -379.30143) (xy 420.003099 -379.361159) (xy 420.026768 -379.424168)
			(xy 420.042737 -379.489554) (xy 420.050777 -379.556381) (xy 420.050772 -379.623689) (xy 420.042724 -379.690514)
			(xy 420.026747 -379.755898) (xy 420.003071 -379.818905) (xy 419.972034 -379.87863) (xy 419.934082 -379.934217)
			(xy 419.912292 -379.95987) (xy 419.906482 -379.967006) (xy 419.899976 -379.984204) (xy 419.899592 -379.993398)
			(xy 419.899592 -380.151386) (xy 419.899056 -380.161539) (xy 419.891292 -380.180302) (xy 419.876939 -380.194667)
			(xy 419.858183 -380.202447) (xy 419.84803 -380.202948) (xy 419.13175 -380.202948) (xy 419.12158 -380.202495)
			(xy 419.102784 -380.194724) (xy 419.088396 -380.180347) (xy 419.080612 -380.161556) (xy 419.080188 -380.151386)
			(xy 419.080188 -379.993398) (xy 419.079781 -379.98421) (xy 419.073266 -379.967026) (xy 419.067488 -379.95987)
			(xy 419.045744 -379.934181) (xy 419.007791 -379.878601) (xy 418.976753 -379.818883) (xy 418.953075 -379.755883)
			(xy 418.937097 -379.690505) (xy 418.929049 -379.623686) (xy 418.929045 -379.556383) (xy 418.937085 -379.489563)
			(xy 418.953055 -379.424183) (xy 418.976724 -379.36118) (xy 419.007755 -379.301458) (xy 419.045702 -379.245873)
			(xy 419.067488 -379.220222) (xy 419.073299 -379.213087) (xy 419.079805 -379.195889) (xy 419.080188 -379.186694)
			(xy 419.080188 -378.693426) (xy 419.079768 -378.68424) (xy 419.073262 -378.667055) (xy 419.067488 -378.659898)
			(xy 419.045673 -378.634268) (xy 419.007722 -378.578679) (xy 418.976687 -378.518953) (xy 418.953014 -378.455946)
			(xy 418.937041 -378.39056) (xy 418.928998 -378.323734) (xy 389.250698 -378.323734) (xy 389.242656 -378.390553)
			(xy 389.226686 -378.455934) (xy 389.203015 -378.518937) (xy 389.171985 -378.57866) (xy 389.134038 -378.634246)
			(xy 389.112252 -378.659898) (xy 389.106468 -378.667052) (xy 389.099947 -378.684236) (xy 389.099552 -378.693426)
			(xy 389.099552 -379.186694) (xy 389.099976 -379.19588) (xy 389.106481 -379.213063) (xy 389.112252 -379.220222)
			(xy 389.134085 -379.245837) (xy 389.172033 -379.301428) (xy 389.203065 -379.361157) (xy 389.226736 -379.424166)
			(xy 389.242706 -379.489553) (xy 389.250746 -379.55638) (xy 389.250742 -379.623689) (xy 389.242693 -379.690515)
			(xy 389.226715 -379.7559) (xy 389.203037 -379.818906) (xy 389.171998 -379.878631) (xy 389.134043 -379.934218)
			(xy 389.112252 -379.95987) (xy 389.106437 -379.967002) (xy 389.099935 -379.984203) (xy 389.099552 -379.993398)
			(xy 389.099552 -380.151386) (xy 389.099125 -380.161558) (xy 389.091342 -380.180354) (xy 389.076958 -380.19474)
			(xy 389.058162 -380.202524) (xy 389.04799 -380.202948) (xy 388.33171 -380.202948) (xy 388.321537 -380.202528)
			(xy 388.30274 -380.194743) (xy 388.288354 -380.180357) (xy 388.280571 -380.161559) (xy 388.280148 -380.151386)
			(xy 388.280148 -379.993398) (xy 388.279728 -379.984212) (xy 388.27322 -379.967028) (xy 388.267448 -379.95987)
			(xy 388.245705 -379.934181) (xy 388.207755 -379.8786) (xy 388.176719 -379.818881) (xy 388.153043 -379.755882)
			(xy 388.137067 -379.690504) (xy 388.129019 -379.623685) (xy 388.129015 -379.556384) (xy 388.137054 -379.489564)
			(xy 388.153023 -379.424184) (xy 388.176691 -379.361182) (xy 388.207719 -379.30146) (xy 388.245663 -379.245874)
			(xy 388.267448 -379.220222) (xy 388.273266 -379.213092) (xy 388.279767 -379.19589) (xy 388.280148 -379.186694)
			(xy 388.280148 -378.693426) (xy 388.279715 -378.684241) (xy 388.273216 -378.667057) (xy 388.267448 -378.659898)
			(xy 388.245634 -378.634267) (xy 388.207686 -378.578678) (xy 388.176653 -378.518951) (xy 388.152981 -378.455944)
			(xy 388.13701 -378.390559) (xy 388.128968 -378.323734) (xy 384.850907 -378.323734) (xy 384.842865 -378.390553)
			(xy 384.826895 -378.455933) (xy 384.803225 -378.518937) (xy 384.772195 -378.57866) (xy 384.73425 -378.634246)
			(xy 384.712464 -378.659898) (xy 384.706681 -378.667053) (xy 384.700159 -378.684236) (xy 384.699764 -378.693426)
			(xy 384.699764 -379.186694) (xy 384.700185 -379.19588) (xy 384.706692 -379.213064) (xy 384.712464 -379.220222)
			(xy 384.734297 -379.245837) (xy 384.772244 -379.301429) (xy 384.803275 -379.361158) (xy 384.826945 -379.424167)
			(xy 384.842915 -379.489554) (xy 384.850955 -379.55638) (xy 384.850951 -379.623689) (xy 384.842903 -379.690515)
			(xy 384.826925 -379.755899) (xy 384.803247 -379.818906) (xy 384.772209 -379.878631) (xy 384.734255 -379.934218)
			(xy 384.712464 -379.95987) (xy 384.706651 -379.967003) (xy 384.700147 -379.984203) (xy 384.699764 -379.993398)
			(xy 384.699764 -380.151386) (xy 384.699325 -380.161556) (xy 384.691545 -380.180351) (xy 384.677164 -380.194736)
			(xy 384.658372 -380.202522) (xy 384.648202 -380.202948) (xy 383.931922 -380.202948) (xy 383.92175 -380.202518)
			(xy 383.902953 -380.194737) (xy 383.888567 -380.180353) (xy 383.880784 -380.161558) (xy 383.88036 -380.151386)
			(xy 383.88036 -379.993398) (xy 383.879937 -379.984212) (xy 383.873431 -379.967029) (xy 383.86766 -379.95987)
			(xy 383.845917 -379.934181) (xy 383.807965 -379.8786) (xy 383.776929 -379.818882) (xy 383.753253 -379.755882)
			(xy 383.737276 -379.690504) (xy 383.729228 -379.623685) (xy 383.729224 -379.556384) (xy 383.737264 -379.489564)
			(xy 383.753232 -379.424184) (xy 383.776901 -379.361181) (xy 383.80793 -379.301459) (xy 383.845875 -379.245874)
			(xy 383.86766 -379.220222) (xy 383.87348 -379.213093) (xy 383.879979 -379.19589) (xy 383.88036 -379.186694)
			(xy 383.88036 -378.693426) (xy 383.879924 -378.684242) (xy 383.873427 -378.667058) (xy 383.86766 -378.659898)
			(xy 383.845846 -378.634267) (xy 383.807896 -378.578678) (xy 383.776863 -378.518952) (xy 383.753191 -378.455945)
			(xy 383.737219 -378.39056) (xy 383.729177 -378.323734) (xy 380.451139 -378.323734) (xy 380.451139 -378.323792)
			(xy 380.443065 -378.390729) (xy 380.427031 -378.456217) (xy 380.403269 -378.519313) (xy 380.372119 -378.579108)
			(xy 380.334032 -378.634741) (xy 380.312168 -378.660406) (xy 380.306382 -378.667559) (xy 380.299862 -378.684744)
			(xy 380.299468 -378.693934) (xy 380.299468 -379.186186) (xy 380.299892 -379.195372) (xy 380.306397 -379.212556)
			(xy 380.312168 -379.219714) (xy 380.334078 -379.245341) (xy 380.372168 -379.300981) (xy 380.403318 -379.360782)
			(xy 380.427081 -379.423884) (xy 380.443114 -379.489378) (xy 380.451187 -379.556321) (xy 380.451183 -379.623749)
			(xy 380.443102 -379.69069) (xy 380.427061 -379.756182) (xy 380.40329 -379.819281) (xy 380.372132 -379.879079)
			(xy 380.334036 -379.934713) (xy 380.312168 -379.960378) (xy 380.306352 -379.967509) (xy 380.29985 -379.984711)
			(xy 380.299468 -379.993906) (xy 380.299468 -380.151386) (xy 380.298962 -380.161511) (xy 380.291241 -380.18023)
			(xy 380.27696 -380.194587) (xy 380.258282 -380.202408) (xy 380.24816 -380.202948) (xy 379.53188 -380.202948)
			(xy 379.521731 -380.202496) (xy 379.502987 -380.194703) (xy 379.488666 -380.180316) (xy 379.480958 -380.161537)
			(xy 379.480572 -380.151386) (xy 379.480572 -379.993906) (xy 379.480165 -379.984718) (xy 379.47365 -379.967534)
			(xy 379.467872 -379.960378) (xy 379.446054 -379.934675) (xy 379.407966 -379.879045) (xy 379.376815 -379.819254)
			(xy 379.353049 -379.756162) (xy 379.337011 -379.690678) (xy 379.328932 -379.623744) (xy 379.328928 -379.556325)
			(xy 379.336999 -379.48939) (xy 379.353029 -379.423904) (xy 379.376787 -379.360809) (xy 379.40793 -379.301014)
			(xy 379.446012 -379.24538) (xy 379.467872 -379.219714) (xy 379.473696 -379.212589) (xy 379.480192 -379.195383)
			(xy 379.480572 -379.186186) (xy 379.480572 -378.693934) (xy 379.480152 -378.684748) (xy 379.473646 -378.667563)
			(xy 379.467872 -378.660406) (xy 379.445983 -378.634761) (xy 379.407897 -378.579123) (xy 379.376749 -378.519324)
			(xy 379.352988 -378.456224) (xy 379.336955 -378.390733) (xy 379.328882 -378.323793) (xy 376.050812 -378.323793)
			(xy 376.042778 -378.390552) (xy 376.026808 -378.455933) (xy 376.003139 -378.518936) (xy 375.97211 -378.578659)
			(xy 375.934166 -378.634246) (xy 375.91238 -378.659898) (xy 375.906599 -378.667054) (xy 375.900076 -378.684236)
			(xy 375.89968 -378.693426) (xy 375.89968 -379.186694) (xy 375.900098 -379.19588) (xy 375.906607 -379.213064)
			(xy 375.91238 -379.220222) (xy 375.934212 -379.245837) (xy 375.972159 -379.301429) (xy 376.003189 -379.361158)
			(xy 376.026858 -379.424168) (xy 376.042827 -379.489554) (xy 376.050868 -379.55638) (xy 376.050863 -379.623689)
			(xy 376.042815 -379.690514) (xy 376.026838 -379.755899) (xy 376.003161 -379.818905) (xy 375.972123 -379.87863)
			(xy 375.93417 -379.934218) (xy 375.91238 -379.95987) (xy 375.906569 -379.967005) (xy 375.900064 -379.984203)
			(xy 375.89968 -379.993398) (xy 375.89968 -380.151386) (xy 375.899156 -380.161541) (xy 375.891389 -380.180306)
			(xy 375.877033 -380.194671) (xy 375.858272 -380.202449) (xy 375.848118 -380.202948) (xy 375.131838 -380.202948)
			(xy 375.121667 -380.202505) (xy 375.102871 -380.19473) (xy 375.088484 -380.18035) (xy 375.0807 -380.161557)
			(xy 375.080276 -380.151386) (xy 375.080276 -379.993398) (xy 375.079872 -379.98421) (xy 375.073355 -379.967025)
			(xy 375.067576 -379.95987) (xy 375.045832 -379.934181) (xy 375.00788 -379.878601) (xy 374.976842 -379.818883)
			(xy 374.953165 -379.755883) (xy 374.937188 -379.690505) (xy 374.92914 -379.623686) (xy 374.929136 -379.556384)
			(xy 374.937176 -379.489563) (xy 374.953145 -379.424183) (xy 374.976814 -379.361181) (xy 375.007844 -379.301459)
			(xy 375.04579 -379.245874) (xy 375.067576 -379.220222) (xy 375.073385 -379.213086) (xy 375.079893 -379.195889)
			(xy 375.080276 -379.186694) (xy 375.080276 -378.693426) (xy 375.079859 -378.684239) (xy 375.073351 -378.667055)
			(xy 375.067576 -378.659898) (xy 375.045762 -378.634267) (xy 375.007811 -378.578679) (xy 374.976777 -378.518952)
			(xy 374.953104 -378.455945) (xy 374.937132 -378.39056) (xy 374.929089 -378.323734) (xy 345.250789 -378.323734)
			(xy 345.242747 -378.390553) (xy 345.226776 -378.455934) (xy 345.203105 -378.518938) (xy 345.172074 -378.57866)
			(xy 345.134127 -378.634246) (xy 345.11234 -378.659898) (xy 345.106554 -378.667051) (xy 345.100035 -378.684236)
			(xy 345.09964 -378.693426) (xy 345.09964 -379.186694) (xy 345.100066 -379.195879) (xy 345.10657 -379.213063)
			(xy 345.11234 -379.220222) (xy 345.134174 -379.245837) (xy 345.172123 -379.301428) (xy 345.203155 -379.361156)
			(xy 345.226826 -379.424166) (xy 345.242797 -379.489553) (xy 345.250837 -379.55638) (xy 345.250833 -379.623689)
			(xy 345.242784 -379.690515) (xy 345.226806 -379.7559) (xy 345.203127 -379.818907) (xy 345.172087 -379.878632)
			(xy 345.134131 -379.934218) (xy 345.11234 -379.95987) (xy 345.106524 -379.967001) (xy 345.100023 -379.984203)
			(xy 345.09964 -379.993398) (xy 345.09964 -380.151386) (xy 345.099224 -380.161559) (xy 345.09144 -380.180358)
			(xy 345.077051 -380.194744) (xy 345.058252 -380.202526) (xy 345.048078 -380.202948) (xy 344.331798 -380.202948)
			(xy 344.321625 -380.202537) (xy 344.302827 -380.194749) (xy 344.288442 -380.180359) (xy 344.280659 -380.16156)
			(xy 344.280236 -380.151386) (xy 344.280236 -379.993398) (xy 344.279819 -379.984212) (xy 344.273309 -379.967028)
			(xy 344.267536 -379.95987) (xy 344.245794 -379.93418) (xy 344.207844 -379.878599) (xy 344.176809 -379.818881)
			(xy 344.153133 -379.755881) (xy 344.137157 -379.690504) (xy 344.12911 -379.623685) (xy 344.129106 -379.556384)
			(xy 344.137145 -379.489565) (xy 344.153113 -379.424185) (xy 344.17678 -379.361182) (xy 344.207808 -379.30146)
			(xy 344.245751 -379.245874) (xy 344.267536 -379.220222) (xy 344.273353 -379.213091) (xy 344.279855 -379.19589)
			(xy 344.280236 -379.186694) (xy 344.280236 -378.693426) (xy 344.279805 -378.684241) (xy 344.273305 -378.667057)
			(xy 344.267536 -378.659898) (xy 344.245723 -378.634267) (xy 344.207775 -378.578677) (xy 344.176743 -378.518951)
			(xy 344.153072 -378.455944) (xy 344.137101 -378.390559) (xy 344.129059 -378.323734) (xy 340.850998 -378.323734)
			(xy 340.842956 -378.390553) (xy 340.826986 -378.455934) (xy 340.803315 -378.518937) (xy 340.772285 -378.57866)
			(xy 340.734338 -378.634246) (xy 340.712552 -378.659898) (xy 340.706768 -378.667052) (xy 340.700247 -378.684236)
			(xy 340.699852 -378.693426) (xy 340.699852 -379.186694) (xy 340.700276 -379.19588) (xy 340.706781 -379.213063)
			(xy 340.712552 -379.220222) (xy 340.734385 -379.245837) (xy 340.772333 -379.301428) (xy 340.803365 -379.361157)
			(xy 340.827036 -379.424166) (xy 340.843006 -379.489553) (xy 340.851046 -379.55638) (xy 340.851042 -379.623689)
			(xy 340.842993 -379.690515) (xy 340.827015 -379.7559) (xy 340.803337 -379.818906) (xy 340.772298 -379.878631)
			(xy 340.734343 -379.934218) (xy 340.712552 -379.95987) (xy 340.706737 -379.967002) (xy 340.700235 -379.984203)
			(xy 340.699852 -379.993398) (xy 340.699852 -380.151386) (xy 340.699425 -380.161558) (xy 340.691642 -380.180354)
			(xy 340.677258 -380.19474) (xy 340.658462 -380.202524) (xy 340.64829 -380.202948) (xy 339.93201 -380.202948)
			(xy 339.921837 -380.202528) (xy 339.90304 -380.194743) (xy 339.888654 -380.180357) (xy 339.880871 -380.161559)
			(xy 339.880448 -380.151386) (xy 339.880448 -379.993398) (xy 339.880028 -379.984212) (xy 339.87352 -379.967028)
			(xy 339.867748 -379.95987) (xy 339.846005 -379.934181) (xy 339.808055 -379.8786) (xy 339.777019 -379.818881)
			(xy 339.753343 -379.755882) (xy 339.737367 -379.690504) (xy 339.729319 -379.623685) (xy 339.729315 -379.556384)
			(xy 339.737354 -379.489564) (xy 339.753323 -379.424184) (xy 339.776991 -379.361182) (xy 339.808019 -379.30146)
			(xy 339.845963 -379.245874) (xy 339.867748 -379.220222) (xy 339.873566 -379.213092) (xy 339.880067 -379.19589)
			(xy 339.880448 -379.186694) (xy 339.880448 -378.693426) (xy 339.880015 -378.684241) (xy 339.873516 -378.667057)
			(xy 339.867748 -378.659898) (xy 339.845934 -378.634267) (xy 339.807986 -378.578678) (xy 339.776953 -378.518951)
			(xy 339.753281 -378.455944) (xy 339.73731 -378.390559) (xy 339.729268 -378.323734) (xy 336.45123 -378.323734)
			(xy 336.45123 -378.323792) (xy 336.443156 -378.390729) (xy 336.427122 -378.456217) (xy 336.403359 -378.519313)
			(xy 336.372208 -378.579108) (xy 336.33412 -378.634742) (xy 336.312256 -378.660406) (xy 336.306469 -378.667558)
			(xy 336.29995 -378.684743) (xy 336.299556 -378.693934) (xy 336.299556 -379.186186) (xy 336.299983 -379.195371)
			(xy 336.306486 -379.212555) (xy 336.312256 -379.219714) (xy 336.334167 -379.245341) (xy 336.372257 -379.30098)
			(xy 336.403408 -379.360781) (xy 336.427172 -379.423883) (xy 336.443205 -379.489377) (xy 336.451278 -379.55632)
			(xy 336.451274 -379.623749) (xy 336.443193 -379.690691) (xy 336.427151 -379.756183) (xy 336.40338 -379.819282)
			(xy 336.372221 -379.879079) (xy 336.334124 -379.934713) (xy 336.312256 -379.960378) (xy 336.306438 -379.967508)
			(xy 336.299937 -379.98471) (xy 336.299556 -379.993906) (xy 336.299556 -380.151386) (xy 336.299062 -380.161512)
			(xy 336.291338 -380.180234) (xy 336.277054 -380.194591) (xy 336.258372 -380.20241) (xy 336.248248 -380.202948)
			(xy 335.531968 -380.202948) (xy 335.521818 -380.202506) (xy 335.503074 -380.194708) (xy 335.488753 -380.180319)
			(xy 335.481046 -380.161538) (xy 335.48066 -380.151386) (xy 335.48066 -379.993906) (xy 335.480234 -379.984721)
			(xy 335.47373 -379.967537) (xy 335.46796 -379.960378) (xy 335.446143 -379.934675) (xy 335.408055 -379.879045)
			(xy 335.376905 -379.819253) (xy 335.35314 -379.756162) (xy 335.337102 -379.690678) (xy 335.329023 -379.623744)
			(xy 335.329019 -379.556325) (xy 335.33709 -379.48939) (xy 335.353119 -379.423904) (xy 335.376876 -379.36081)
			(xy 335.40802 -379.301015) (xy 335.4461 -379.24538) (xy 335.46796 -379.219714) (xy 335.473783 -379.212588)
			(xy 335.48028 -379.195382) (xy 335.48066 -379.186186) (xy 335.48066 -378.693934) (xy 335.48022 -378.68475)
			(xy 335.473726 -378.667566) (xy 335.46796 -378.660406) (xy 335.446072 -378.634761) (xy 335.407987 -378.579123)
			(xy 335.376839 -378.519323) (xy 335.353078 -378.456224) (xy 335.337046 -378.390733) (xy 335.328973 -378.323793)
			(xy 332.050903 -378.323793) (xy 332.042868 -378.390553) (xy 332.026898 -378.455933) (xy 332.003229 -378.518937)
			(xy 331.972199 -378.578659) (xy 331.934254 -378.634246) (xy 331.912468 -378.659898) (xy 331.906686 -378.667053)
			(xy 331.900163 -378.684236) (xy 331.899768 -378.693426) (xy 331.899768 -379.186694) (xy 331.900188 -379.19588)
			(xy 331.906696 -379.213064) (xy 331.912468 -379.220222) (xy 331.934301 -379.245837) (xy 331.972248 -379.301429)
			(xy 332.003279 -379.361158) (xy 332.026949 -379.424167) (xy 332.042918 -379.489554) (xy 332.050958 -379.55638)
			(xy 332.050954 -379.623689) (xy 332.042906 -379.690514) (xy 332.026928 -379.755899) (xy 332.00325 -379.818906)
			(xy 331.972212 -379.878631) (xy 331.934258 -379.934218) (xy 331.912468 -379.95987) (xy 331.906655 -379.967003)
			(xy 331.900151 -379.984203) (xy 331.899768 -379.993398) (xy 331.899768 -380.151386) (xy 331.899325 -380.161556)
			(xy 331.891546 -380.180349) (xy 331.877166 -380.194734) (xy 331.858376 -380.202521) (xy 331.848206 -380.202948)
			(xy 331.131926 -380.202948) (xy 331.121754 -380.202514) (xy 331.102958 -380.194735) (xy 331.088571 -380.180352)
			(xy 331.080788 -380.161558) (xy 331.080364 -380.151386) (xy 331.080364 -379.993398) (xy 331.07994 -379.984213)
			(xy 331.073434 -379.967029) (xy 331.067664 -379.95987) (xy 331.045921 -379.934181) (xy 331.007969 -379.8786)
			(xy 330.976932 -379.818882) (xy 330.953256 -379.755882) (xy 330.937279 -379.690504) (xy 330.929231 -379.623686)
			(xy 330.929227 -379.556384) (xy 330.937267 -379.489564) (xy 330.953235 -379.424184) (xy 330.976904 -379.361181)
			(xy 331.007933 -379.301459) (xy 331.045878 -379.245874) (xy 331.067664 -379.220222) (xy 331.073484 -379.213094)
			(xy 331.079983 -379.19589) (xy 331.080364 -379.186694) (xy 331.080364 -378.693426) (xy 331.079927 -378.684242)
			(xy 331.07343 -378.667058) (xy 331.067664 -378.659898) (xy 331.04585 -378.634267) (xy 331.0079 -378.578678)
			(xy 330.976866 -378.518952) (xy 330.953194 -378.455945) (xy 330.937222 -378.39056) (xy 330.92918 -378.323734)
			(xy 301.250878 -378.323734) (xy 301.250878 -378.323791) (xy 301.242805 -378.390727) (xy 301.226773 -378.456215)
			(xy 301.203013 -378.51931) (xy 301.171866 -378.579106) (xy 301.133782 -378.63474) (xy 301.11192 -378.660406)
			(xy 301.106141 -378.667564) (xy 301.099615 -378.684745) (xy 301.09922 -378.693934) (xy 301.09922 -379.186186)
			(xy 301.099632 -379.195373) (xy 301.106144 -379.212558) (xy 301.11192 -379.219714) (xy 301.133828 -379.245342)
			(xy 301.171914 -379.300983) (xy 301.203062 -379.360784) (xy 301.226823 -379.423886) (xy 301.242854 -379.489379)
			(xy 301.250926 -379.556321) (xy 301.250922 -379.623748) (xy 301.242842 -379.690689) (xy 301.226802 -379.75618)
			(xy 301.203034 -379.819279) (xy 301.171879 -379.879077) (xy 301.133786 -379.934712) (xy 301.11192 -379.960378)
			(xy 301.10611 -379.967514) (xy 301.099603 -379.984711) (xy 301.09922 -379.993906) (xy 301.09922 -380.151386)
			(xy 301.098761 -380.161517) (xy 301.09103 -380.180245) (xy 301.076735 -380.194603) (xy 301.058041 -380.202416)
			(xy 301.047912 -380.202948) (xy 300.331632 -380.202948) (xy 300.321486 -380.202453) (xy 300.302743 -380.194677)
			(xy 300.28842 -380.180304) (xy 300.280711 -380.161534) (xy 300.280324 -380.151386) (xy 300.280324 -379.993906)
			(xy 300.279906 -379.98472) (xy 300.273397 -379.967536) (xy 300.267624 -379.960378) (xy 300.245804 -379.934676)
			(xy 300.207713 -379.879047) (xy 300.176559 -379.819256) (xy 300.152791 -379.756164) (xy 300.136751 -379.690679)
			(xy 300.128672 -379.623745) (xy 300.128667 -379.556324) (xy 300.136739 -379.489389) (xy 300.15277 -379.423902)
			(xy 300.17653 -379.360807) (xy 300.207677 -379.301012) (xy 300.245762 -379.245379) (xy 300.267624 -379.219714)
			(xy 300.273442 -379.212584) (xy 300.279943 -379.195382) (xy 300.280324 -379.186186) (xy 300.280324 -378.693934)
			(xy 300.279892 -378.684749) (xy 300.273393 -378.667565) (xy 300.267624 -378.660406) (xy 300.245734 -378.634762)
			(xy 300.207644 -378.579125) (xy 300.176493 -378.519326) (xy 300.152729 -378.456227) (xy 300.136695 -378.390735)
			(xy 300.128621 -378.323794) (xy 296.851087 -378.323794) (xy 296.843014 -378.390727) (xy 296.826983 -378.456214)
			(xy 296.803223 -378.51931) (xy 296.772077 -378.579105) (xy 296.733993 -378.63474) (xy 296.712132 -378.660406)
			(xy 296.706342 -378.667556) (xy 296.699825 -378.684743) (xy 296.699432 -378.693934) (xy 296.699432 -379.186186)
			(xy 296.699864 -379.195371) (xy 296.706364 -379.212554) (xy 296.712132 -379.219714) (xy 296.73404 -379.245342)
			(xy 296.772125 -379.300983) (xy 296.803272 -379.360785) (xy 296.827032 -379.423886) (xy 296.843064 -379.489379)
			(xy 296.851135 -379.556321) (xy 296.851131 -379.623748) (xy 296.843051 -379.690689) (xy 296.827012 -379.75618)
			(xy 296.803244 -379.819279) (xy 296.77209 -379.879076) (xy 296.733998 -379.934712) (xy 296.712132 -379.960378)
			(xy 296.706312 -379.967506) (xy 296.699813 -379.98471) (xy 296.699432 -379.993906) (xy 296.699432 -380.151386)
			(xy 296.698961 -380.161515) (xy 296.691233 -380.180241) (xy 296.676941 -380.194599) (xy 296.658251 -380.202414)
			(xy 296.648124 -380.202948) (xy 295.931844 -380.202948) (xy 295.921699 -380.202443) (xy 295.902957 -380.194671)
			(xy 295.888633 -380.1803) (xy 295.880924 -380.161533) (xy 295.880536 -380.151386) (xy 295.880536 -379.993906)
			(xy 295.880115 -379.98472) (xy 295.873608 -379.967536) (xy 295.867836 -379.960378) (xy 295.846016 -379.934676)
			(xy 295.807924 -379.879048) (xy 295.776769 -379.819257) (xy 295.753 -379.756165) (xy 295.736961 -379.69068)
			(xy 295.728881 -379.623745) (xy 295.728876 -379.556324) (xy 295.736948 -379.489388) (xy 295.75298 -379.423901)
			(xy 295.776741 -379.360806) (xy 295.807888 -379.301012) (xy 295.845974 -379.245379) (xy 295.867836 -379.219714)
			(xy 295.873656 -379.212586) (xy 295.880156 -379.195382) (xy 295.880536 -379.186186) (xy 295.880536 -378.693934)
			(xy 295.880101 -378.68475) (xy 295.873604 -378.667565) (xy 295.867836 -378.660406) (xy 295.845945 -378.634762)
			(xy 295.807855 -378.579126) (xy 295.776703 -378.519327) (xy 295.752939 -378.456227) (xy 295.736904 -378.390735)
			(xy 295.72883 -378.323794) (xy 292.450785 -378.323794) (xy 292.44275 -378.390553) (xy 292.426779 -378.455934)
			(xy 292.403109 -378.518938) (xy 292.372077 -378.57866) (xy 292.334131 -378.634246) (xy 292.312344 -378.659898)
			(xy 292.306559 -378.667051) (xy 292.300039 -378.684236) (xy 292.299644 -378.693426) (xy 292.299644 -379.186694)
			(xy 292.30007 -379.195879) (xy 292.306574 -379.213063) (xy 292.312344 -379.220222) (xy 292.334178 -379.245837)
			(xy 292.372126 -379.301428) (xy 292.403158 -379.361157) (xy 292.426829 -379.424166) (xy 292.4428 -379.489553)
			(xy 292.45084 -379.55638) (xy 292.450836 -379.623689) (xy 292.442787 -379.690515) (xy 292.426809 -379.7559)
			(xy 292.40313 -379.818907) (xy 292.372091 -379.878631) (xy 292.334135 -379.934218) (xy 292.312344 -379.95987)
			(xy 292.306528 -379.967001) (xy 292.300027 -379.984203) (xy 292.299644 -379.993398) (xy 292.299644 -380.151386)
			(xy 292.299224 -380.161559) (xy 292.291441 -380.180357) (xy 292.277054 -380.194743) (xy 292.258255 -380.202525)
			(xy 292.248082 -380.202948) (xy 291.531802 -380.202948) (xy 291.521629 -380.202534) (xy 291.502831 -380.194747)
			(xy 291.488446 -380.180358) (xy 291.480663 -380.161559) (xy 291.48024 -380.151386) (xy 291.48024 -379.993398)
			(xy 291.479822 -379.984212) (xy 291.473313 -379.967028) (xy 291.46754 -379.95987) (xy 291.445798 -379.934181)
			(xy 291.407847 -379.878599) (xy 291.376812 -379.818881) (xy 291.353137 -379.755881) (xy 291.337161 -379.690504)
			(xy 291.329113 -379.623685) (xy 291.329109 -379.556384) (xy 291.337148 -379.489564) (xy 291.353116 -379.424185)
			(xy 291.376784 -379.361182) (xy 291.407812 -379.30146) (xy 291.445755 -379.245874) (xy 291.46754 -379.220222)
			(xy 291.473357 -379.213092) (xy 291.479859 -379.19589) (xy 291.48024 -379.186694) (xy 291.48024 -378.693426)
			(xy 291.479809 -378.684241) (xy 291.473309 -378.667057) (xy 291.46754 -378.659898) (xy 291.445727 -378.634267)
			(xy 291.407778 -378.578678) (xy 291.376746 -378.518951) (xy 291.353075 -378.455944) (xy 291.337104 -378.390559)
			(xy 291.329062 -378.323734) (xy 288.051024 -378.323734) (xy 288.051024 -378.323792) (xy 288.04295 -378.390729)
			(xy 288.026915 -378.456218) (xy 288.003152 -378.519314) (xy 287.972001 -378.579109) (xy 287.933912 -378.634742)
			(xy 287.912048 -378.660406) (xy 287.90626 -378.667557) (xy 287.899742 -378.684743) (xy 287.899348 -378.693934)
			(xy 287.899348 -379.186186) (xy 287.899776 -379.195371) (xy 287.906279 -379.212555) (xy 287.912048 -379.219714)
			(xy 287.933959 -379.245341) (xy 287.97205 -379.30098) (xy 288.003201 -379.360781) (xy 288.026965 -379.423883)
			(xy 288.042999 -379.489377) (xy 288.051072 -379.55632) (xy 288.051068 -379.623749) (xy 288.042987 -379.690691)
			(xy 288.026945 -379.756183) (xy 288.003173 -379.819282) (xy 287.972014 -379.879079) (xy 287.933917 -379.934714)
			(xy 287.912048 -379.960378) (xy 287.906229 -379.967507) (xy 287.899729 -379.98471) (xy 287.899348 -379.993906)
			(xy 287.899348 -380.151386) (xy 287.898862 -380.161513) (xy 287.891136 -380.180236) (xy 287.87685 -380.194594)
			(xy 287.858165 -380.202411) (xy 287.84804 -380.202948) (xy 287.13176 -380.202948) (xy 287.121655 -380.202449)
			(xy 287.102985 -380.194707) (xy 287.088693 -380.180415) (xy 287.080951 -380.161745) (xy 287.080452 -380.15164)
			(xy 287.080452 -379.993906) (xy 287.080027 -379.984721) (xy 287.073523 -379.967537) (xy 287.067752 -379.960378)
			(xy 287.045931 -379.934676) (xy 287.007838 -379.879048) (xy 286.976682 -379.819258) (xy 286.952913 -379.756165)
			(xy 286.936873 -379.69068) (xy 286.928793 -379.623745) (xy 286.928788 -379.556324) (xy 286.936861 -379.489388)
			(xy 286.952893 -379.423901) (xy 286.976654 -379.360806) (xy 287.007802 -379.301011) (xy 287.045889 -379.245378)
			(xy 287.067752 -379.219714) (xy 287.073574 -379.212587) (xy 287.080072 -379.195382) (xy 287.080452 -379.186186)
			(xy 287.080452 -378.693934) (xy 287.080014 -378.68475) (xy 287.073519 -378.667566) (xy 287.067752 -378.660406)
			(xy 287.045861 -378.634763) (xy 287.007769 -378.579126) (xy 286.976617 -378.519328) (xy 286.952852 -378.456228)
			(xy 286.936817 -378.390735) (xy 286.928742 -378.323794) (xy 274.077801 -378.323794) (xy 274.085782 -378.367343)
			(xy 274.101882 -378.499931) (xy 274.109946 -378.633249) (xy 274.11045 -378.70003) (xy 274.109946 -378.766811)
			(xy 274.101882 -378.900129) (xy 274.085782 -379.032717) (xy 274.061707 -379.164091) (xy 274.029744 -379.293772)
			(xy 273.990009 -379.421286) (xy 273.942647 -379.546169) (xy 273.887832 -379.667964) (xy 273.825762 -379.786227)
			(xy 273.756666 -379.900526) (xy 273.680794 -380.010446) (xy 273.598424 -380.115583) (xy 273.509856 -380.215556)
			(xy 273.415414 -380.309998) (xy 273.315441 -380.398566) (xy 273.210304 -380.480936) (xy 273.100384 -380.556808)
			(xy 272.986085 -380.625904) (xy 272.92786 -380.656463) (xy 289.128932 -380.656463) (xy 289.136975 -380.589641)
			(xy 289.152947 -380.524259) (xy 289.17662 -380.461255) (xy 289.207654 -380.401532) (xy 289.245604 -380.345947)
			(xy 289.267392 -380.320296) (xy 289.273172 -380.313139) (xy 289.279697 -380.295958) (xy 289.280092 -380.286768)
			(xy 289.280092 -379.7935) (xy 289.279684 -379.784313) (xy 289.273169 -379.767128) (xy 289.267392 -379.759972)
			(xy 289.24565 -379.734282) (xy 289.207696 -379.678702) (xy 289.176658 -379.618984) (xy 289.15298 -379.555985)
			(xy 289.137002 -379.490606) (xy 289.128953 -379.423787) (xy 289.128949 -379.356485) (xy 289.136989 -379.289665)
			(xy 289.152959 -379.224284) (xy 289.176628 -379.161282) (xy 289.207659 -379.10156) (xy 289.245606 -379.045975)
			(xy 289.267392 -379.020324) (xy 289.273202 -379.013189) (xy 289.279709 -378.995991) (xy 289.280092 -378.986796)
			(xy 289.280092 -378.828554) (xy 289.280595 -378.818399) (xy 289.288376 -378.799638) (xy 289.302738 -378.785276)
			(xy 289.321499 -378.777495) (xy 289.331654 -378.776992) (xy 290.047934 -378.776992) (xy 290.058088 -378.777504)
			(xy 290.076849 -378.785281) (xy 290.091212 -378.799641) (xy 290.098993 -378.8184) (xy 290.099496 -378.828554)
			(xy 290.099496 -378.986796) (xy 290.099909 -378.995983) (xy 290.106421 -379.013167) (xy 290.112196 -379.020324)
			(xy 290.13403 -379.045938) (xy 290.171975 -379.101531) (xy 290.203004 -379.16126) (xy 290.226673 -379.224269)
			(xy 290.242641 -379.289656) (xy 290.250681 -379.356482) (xy 290.250677 -379.42379) (xy 290.242628 -379.490615)
			(xy 290.226651 -379.556) (xy 290.202975 -379.619006) (xy 290.171938 -379.678731) (xy 290.133986 -379.734319)
			(xy 290.112196 -379.759972) (xy 290.106386 -379.767108) (xy 290.099879 -379.784305) (xy 290.099496 -379.7935)
			(xy 290.099496 -380.286768) (xy 290.099922 -380.295953) (xy 290.106425 -380.313138) (xy 290.112196 -380.320296)
			(xy 290.134002 -380.345932) (xy 290.171948 -380.401522) (xy 290.202979 -380.461248) (xy 290.226649 -380.524255)
			(xy 290.242619 -380.589638) (xy 290.250654 -380.656404) (xy 293.528724 -380.656404) (xy 293.536798 -380.589467)
			(xy 293.552831 -380.52398) (xy 293.576592 -380.460884) (xy 293.60774 -380.401088) (xy 293.645826 -380.345453)
			(xy 293.667688 -380.319788) (xy 293.673471 -380.312633) (xy 293.679994 -380.29545) (xy 293.680388 -380.28626)
			(xy 293.680388 -379.794008) (xy 293.679977 -379.784821) (xy 293.673464 -379.767636) (xy 293.667688 -379.76048)
			(xy 293.645872 -379.734776) (xy 293.607782 -379.679146) (xy 293.57663 -379.619356) (xy 293.552864 -379.556264)
			(xy 293.536825 -379.49078) (xy 293.528746 -379.423846) (xy 293.528741 -379.356426) (xy 293.536812 -379.289491)
			(xy 293.552842 -379.224005) (xy 293.576601 -379.16091) (xy 293.607745 -379.101115) (xy 293.645827 -379.045481)
			(xy 293.667688 -379.019816) (xy 293.673501 -379.012683) (xy 293.680006 -378.995483) (xy 293.680388 -378.986288)
			(xy 293.680388 -378.828554) (xy 293.680887 -378.818431) (xy 293.688621 -378.799718) (xy 293.702902 -378.785366)
			(xy 293.721575 -378.777539) (xy 293.731696 -378.776992) (xy 294.447976 -378.776992) (xy 294.458096 -378.777435)
			(xy 294.476798 -378.785174) (xy 294.491112 -378.799482) (xy 294.49886 -378.81818) (xy 294.499284 -378.8283)
			(xy 294.499284 -378.986288) (xy 294.499704 -378.995474) (xy 294.506211 -379.012658) (xy 294.511984 -379.019816)
			(xy 294.533896 -379.045442) (xy 294.571984 -379.101082) (xy 294.603134 -379.160883) (xy 294.626896 -379.223985)
			(xy 294.642928 -379.289479) (xy 294.651001 -379.356422) (xy 294.650996 -379.42385) (xy 294.642915 -379.490792)
			(xy 294.626874 -379.556284) (xy 294.603104 -379.619383) (xy 294.571947 -379.67918) (xy 294.533851 -379.734815)
			(xy 294.511984 -379.76048) (xy 294.506169 -379.767612) (xy 294.499666 -379.784813) (xy 294.499284 -379.794008)
			(xy 294.499284 -380.28626) (xy 294.499717 -380.295445) (xy 294.506215 -380.312629) (xy 294.511984 -380.319788)
			(xy 294.533868 -380.345437) (xy 294.571957 -380.401073) (xy 294.603108 -380.460872) (xy 294.626872 -380.523971)
			(xy 294.642906 -380.589462) (xy 294.650981 -380.656402) (xy 294.650981 -380.656463) (xy 297.92902 -380.656463)
			(xy 297.937062 -380.589641) (xy 297.953034 -380.52426) (xy 297.976707 -380.461256) (xy 298.00774 -380.401533)
			(xy 298.045688 -380.345948) (xy 298.067476 -380.320296) (xy 298.073254 -380.313137) (xy 298.079781 -380.295957)
			(xy 298.080176 -380.286768) (xy 298.080176 -379.7935) (xy 298.079771 -379.784312) (xy 298.073254 -379.767128)
			(xy 298.067476 -379.759972) (xy 298.045734 -379.734282) (xy 298.007782 -379.678701) (xy 297.976744 -379.618984)
			(xy 297.953067 -379.555984) (xy 297.93709 -379.490606) (xy 297.929041 -379.423787) (xy 297.929037 -379.356485)
			(xy 297.937077 -379.289665) (xy 297.953046 -379.224285) (xy 297.976715 -379.161283) (xy 298.007745 -379.101561)
			(xy 298.04569 -379.045976) (xy 298.067476 -379.020324) (xy 298.073285 -379.013187) (xy 298.079793 -378.99599)
			(xy 298.080176 -378.986796) (xy 298.080176 -378.828554) (xy 298.080597 -378.818389) (xy 298.088393 -378.799611)
			(xy 298.102782 -378.785246) (xy 298.121572 -378.77748) (xy 298.131738 -378.776992) (xy 298.848018 -378.776992)
			(xy 298.858171 -378.777517) (xy 298.876932 -378.785289) (xy 298.891295 -378.799644) (xy 298.899077 -378.818401)
			(xy 298.89958 -378.828554) (xy 298.89958 -378.986796) (xy 298.899996 -378.995982) (xy 298.906506 -379.013167)
			(xy 298.91228 -379.020324) (xy 298.934114 -379.045938) (xy 298.972061 -379.10153) (xy 299.003091 -379.161259)
			(xy 299.02676 -379.224269) (xy 299.042729 -379.289655) (xy 299.050769 -379.356482) (xy 299.050765 -379.42379)
			(xy 299.042716 -379.490616) (xy 299.026739 -379.556) (xy 299.003061 -379.619007) (xy 298.972023 -379.678732)
			(xy 298.93407 -379.73432) (xy 298.91228 -379.759972) (xy 298.906468 -379.767106) (xy 298.899963 -379.784305)
			(xy 298.89958 -379.7935) (xy 298.89958 -380.286768) (xy 298.90001 -380.295953) (xy 298.90651 -380.313137)
			(xy 298.91228 -380.320296) (xy 298.934087 -380.345932) (xy 298.972034 -380.401521) (xy 299.003065 -380.461247)
			(xy 299.026736 -380.524254) (xy 299.042707 -380.589638) (xy 299.050742 -380.656404) (xy 302.328812 -380.656404)
			(xy 302.336886 -380.589468) (xy 302.352918 -380.52398) (xy 302.376679 -380.460884) (xy 302.407826 -380.401089)
			(xy 302.44591 -380.345454) (xy 302.467772 -380.319788) (xy 302.473565 -380.312641) (xy 302.48008 -380.295451)
			(xy 302.480472 -380.28626) (xy 302.480472 -379.794008) (xy 302.480064 -379.78482) (xy 302.47355 -379.767636)
			(xy 302.467772 -379.76048) (xy 302.445956 -379.734775) (xy 302.407868 -379.679146) (xy 302.376717 -379.619355)
			(xy 302.352951 -379.556263) (xy 302.336913 -379.490779) (xy 302.328834 -379.423846) (xy 302.328829 -379.356426)
			(xy 302.3369 -379.289492) (xy 302.35293 -379.224006) (xy 302.376687 -379.160911) (xy 302.407831 -379.101116)
			(xy 302.445912 -379.045482) (xy 302.467772 -379.019816) (xy 302.473595 -379.01269) (xy 302.480092 -378.995485)
			(xy 302.480472 -378.986288) (xy 302.480472 -378.828554) (xy 302.48089 -378.81842) (xy 302.488639 -378.799692)
			(xy 302.502946 -378.785336) (xy 302.521648 -378.777525) (xy 302.53178 -378.776992) (xy 303.24806 -378.776992)
			(xy 303.258211 -378.777454) (xy 303.27696 -378.785235) (xy 303.291285 -378.79962) (xy 303.298987 -378.818402)
			(xy 303.299368 -378.828554) (xy 303.299368 -378.986288) (xy 303.299791 -378.995474) (xy 303.306296 -379.012658)
			(xy 303.312068 -379.019816) (xy 303.33398 -379.045442) (xy 303.37207 -379.101081) (xy 303.40322 -379.160883)
			(xy 303.426983 -379.223985) (xy 303.443016 -379.289479) (xy 303.451089 -379.356422) (xy 303.451084 -379.42385)
			(xy 303.443003 -379.490792) (xy 303.426962 -379.556284) (xy 303.403191 -379.619383) (xy 303.372032 -379.679181)
			(xy 303.333936 -379.734815) (xy 303.312068 -379.76048) (xy 303.306251 -379.76761) (xy 303.299749 -379.784812)
			(xy 303.299368 -379.794008) (xy 303.299368 -380.28626) (xy 303.299805 -380.295444) (xy 303.306301 -380.312628)
			(xy 303.312068 -380.319788) (xy 303.333953 -380.345436) (xy 303.372043 -380.401073) (xy 303.403195 -380.460871)
			(xy 303.426959 -380.52397) (xy 303.442994 -380.589461) (xy 303.451069 -380.656402) (xy 303.451069 -380.656404)
			(xy 333.128842 -380.656404) (xy 333.136916 -380.589467) (xy 333.15295 -380.523979) (xy 333.176713 -380.460883)
			(xy 333.207862 -380.401087) (xy 333.245949 -380.345453) (xy 333.267812 -380.319788) (xy 333.273598 -380.312635)
			(xy 333.280118 -380.29545) (xy 333.280512 -380.28626) (xy 333.280512 -379.794008) (xy 333.280095 -379.784822)
			(xy 333.273586 -379.767637) (xy 333.267812 -379.76048) (xy 333.245995 -379.734776) (xy 333.207904 -379.679147)
			(xy 333.17675 -379.619357) (xy 333.152983 -379.556265) (xy 333.136944 -379.49078) (xy 333.128864 -379.423846)
			(xy 333.12886 -379.356426) (xy 333.136931 -379.289491) (xy 333.152962 -379.224004) (xy 333.176721 -379.160909)
			(xy 333.207867 -379.101115) (xy 333.24595 -379.045481) (xy 333.267812 -379.019816) (xy 333.273628 -379.012685)
			(xy 333.280131 -378.995483) (xy 333.280512 -378.986288) (xy 333.280512 -378.828554) (xy 333.280988 -378.818428)
			(xy 333.288726 -378.799711) (xy 333.303015 -378.785357) (xy 333.321696 -378.777535) (xy 333.33182 -378.776992)
			(xy 334.0481 -378.776992) (xy 334.058253 -378.777422) (xy 334.077004 -378.785216) (xy 334.091327 -378.79961)
			(xy 334.099028 -378.818399) (xy 334.099408 -378.828554) (xy 334.099408 -378.986288) (xy 334.099822 -378.995475)
			(xy 334.106333 -379.012659) (xy 334.112108 -379.019816) (xy 334.134019 -379.045442) (xy 334.172106 -379.101083)
			(xy 334.203254 -379.160884) (xy 334.227015 -379.223986) (xy 334.243047 -379.28948) (xy 334.251119 -379.356422)
			(xy 334.251114 -379.42385) (xy 334.243034 -379.490791) (xy 334.226994 -379.556283) (xy 334.203224 -379.619382)
			(xy 334.172068 -379.679179) (xy 334.133975 -379.734815) (xy 334.112108 -379.76048) (xy 334.106296 -379.767614)
			(xy 334.09979 -379.784813) (xy 334.099408 -379.794008) (xy 334.099408 -380.28626) (xy 334.099836 -380.295445)
			(xy 334.106337 -380.31263) (xy 334.112108 -380.319788) (xy 334.133991 -380.345437) (xy 334.172079 -380.401074)
			(xy 334.203228 -380.460873) (xy 334.226991 -380.523972) (xy 334.243025 -380.589463) (xy 334.251099 -380.656402)
			(xy 334.251099 -380.656464) (xy 337.529162 -380.656464) (xy 337.537203 -380.589643) (xy 337.553173 -380.524262)
			(xy 337.576842 -380.461259) (xy 337.607871 -380.401536) (xy 337.645815 -380.345949) (xy 337.6676 -380.320296)
			(xy 337.673381 -380.31314) (xy 337.679905 -380.295958) (xy 337.6803 -380.286768) (xy 337.6803 -379.7935)
			(xy 337.67989 -379.784313) (xy 337.673376 -379.767129) (xy 337.6676 -379.759972) (xy 337.645861 -379.734281)
			(xy 337.607913 -379.678699) (xy 337.57688 -379.61898) (xy 337.553206 -379.555981) (xy 337.537231 -379.490604)
			(xy 337.529183 -379.423786) (xy 337.529179 -379.356486) (xy 337.537218 -379.289667) (xy 337.553185 -379.224288)
			(xy 337.57685 -379.161286) (xy 337.607876 -379.101563) (xy 337.645816 -379.045977) (xy 337.6676 -379.020324)
			(xy 337.673411 -379.013189) (xy 337.679917 -378.995991) (xy 337.6803 -378.986796) (xy 337.6803 -378.828554)
			(xy 337.680795 -378.818398) (xy 337.688577 -378.799635) (xy 337.702942 -378.785273) (xy 337.721706 -378.777493)
			(xy 337.731862 -378.776992) (xy 338.448142 -378.776992) (xy 338.458297 -378.777498) (xy 338.477058 -378.785278)
			(xy 338.49142 -378.799639) (xy 338.499201 -378.818399) (xy 338.499704 -378.828554) (xy 338.499704 -378.986796)
			(xy 338.500115 -378.995983) (xy 338.506628 -379.013167) (xy 338.512404 -379.020324) (xy 338.534237 -379.045938)
			(xy 338.572182 -379.101531) (xy 338.603211 -379.16126) (xy 338.626879 -379.22427) (xy 338.642847 -379.289656)
			(xy 338.650887 -379.356482) (xy 338.650883 -379.42379) (xy 338.642834 -379.490615) (xy 338.626858 -379.556)
			(xy 338.603181 -379.619006) (xy 338.572145 -379.678731) (xy 338.534193 -379.734319) (xy 338.512404 -379.759972)
			(xy 338.506595 -379.767108) (xy 338.500088 -379.784306) (xy 338.499704 -379.7935) (xy 338.499704 -380.286768)
			(xy 338.500129 -380.295954) (xy 338.506632 -380.313138) (xy 338.512404 -380.320296) (xy 338.53421 -380.345933)
			(xy 338.572155 -380.401522) (xy 338.603185 -380.461248) (xy 338.626855 -380.524255) (xy 338.642826 -380.589639)
			(xy 338.65086 -380.656404) (xy 341.92893 -380.656404) (xy 341.937004 -380.589467) (xy 341.953037 -380.523979)
			(xy 341.976799 -380.460883) (xy 342.007947 -380.401088) (xy 342.046033 -380.345453) (xy 342.067896 -380.319788)
			(xy 342.07368 -380.312634) (xy 342.080202 -380.29545) (xy 342.080596 -380.28626) (xy 342.080596 -379.794008)
			(xy 342.080183 -379.784821) (xy 342.073671 -379.767637) (xy 342.067896 -379.76048) (xy 342.046079 -379.734776)
			(xy 342.007989 -379.679147) (xy 341.976837 -379.619356) (xy 341.95307 -379.556264) (xy 341.937032 -379.49078)
			(xy 341.928952 -379.423846) (xy 341.928948 -379.356426) (xy 341.937019 -379.289491) (xy 341.953049 -379.224005)
			(xy 341.976807 -379.16091) (xy 342.007952 -379.101115) (xy 342.046035 -379.045481) (xy 342.067896 -379.019816)
			(xy 342.07371 -379.012683) (xy 342.080215 -378.995483) (xy 342.080596 -378.986288) (xy 342.080596 -378.828554)
			(xy 342.081088 -378.81843) (xy 342.088822 -378.799716) (xy 342.103106 -378.785363) (xy 342.121782 -378.777538)
			(xy 342.131904 -378.776992) (xy 342.848184 -378.776992) (xy 342.858336 -378.777434) (xy 342.877087 -378.785223)
			(xy 342.89141 -378.799614) (xy 342.899112 -378.8184) (xy 342.899492 -378.828554) (xy 342.899492 -378.986288)
			(xy 342.89991 -378.995474) (xy 342.906418 -379.012659) (xy 342.912192 -379.019816) (xy 342.934103 -379.045442)
			(xy 342.972191 -379.101082) (xy 343.00334 -379.160884) (xy 343.027102 -379.223986) (xy 343.043135 -379.28948)
			(xy 343.051207 -379.356422) (xy 343.051202 -379.42385) (xy 343.043122 -379.490792) (xy 343.027081 -379.556283)
			(xy 343.003311 -379.619382) (xy 342.972154 -379.67918) (xy 342.934059 -379.734815) (xy 342.912192 -379.76048)
			(xy 342.906378 -379.767613) (xy 342.899874 -379.784813) (xy 342.899492 -379.794008) (xy 342.899492 -380.28626)
			(xy 342.899923 -380.295445) (xy 342.906422 -380.312629) (xy 342.912192 -380.319788) (xy 342.934076 -380.345437)
			(xy 342.972165 -380.401074) (xy 343.003315 -380.460872) (xy 343.027078 -380.523971) (xy 343.043113 -380.589462)
			(xy 343.051187 -380.656402) (xy 343.051187 -380.656463) (xy 346.329226 -380.656463) (xy 346.337269 -380.589641)
			(xy 346.353241 -380.524259) (xy 346.376913 -380.461255) (xy 346.407947 -380.401533) (xy 346.445896 -380.345948)
			(xy 346.467684 -380.320296) (xy 346.473463 -380.313138) (xy 346.479989 -380.295957) (xy 346.480384 -380.286768)
			(xy 346.480384 -379.7935) (xy 346.479977 -379.784312) (xy 346.473462 -379.767128) (xy 346.467684 -379.759972)
			(xy 346.445942 -379.734282) (xy 346.407989 -379.678702) (xy 346.376951 -379.618984) (xy 346.353274 -379.555984)
			(xy 346.337296 -379.490606) (xy 346.329247 -379.423787) (xy 346.329243 -379.356485) (xy 346.337283 -379.289665)
			(xy 346.353252 -379.224285) (xy 346.376922 -379.161282) (xy 346.407952 -379.10156) (xy 346.445898 -379.045976)
			(xy 346.467684 -379.020324) (xy 346.473493 -379.013188) (xy 346.480001 -378.99599) (xy 346.480384 -378.986796)
			(xy 346.480384 -378.828554) (xy 346.480797 -378.818388) (xy 346.488595 -378.799609) (xy 346.502986 -378.785243)
			(xy 346.521779 -378.777479) (xy 346.531946 -378.776992) (xy 347.248226 -378.776992) (xy 347.25838 -378.777511)
			(xy 347.277141 -378.785285) (xy 347.291504 -378.799642) (xy 347.299285 -378.8184) (xy 347.299788 -378.828554)
			(xy 347.299788 -378.986796) (xy 347.300203 -378.995983) (xy 347.306714 -379.013167) (xy 347.312488 -379.020324)
			(xy 347.334322 -379.045938) (xy 347.372268 -379.10153) (xy 347.403297 -379.161259) (xy 347.426966 -379.224269)
			(xy 347.442935 -379.289656) (xy 347.450975 -379.356482) (xy 347.450971 -379.42379) (xy 347.442922 -379.490616)
			(xy 347.426945 -379.556) (xy 347.403268 -379.619007) (xy 347.372231 -379.678732) (xy 347.334278 -379.734319)
			(xy 347.312488 -379.759972) (xy 347.306677 -379.767107) (xy 347.300171 -379.784305) (xy 347.299788 -379.7935)
			(xy 347.299788 -380.286768) (xy 347.300216 -380.295953) (xy 347.306718 -380.313138) (xy 347.312488 -380.320296)
			(xy 347.334295 -380.345932) (xy 347.372241 -380.401522) (xy 347.403272 -380.461248) (xy 347.426942 -380.524254)
			(xy 347.442913 -380.589638) (xy 347.450948 -380.656404) (xy 377.128751 -380.656404) (xy 377.136826 -380.589466)
			(xy 377.15286 -380.523978) (xy 377.176623 -380.460882) (xy 377.207772 -380.401087) (xy 377.24586 -380.345453)
			(xy 377.267724 -380.319788) (xy 377.273511 -380.312636) (xy 377.280031 -380.295451) (xy 377.280424 -380.28626)
			(xy 377.280424 -379.794008) (xy 377.280005 -379.784822) (xy 377.273497 -379.767638) (xy 377.267724 -379.76048)
			(xy 377.245906 -379.734776) (xy 377.207815 -379.679148) (xy 377.17666 -379.619357) (xy 377.152893 -379.556265)
			(xy 377.136853 -379.490781) (xy 377.128773 -379.423846) (xy 377.128769 -379.356426) (xy 377.13684 -379.28949)
			(xy 377.152871 -379.224004) (xy 377.176631 -379.160909) (xy 377.207777 -379.101114) (xy 377.245862 -379.045481)
			(xy 377.267724 -379.019816) (xy 377.273542 -379.012686) (xy 377.280043 -378.995484) (xy 377.280424 -378.986288)
			(xy 377.280424 -378.828554) (xy 377.280888 -378.818426) (xy 377.288628 -378.799707) (xy 377.302921 -378.785353)
			(xy 377.321607 -378.777533) (xy 377.331732 -378.776992) (xy 378.048012 -378.776992) (xy 378.058166 -378.777411)
			(xy 378.076917 -378.785209) (xy 378.09124 -378.799607) (xy 378.098941 -378.818398) (xy 378.09932 -378.828554)
			(xy 378.09932 -378.986288) (xy 378.099731 -378.995475) (xy 378.106244 -379.01266) (xy 378.11202 -379.019816)
			(xy 378.13393 -379.045443) (xy 378.172016 -379.101083) (xy 378.203164 -379.160885) (xy 378.226924 -379.223987)
			(xy 378.242956 -379.28948) (xy 378.251028 -379.356423) (xy 378.251023 -379.42385) (xy 378.242943 -379.490791)
			(xy 378.226903 -379.556282) (xy 378.203134 -379.619381) (xy 378.171979 -379.679179) (xy 378.133886 -379.734814)
			(xy 378.11202 -379.76048) (xy 378.106209 -379.767615) (xy 378.099702 -379.784813) (xy 378.09932 -379.794008)
			(xy 378.09932 -380.28626) (xy 378.099745 -380.295446) (xy 378.106248 -380.312631) (xy 378.11202 -380.319788)
			(xy 378.133903 -380.345437) (xy 378.17199 -380.401075) (xy 378.203138 -380.460873) (xy 378.226901 -380.523972)
			(xy 378.242934 -380.589463) (xy 378.251008 -380.656403) (xy 378.251008 -380.656464) (xy 381.529071 -380.656464)
			(xy 381.537113 -380.589643) (xy 381.553083 -380.524262) (xy 381.576752 -380.461258) (xy 381.607782 -380.401535)
			(xy 381.645726 -380.345948) (xy 381.667512 -380.320296) (xy 381.673294 -380.313141) (xy 381.679817 -380.295958)
			(xy 381.680212 -380.286768) (xy 381.680212 -379.7935) (xy 381.679799 -379.784313) (xy 381.673287 -379.767129)
			(xy 381.667512 -379.759972) (xy 381.645773 -379.73428) (xy 381.607824 -379.678699) (xy 381.57679 -379.618981)
			(xy 381.553116 -379.555981) (xy 381.537141 -379.490604) (xy 381.529093 -379.423786) (xy 381.529089 -379.356486)
			(xy 381.537128 -379.289667) (xy 381.553095 -379.224288) (xy 381.576761 -379.161285) (xy 381.607787 -379.101563)
			(xy 381.645728 -379.045977) (xy 381.667512 -379.020324) (xy 381.673325 -379.01319) (xy 381.679829 -378.995991)
			(xy 381.680212 -378.986796) (xy 381.680212 -378.828554) (xy 381.680695 -378.818397) (xy 381.68848 -378.799631)
			(xy 381.702848 -378.785269) (xy 381.721616 -378.777491) (xy 381.731774 -378.776992) (xy 382.448054 -378.776992)
			(xy 382.458203 -378.77757) (xy 382.476962 -378.785321) (xy 382.491328 -378.79966) (xy 382.499112 -378.818406)
			(xy 382.499616 -378.828554) (xy 382.499616 -378.986796) (xy 382.500025 -378.995983) (xy 382.506539 -379.013168)
			(xy 382.512316 -379.020324) (xy 382.534153 -379.045936) (xy 382.572103 -379.101528) (xy 382.603137 -379.161256)
			(xy 382.626809 -379.224266) (xy 382.64278 -379.289654) (xy 382.650821 -379.356481) (xy 382.650816 -379.423791)
			(xy 382.642767 -379.490618) (xy 382.626787 -379.556003) (xy 382.603107 -379.61901) (xy 382.572066 -379.678734)
			(xy 382.534108 -379.734321) (xy 382.512316 -379.759972) (xy 382.506508 -379.767109) (xy 382.5 -379.784306)
			(xy 382.499616 -379.7935) (xy 382.499616 -380.286768) (xy 382.500038 -380.295954) (xy 382.506543 -380.313139)
			(xy 382.512316 -380.320296) (xy 382.534125 -380.345931) (xy 382.572076 -380.401519) (xy 382.603111 -380.461245)
			(xy 382.626784 -380.524251) (xy 382.642757 -380.589636) (xy 382.650793 -380.656404) (xy 385.928839 -380.656404)
			(xy 385.936913 -380.589467) (xy 385.952947 -380.523979) (xy 385.976709 -380.460883) (xy 386.007858 -380.401087)
			(xy 386.045945 -380.345453) (xy 386.067808 -380.319788) (xy 386.073593 -380.312635) (xy 386.080114 -380.29545)
			(xy 386.080508 -380.28626) (xy 386.080508 -379.794008) (xy 386.080092 -379.784821) (xy 386.073582 -379.767637)
			(xy 386.067808 -379.76048) (xy 386.045991 -379.734776) (xy 386.0079 -379.679147) (xy 385.976747 -379.619356)
			(xy 385.95298 -379.556265) (xy 385.936941 -379.49078) (xy 385.928861 -379.423846) (xy 385.928857 -379.356426)
			(xy 385.936928 -379.289491) (xy 385.952958 -379.224004) (xy 385.976718 -379.160909) (xy 386.007863 -379.101115)
			(xy 386.045947 -379.045481) (xy 386.067808 -379.019816) (xy 386.073624 -379.012684) (xy 386.080127 -378.995483)
			(xy 386.080508 -378.986288) (xy 386.080508 -378.828554) (xy 386.080988 -378.818428) (xy 386.088725 -378.799712)
			(xy 386.103012 -378.785359) (xy 386.121693 -378.777535) (xy 386.131816 -378.776992) (xy 386.848096 -378.776992)
			(xy 386.858249 -378.777425) (xy 386.877 -378.785218) (xy 386.891323 -378.799611) (xy 386.899024 -378.818399)
			(xy 386.899404 -378.828554) (xy 386.899404 -378.986288) (xy 386.899819 -378.995475) (xy 386.906329 -379.012659)
			(xy 386.912104 -379.019816) (xy 386.934015 -379.045442) (xy 386.972102 -379.101083) (xy 387.00325 -379.160884)
			(xy 387.027012 -379.223986) (xy 387.043044 -379.28948) (xy 387.051116 -379.356422) (xy 387.051111 -379.42385)
			(xy 387.043031 -379.490791) (xy 387.02699 -379.556283) (xy 387.003221 -379.619382) (xy 386.972065 -379.679179)
			(xy 386.933971 -379.734815) (xy 386.912104 -379.76048) (xy 386.906291 -379.767614) (xy 386.899786 -379.784813)
			(xy 386.899404 -379.794008) (xy 386.899404 -380.28626) (xy 386.899832 -380.295445) (xy 386.906333 -380.31263)
			(xy 386.912104 -380.319788) (xy 386.933987 -380.345437) (xy 386.972075 -380.401074) (xy 387.003225 -380.460872)
			(xy 387.026988 -380.523971) (xy 387.043022 -380.589462) (xy 387.051096 -380.656402) (xy 387.051096 -380.656464)
			(xy 390.329159 -380.656464) (xy 390.3372 -380.589643) (xy 390.35317 -380.524263) (xy 390.376839 -380.461259)
			(xy 390.407867 -380.401536) (xy 390.445811 -380.345949) (xy 390.467596 -380.320296) (xy 390.473376 -380.313139)
			(xy 390.479901 -380.295958) (xy 390.480296 -380.286768) (xy 390.480296 -379.7935) (xy 390.479887 -379.784313)
			(xy 390.473372 -379.767128) (xy 390.467596 -379.759972) (xy 390.445857 -379.73428) (xy 390.407909 -379.678699)
			(xy 390.376876 -379.61898) (xy 390.353203 -379.555981) (xy 390.337228 -379.490604) (xy 390.32918 -379.423786)
			(xy 390.329176 -379.356486) (xy 390.337215 -379.289667) (xy 390.353181 -379.224288) (xy 390.376847 -379.161286)
			(xy 390.407872 -379.101563) (xy 390.445812 -379.045977) (xy 390.467596 -379.020324) (xy 390.473407 -379.013189)
			(xy 390.479913 -378.995991) (xy 390.480296 -378.986796) (xy 390.480296 -378.828554) (xy 390.480795 -378.818398)
			(xy 390.488576 -378.799636) (xy 390.50294 -378.785274) (xy 390.521702 -378.777494) (xy 390.531858 -378.776992)
			(xy 391.248138 -378.776992) (xy 391.258293 -378.777501) (xy 391.277054 -378.785279) (xy 391.291416 -378.79964)
			(xy 391.299197 -378.8184) (xy 391.2997 -378.828554) (xy 391.2997 -378.986796) (xy 391.300112 -378.995983)
			(xy 391.306625 -379.013167) (xy 391.3124 -379.020324) (xy 391.334234 -379.045938) (xy 391.372178 -379.101531)
			(xy 391.403207 -379.16126) (xy 391.426876 -379.224269) (xy 391.442844 -379.289656) (xy 391.450884 -379.356482)
			(xy 391.45088 -379.42379) (xy 391.442831 -379.490615) (xy 391.426855 -379.556) (xy 391.403178 -379.619006)
			(xy 391.372141 -379.678731) (xy 391.334189 -379.734319) (xy 391.3124 -379.759972) (xy 391.30659 -379.767108)
			(xy 391.300083 -379.784306) (xy 391.2997 -379.7935) (xy 391.2997 -380.286768) (xy 391.300126 -380.295954)
			(xy 391.306629 -380.313138) (xy 391.3124 -380.320296) (xy 391.334206 -380.345933) (xy 391.372152 -380.401522)
			(xy 391.403182 -380.461248) (xy 391.426852 -380.524255) (xy 391.442822 -380.589638) (xy 391.450857 -380.656404)
			(xy 421.12866 -380.656404) (xy 421.136735 -380.589466) (xy 421.152769 -380.523978) (xy 421.176533 -380.460881)
			(xy 421.207683 -380.401086) (xy 421.245772 -380.345453) (xy 421.267636 -380.319788) (xy 421.273425 -380.312637)
			(xy 421.279943 -380.295451) (xy 421.280336 -380.28626) (xy 421.280336 -379.794008) (xy 421.279914 -379.784822)
			(xy 421.273408 -379.767638) (xy 421.267636 -379.76048) (xy 421.245818 -379.734776) (xy 421.207725 -379.679148)
			(xy 421.176571 -379.619358) (xy 421.152802 -379.556266) (xy 421.136762 -379.490781) (xy 421.128682 -379.423846)
			(xy 421.128678 -379.356426) (xy 421.136749 -379.28949) (xy 421.152781 -379.224003) (xy 421.176541 -379.160908)
			(xy 421.207688 -379.101114) (xy 421.245774 -379.045481) (xy 421.267636 -379.019816) (xy 421.273455 -379.012687)
			(xy 421.279956 -378.995484) (xy 421.280336 -378.986288) (xy 421.280336 -378.828554) (xy 421.280789 -378.818425)
			(xy 421.288531 -378.799703) (xy 421.302827 -378.785349) (xy 421.321517 -378.777531) (xy 421.331644 -378.776992)
			(xy 422.047924 -378.776992) (xy 422.058033 -378.777465) (xy 422.076711 -378.785209) (xy 422.091004 -378.79951)
			(xy 422.09874 -378.81819) (xy 422.099232 -378.8283) (xy 422.099232 -378.986288) (xy 422.099663 -378.995473)
			(xy 422.106164 -379.012656) (xy 422.111932 -379.019816) (xy 422.133842 -379.045443) (xy 422.171927 -379.101084)
			(xy 422.203074 -379.160885) (xy 422.226834 -379.223987) (xy 422.242865 -379.289481) (xy 422.250937 -379.356423)
			(xy 422.250932 -379.423849) (xy 422.242852 -379.49079) (xy 422.226813 -379.556282) (xy 422.203045 -379.61938)
			(xy 422.17189 -379.679178) (xy 422.133798 -379.734814) (xy 422.111932 -379.76048) (xy 422.106111 -379.767607)
			(xy 422.099613 -379.784812) (xy 422.099232 -379.794008) (xy 422.099232 -380.28626) (xy 422.099677 -380.295443)
			(xy 422.106168 -380.312627) (xy 422.111932 -380.319788) (xy 422.133814 -380.345438) (xy 422.171901 -380.401075)
			(xy 422.203049 -380.460874) (xy 422.22681 -380.523973) (xy 422.242843 -380.589463) (xy 422.250917 -380.656403)
			(xy 422.250917 -380.656463) (xy 425.52898 -380.656463) (xy 425.537022 -380.589642) (xy 425.552992 -380.524262)
			(xy 425.576662 -380.461258) (xy 425.607692 -380.401535) (xy 425.645638 -380.345948) (xy 425.667424 -380.320296)
			(xy 425.673208 -380.313142) (xy 425.679729 -380.295958) (xy 425.680124 -380.286768) (xy 425.680124 -379.7935)
			(xy 425.679709 -379.784313) (xy 425.673198 -379.767129) (xy 425.667424 -379.759972) (xy 425.645684 -379.734281)
			(xy 425.607735 -379.678699) (xy 425.5767 -379.618981) (xy 425.553026 -379.555982) (xy 425.53705 -379.490605)
			(xy 425.529002 -379.423787) (xy 425.528998 -379.356486) (xy 425.537037 -379.289667) (xy 425.553004 -379.224287)
			(xy 425.576671 -379.161285) (xy 425.607698 -379.101563) (xy 425.64564 -379.045977) (xy 425.667424 -379.020324)
			(xy 425.673238 -379.013191) (xy 425.679742 -378.995991) (xy 425.680124 -378.986796) (xy 425.680124 -378.828554)
			(xy 425.680595 -378.818395) (xy 425.688382 -378.799628) (xy 425.702754 -378.785264) (xy 425.721527 -378.777489)
			(xy 425.731686 -378.776992) (xy 426.447966 -378.776992) (xy 426.458116 -378.77756) (xy 426.476875 -378.785315)
			(xy 426.49124 -378.799657) (xy 426.499024 -378.818405) (xy 426.499528 -378.828554) (xy 426.499528 -378.986796)
			(xy 426.499934 -378.995984) (xy 426.50645 -379.013168) (xy 426.512228 -379.020324) (xy 426.534064 -379.045937)
			(xy 426.572014 -379.101528) (xy 426.603047 -379.161257) (xy 426.626718 -379.224267) (xy 426.642689 -379.289654)
			(xy 426.65073 -379.356481) (xy 426.650725 -379.423791) (xy 426.642676 -379.490617) (xy 426.626697 -379.556003)
			(xy 426.603017 -379.619009) (xy 426.571977 -379.678734) (xy 426.53402 -379.73432) (xy 426.512228 -379.759972)
			(xy 426.50641 -379.767101) (xy 426.49991 -379.784304) (xy 426.499528 -379.7935) (xy 426.499528 -380.286768)
			(xy 426.499947 -380.295954) (xy 426.506454 -380.313139) (xy 426.512228 -380.320296) (xy 426.534036 -380.345932)
			(xy 426.571987 -380.40152) (xy 426.603021 -380.461245) (xy 426.626694 -380.524252) (xy 426.642667 -380.589636)
			(xy 426.650703 -380.656404) (xy 429.928748 -380.656404) (xy 429.936823 -380.589467) (xy 429.952857 -380.523978)
			(xy 429.976619 -380.460882) (xy 430.007769 -380.401087) (xy 430.045857 -380.345453) (xy 430.06772 -380.319788)
			(xy 430.073506 -380.312636) (xy 430.080027 -380.295451) (xy 430.08042 -380.28626) (xy 430.08042 -379.794008)
			(xy 430.080001 -379.784822) (xy 430.073493 -379.767638) (xy 430.06772 -379.76048) (xy 430.045902 -379.734776)
			(xy 430.007811 -379.679148) (xy 429.976657 -379.619357) (xy 429.952889 -379.556265) (xy 429.93685 -379.490781)
			(xy 429.92877 -379.423846) (xy 429.928766 -379.356426) (xy 429.936837 -379.289491) (xy 429.952868 -379.224004)
			(xy 429.976628 -379.160909) (xy 430.007774 -379.101114) (xy 430.045858 -379.045481) (xy 430.06772 -379.019816)
			(xy 430.073537 -379.012685) (xy 430.080039 -378.995484) (xy 430.08042 -378.986288) (xy 430.08042 -378.828554)
			(xy 430.080888 -378.818427) (xy 430.088628 -378.799708) (xy 430.102919 -378.785354) (xy 430.121603 -378.777533)
			(xy 430.131728 -378.776992) (xy 430.848008 -378.776992) (xy 430.858162 -378.777415) (xy 430.876913 -378.785212)
			(xy 430.891235 -378.799608) (xy 430.898936 -378.818398) (xy 430.899316 -378.828554) (xy 430.899316 -378.986288)
			(xy 430.899728 -378.995475) (xy 430.90624 -379.01266) (xy 430.912016 -379.019816) (xy 430.933927 -379.045443)
			(xy 430.972013 -379.101083) (xy 431.003161 -379.160885) (xy 431.026921 -379.223987) (xy 431.042953 -379.28948)
			(xy 431.051025 -379.356422) (xy 431.05102 -379.42385) (xy 431.04294 -379.490791) (xy 431.0269 -379.556282)
			(xy 431.003131 -379.619381) (xy 430.971976 -379.679179) (xy 430.933882 -379.734814) (xy 430.912016 -379.76048)
			(xy 430.906205 -379.767615) (xy 430.899698 -379.784813) (xy 430.899316 -379.794008) (xy 430.899316 -380.28626)
			(xy 430.899742 -380.295446) (xy 430.906244 -380.31263) (xy 430.912016 -380.319788) (xy 430.933899 -380.345437)
			(xy 430.971986 -380.401074) (xy 431.003135 -380.460873) (xy 431.026897 -380.523972) (xy 431.042931 -380.589463)
			(xy 431.051005 -380.656403) (xy 431.051005 -380.656464) (xy 434.329068 -380.656464) (xy 434.33711 -380.589643)
			(xy 434.35308 -380.524262) (xy 434.376749 -380.461259) (xy 434.407778 -380.401535) (xy 434.445722 -380.345949)
			(xy 434.467508 -380.320296) (xy 434.47329 -380.31314) (xy 434.479813 -380.295958) (xy 434.480208 -380.286768)
			(xy 434.480208 -379.7935) (xy 434.479796 -379.784313) (xy 434.473283 -379.767129) (xy 434.467508 -379.759972)
			(xy 434.445769 -379.73428) (xy 434.407821 -379.678699) (xy 434.376787 -379.61898) (xy 434.353113 -379.555981)
			(xy 434.337137 -379.490604) (xy 434.32909 -379.423786) (xy 434.329086 -379.356486) (xy 434.337125 -379.289667)
			(xy 434.353091 -379.224288) (xy 434.376757 -379.161286) (xy 434.407783 -379.101563) (xy 434.445724 -379.045977)
			(xy 434.467508 -379.020324) (xy 434.47332 -379.01319) (xy 434.479825 -378.995991) (xy 434.480208 -378.986796)
			(xy 434.480208 -378.828554) (xy 434.480695 -378.818397) (xy 434.488479 -378.799633) (xy 434.502846 -378.78527)
			(xy 434.521613 -378.777492) (xy 434.53177 -378.776992) (xy 435.24805 -378.776992) (xy 435.258213 -378.777504)
			(xy 435.276998 -378.785264) (xy 435.291383 -378.799622) (xy 435.299177 -378.818392) (xy 435.299612 -378.828554)
			(xy 435.299612 -378.986796) (xy 435.300021 -378.995983) (xy 435.306535 -379.013168) (xy 435.312312 -379.020324)
			(xy 435.334148 -379.045937) (xy 435.372099 -379.101528) (xy 435.403133 -379.161256) (xy 435.426805 -379.224266)
			(xy 435.442776 -379.289654) (xy 435.450817 -379.356481) (xy 435.450813 -379.423791) (xy 435.442763 -379.490618)
			(xy 435.426784 -379.556003) (xy 435.403103 -379.61901) (xy 435.372062 -379.678734) (xy 435.334104 -379.73432)
			(xy 435.312312 -379.759972) (xy 435.306504 -379.767109) (xy 435.299996 -379.784306) (xy 435.299612 -379.7935)
			(xy 435.299612 -380.286768) (xy 435.300035 -380.295954) (xy 435.306539 -380.313139) (xy 435.312312 -380.320296)
			(xy 435.334121 -380.345931) (xy 435.372072 -380.401519) (xy 435.403107 -380.461244) (xy 435.426781 -380.524251)
			(xy 435.442754 -380.589636) (xy 435.450797 -380.656461) (xy 435.450796 -380.723769) (xy 435.442749 -380.790594)
			(xy 435.426772 -380.855977) (xy 435.403095 -380.918983) (xy 435.372057 -380.978707) (xy 435.334102 -381.034292)
			(xy 435.312312 -381.059944) (xy 435.306516 -381.067089) (xy 435.3 -381.08428) (xy 435.299612 -381.093472)
			(xy 435.299612 -381.251206) (xy 435.29924 -381.261384) (xy 435.291444 -381.280189) (xy 435.277041 -381.294575)
			(xy 435.258229 -381.302351) (xy 435.24805 -381.302768) (xy 434.53177 -381.302768) (xy 434.521611 -381.302291)
			(xy 434.502842 -381.294508) (xy 434.488478 -381.280138) (xy 434.480704 -381.261365) (xy 434.480208 -381.251206)
			(xy 434.480208 -381.093472) (xy 434.47981 -381.084284) (xy 434.473288 -381.067099) (xy 434.467508 -381.059944)
			(xy 434.445741 -381.034275) (xy 434.407793 -380.97869) (xy 434.376761 -380.918969) (xy 434.353088 -380.855967)
			(xy 434.337115 -380.790587) (xy 434.32907 -380.723766) (xy 434.329068 -380.656464) (xy 431.051005 -380.656464)
			(xy 431.051003 -380.723827) (xy 431.042926 -380.790767) (xy 431.026889 -380.856257) (xy 431.003123 -380.919354)
			(xy 430.971971 -380.979151) (xy 430.933881 -381.034786) (xy 430.912016 -381.060452) (xy 430.906217 -381.067595)
			(xy 430.899703 -381.084787) (xy 430.899316 -381.09398) (xy 430.899316 -381.251206) (xy 430.898877 -381.261338)
			(xy 430.891139 -381.280068) (xy 430.876838 -381.294426) (xy 430.858138 -381.302237) (xy 430.848008 -381.302768)
			(xy 430.131728 -381.302768) (xy 430.121572 -381.302355) (xy 430.102814 -381.294563) (xy 430.088488 -381.280163)
			(xy 430.080793 -381.261364) (xy 430.08042 -381.251206) (xy 430.08042 -381.09398) (xy 430.080015 -381.084792)
			(xy 430.073497 -381.067608) (xy 430.06772 -381.060452) (xy 430.045875 -381.034771) (xy 430.007784 -380.979139)
			(xy 429.976632 -380.919345) (xy 429.952865 -380.85625) (xy 429.936828 -380.790763) (xy 429.92875 -380.723826)
			(xy 429.928748 -380.656404) (xy 426.650703 -380.656404) (xy 426.65071 -380.656461) (xy 426.650708 -380.723769)
			(xy 426.642661 -380.790593) (xy 426.626685 -380.855977) (xy 426.603009 -380.918982) (xy 426.571971 -380.978706)
			(xy 426.534018 -381.034292) (xy 426.512228 -381.059944) (xy 426.506422 -381.067082) (xy 426.499915 -381.084278)
			(xy 426.499528 -381.093472) (xy 426.499528 -381.251206) (xy 426.49914 -381.261382) (xy 426.491347 -381.280184)
			(xy 426.47695 -381.294569) (xy 426.458143 -381.302348) (xy 426.447966 -381.302768) (xy 425.731686 -381.302768)
			(xy 425.721528 -381.302278) (xy 425.70276 -381.2945) (xy 425.688395 -381.280133) (xy 425.68062 -381.261364)
			(xy 425.680124 -381.251206) (xy 425.680124 -381.093472) (xy 425.679722 -381.084284) (xy 425.673202 -381.0671)
			(xy 425.667424 -381.059944) (xy 425.645656 -381.034276) (xy 425.607708 -380.978691) (xy 425.576675 -380.91897)
			(xy 425.553001 -380.855967) (xy 425.537027 -380.790587) (xy 425.528982 -380.723767) (xy 425.52898 -380.656463)
			(xy 422.250917 -380.656463) (xy 422.250915 -380.723827) (xy 422.242838 -380.790766) (xy 422.226801 -380.856256)
			(xy 422.203036 -380.919354) (xy 422.171885 -380.979151) (xy 422.133796 -381.034786) (xy 422.111932 -381.060452)
			(xy 422.106123 -381.067588) (xy 422.099618 -381.084786) (xy 422.099232 -381.09398) (xy 422.099232 -381.251206)
			(xy 422.098777 -381.261337) (xy 422.091042 -381.280063) (xy 422.076746 -381.29442) (xy 422.058052 -381.302234)
			(xy 422.047924 -381.302768) (xy 421.331644 -381.302768) (xy 421.32152 -381.302347) (xy 421.302812 -381.294608)
			(xy 421.288495 -381.280292) (xy 421.280754 -381.261584) (xy 421.280336 -381.25146) (xy 421.280336 -381.09398)
			(xy 421.279927 -381.084793) (xy 421.273412 -381.067609) (xy 421.267636 -381.060452) (xy 421.24579 -381.034771)
			(xy 421.207699 -380.97914) (xy 421.176545 -380.919346) (xy 421.152778 -380.856251) (xy 421.13674 -380.790764)
			(xy 421.128662 -380.723826) (xy 421.12866 -380.656404) (xy 391.450857 -380.656404) (xy 391.450864 -380.656462)
			(xy 391.450863 -380.723768) (xy 391.442817 -380.790591) (xy 391.426843 -380.855974) (xy 391.40317 -380.918979)
			(xy 391.372136 -380.978704) (xy 391.334188 -381.034291) (xy 391.3124 -381.059944) (xy 391.306602 -381.067088)
			(xy 391.300088 -381.08428) (xy 391.2997 -381.093472) (xy 391.2997 -381.251206) (xy 391.299172 -381.261359)
			(xy 391.291403 -381.280121) (xy 391.277048 -381.294485) (xy 391.258291 -381.302266) (xy 391.248138 -381.302768)
			(xy 390.531858 -381.302768) (xy 390.521698 -381.302301) (xy 390.502929 -381.294514) (xy 390.488566 -381.28014)
			(xy 390.480792 -381.261366) (xy 390.480296 -381.251206) (xy 390.480296 -381.093472) (xy 390.4799 -381.084283)
			(xy 390.473377 -381.067099) (xy 390.467596 -381.059944) (xy 390.445829 -381.034275) (xy 390.407883 -380.97869)
			(xy 390.376851 -380.918968) (xy 390.353179 -380.855966) (xy 390.337206 -380.790586) (xy 390.329161 -380.723766)
			(xy 390.329159 -380.656464) (xy 387.051096 -380.656464) (xy 387.051094 -380.723828) (xy 387.043016 -380.790767)
			(xy 387.026979 -380.856257) (xy 387.003213 -380.919355) (xy 386.97206 -380.979152) (xy 386.933969 -381.034787)
			(xy 386.912104 -381.060452) (xy 386.906303 -381.067594) (xy 386.899791 -381.084787) (xy 386.899404 -381.09398)
			(xy 386.899404 -381.251206) (xy 386.89888 -381.261328) (xy 386.891158 -381.280041) (xy 386.876884 -381.294395)
			(xy 386.858215 -381.302222) (xy 386.848096 -381.302768) (xy 386.131816 -381.302768) (xy 386.121659 -381.302365)
			(xy 386.102901 -381.294568) (xy 386.088576 -381.280166) (xy 386.080881 -381.261365) (xy 386.080508 -381.251206)
			(xy 386.080508 -381.09398) (xy 386.080106 -381.084792) (xy 386.073587 -381.067608) (xy 386.067808 -381.060452)
			(xy 386.045963 -381.034771) (xy 386.007874 -380.979139) (xy 385.976722 -380.919345) (xy 385.952956 -380.85625)
			(xy 385.936919 -380.790763) (xy 385.928841 -380.723826) (xy 385.928839 -380.656404) (xy 382.650793 -380.656404)
			(xy 382.6508 -380.656461) (xy 382.650799 -380.723769) (xy 382.642752 -380.790593) (xy 382.626775 -380.855977)
			(xy 382.603098 -380.918983) (xy 382.57206 -380.978707) (xy 382.534106 -381.034292) (xy 382.512316 -381.059944)
			(xy 382.50652 -381.06709) (xy 382.500005 -381.08428) (xy 382.499616 -381.093472) (xy 382.499616 -381.251206)
			(xy 382.49924 -381.261384) (xy 382.491444 -381.280187) (xy 382.477044 -381.294574) (xy 382.458232 -381.30235)
			(xy 382.448054 -381.302768) (xy 381.731774 -381.302768) (xy 381.721615 -381.302288) (xy 381.702847 -381.294506)
			(xy 381.688482 -381.280137) (xy 381.680708 -381.261365) (xy 381.680212 -381.251206) (xy 381.680212 -381.093472)
			(xy 381.679813 -381.084284) (xy 381.673291 -381.0671) (xy 381.667512 -381.059944) (xy 381.645745 -381.034275)
			(xy 381.607797 -380.978691) (xy 381.576764 -380.918969) (xy 381.553092 -380.855967) (xy 381.537118 -380.790587)
			(xy 381.529073 -380.723767) (xy 381.529071 -380.656464) (xy 378.251008 -380.656464) (xy 378.251006 -380.723827)
			(xy 378.242929 -380.790767) (xy 378.226892 -380.856257) (xy 378.203126 -380.919354) (xy 378.171974 -380.979151)
			(xy 378.133884 -381.034786) (xy 378.11202 -381.060452) (xy 378.106221 -381.067596) (xy 378.099707 -381.084787)
			(xy 378.09932 -381.09398) (xy 378.09932 -381.251206) (xy 378.098877 -381.261338) (xy 378.09114 -381.280067)
			(xy 378.07684 -381.294424) (xy 378.058142 -381.302236) (xy 378.048012 -381.302768) (xy 377.331732 -381.302768)
			(xy 377.321576 -381.302352) (xy 377.302818 -381.294561) (xy 377.288492 -381.280162) (xy 377.280797 -381.261364)
			(xy 377.280424 -381.251206) (xy 377.280424 -381.09398) (xy 377.280018 -381.084792) (xy 377.273501 -381.067608)
			(xy 377.267724 -381.060452) (xy 377.245879 -381.034771) (xy 377.207788 -380.979139) (xy 377.176635 -380.919345)
			(xy 377.152869 -380.856251) (xy 377.136831 -380.790763) (xy 377.128753 -380.723826) (xy 377.128751 -380.656404)
			(xy 347.450948 -380.656404) (xy 347.450955 -380.656462) (xy 347.450954 -380.723768) (xy 347.442908 -380.790592)
			(xy 347.426934 -380.855975) (xy 347.40326 -380.91898) (xy 347.372226 -380.978704) (xy 347.334276 -381.034291)
			(xy 347.312488 -381.059944) (xy 347.306689 -381.067087) (xy 347.300176 -381.084279) (xy 347.299788 -381.093472)
			(xy 347.299788 -381.251206) (xy 347.299272 -381.261361) (xy 347.2915 -381.280125) (xy 347.277142 -381.294489)
			(xy 347.258381 -381.302268) (xy 347.248226 -381.302768) (xy 346.531946 -381.302768) (xy 346.521778 -381.302299)
			(xy 346.502986 -381.29453) (xy 346.488599 -381.280158) (xy 346.480812 -381.261373) (xy 346.480384 -381.251206)
			(xy 346.480384 -381.093472) (xy 346.479991 -381.084283) (xy 346.473466 -381.067099) (xy 346.467684 -381.059944)
			(xy 346.445915 -381.034276) (xy 346.407962 -380.978693) (xy 346.376926 -380.918972) (xy 346.35325 -380.85597)
			(xy 346.337274 -380.790589) (xy 346.329228 -380.723767) (xy 346.329226 -380.656463) (xy 343.051187 -380.656463)
			(xy 343.051185 -380.723828) (xy 343.043107 -380.790767) (xy 343.027069 -380.856258) (xy 343.003303 -380.919356)
			(xy 342.972149 -380.979152) (xy 342.934057 -381.034787) (xy 342.912192 -381.060452) (xy 342.90639 -381.067593)
			(xy 342.899879 -381.084787) (xy 342.899492 -381.09398) (xy 342.899492 -381.251206) (xy 342.898979 -381.261329)
			(xy 342.891255 -381.280044) (xy 342.876978 -381.294399) (xy 342.858304 -381.302224) (xy 342.848184 -381.302768)
			(xy 342.131904 -381.302768) (xy 342.121746 -381.302374) (xy 342.102988 -381.294574) (xy 342.088663 -381.280168)
			(xy 342.080969 -381.261366) (xy 342.080596 -381.251206) (xy 342.080596 -381.09398) (xy 342.080196 -381.084792)
			(xy 342.073675 -381.067608) (xy 342.067896 -381.060452) (xy 342.046052 -381.03477) (xy 342.007963 -380.979138)
			(xy 341.976811 -380.919344) (xy 341.953046 -380.856249) (xy 341.93701 -380.790762) (xy 341.928932 -380.723826)
			(xy 341.92893 -380.656404) (xy 338.65086 -380.656404) (xy 338.650867 -380.656462) (xy 338.650866 -380.723768)
			(xy 338.64282 -380.790591) (xy 338.626846 -380.855974) (xy 338.603173 -380.918979) (xy 338.57214 -380.978704)
			(xy 338.534192 -381.034291) (xy 338.512404 -381.059944) (xy 338.506607 -381.067089) (xy 338.500092 -381.08428)
			(xy 338.499704 -381.093472) (xy 338.499704 -381.251206) (xy 338.499172 -381.261359) (xy 338.491404 -381.28012)
			(xy 338.47705 -381.294484) (xy 338.458295 -381.302265) (xy 338.448142 -381.302768) (xy 337.731862 -381.302768)
			(xy 337.721703 -381.302298) (xy 337.702934 -381.294512) (xy 337.68857 -381.280139) (xy 337.680796 -381.261366)
			(xy 337.6803 -381.251206) (xy 337.6803 -381.093472) (xy 337.679904 -381.084283) (xy 337.67338 -381.067099)
			(xy 337.6676 -381.059944) (xy 337.645833 -381.034275) (xy 337.607886 -380.97869) (xy 337.576854 -380.918969)
			(xy 337.553182 -380.855966) (xy 337.537209 -380.790587) (xy 337.529164 -380.723766) (xy 337.529162 -380.656464)
			(xy 334.251099 -380.656464) (xy 334.251097 -380.723828) (xy 334.243019 -380.790767) (xy 334.226982 -380.856257)
			(xy 334.203216 -380.919355) (xy 334.172063 -380.979152) (xy 334.133973 -381.034787) (xy 334.112108 -381.060452)
			(xy 334.106308 -381.067595) (xy 334.099795 -381.084787) (xy 334.099408 -381.09398) (xy 334.099408 -381.251206)
			(xy 334.09888 -381.261327) (xy 334.091159 -381.280039) (xy 334.076886 -381.294394) (xy 334.058218 -381.302221)
			(xy 334.0481 -381.302768) (xy 333.33182 -381.302768) (xy 333.321663 -381.302362) (xy 333.302905 -381.294567)
			(xy 333.28858 -381.280165) (xy 333.280885 -381.261365) (xy 333.280512 -381.251206) (xy 333.280512 -381.09398)
			(xy 333.280109 -381.084792) (xy 333.27359 -381.067608) (xy 333.267812 -381.060452) (xy 333.245967 -381.034771)
			(xy 333.207877 -380.979139) (xy 333.176725 -380.919345) (xy 333.152959 -380.85625) (xy 333.136922 -380.790763)
			(xy 333.128844 -380.723826) (xy 333.128842 -380.656404) (xy 303.451069 -380.656404) (xy 303.451067 -380.723828)
			(xy 303.442989 -380.790768) (xy 303.42695 -380.856259) (xy 303.403182 -380.919357) (xy 303.372027 -380.979153)
			(xy 303.333934 -381.034787) (xy 303.312068 -381.060452) (xy 303.306263 -381.067591) (xy 303.299754 -381.084786)
			(xy 303.299368 -381.09398) (xy 303.299368 -381.251206) (xy 303.298878 -381.261332) (xy 303.29115 -381.280052)
			(xy 303.276865 -381.294408) (xy 303.258184 -381.302228) (xy 303.24806 -381.302768) (xy 302.53178 -381.302768)
			(xy 302.521621 -381.302394) (xy 302.502861 -381.294586) (xy 302.488538 -381.280174) (xy 302.480844 -381.261368)
			(xy 302.480472 -381.251206) (xy 302.480472 -381.09398) (xy 302.480078 -381.084791) (xy 302.473554 -381.067607)
			(xy 302.467772 -381.060452) (xy 302.445929 -381.03477) (xy 302.407841 -380.979137) (xy 302.376691 -380.919343)
			(xy 302.352927 -380.856248) (xy 302.336891 -380.790762) (xy 302.328814 -380.723826) (xy 302.328812 -380.656404)
			(xy 299.050742 -380.656404) (xy 299.050749 -380.656462) (xy 299.050747 -380.723768) (xy 299.042702 -380.790592)
			(xy 299.026727 -380.855975) (xy 299.003053 -380.91898) (xy 298.972018 -380.978704) (xy 298.934068 -381.034292)
			(xy 298.91228 -381.059944) (xy 298.90648 -381.067087) (xy 298.899968 -381.084279) (xy 298.89958 -381.093472)
			(xy 298.89958 -381.251206) (xy 298.899072 -381.261362) (xy 298.891299 -381.280128) (xy 298.876938 -381.294492)
			(xy 298.858174 -381.302269) (xy 298.848018 -381.302768) (xy 298.131738 -381.302768) (xy 298.12157 -381.302305)
			(xy 298.102777 -381.294534) (xy 298.088391 -381.28016) (xy 298.080604 -381.261374) (xy 298.080176 -381.251206)
			(xy 298.080176 -381.093472) (xy 298.079785 -381.084283) (xy 298.073258 -381.067098) (xy 298.067476 -381.059944)
			(xy 298.045707 -381.034276) (xy 298.007755 -380.978693) (xy 297.976719 -380.918972) (xy 297.953043 -380.855969)
			(xy 297.937068 -380.790589) (xy 297.929022 -380.723767) (xy 297.92902 -380.656463) (xy 294.650981 -380.656463)
			(xy 294.650979 -380.723828) (xy 294.642901 -380.790768) (xy 294.626863 -380.856258) (xy 294.603096 -380.919356)
			(xy 294.571942 -380.979153) (xy 294.53385 -381.034787) (xy 294.511984 -381.060452) (xy 294.506181 -381.067593)
			(xy 294.499671 -381.084787) (xy 294.499284 -381.09398) (xy 294.499284 -381.251206) (xy 294.498779 -381.26133)
			(xy 294.491054 -381.280047) (xy 294.476773 -381.294402) (xy 294.458097 -381.302225) (xy 294.447976 -381.302768)
			(xy 293.731696 -381.302768) (xy 293.721569 -381.302386) (xy 293.70286 -381.294631) (xy 293.688544 -381.280303)
			(xy 293.680805 -381.261587) (xy 293.680388 -381.25146) (xy 293.680388 -381.09398) (xy 293.67999 -381.084791)
			(xy 293.673468 -381.067607) (xy 293.667688 -381.060452) (xy 293.645844 -381.03477) (xy 293.607756 -380.979138)
			(xy 293.576605 -380.919344) (xy 293.55284 -380.856249) (xy 293.536803 -380.790762) (xy 293.528726 -380.723826)
			(xy 293.528724 -380.656404) (xy 290.250654 -380.656404) (xy 290.250661 -380.656462) (xy 290.25066 -380.723768)
			(xy 290.242614 -380.790591) (xy 290.22664 -380.855974) (xy 290.202966 -380.918979) (xy 290.171933 -380.978704)
			(xy 290.133984 -381.034291) (xy 290.112196 -381.059944) (xy 290.106398 -381.067088) (xy 290.099884 -381.084279)
			(xy 290.099496 -381.093472) (xy 290.099496 -381.251206) (xy 290.098972 -381.26136) (xy 290.091202 -381.280123)
			(xy 290.076846 -381.294486) (xy 290.058088 -381.302267) (xy 290.047934 -381.302768) (xy 289.331654 -381.302768)
			(xy 289.321494 -381.302304) (xy 289.302725 -381.294516) (xy 289.288362 -381.280141) (xy 289.280588 -381.261366)
			(xy 289.280092 -381.251206) (xy 289.280092 -381.093472) (xy 289.279697 -381.084283) (xy 289.273173 -381.067099)
			(xy 289.267392 -381.059944) (xy 289.245622 -381.034276) (xy 289.207669 -380.978693) (xy 289.176632 -380.918972)
			(xy 289.152956 -380.85597) (xy 289.13698 -380.790589) (xy 289.128934 -380.723767) (xy 289.128932 -380.656463)
			(xy 272.92786 -380.656463) (xy 272.867822 -380.687974) (xy 272.746027 -380.742789) (xy 272.621144 -380.790151)
			(xy 272.49363 -380.829886) (xy 272.363949 -380.861849) (xy 272.232575 -380.885924) (xy 272.099987 -380.902024)
			(xy 271.966669 -380.910088) (xy 271.833107 -380.910088) (xy 271.699789 -380.902024) (xy 271.567201 -380.885924)
			(xy 271.435827 -380.861849) (xy 271.306146 -380.829886) (xy 271.178632 -380.790151) (xy 271.053749 -380.742789)
			(xy 270.931954 -380.687974) (xy 270.813691 -380.625904) (xy 270.699392 -380.556808) (xy 270.589472 -380.480936)
			(xy 270.484335 -380.398566) (xy 270.384362 -380.309998) (xy 270.28992 -380.215556) (xy 270.201352 -380.115583)
			(xy 270.118982 -380.010446) (xy 270.04311 -379.900526) (xy 269.974014 -379.786227) (xy 269.911944 -379.667964)
			(xy 269.857129 -379.546169) (xy 269.809767 -379.421286) (xy 269.770032 -379.293772) (xy 269.738069 -379.164091)
			(xy 269.713994 -379.032717) (xy 269.697894 -378.900129) (xy 269.68983 -378.766811) (xy 236.356885 -378.766811)
			(xy 237.084108 -379.494034) (xy 237.084616 -379.494542) (xy 237.093852 -379.502751) (xy 237.116722 -379.512039)
			(xy 237.129066 -379.512576) (xy 239.773968 -379.512576) (xy 239.786313 -379.512049) (xy 239.809185 -379.502755)
			(xy 239.818418 -379.494542) (xy 239.818926 -379.494034) (xy 240.443004 -378.869702) (xy 240.450409 -378.862868)
			(xy 240.469004 -378.855145) (xy 240.479072 -378.854716) (xy 262.036814 -378.854716) (xy 262.046885 -378.85513)
			(xy 262.065482 -378.862858) (xy 262.072882 -378.869702) (xy 262.259318 -379.056138) (xy 262.26617 -379.063529)
			(xy 262.273882 -379.082135) (xy 262.274304 -379.092206) (xy 262.274304 -382.223705) (xy 286.928753 -382.223705)
			(xy 286.928754 -382.15628) (xy 286.936832 -382.08934) (xy 286.95287 -382.02385) (xy 286.976638 -381.960752)
			(xy 287.007792 -381.900956) (xy 287.045886 -381.845322) (xy 287.067752 -381.819658) (xy 287.073555 -381.812518)
			(xy 287.080065 -381.795323) (xy 287.080452 -381.78613) (xy 287.080452 -381.628904) (xy 287.080987 -381.618801)
			(xy 287.088715 -381.600133) (xy 287.102996 -381.585839) (xy 287.121658 -381.578096) (xy 287.13176 -381.577596)
			(xy 287.84804 -381.577596) (xy 287.858151 -381.578052) (xy 287.876829 -381.585802) (xy 287.891122 -381.600108)
			(xy 287.898856 -381.618793) (xy 287.899348 -381.628904) (xy 287.899348 -381.78613) (xy 287.899755 -381.795317)
			(xy 287.906272 -381.812501) (xy 287.912048 -381.819658) (xy 287.933904 -381.84533) (xy 287.971996 -381.900963)
			(xy 288.00315 -381.960757) (xy 288.026917 -382.023853) (xy 288.042955 -382.089342) (xy 288.051033 -382.156281)
			(xy 288.051034 -382.223645) (xy 291.329073 -382.223645) (xy 291.329074 -382.15634) (xy 291.337119 -382.089516)
			(xy 291.353093 -382.024133) (xy 291.376767 -381.961128) (xy 291.407801 -381.901405) (xy 291.445751 -381.845818)
			(xy 291.46754 -381.820166) (xy 291.473339 -381.813022) (xy 291.479851 -381.795831) (xy 291.48024 -381.786638)
			(xy 291.48024 -381.628904) (xy 291.48062 -381.618777) (xy 291.488375 -381.600066) (xy 291.502703 -381.58575)
			(xy 291.52142 -381.578012) (xy 291.531548 -381.577596) (xy 292.248082 -381.577596) (xy 292.258202 -381.57814)
			(xy 292.276915 -381.585854) (xy 292.29127 -381.600122) (xy 292.299098 -381.618787) (xy 292.299644 -381.628904)
			(xy 292.299644 -381.786638) (xy 292.300049 -381.795826) (xy 292.306568 -381.813009) (xy 292.312344 -381.820166)
			(xy 292.334122 -381.845826) (xy 292.372072 -381.901411) (xy 292.403107 -381.961133) (xy 292.426781 -382.024137)
			(xy 292.442755 -382.089518) (xy 292.450801 -382.15634) (xy 292.450801 -382.223645) (xy 292.450794 -382.223705)
			(xy 295.728841 -382.223705) (xy 295.728842 -382.15628) (xy 295.73692 -382.08934) (xy 295.752957 -382.02385)
			(xy 295.776724 -381.960753) (xy 295.807878 -381.900957) (xy 295.84597 -381.845323) (xy 295.867836 -381.819658)
			(xy 295.873637 -381.812516) (xy 295.880148 -381.795323) (xy 295.880536 -381.78613) (xy 295.880536 -381.628904)
			(xy 295.88092 -381.618777) (xy 295.888674 -381.600067) (xy 295.903001 -381.585751) (xy 295.921717 -381.578012)
			(xy 295.931844 -381.577596) (xy 296.648124 -381.577596) (xy 296.658234 -381.578065) (xy 296.676912 -381.58581)
			(xy 296.691206 -381.600112) (xy 296.69894 -381.618794) (xy 296.699432 -381.628904) (xy 296.699432 -381.78613)
			(xy 296.699843 -381.795317) (xy 296.706358 -381.8125) (xy 296.712132 -381.819658) (xy 296.733985 -381.845332)
			(xy 296.772072 -381.900966) (xy 296.803221 -381.960761) (xy 296.826985 -382.023857) (xy 296.84302 -382.089345)
			(xy 296.851096 -382.156281) (xy 296.851097 -382.223704) (xy 296.851097 -382.223705) (xy 300.128632 -382.223705)
			(xy 300.128633 -382.15628) (xy 300.13671 -382.089341) (xy 300.152748 -382.023851) (xy 300.176514 -381.960753)
			(xy 300.207667 -381.900957) (xy 300.245759 -381.845323) (xy 300.267624 -381.819658) (xy 300.273424 -381.812515)
			(xy 300.279936 -381.795323) (xy 300.280324 -381.78613) (xy 300.280324 -381.628904) (xy 300.28072 -381.618779)
			(xy 300.288471 -381.600071) (xy 300.302794 -381.585755) (xy 300.321507 -381.578014) (xy 300.331632 -381.577596)
			(xy 301.047912 -381.577596) (xy 301.058021 -381.578075) (xy 301.076699 -381.585816) (xy 301.090993 -381.600115)
			(xy 301.098728 -381.618795) (xy 301.09922 -381.628904) (xy 301.09922 -381.78613) (xy 301.099611 -381.795319)
			(xy 301.106138 -381.812504) (xy 301.11192 -381.819658) (xy 301.133773 -381.845332) (xy 301.171861 -381.900965)
			(xy 301.203011 -381.960761) (xy 301.226775 -382.023856) (xy 301.242811 -382.089344) (xy 301.250887 -382.156281)
			(xy 301.250888 -382.223646) (xy 330.929191 -382.223646) (xy 330.929192 -382.156339) (xy 330.937238 -382.089516)
			(xy 330.953213 -382.024133) (xy 330.976888 -381.961128) (xy 331.007923 -381.901404) (xy 331.045875 -381.845818)
			(xy 331.067664 -381.820166) (xy 331.073465 -381.813025) (xy 331.079975 -381.795831) (xy 331.080364 -381.786638)
			(xy 331.080364 -381.628904) (xy 331.080824 -381.618755) (xy 331.088612 -381.600009) (xy 331.102996 -381.585687)
			(xy 331.121775 -381.577981) (xy 331.131926 -381.577596) (xy 331.848206 -381.577596) (xy 331.858328 -381.57812)
			(xy 331.877041 -381.585842) (xy 331.891395 -381.600116) (xy 331.899222 -381.618785) (xy 331.899768 -381.628904)
			(xy 331.899768 -381.786638) (xy 331.900167 -381.795826) (xy 331.906689 -381.81301) (xy 331.912468 -381.820166)
			(xy 331.934246 -381.845826) (xy 331.972195 -381.901412) (xy 332.003228 -381.961134) (xy 332.026901 -382.024138)
			(xy 332.042874 -382.089519) (xy 332.050919 -382.15634) (xy 332.05092 -382.223645) (xy 332.050913 -382.223704)
			(xy 335.328984 -382.223704) (xy 335.328985 -382.156281) (xy 335.337061 -382.089342) (xy 335.353096 -382.023853)
			(xy 335.37686 -381.960756) (xy 335.40801 -381.900959) (xy 335.446097 -381.845324) (xy 335.46796 -381.819658)
			(xy 335.473764 -381.812519) (xy 335.480273 -381.795323) (xy 335.48066 -381.78613) (xy 335.48066 -381.628904)
			(xy 335.481187 -381.6188) (xy 335.488916 -381.60013) (xy 335.5032 -381.585837) (xy 335.521865 -381.578095)
			(xy 335.531968 -381.577596) (xy 336.248248 -381.577596) (xy 336.258359 -381.578046) (xy 336.277038 -381.585799)
			(xy 336.291331 -381.600106) (xy 336.299064 -381.618792) (xy 336.299556 -381.628904) (xy 336.299556 -381.78613)
			(xy 336.299962 -381.795317) (xy 336.30648 -381.812501) (xy 336.312256 -381.819658) (xy 336.334112 -381.845331)
			(xy 336.372204 -381.900963) (xy 336.403357 -381.960758) (xy 336.427124 -382.023854) (xy 336.443161 -382.089342)
			(xy 336.451239 -382.156281) (xy 336.45124 -382.223645) (xy 339.729279 -382.223645) (xy 339.72928 -382.156339)
			(xy 339.737325 -382.089516) (xy 339.753299 -382.024133) (xy 339.776974 -381.961128) (xy 339.808009 -381.901404)
			(xy 339.845959 -381.845818) (xy 339.867748 -381.820166) (xy 339.873547 -381.813023) (xy 339.880059 -381.795831)
			(xy 339.880448 -381.786638) (xy 339.880448 -381.628904) (xy 339.880924 -381.618757) (xy 339.888708 -381.600014)
			(xy 339.903088 -381.585693) (xy 339.921861 -381.577984) (xy 339.93201 -381.577596) (xy 340.64829 -381.577596)
			(xy 340.658411 -381.578133) (xy 340.677123 -381.58585) (xy 340.691478 -381.60012) (xy 340.699306 -381.618786)
			(xy 340.699852 -381.628904) (xy 340.699852 -381.786638) (xy 340.700255 -381.795826) (xy 340.706775 -381.813009)
			(xy 340.712552 -381.820166) (xy 340.73433 -381.845826) (xy 340.77228 -381.901411) (xy 340.803314 -381.961134)
			(xy 340.826988 -382.024137) (xy 340.842962 -382.089518) (xy 340.851007 -382.15634) (xy 340.851007 -382.223645)
			(xy 344.12907 -382.223645) (xy 344.129071 -382.15634) (xy 344.137116 -382.089516) (xy 344.15309 -382.024134)
			(xy 344.176764 -381.961129) (xy 344.207798 -381.901405) (xy 344.245748 -381.845818) (xy 344.267536 -381.820166)
			(xy 344.273334 -381.813022) (xy 344.279847 -381.79583) (xy 344.280236 -381.786638) (xy 344.280236 -381.628904)
			(xy 344.280626 -381.618746) (xy 344.288427 -381.599986) (xy 344.302834 -381.585662) (xy 344.321637 -381.577968)
			(xy 344.331798 -381.577596) (xy 345.048078 -381.577596) (xy 345.058198 -381.578143) (xy 345.07691 -381.585856)
			(xy 345.091266 -381.600123) (xy 345.099094 -381.618787) (xy 345.09964 -381.628904) (xy 345.09964 -381.786638)
			(xy 345.100045 -381.795825) (xy 345.106564 -381.813009) (xy 345.11234 -381.820166) (xy 345.134118 -381.845826)
			(xy 345.172069 -381.901411) (xy 345.203104 -381.961133) (xy 345.226778 -382.024137) (xy 345.242752 -382.089518)
			(xy 345.250798 -382.15634) (xy 345.250798 -382.223645) (xy 345.250798 -382.223646) (xy 374.9291 -382.223646)
			(xy 374.929101 -382.156339) (xy 374.937147 -382.089515) (xy 374.953122 -382.024132) (xy 374.976798 -381.961127)
			(xy 375.007834 -381.901404) (xy 375.045787 -381.845818) (xy 375.067576 -381.820166) (xy 375.073367 -381.813016)
			(xy 375.079886 -381.795829) (xy 375.080276 -381.786638) (xy 375.080276 -381.628904) (xy 375.080724 -381.618753)
			(xy 375.088514 -381.600005) (xy 375.102902 -381.585683) (xy 375.121685 -381.577979) (xy 375.131838 -381.577596)
			(xy 375.848118 -381.577596) (xy 375.85824 -381.57811) (xy 375.876954 -381.585836) (xy 375.891308 -381.600113)
			(xy 375.899134 -381.618784) (xy 375.89968 -381.628904) (xy 375.89968 -381.786638) (xy 375.900076 -381.795827)
			(xy 375.9066 -381.813011) (xy 375.91238 -381.820166) (xy 375.934157 -381.845826) (xy 375.972105 -381.901412)
			(xy 376.003138 -381.961135) (xy 376.02681 -382.024138) (xy 376.042784 -382.089519) (xy 376.050828 -382.156341)
			(xy 376.050829 -382.223644) (xy 376.050822 -382.223704) (xy 379.328893 -382.223704) (xy 379.328894 -382.156281)
			(xy 379.33697 -382.089342) (xy 379.353006 -382.023853) (xy 379.37677 -381.960756) (xy 379.40792 -381.900959)
			(xy 379.446008 -381.845324) (xy 379.467872 -381.819658) (xy 379.473678 -381.81252) (xy 379.480185 -381.795324)
			(xy 379.480572 -381.78613) (xy 379.480572 -381.628904) (xy 379.481088 -381.618799) (xy 379.488819 -381.600126)
			(xy 379.503106 -381.585832) (xy 379.521775 -381.578092) (xy 379.53188 -381.577596) (xy 380.24816 -381.577596)
			(xy 380.258279 -381.578049) (xy 380.276981 -381.585783) (xy 380.291297 -381.600088) (xy 380.299044 -381.618785)
			(xy 380.299468 -381.628904) (xy 380.299468 -381.78613) (xy 380.299871 -381.795318) (xy 380.30639 -381.812502)
			(xy 380.312168 -381.819658) (xy 380.334023 -381.845331) (xy 380.372114 -381.900963) (xy 380.403267 -381.960758)
			(xy 380.427033 -382.023854) (xy 380.443071 -382.089343) (xy 380.451148 -382.156281) (xy 380.451149 -382.223646)
			(xy 383.729188 -382.223646) (xy 383.729189 -382.156339) (xy 383.737235 -382.089516) (xy 383.753209 -382.024133)
			(xy 383.776884 -381.961128) (xy 383.80792 -381.901404) (xy 383.845871 -381.845818) (xy 383.86766 -381.820166)
			(xy 383.873461 -381.813024) (xy 383.879971 -381.795831) (xy 383.88036 -381.786638) (xy 383.88036 -381.628904)
			(xy 383.880824 -381.618755) (xy 383.888611 -381.600011) (xy 383.902994 -381.585689) (xy 383.921771 -381.577981)
			(xy 383.931922 -381.577596) (xy 384.648202 -381.577596) (xy 384.658323 -381.578124) (xy 384.677036 -381.585844)
			(xy 384.691391 -381.600117) (xy 384.699218 -381.618786) (xy 384.699764 -381.628904) (xy 384.699764 -381.786638)
			(xy 384.700164 -381.795826) (xy 384.706686 -381.81301) (xy 384.712464 -381.820166) (xy 384.734242 -381.845826)
			(xy 384.772191 -381.901412) (xy 384.803224 -381.961134) (xy 384.826898 -382.024137) (xy 384.842871 -382.089519)
			(xy 384.850916 -382.15634) (xy 384.850917 -382.223645) (xy 388.128979 -382.223645) (xy 388.12898 -382.156339)
			(xy 388.137025 -382.089516) (xy 388.152999 -382.024133) (xy 388.176674 -381.961128) (xy 388.207709 -381.901404)
			(xy 388.245659 -381.845818) (xy 388.267448 -381.820166) (xy 388.273247 -381.813023) (xy 388.279759 -381.795831)
			(xy 388.280148 -381.786638) (xy 388.280148 -381.628904) (xy 388.280624 -381.618757) (xy 388.288408 -381.600014)
			(xy 388.302788 -381.585693) (xy 388.321561 -381.577984) (xy 388.33171 -381.577596) (xy 389.04799 -381.577596)
			(xy 389.058111 -381.578133) (xy 389.076823 -381.58585) (xy 389.091178 -381.60012) (xy 389.099006 -381.618786)
			(xy 389.099552 -381.628904) (xy 389.099552 -381.786638) (xy 389.099955 -381.795826) (xy 389.106475 -381.813009)
			(xy 389.112252 -381.820166) (xy 389.13403 -381.845826) (xy 389.17198 -381.901411) (xy 389.203014 -381.961134)
			(xy 389.226688 -382.024137) (xy 389.242662 -382.089518) (xy 389.250707 -382.15634) (xy 389.250707 -382.223645)
			(xy 389.250707 -382.223646) (xy 418.92901 -382.223646) (xy 418.92901 -382.156339) (xy 418.937056 -382.089515)
			(xy 418.953032 -382.024132) (xy 418.976708 -381.961127) (xy 419.007745 -381.901403) (xy 419.045698 -381.845818)
			(xy 419.067488 -381.820166) (xy 419.07328 -381.813018) (xy 419.079798 -381.79583) (xy 419.080188 -381.786638)
			(xy 419.080188 -381.628904) (xy 419.080688 -381.618797) (xy 419.088422 -381.600121) (xy 419.102714 -381.585827)
			(xy 419.121389 -381.57809) (xy 419.131496 -381.577596) (xy 419.84803 -381.577596) (xy 419.858153 -381.578101)
			(xy 419.876867 -381.58583) (xy 419.89122 -381.60011) (xy 419.899046 -381.618783) (xy 419.899592 -381.628904)
			(xy 419.899592 -381.786638) (xy 419.899986 -381.795827) (xy 419.906511 -381.813011) (xy 419.912292 -381.820166)
			(xy 419.934069 -381.845827) (xy 419.972016 -381.901413) (xy 420.003048 -381.961135) (xy 420.02672 -382.024139)
			(xy 420.042693 -382.089519) (xy 420.050737 -382.156341) (xy 420.050738 -382.223644) (xy 420.050731 -382.223705)
			(xy 423.328802 -382.223705) (xy 423.328803 -382.15628) (xy 423.33688 -382.089342) (xy 423.352916 -382.023852)
			(xy 423.37668 -381.960755) (xy 423.407831 -381.900959) (xy 423.44592 -381.845324) (xy 423.467784 -381.819658)
			(xy 423.473579 -381.812512) (xy 423.480095 -381.795322) (xy 423.480484 -381.78613) (xy 423.480484 -381.628904)
			(xy 423.480988 -381.618798) (xy 423.488721 -381.600122) (xy 423.503012 -381.585828) (xy 423.521686 -381.57809)
			(xy 423.531792 -381.577596) (xy 424.248072 -381.577596) (xy 424.258192 -381.578039) (xy 424.276895 -381.585777)
			(xy 424.29121 -381.600085) (xy 424.298957 -381.618784) (xy 424.29938 -381.628904) (xy 424.29938 -381.78613)
			(xy 424.29978 -381.795318) (xy 424.306301 -381.812502) (xy 424.31208 -381.819658) (xy 424.333935 -381.845331)
			(xy 424.372025 -381.900964) (xy 424.403177 -381.960759) (xy 424.426943 -382.023855) (xy 424.44298 -382.089343)
			(xy 424.451057 -382.156281) (xy 424.451058 -382.223646) (xy 427.729097 -382.223646) (xy 427.729098 -382.156339)
			(xy 427.737144 -382.089515) (xy 427.753119 -382.024132) (xy 427.776794 -381.961127) (xy 427.807831 -381.901404)
			(xy 427.845783 -381.845818) (xy 427.867572 -381.820166) (xy 427.873374 -381.813025) (xy 427.879883 -381.795831)
			(xy 427.880272 -381.786638) (xy 427.880272 -381.628904) (xy 427.880724 -381.618754) (xy 427.888513 -381.600007)
			(xy 427.9029 -381.585684) (xy 427.921682 -381.577979) (xy 427.931834 -381.577596) (xy 428.648114 -381.577596)
			(xy 428.658236 -381.578114) (xy 428.676949 -381.585838) (xy 428.691303 -381.600114) (xy 428.69913 -381.618785)
			(xy 428.699676 -381.628904) (xy 428.699676 -381.786638) (xy 428.700073 -381.795826) (xy 428.706596 -381.81301)
			(xy 428.712376 -381.820166) (xy 428.734154 -381.845826) (xy 428.772102 -381.901412) (xy 428.803135 -381.961135)
			(xy 428.826807 -382.024138) (xy 428.84278 -382.089519) (xy 428.850825 -382.15634) (xy 428.850826 -382.223644)
			(xy 428.850826 -382.223646) (xy 432.128888 -382.223646) (xy 432.128889 -382.156339) (xy 432.136935 -382.089516)
			(xy 432.152909 -382.024133) (xy 432.176584 -381.961128) (xy 432.20762 -381.901404) (xy 432.245571 -381.845818)
			(xy 432.26736 -381.820166) (xy 432.273161 -381.813024) (xy 432.279671 -381.795831) (xy 432.28006 -381.786638)
			(xy 432.28006 -381.628904) (xy 432.280524 -381.618755) (xy 432.288311 -381.600011) (xy 432.302694 -381.585689)
			(xy 432.321471 -381.577981) (xy 432.331622 -381.577596) (xy 433.047902 -381.577596) (xy 433.058023 -381.578124)
			(xy 433.076736 -381.585844) (xy 433.091091 -381.600117) (xy 433.098918 -381.618786) (xy 433.099464 -381.628904)
			(xy 433.099464 -381.786638) (xy 433.099864 -381.795826) (xy 433.106386 -381.81301) (xy 433.112164 -381.820166)
			(xy 433.133942 -381.845826) (xy 433.171891 -381.901412) (xy 433.202924 -381.961134) (xy 433.226598 -382.024137)
			(xy 433.242571 -382.089519) (xy 433.250616 -382.15634) (xy 433.250617 -382.223645) (xy 433.242574 -382.290466)
			(xy 433.226602 -382.355848) (xy 433.202931 -382.418852) (xy 433.171899 -382.478576) (xy 433.133951 -382.534162)
			(xy 433.112164 -382.559814) (xy 433.106374 -382.566964) (xy 433.099856 -382.584151) (xy 433.099464 -382.593342)
			(xy 433.099464 -383.086864) (xy 433.0999 -383.096048) (xy 433.106397 -383.113232) (xy 433.112164 -383.120392)
			(xy 433.133967 -383.146031) (xy 433.171916 -383.20162) (xy 433.202948 -383.261345) (xy 433.226386 -383.323727)
			(xy 434.32903 -383.323727) (xy 434.329034 -383.256419) (xy 434.337081 -383.189595) (xy 434.353057 -383.124211)
			(xy 434.376732 -383.061205) (xy 434.407768 -383.00148) (xy 434.445719 -382.945893) (xy 434.467508 -382.92024)
			(xy 434.473313 -382.913101) (xy 434.479823 -382.895906) (xy 434.480208 -382.886712) (xy 434.480208 -382.728724)
			(xy 434.480641 -382.71857) (xy 434.48843 -382.699817) (xy 434.502824 -382.685492) (xy 434.521614 -382.677793)
			(xy 434.53177 -382.677416) (xy 435.24805 -382.677416) (xy 435.258171 -382.677967) (xy 435.276886 -382.685674)
			(xy 435.291243 -382.69994) (xy 435.299068 -382.718607) (xy 435.299612 -382.728724) (xy 435.299612 -382.886712)
			(xy 435.300014 -382.8959) (xy 435.306533 -382.913084) (xy 435.312312 -382.92024) (xy 435.334066 -382.945921)
			(xy 435.372019 -383.001502) (xy 435.403056 -383.061221) (xy 435.426733 -383.124222) (xy 435.44271 -383.189601)
			(xy 435.450758 -383.256421) (xy 435.450761 -383.323724) (xy 435.44272 -383.390546) (xy 435.426749 -383.455926)
			(xy 435.403079 -383.518929) (xy 435.372047 -383.578652) (xy 435.334099 -383.634237) (xy 435.312312 -383.659888)
			(xy 435.306497 -383.66702) (xy 435.299993 -383.684221) (xy 435.299612 -383.693416) (xy 435.299612 -384.186684)
			(xy 435.300027 -384.195871) (xy 435.306537 -384.213055) (xy 435.312312 -384.220212) (xy 435.334137 -384.245834)
			(xy 435.372087 -384.301424) (xy 435.403122 -384.361151) (xy 435.426795 -384.42416) (xy 435.442767 -384.489546)
			(xy 435.450809 -384.556373) (xy 435.450805 -384.623681) (xy 435.442757 -384.690507) (xy 435.426779 -384.755892)
			(xy 435.4031 -384.818898) (xy 435.37206 -384.878623) (xy 435.334103 -384.934208) (xy 435.312312 -384.95986)
			(xy 435.306509 -384.967001) (xy 435.299998 -384.984195) (xy 435.299612 -384.993388) (xy 435.299612 -385.151376)
			(xy 435.299159 -385.161527) (xy 435.291374 -385.180277) (xy 435.276987 -385.194601) (xy 435.258203 -385.202303)
			(xy 435.24805 -385.202684) (xy 434.53177 -385.202684) (xy 434.521644 -385.202199) (xy 434.502927 -385.194466)
			(xy 434.488573 -385.180179) (xy 434.48075 -385.161499) (xy 434.480208 -385.151376) (xy 434.480208 -384.993388)
			(xy 434.479802 -384.9842) (xy 434.473285 -384.967016) (xy 434.467508 -384.95986) (xy 434.445757 -384.934178)
			(xy 434.407809 -384.878595) (xy 434.376776 -384.818876) (xy 434.353102 -384.755875) (xy 434.337128 -384.690497)
			(xy 434.329081 -384.623678) (xy 434.329078 -384.556376) (xy 434.337118 -384.489557) (xy 434.353086 -384.424177)
			(xy 434.376753 -384.361174) (xy 434.407781 -384.301451) (xy 434.445723 -384.245864) (xy 434.467508 -384.220212)
			(xy 434.473325 -384.213082) (xy 434.479827 -384.19588) (xy 434.480208 -384.186684) (xy 434.480208 -383.693416)
			(xy 434.479788 -383.68423) (xy 434.473281 -383.667046) (xy 434.467508 -383.659888) (xy 434.445686 -383.634265)
			(xy 434.40774 -383.578673) (xy 434.37671 -383.518945) (xy 434.353041 -383.455937) (xy 434.337071 -383.390552)
			(xy 434.32903 -383.323727) (xy 433.226386 -383.323727) (xy 433.22662 -383.324351) (xy 433.242592 -383.389735)
			(xy 433.250634 -383.456559) (xy 433.250633 -383.523865) (xy 433.242587 -383.590689) (xy 433.226613 -383.656072)
			(xy 433.202938 -383.719077) (xy 433.171903 -383.778801) (xy 433.133953 -383.834388) (xy 433.112164 -383.86004)
			(xy 433.106363 -383.867182) (xy 433.099852 -383.884375) (xy 433.099464 -383.893568) (xy 433.099464 -384.051556)
			(xy 433.099042 -384.061712) (xy 433.091254 -384.08047) (xy 433.076856 -384.094796) (xy 433.05806 -384.102491)
			(xy 433.047902 -384.102864) (xy 432.331622 -384.102864) (xy 432.321497 -384.102356) (xy 432.302777 -384.094636)
			(xy 432.28842 -384.080356) (xy 432.2806 -384.061678) (xy 432.28006 -384.051556) (xy 432.28006 -383.893568)
			(xy 432.279652 -383.884381) (xy 432.273135 -383.867197) (xy 432.26736 -383.86004) (xy 432.245587 -383.834375)
			(xy 432.207637 -383.778791) (xy 432.176602 -383.719069) (xy 432.152927 -383.656066) (xy 432.136952 -383.590686)
			(xy 432.128907 -383.523864) (xy 432.128905 -383.45656) (xy 432.136948 -383.389738) (xy 432.15292 -383.324357)
			(xy 432.176592 -383.261353) (xy 432.207624 -383.20163) (xy 432.245573 -383.146044) (xy 432.26736 -383.120392)
			(xy 432.27315 -383.113242) (xy 432.279667 -383.096055) (xy 432.28006 -383.086864) (xy 432.28006 -382.593342)
			(xy 432.279616 -382.584159) (xy 432.273125 -382.566975) (xy 432.26736 -382.559814) (xy 432.245562 -382.53417)
			(xy 432.207612 -382.478583) (xy 432.176578 -382.418858) (xy 432.152905 -382.355853) (xy 432.136932 -382.290469)
			(xy 432.128888 -382.223646) (xy 428.850826 -382.223646) (xy 428.842783 -382.290466) (xy 428.826812 -382.355848)
			(xy 428.803141 -382.418852) (xy 428.772109 -382.478575) (xy 428.734163 -382.534162) (xy 428.712376 -382.559814)
			(xy 428.706588 -382.566965) (xy 428.700069 -382.584151) (xy 428.699676 -382.593342) (xy 428.699676 -383.086864)
			(xy 428.700109 -383.096049) (xy 428.706607 -383.113233) (xy 428.712376 -383.120392) (xy 428.734179 -383.146031)
			(xy 428.772126 -383.20162) (xy 428.803158 -383.261345) (xy 428.826616 -383.323786) (xy 429.928711 -383.323786)
			(xy 429.928714 -383.25636) (xy 429.936794 -383.189418) (xy 429.952834 -383.123927) (xy 429.976603 -383.060829)
			(xy 430.007759 -383.001032) (xy 430.045853 -382.945397) (xy 430.06772 -382.919732) (xy 430.07353 -382.912597)
			(xy 430.080036 -382.895398) (xy 430.08042 -382.886204) (xy 430.08042 -382.728724) (xy 430.080836 -382.718601)
			(xy 430.08858 -382.699894) (xy 430.102897 -382.685578) (xy 430.121605 -382.677835) (xy 430.131728 -382.677416)
			(xy 430.848008 -382.677416) (xy 430.858133 -382.67781) (xy 430.87684 -382.685564) (xy 430.891154 -382.699887)
			(xy 430.898896 -382.718599) (xy 430.899316 -382.728724) (xy 430.899316 -382.886204) (xy 430.899721 -382.895392)
			(xy 430.906238 -382.912576) (xy 430.912016 -382.919732) (xy 430.933844 -382.945427) (xy 430.971933 -383.001057)
			(xy 431.003084 -383.06085) (xy 431.02685 -383.123943) (xy 431.042887 -383.189428) (xy 431.050966 -383.256363)
			(xy 431.050969 -383.323783) (xy 431.042897 -383.390719) (xy 431.026866 -383.456206) (xy 431.003106 -383.519301)
			(xy 430.971961 -383.579096) (xy 430.933877 -383.634731) (xy 430.912016 -383.660396) (xy 430.90624 -383.667556)
			(xy 430.899713 -383.684735) (xy 430.899316 -383.693924) (xy 430.899316 -384.186176) (xy 430.899734 -384.195362)
			(xy 430.906242 -384.212547) (xy 430.912016 -384.219704) (xy 430.933915 -384.24534) (xy 430.972001 -384.300979)
			(xy 431.00315 -384.36078) (xy 431.026911 -384.42388) (xy 431.042944 -384.489373) (xy 431.051016 -384.556314)
			(xy 431.051013 -384.62374) (xy 431.042934 -384.690681) (xy 431.026895 -384.756171) (xy 431.003128 -384.81927)
			(xy 430.971974 -384.879067) (xy 430.933882 -384.934702) (xy 430.912016 -384.960368) (xy 430.90621 -384.967507)
			(xy 430.8997 -384.984702) (xy 430.899316 -384.993896) (xy 430.899316 -385.151376) (xy 430.898865 -385.161495)
			(xy 430.891128 -385.180195) (xy 430.876822 -385.19451) (xy 430.858127 -385.202259) (xy 430.848008 -385.202684)
			(xy 430.131728 -385.202684) (xy 430.121605 -385.202261) (xy 430.102899 -385.194519) (xy 430.088583 -385.180204)
			(xy 430.08084 -385.161499) (xy 430.08042 -385.151376) (xy 430.08042 -384.993896) (xy 430.080008 -384.984709)
			(xy 430.073495 -384.967525) (xy 430.06772 -384.960368) (xy 430.045891 -384.934674) (xy 430.0078 -384.879044)
			(xy 429.976646 -384.819252) (xy 429.952879 -384.756159) (xy 429.936841 -384.690673) (xy 429.928761 -384.623738)
			(xy 429.928758 -384.556316) (xy 429.936831 -384.48938) (xy 429.952863 -384.423893) (xy 429.976624 -384.360797)
			(xy 430.007772 -384.301002) (xy 430.045857 -384.245369) (xy 430.06772 -384.219704) (xy 430.0735 -384.212547)
			(xy 430.080024 -384.195365) (xy 430.08042 -384.186176) (xy 430.08042 -383.693924) (xy 430.079994 -383.684739)
			(xy 430.073491 -383.667554) (xy 430.06772 -383.660396) (xy 430.04582 -383.63476) (xy 430.007731 -383.579122)
			(xy 429.976581 -383.519322) (xy 429.952818 -383.456221) (xy 429.936784 -383.390728) (xy 429.928711 -383.323786)
			(xy 428.826616 -383.323786) (xy 428.826829 -383.324352) (xy 428.842801 -383.389735) (xy 428.850843 -383.456559)
			(xy 428.850842 -383.523865) (xy 428.842797 -383.590688) (xy 428.826822 -383.656071) (xy 428.803148 -383.719077)
			(xy 428.772114 -383.778801) (xy 428.734164 -383.834388) (xy 428.712376 -383.86004) (xy 428.706577 -383.867183)
			(xy 428.700065 -383.884375) (xy 428.699676 -383.893568) (xy 428.699676 -384.051556) (xy 428.699242 -384.06171)
			(xy 428.691456 -384.080466) (xy 428.677063 -384.094792) (xy 428.65827 -384.102489) (xy 428.648114 -384.102864)
			(xy 427.931834 -384.102864) (xy 427.92171 -384.102345) (xy 427.90299 -384.09463) (xy 427.888633 -384.080353)
			(xy 427.880812 -384.061677) (xy 427.880272 -384.051556) (xy 427.880272 -383.893568) (xy 427.879883 -383.884378)
			(xy 427.873355 -383.867194) (xy 427.867572 -383.86004) (xy 427.845799 -383.834375) (xy 427.807848 -383.778791)
			(xy 427.776812 -383.71907) (xy 427.753137 -383.656067) (xy 427.737162 -383.590686) (xy 427.729116 -383.523864)
			(xy 427.729114 -383.45656) (xy 427.737157 -383.389738) (xy 427.75313 -383.324356) (xy 427.776802 -383.261352)
			(xy 427.807835 -383.201629) (xy 427.845784 -383.146044) (xy 427.867572 -383.120392) (xy 427.873363 -383.113243)
			(xy 427.879879 -383.096055) (xy 427.880272 -383.086864) (xy 427.880272 -382.593342) (xy 427.879848 -382.584156)
			(xy 427.873344 -382.566971) (xy 427.867572 -382.559814) (xy 427.845774 -382.53417) (xy 427.807823 -382.478583)
			(xy 427.776788 -382.418859) (xy 427.753115 -382.355853) (xy 427.737141 -382.29047) (xy 427.729097 -382.223646)
			(xy 424.451058 -382.223646) (xy 424.451058 -382.223704) (xy 424.442983 -382.290642) (xy 424.426948 -382.356131)
			(xy 424.403184 -382.419227) (xy 424.372033 -382.479023) (xy 424.333944 -382.534657) (xy 424.31208 -382.560322)
			(xy 424.306289 -382.567471) (xy 424.299772 -382.584659) (xy 424.29938 -382.59385) (xy 424.29938 -383.086356)
			(xy 424.299816 -383.09554) (xy 424.306312 -383.112725) (xy 424.31208 -383.119884) (xy 424.33396 -383.145536)
			(xy 424.37205 -383.201172) (xy 424.403201 -383.26097) (xy 424.426837 -383.323727) (xy 425.528942 -383.323727)
			(xy 425.528946 -383.256419) (xy 425.536993 -383.189594) (xy 425.55297 -383.12421) (xy 425.576646 -383.061204)
			(xy 425.607682 -383.00148) (xy 425.645635 -382.945892) (xy 425.667424 -382.92024) (xy 425.673231 -382.913103)
			(xy 425.679739 -382.895906) (xy 425.680124 -382.886712) (xy 425.680124 -382.728724) (xy 425.680536 -382.7186)
			(xy 425.688281 -382.699892) (xy 425.702599 -382.685576) (xy 425.721308 -382.677834) (xy 425.731432 -382.677416)
			(xy 426.447966 -382.677416) (xy 426.458088 -382.677954) (xy 426.476803 -382.685666) (xy 426.49116 -382.699937)
			(xy 426.498984 -382.718606) (xy 426.499528 -382.728724) (xy 426.499528 -382.886712) (xy 426.499926 -382.895901)
			(xy 426.506447 -382.913085) (xy 426.512228 -382.92024) (xy 426.533981 -382.945921) (xy 426.571933 -383.001502)
			(xy 426.60297 -383.061222) (xy 426.626646 -383.124223) (xy 426.642623 -383.189602) (xy 426.65067 -383.256422)
			(xy 426.650673 -383.323724) (xy 426.642632 -383.390545) (xy 426.626662 -383.455926) (xy 426.602992 -383.518929)
			(xy 426.571961 -383.578651) (xy 426.534014 -383.634236) (xy 426.512228 -383.659888) (xy 426.506403 -383.667013)
			(xy 426.499907 -383.684219) (xy 426.499528 -383.693416) (xy 426.499528 -384.186684) (xy 426.499939 -384.195871)
			(xy 426.506451 -384.213056) (xy 426.512228 -384.220212) (xy 426.534052 -384.245834) (xy 426.572002 -384.301424)
			(xy 426.603036 -384.361152) (xy 426.626708 -384.42416) (xy 426.64268 -384.489546) (xy 426.650721 -384.556373)
			(xy 426.650718 -384.623681) (xy 426.64267 -384.690507) (xy 426.626692 -384.755892) (xy 426.603014 -384.818898)
			(xy 426.571974 -384.878622) (xy 426.534019 -384.934208) (xy 426.512228 -384.95986) (xy 426.506415 -384.966993)
			(xy 426.499912 -384.984193) (xy 426.499528 -384.993388) (xy 426.499528 -385.151376) (xy 426.499065 -385.161494)
			(xy 426.49133 -385.180191) (xy 426.477028 -385.194505) (xy 426.458337 -385.202257) (xy 426.44822 -385.202684)
			(xy 425.731686 -385.202684) (xy 425.721561 -385.202185) (xy 425.702845 -385.194457) (xy 425.68849 -385.180175)
			(xy 425.680667 -385.161498) (xy 425.680124 -385.151376) (xy 425.680124 -384.993388) (xy 425.679714 -384.984201)
			(xy 425.6732 -384.967017) (xy 425.667424 -384.95986) (xy 425.645672 -384.934178) (xy 425.607723 -384.878596)
			(xy 425.576689 -384.818876) (xy 425.553015 -384.755876) (xy 425.53704 -384.690497) (xy 425.528994 -384.623678)
			(xy 425.52899 -384.556376) (xy 425.537031 -384.489556) (xy 425.552999 -384.424176) (xy 425.576667 -384.361173)
			(xy 425.607696 -384.301451) (xy 425.645639 -384.245865) (xy 425.667424 -384.220212) (xy 425.673243 -384.213083)
			(xy 425.679744 -384.19588) (xy 425.680124 -384.186684) (xy 425.680124 -383.693416) (xy 425.679701 -383.68423)
			(xy 425.673195 -383.667046) (xy 425.667424 -383.659888) (xy 425.645601 -383.634265) (xy 425.607655 -383.578674)
			(xy 425.576624 -383.518946) (xy 425.552954 -383.455938) (xy 425.536984 -383.390552) (xy 425.528942 -383.323727)
			(xy 424.426837 -383.323727) (xy 424.426965 -383.324068) (xy 424.443 -383.389559) (xy 424.451075 -383.456499)
			(xy 424.451074 -383.523925) (xy 424.442996 -383.590864) (xy 424.426958 -383.656355) (xy 424.403191 -383.719452)
			(xy 424.372038 -383.779249) (xy 424.333946 -383.834883) (xy 424.31208 -383.860548) (xy 424.306278 -383.867689)
			(xy 424.299767 -383.884883) (xy 424.29938 -383.894076) (xy 424.29938 -384.051556) (xy 424.298947 -384.061678)
			(xy 424.29121 -384.080385) (xy 424.276898 -384.094701) (xy 424.258194 -384.102444) (xy 424.248072 -384.102864)
			(xy 423.531792 -384.102864) (xy 423.521665 -384.10249) (xy 423.502954 -384.094732) (xy 423.488639 -384.080402)
			(xy 423.4809 -384.061684) (xy 423.480484 -384.051556) (xy 423.480484 -383.894076) (xy 423.480089 -383.884887)
			(xy 423.473565 -383.867703) (xy 423.467784 -383.860548) (xy 423.445936 -383.83487) (xy 423.407848 -383.779237)
			(xy 423.376698 -383.719442) (xy 423.352933 -383.656347) (xy 423.336897 -383.59086) (xy 423.32882 -383.523923)
			(xy 423.328819 -383.456501) (xy 423.336893 -383.389564) (xy 423.352926 -383.324076) (xy 423.376688 -383.26098)
			(xy 423.407836 -383.201184) (xy 423.445922 -383.145549) (xy 423.467784 -383.119884) (xy 423.473568 -383.11273)
			(xy 423.480091 -383.095546) (xy 423.480484 -383.086356) (xy 423.480484 -382.59385) (xy 423.480054 -382.584665)
			(xy 423.473554 -382.56748) (xy 423.467784 -382.560322) (xy 423.445911 -382.534665) (xy 423.407823 -382.479029)
			(xy 423.376674 -382.419231) (xy 423.352911 -382.356133) (xy 423.336877 -382.290643) (xy 423.328802 -382.223705)
			(xy 420.050731 -382.223705) (xy 420.042695 -382.290466) (xy 420.026725 -382.355847) (xy 420.003054 -382.418851)
			(xy 419.972024 -382.478574) (xy 419.934078 -382.534161) (xy 419.912292 -382.559814) (xy 419.906506 -382.566967)
			(xy 419.899985 -382.584151) (xy 419.899592 -382.593342) (xy 419.899592 -383.086864) (xy 419.900021 -383.096049)
			(xy 419.906522 -383.113234) (xy 419.912292 -383.120392) (xy 419.934094 -383.146032) (xy 419.972041 -383.201621)
			(xy 420.003072 -383.261346) (xy 420.02653 -383.323787) (xy 421.128623 -383.323787) (xy 421.128626 -383.256359)
			(xy 421.136706 -383.189418) (xy 421.152747 -383.123926) (xy 421.176516 -383.060828) (xy 421.207673 -383.001031)
			(xy 421.245769 -382.945397) (xy 421.267636 -382.919732) (xy 421.273449 -382.912598) (xy 421.279953 -382.895399)
			(xy 421.280336 -382.886204) (xy 421.280336 -382.728724) (xy 421.280736 -382.718599) (xy 421.288483 -382.699889)
			(xy 421.302805 -382.685572) (xy 421.321518 -382.677832) (xy 421.331644 -382.677416) (xy 422.047924 -382.677416)
			(xy 422.058036 -382.677866) (xy 422.076718 -382.685614) (xy 422.091013 -382.699922) (xy 422.098744 -382.718611)
			(xy 422.099232 -382.728724) (xy 422.099232 -382.886204) (xy 422.099656 -382.895389) (xy 422.106162 -382.912573)
			(xy 422.111932 -382.919732) (xy 422.133759 -382.945427) (xy 422.171847 -383.001058) (xy 422.202998 -383.06085)
			(xy 422.226762 -383.123943) (xy 422.242799 -383.189428) (xy 422.250878 -383.256363) (xy 422.250881 -383.323783)
			(xy 422.242809 -383.390718) (xy 422.226778 -383.456205) (xy 422.20302 -383.5193) (xy 422.171875 -383.579096)
			(xy 422.133793 -383.63473) (xy 422.111932 -383.660396) (xy 422.106146 -383.667549) (xy 422.099627 -383.684734)
			(xy 422.099232 -383.693924) (xy 422.099232 -384.186176) (xy 422.099669 -384.19536) (xy 422.106166 -384.212544)
			(xy 422.111932 -384.219704) (xy 422.13383 -384.245341) (xy 422.171916 -384.30098) (xy 422.203063 -384.36078)
			(xy 422.226824 -384.423881) (xy 422.242856 -384.489373) (xy 422.250928 -384.556314) (xy 422.250925 -384.62374)
			(xy 422.242846 -384.69068) (xy 422.226808 -384.756171) (xy 422.203041 -384.819269) (xy 422.171888 -384.879066)
			(xy 422.133797 -384.934702) (xy 422.111932 -384.960368) (xy 422.106116 -384.967499) (xy 422.099615 -384.984701)
			(xy 422.099232 -384.993896) (xy 422.099232 -385.151376) (xy 422.098696 -385.161479) (xy 422.090972 -385.180151)
			(xy 422.076691 -385.194445) (xy 422.058027 -385.202187) (xy 422.047924 -385.202684) (xy 421.331644 -385.202684)
			(xy 421.321522 -385.202247) (xy 421.302817 -385.194511) (xy 421.2885 -385.1802) (xy 421.280756 -385.161497)
			(xy 421.280336 -385.151376) (xy 421.280336 -384.993896) (xy 421.27992 -384.98471) (xy 421.27341 -384.967526)
			(xy 421.267636 -384.960368) (xy 421.245806 -384.934674) (xy 421.207714 -384.879045) (xy 421.17656 -384.819253)
			(xy 421.152792 -384.756159) (xy 421.136753 -384.690673) (xy 421.128674 -384.623738) (xy 421.12867 -384.556316)
			(xy 421.136743 -384.48938) (xy 421.152776 -384.423892) (xy 421.176538 -384.360797) (xy 421.207686 -384.301002)
			(xy 421.245773 -384.245369) (xy 421.267636 -384.219704) (xy 421.273418 -384.212549) (xy 421.27994 -384.195366)
			(xy 421.280336 -384.186176) (xy 421.280336 -383.693924) (xy 421.279906 -383.684739) (xy 421.273405 -383.667555)
			(xy 421.267636 -383.660396) (xy 421.245735 -383.634761) (xy 421.207645 -383.579123) (xy 421.176494 -383.519323)
			(xy 421.152731 -383.456222) (xy 421.136696 -383.390729) (xy 421.128623 -383.323787) (xy 420.02653 -383.323787)
			(xy 420.026742 -383.324352) (xy 420.042713 -383.389736) (xy 420.050756 -383.456559) (xy 420.050754 -383.523865)
			(xy 420.042709 -383.590688) (xy 420.026735 -383.656071) (xy 420.003062 -383.719076) (xy 419.972028 -383.7788)
			(xy 419.93408 -383.834387) (xy 419.912292 -383.86004) (xy 419.906495 -383.867185) (xy 419.899981 -383.884376)
			(xy 419.899592 -383.893568) (xy 419.899592 -384.051556) (xy 419.899148 -384.061677) (xy 419.891413 -384.080381)
			(xy 419.877104 -384.094697) (xy 419.858404 -384.102442) (xy 419.848284 -384.102864) (xy 419.13175 -384.102864)
			(xy 419.121627 -384.102333) (xy 419.102908 -384.094622) (xy 419.08855 -384.080349) (xy 419.080728 -384.061676)
			(xy 419.080188 -384.051556) (xy 419.080188 -383.893568) (xy 419.079796 -383.884379) (xy 419.07327 -383.867194)
			(xy 419.067488 -383.86004) (xy 419.045715 -383.834376) (xy 419.007762 -383.778792) (xy 418.976725 -383.719071)
			(xy 418.95305 -383.656068) (xy 418.937074 -383.590686) (xy 418.929028 -383.523864) (xy 418.929026 -383.45656)
			(xy 418.93707 -383.389737) (xy 418.953042 -383.324355) (xy 418.976716 -383.261351) (xy 419.00775 -383.201629)
			(xy 419.0457 -383.146043) (xy 419.067488 -383.120392) (xy 419.073269 -383.113236) (xy 419.079793 -383.096054)
			(xy 419.080188 -383.086864) (xy 419.080188 -382.593342) (xy 419.07976 -382.584157) (xy 419.073259 -382.566972)
			(xy 419.067488 -382.559814) (xy 419.045689 -382.534171) (xy 419.007737 -382.478584) (xy 418.976702 -382.41886)
			(xy 418.953027 -382.355854) (xy 418.937054 -382.29047) (xy 418.92901 -382.223646) (xy 389.250707 -382.223646)
			(xy 389.242664 -382.290467) (xy 389.226692 -382.355848) (xy 389.20302 -382.418853) (xy 389.171987 -382.478576)
			(xy 389.134039 -382.534162) (xy 389.112252 -382.559814) (xy 389.106461 -382.566963) (xy 389.099944 -382.584151)
			(xy 389.099552 -382.593342) (xy 389.099552 -383.086864) (xy 389.09999 -383.096048) (xy 389.106485 -383.113232)
			(xy 389.112252 -383.120392) (xy 389.134056 -383.146031) (xy 389.172005 -383.201619) (xy 389.203038 -383.261344)
			(xy 389.226475 -383.323726) (xy 390.329121 -383.323726) (xy 390.329125 -383.256419) (xy 390.337172 -383.189595)
			(xy 390.353147 -383.124211) (xy 390.376822 -383.061206) (xy 390.407857 -383.001481) (xy 390.445807 -382.945893)
			(xy 390.467596 -382.92024) (xy 390.4734 -382.9131) (xy 390.47991 -382.895906) (xy 390.480296 -382.886712)
			(xy 390.480296 -382.728724) (xy 390.480741 -382.718572) (xy 390.488528 -382.699821) (xy 390.502918 -382.685497)
			(xy 390.521704 -382.677795) (xy 390.531858 -382.677416) (xy 391.248138 -382.677416) (xy 391.258264 -382.677895)
			(xy 391.276982 -382.685631) (xy 391.291336 -382.699919) (xy 391.299158 -382.7186) (xy 391.2997 -382.728724)
			(xy 391.2997 -382.886712) (xy 391.300105 -382.8959) (xy 391.306622 -382.913084) (xy 391.3124 -382.92024)
			(xy 391.334151 -382.945922) (xy 391.372099 -383.001505) (xy 391.403131 -383.061225) (xy 391.426804 -383.124225)
			(xy 391.442779 -383.189603) (xy 391.450825 -383.256422) (xy 391.450828 -383.323724) (xy 391.442788 -383.390543)
			(xy 391.42682 -383.455923) (xy 391.403153 -383.518926) (xy 391.372126 -383.578649) (xy 391.334184 -383.634235)
			(xy 391.3124 -383.659888) (xy 391.306584 -383.667019) (xy 391.300081 -383.68422) (xy 391.2997 -383.693416)
			(xy 391.2997 -384.186684) (xy 391.300118 -384.19587) (xy 391.306626 -384.213055) (xy 391.3124 -384.220212)
			(xy 391.334222 -384.245836) (xy 391.372167 -384.301427) (xy 391.403197 -384.361155) (xy 391.426866 -384.424163)
			(xy 391.442835 -384.489548) (xy 391.450876 -384.556374) (xy 391.450872 -384.623681) (xy 391.442825 -384.690505)
			(xy 391.42685 -384.755889) (xy 391.403175 -384.818895) (xy 391.372139 -384.878619) (xy 391.334189 -384.934207)
			(xy 391.3124 -384.95986) (xy 391.306595 -384.967) (xy 391.300086 -384.984194) (xy 391.2997 -384.993388)
			(xy 391.2997 -385.151376) (xy 391.299259 -385.161529) (xy 391.291471 -385.180281) (xy 391.27708 -385.194605)
			(xy 391.258292 -385.202305) (xy 391.248138 -385.202684) (xy 390.531858 -385.202684) (xy 390.521732 -385.202209)
			(xy 390.503014 -385.194471) (xy 390.48866 -385.180182) (xy 390.480838 -385.1615) (xy 390.480296 -385.151376)
			(xy 390.480296 -384.993388) (xy 390.479892 -384.9842) (xy 390.473374 -384.967016) (xy 390.467596 -384.95986)
			(xy 390.445845 -384.934178) (xy 390.407898 -384.878595) (xy 390.376865 -384.818875) (xy 390.353192 -384.755875)
			(xy 390.337218 -384.690496) (xy 390.329172 -384.623678) (xy 390.329169 -384.556376) (xy 390.337209 -384.489557)
			(xy 390.353176 -384.424177) (xy 390.376843 -384.361174) (xy 390.40787 -384.301452) (xy 390.445812 -384.245865)
			(xy 390.467596 -384.220212) (xy 390.473412 -384.21308) (xy 390.479915 -384.19588) (xy 390.480296 -384.186684)
			(xy 390.480296 -383.693416) (xy 390.479879 -383.68423) (xy 390.47337 -383.667045) (xy 390.467596 -383.659888)
			(xy 390.445774 -383.634264) (xy 390.407829 -383.578673) (xy 390.3768 -383.518945) (xy 390.353131 -383.455937)
			(xy 390.337162 -383.390552) (xy 390.329121 -383.323726) (xy 389.226475 -383.323726) (xy 389.22671 -383.324351)
			(xy 389.242682 -383.389735) (xy 389.250725 -383.456559) (xy 389.250724 -383.523865) (xy 389.242678 -383.590689)
			(xy 389.226703 -383.656072) (xy 389.203028 -383.719078) (xy 389.171992 -383.778802) (xy 389.134041 -383.834388)
			(xy 389.112252 -383.86004) (xy 389.10645 -383.867181) (xy 389.09994 -383.884375) (xy 389.099552 -383.893568)
			(xy 389.099552 -384.051556) (xy 389.099043 -384.061701) (xy 389.091272 -384.080442) (xy 389.076902 -384.094765)
			(xy 389.058136 -384.102476) (xy 389.04799 -384.102864) (xy 388.33171 -384.102864) (xy 388.321584 -384.102365)
			(xy 388.302864 -384.094642) (xy 388.288508 -384.080359) (xy 388.280687 -384.061679) (xy 388.280148 -384.051556)
			(xy 388.280148 -383.893568) (xy 388.279742 -383.884381) (xy 388.273224 -383.867197) (xy 388.267448 -383.86004)
			(xy 388.245676 -383.834375) (xy 388.207726 -383.778791) (xy 388.176692 -383.719069) (xy 388.153018 -383.656066)
			(xy 388.137043 -383.590685) (xy 388.128998 -383.523864) (xy 388.128996 -383.45656) (xy 388.137039 -383.389738)
			(xy 388.15301 -383.324357) (xy 388.176682 -383.261353) (xy 388.207714 -383.20163) (xy 388.245661 -383.146044)
			(xy 388.267448 -383.120392) (xy 388.273236 -383.113241) (xy 388.279755 -383.096055) (xy 388.280148 -383.086864)
			(xy 388.280148 -382.593342) (xy 388.279707 -382.584158) (xy 388.273213 -382.566974) (xy 388.267448 -382.559814)
			(xy 388.24565 -382.53417) (xy 388.207701 -382.478583) (xy 388.176668 -382.418858) (xy 388.152995 -382.355852)
			(xy 388.137022 -382.290469) (xy 388.128979 -382.223645) (xy 384.850917 -382.223645) (xy 384.842874 -382.290466)
			(xy 384.826902 -382.355848) (xy 384.803231 -382.418852) (xy 384.772199 -382.478576) (xy 384.734251 -382.534162)
			(xy 384.712464 -382.559814) (xy 384.706674 -382.566964) (xy 384.700156 -382.584151) (xy 384.699764 -382.593342)
			(xy 384.699764 -383.086864) (xy 384.7002 -383.096048) (xy 384.706697 -383.113232) (xy 384.712464 -383.120392)
			(xy 384.734267 -383.146031) (xy 384.772216 -383.20162) (xy 384.803248 -383.261345) (xy 384.826708 -383.323786)
			(xy 385.928802 -383.323786) (xy 385.928805 -383.25636) (xy 385.936885 -383.189419) (xy 385.952924 -383.123928)
			(xy 385.976693 -383.060829) (xy 386.007848 -383.001032) (xy 386.045942 -382.945397) (xy 386.067808 -382.919732)
			(xy 386.073617 -382.912596) (xy 386.080124 -382.895398) (xy 386.080508 -382.886204) (xy 386.080508 -382.728724)
			(xy 386.080936 -382.718602) (xy 386.088677 -382.699897) (xy 386.102991 -382.685582) (xy 386.121694 -382.677837)
			(xy 386.131816 -382.677416) (xy 386.848096 -382.677416) (xy 386.85822 -382.67782) (xy 386.876927 -382.685569)
			(xy 386.891242 -382.69989) (xy 386.898984 -382.7186) (xy 386.899404 -382.728724) (xy 386.899404 -382.886204)
			(xy 386.899811 -382.895391) (xy 386.906327 -382.912576) (xy 386.912104 -382.919732) (xy 386.933932 -382.945426)
			(xy 386.972022 -383.001057) (xy 387.003174 -383.060849) (xy 387.02694 -383.123942) (xy 387.042978 -383.189428)
			(xy 387.051057 -383.256363) (xy 387.05106 -383.323783) (xy 387.042988 -383.390719) (xy 387.026956 -383.456206)
			(xy 387.003196 -383.519301) (xy 386.97205 -383.579097) (xy 386.933966 -383.634731) (xy 386.912104 -383.660396)
			(xy 386.906327 -383.667555) (xy 386.899801 -383.684735) (xy 386.899404 -383.693924) (xy 386.899404 -384.186176)
			(xy 386.899825 -384.195362) (xy 386.906331 -384.212547) (xy 386.912104 -384.219704) (xy 386.934003 -384.24534)
			(xy 386.972091 -384.300979) (xy 387.003239 -384.360779) (xy 387.027001 -384.42388) (xy 387.043034 -384.489372)
			(xy 387.051107 -384.556314) (xy 387.051104 -384.62374) (xy 387.043025 -384.690681) (xy 387.026985 -384.756172)
			(xy 387.003217 -384.81927) (xy 386.972063 -384.879068) (xy 386.93397 -384.934703) (xy 386.912104 -384.960368)
			(xy 386.906297 -384.967506) (xy 386.899788 -384.984702) (xy 386.899404 -384.993896) (xy 386.899404 -385.151376)
			(xy 386.898965 -385.161496) (xy 386.891225 -385.180199) (xy 386.876916 -385.194514) (xy 386.858216 -385.202261)
			(xy 386.848096 -385.202684) (xy 386.131816 -385.202684) (xy 386.121693 -385.202271) (xy 386.102986 -385.194525)
			(xy 386.088671 -385.180207) (xy 386.080928 -385.1615) (xy 386.080508 -385.151376) (xy 386.080508 -384.993896)
			(xy 386.080098 -384.984709) (xy 386.073584 -384.967525) (xy 386.067808 -384.960368) (xy 386.045979 -384.934674)
			(xy 386.007889 -384.879044) (xy 385.976736 -384.819251) (xy 385.95297 -384.756158) (xy 385.936931 -384.690673)
			(xy 385.928852 -384.623738) (xy 385.928849 -384.556317) (xy 385.936922 -384.489381) (xy 385.952954 -384.423893)
			(xy 385.976714 -384.360798) (xy 386.007861 -384.301003) (xy 386.045946 -384.245369) (xy 386.067808 -384.219704)
			(xy 386.073586 -384.212546) (xy 386.080112 -384.195365) (xy 386.080508 -384.186176) (xy 386.080508 -383.693924)
			(xy 386.080084 -383.684738) (xy 386.07358 -383.667554) (xy 386.067808 -383.660396) (xy 386.045908 -383.63476)
			(xy 386.00782 -383.579122) (xy 385.976671 -383.519321) (xy 385.952908 -383.456221) (xy 385.936875 -383.390728)
			(xy 385.928802 -383.323786) (xy 384.826708 -383.323786) (xy 384.82692 -383.324351) (xy 384.842892 -383.389735)
			(xy 384.850934 -383.456559) (xy 384.850933 -383.523865) (xy 384.842887 -383.590689) (xy 384.826913 -383.656072)
			(xy 384.803238 -383.719077) (xy 384.772203 -383.778801) (xy 384.734253 -383.834388) (xy 384.712464 -383.86004)
			(xy 384.706663 -383.867182) (xy 384.700152 -383.884375) (xy 384.699764 -383.893568) (xy 384.699764 -384.051556)
			(xy 384.699342 -384.061712) (xy 384.691554 -384.08047) (xy 384.677156 -384.094796) (xy 384.65836 -384.102491)
			(xy 384.648202 -384.102864) (xy 383.931922 -384.102864) (xy 383.921797 -384.102356) (xy 383.903077 -384.094636)
			(xy 383.88872 -384.080356) (xy 383.8809 -384.061678) (xy 383.88036 -384.051556) (xy 383.88036 -383.893568)
			(xy 383.879952 -383.884381) (xy 383.873435 -383.867197) (xy 383.86766 -383.86004) (xy 383.845887 -383.834375)
			(xy 383.807937 -383.778791) (xy 383.776902 -383.719069) (xy 383.753227 -383.656066) (xy 383.737252 -383.590686)
			(xy 383.729207 -383.523864) (xy 383.729205 -383.45656) (xy 383.737248 -383.389738) (xy 383.75322 -383.324357)
			(xy 383.776892 -383.261353) (xy 383.807924 -383.20163) (xy 383.845873 -383.146044) (xy 383.86766 -383.120392)
			(xy 383.87345 -383.113242) (xy 383.879967 -383.096055) (xy 383.88036 -383.086864) (xy 383.88036 -382.593342)
			(xy 383.879916 -382.584159) (xy 383.873425 -382.566975) (xy 383.86766 -382.559814) (xy 383.845862 -382.53417)
			(xy 383.807912 -382.478583) (xy 383.776878 -382.418858) (xy 383.753205 -382.355853) (xy 383.737232 -382.290469)
			(xy 383.729188 -382.223646) (xy 380.451149 -382.223646) (xy 380.451149 -382.223704) (xy 380.443073 -382.290642)
			(xy 380.427038 -382.356131) (xy 380.403273 -382.419228) (xy 380.372122 -382.479024) (xy 380.334032 -382.534657)
			(xy 380.312168 -382.560322) (xy 380.306375 -382.56747) (xy 380.299859 -382.584658) (xy 380.299468 -382.59385)
			(xy 380.299468 -383.086356) (xy 380.299907 -383.09554) (xy 380.306401 -383.112724) (xy 380.312168 -383.119884)
			(xy 380.334049 -383.145536) (xy 380.372139 -383.201171) (xy 380.403291 -383.260969) (xy 380.426928 -383.323727)
			(xy 381.529033 -383.323727) (xy 381.529037 -383.256419) (xy 381.537084 -383.189595) (xy 381.55306 -383.124211)
			(xy 381.576736 -383.061205) (xy 381.607772 -383.00148) (xy 381.645723 -382.945893) (xy 381.667512 -382.92024)
			(xy 381.673318 -382.913101) (xy 381.679827 -382.895906) (xy 381.680212 -382.886712) (xy 381.680212 -382.728724)
			(xy 381.680641 -382.71857) (xy 381.688431 -382.699816) (xy 381.702826 -382.685491) (xy 381.721618 -382.677793)
			(xy 381.731774 -382.677416) (xy 382.448054 -382.677416) (xy 382.458175 -382.677964) (xy 382.47689 -382.685672)
			(xy 382.491247 -382.699939) (xy 382.499072 -382.718606) (xy 382.499616 -382.728724) (xy 382.499616 -382.886712)
			(xy 382.500017 -382.8959) (xy 382.506537 -382.913085) (xy 382.512316 -382.92024) (xy 382.53407 -382.945921)
			(xy 382.572023 -383.001502) (xy 382.60306 -383.061221) (xy 382.626737 -383.124222) (xy 382.642713 -383.189601)
			(xy 382.650761 -383.256421) (xy 382.650764 -383.323724) (xy 382.642723 -383.390545) (xy 382.626753 -383.455926)
			(xy 382.603082 -383.518929) (xy 382.57205 -383.578652) (xy 382.534103 -383.634236) (xy 382.512316 -383.659888)
			(xy 382.506501 -383.667021) (xy 382.499997 -383.684221) (xy 382.499616 -383.693416) (xy 382.499616 -384.186684)
			(xy 382.50003 -384.195871) (xy 382.506541 -384.213055) (xy 382.512316 -384.220212) (xy 382.53414 -384.245834)
			(xy 382.572091 -384.301424) (xy 382.603125 -384.361151) (xy 382.626798 -384.42416) (xy 382.64277 -384.489546)
			(xy 382.650812 -384.556373) (xy 382.650808 -384.623681) (xy 382.64276 -384.690507) (xy 382.626782 -384.755892)
			(xy 382.603103 -384.818898) (xy 382.572063 -384.878622) (xy 382.534107 -384.934208) (xy 382.512316 -384.95986)
			(xy 382.506513 -384.967001) (xy 382.500002 -384.984195) (xy 382.499616 -384.993388) (xy 382.499616 -385.151376)
			(xy 382.499159 -385.161527) (xy 382.491375 -385.180275) (xy 382.476989 -385.194599) (xy 382.458206 -385.202303)
			(xy 382.448054 -385.202684) (xy 381.731774 -385.202684) (xy 381.721649 -385.202196) (xy 381.702931 -385.194464)
			(xy 381.688577 -385.180179) (xy 381.680754 -385.161499) (xy 381.680212 -385.151376) (xy 381.680212 -384.993388)
			(xy 381.679805 -384.984201) (xy 381.673289 -384.967016) (xy 381.667512 -384.95986) (xy 381.64576 -384.934178)
			(xy 381.607812 -384.878596) (xy 381.576779 -384.818876) (xy 381.553105 -384.755875) (xy 381.537131 -384.690497)
			(xy 381.529084 -384.623678) (xy 381.529081 -384.556376) (xy 381.537121 -384.489557) (xy 381.553089 -384.424177)
			(xy 381.576757 -384.361174) (xy 381.607784 -384.301451) (xy 381.645727 -384.245864) (xy 381.667512 -384.220212)
			(xy 381.67333 -384.213082) (xy 381.679831 -384.19588) (xy 381.680212 -384.186684) (xy 381.680212 -383.693416)
			(xy 381.679791 -383.68423) (xy 381.673285 -383.667046) (xy 381.667512 -383.659888) (xy 381.64569 -383.634265)
			(xy 381.607744 -383.578673) (xy 381.576714 -383.518946) (xy 381.553044 -383.455937) (xy 381.537074 -383.390552)
			(xy 381.529033 -383.323727) (xy 380.426928 -383.323727) (xy 380.427056 -383.324068) (xy 380.443091 -383.389559)
			(xy 380.451166 -383.456499) (xy 380.451165 -383.523925) (xy 380.443087 -383.590865) (xy 380.427049 -383.656355)
			(xy 380.403281 -383.719453) (xy 380.372127 -383.779249) (xy 380.334034 -383.834883) (xy 380.312168 -383.860548)
			(xy 380.306364 -383.867688) (xy 380.299855 -383.884883) (xy 380.299468 -383.894076) (xy 380.299468 -384.051556)
			(xy 380.299047 -384.06168) (xy 380.291308 -384.080388) (xy 380.276992 -384.094705) (xy 380.258284 -384.102446)
			(xy 380.24816 -384.102864) (xy 379.53188 -384.102864) (xy 379.521752 -384.1025) (xy 379.503041 -384.094738)
			(xy 379.488726 -384.080405) (xy 379.480988 -384.061685) (xy 379.480572 -384.051556) (xy 379.480572 -383.894076)
			(xy 379.48018 -383.884887) (xy 379.473654 -383.867702) (xy 379.467872 -383.860548) (xy 379.446025 -383.834869)
			(xy 379.407937 -383.779236) (xy 379.376788 -383.719441) (xy 379.353024 -383.656346) (xy 379.336988 -383.590859)
			(xy 379.328911 -383.523923) (xy 379.32891 -383.456501) (xy 379.336984 -383.389564) (xy 379.353017 -383.324077)
			(xy 379.376778 -383.260981) (xy 379.407925 -383.201185) (xy 379.44601 -383.14555) (xy 379.467872 -383.119884)
			(xy 379.473667 -383.112738) (xy 379.48018 -383.095548) (xy 379.480572 -383.086356) (xy 379.480572 -382.59385)
			(xy 379.480144 -382.584665) (xy 379.473643 -382.56748) (xy 379.467872 -382.560322) (xy 379.445999 -382.534664)
			(xy 379.407913 -382.479028) (xy 379.376764 -382.419231) (xy 379.353002 -382.356133) (xy 379.336968 -382.290643)
			(xy 379.328893 -382.223704) (xy 376.050822 -382.223704) (xy 376.042786 -382.290466) (xy 376.026815 -382.355847)
			(xy 376.003144 -382.418851) (xy 375.972113 -382.478575) (xy 375.934167 -382.534162) (xy 375.91238 -382.559814)
			(xy 375.906593 -382.566966) (xy 375.900073 -382.584151) (xy 375.89968 -382.593342) (xy 375.89968 -383.086864)
			(xy 375.900112 -383.096049) (xy 375.906611 -383.113233) (xy 375.91238 -383.120392) (xy 375.934183 -383.146031)
			(xy 375.97213 -383.20162) (xy 376.003162 -383.261346) (xy 376.02662 -383.323786) (xy 377.128714 -383.323786)
			(xy 377.128717 -383.256359) (xy 377.136797 -383.189418) (xy 377.152837 -383.123927) (xy 377.176606 -383.060828)
			(xy 377.207762 -383.001031) (xy 377.245857 -382.945397) (xy 377.267724 -382.919732) (xy 377.273535 -382.912597)
			(xy 377.28004 -382.895399) (xy 377.280424 -382.886204) (xy 377.280424 -382.728724) (xy 377.280836 -382.7186)
			(xy 377.288581 -382.699892) (xy 377.302899 -382.685576) (xy 377.321608 -382.677834) (xy 377.331732 -382.677416)
			(xy 378.048012 -382.677416) (xy 378.058137 -382.677806) (xy 378.076844 -382.685561) (xy 378.091159 -382.699886)
			(xy 378.098901 -382.718598) (xy 378.09932 -382.728724) (xy 378.09932 -382.886204) (xy 378.099724 -382.895392)
			(xy 378.106241 -382.912576) (xy 378.11202 -382.919732) (xy 378.133848 -382.945427) (xy 378.171936 -383.001058)
			(xy 378.203088 -383.06085) (xy 378.226853 -383.123943) (xy 378.24289 -383.189428) (xy 378.250969 -383.256363)
			(xy 378.250972 -383.323783) (xy 378.2429 -383.390719) (xy 378.226869 -383.456205) (xy 378.20311 -383.519301)
			(xy 378.171964 -383.579096) (xy 378.133881 -383.63473) (xy 378.11202 -383.660396) (xy 378.106245 -383.667557)
			(xy 378.099717 -383.684735) (xy 378.09932 -383.693924) (xy 378.09932 -384.186176) (xy 378.099737 -384.195363)
			(xy 378.106245 -384.212547) (xy 378.11202 -384.219704) (xy 378.133919 -384.24534) (xy 378.172005 -384.30098)
			(xy 378.203153 -384.36078) (xy 378.226914 -384.423881) (xy 378.242947 -384.489373) (xy 378.251019 -384.556314)
			(xy 378.251016 -384.62374) (xy 378.242937 -384.69068) (xy 378.226898 -384.756171) (xy 378.203131 -384.81927)
			(xy 378.171977 -384.879067) (xy 378.133885 -384.934702) (xy 378.11202 -384.960368) (xy 378.106214 -384.967507)
			(xy 378.099704 -384.984702) (xy 378.09932 -384.993896) (xy 378.09932 -385.151376) (xy 378.098865 -385.161494)
			(xy 378.091128 -385.180194) (xy 378.076824 -385.194508) (xy 378.05813 -385.202258) (xy 378.048012 -385.202684)
			(xy 377.331732 -385.202684) (xy 377.32161 -385.202258) (xy 377.302903 -385.194517) (xy 377.288587 -385.180203)
			(xy 377.280844 -385.161498) (xy 377.280424 -385.151376) (xy 377.280424 -384.993896) (xy 377.280011 -384.984709)
			(xy 377.273499 -384.967525) (xy 377.267724 -384.960368) (xy 377.245895 -384.934674) (xy 377.207803 -384.879044)
			(xy 377.17665 -384.819252) (xy 377.152882 -384.756159) (xy 377.136844 -384.690673) (xy 377.128765 -384.623738)
			(xy 377.128761 -384.556316) (xy 377.136834 -384.48938) (xy 377.152866 -384.423893) (xy 377.176627 -384.360797)
			(xy 377.207775 -384.301002) (xy 377.245861 -384.245369) (xy 377.267724 -384.219704) (xy 377.273504 -384.212547)
			(xy 377.280028 -384.195365) (xy 377.280424 -384.186176) (xy 377.280424 -383.693924) (xy 377.279997 -383.684739)
			(xy 377.273494 -383.667555) (xy 377.267724 -383.660396) (xy 377.245824 -383.63476) (xy 377.207735 -383.579122)
			(xy 377.176584 -383.519322) (xy 377.152821 -383.456221) (xy 377.136787 -383.390728) (xy 377.128714 -383.323786)
			(xy 376.02662 -383.323786) (xy 376.026833 -383.324352) (xy 376.042804 -383.389735) (xy 376.050846 -383.456559)
			(xy 376.050845 -383.523865) (xy 376.0428 -383.590688) (xy 376.026826 -383.656071) (xy 376.003152 -383.719076)
			(xy 375.972118 -383.778801) (xy 375.934168 -383.834388) (xy 375.91238 -383.86004) (xy 375.906582 -383.867184)
			(xy 375.900069 -383.884375) (xy 375.89968 -383.893568) (xy 375.89968 -384.051556) (xy 375.899242 -384.06171)
			(xy 375.891457 -384.080465) (xy 375.877065 -384.094791) (xy 375.858274 -384.102488) (xy 375.848118 -384.102864)
			(xy 375.131838 -384.102864) (xy 375.121714 -384.102342) (xy 375.102995 -384.094628) (xy 375.088637 -384.080352)
			(xy 375.080816 -384.061677) (xy 375.080276 -384.051556) (xy 375.080276 -383.893568) (xy 375.079886 -383.884379)
			(xy 375.073359 -383.867194) (xy 375.067576 -383.86004) (xy 375.045803 -383.834375) (xy 375.007851 -383.778792)
			(xy 374.976815 -383.71907) (xy 374.95314 -383.656067) (xy 374.937165 -383.590686) (xy 374.929119 -383.523864)
			(xy 374.929117 -383.45656) (xy 374.93716 -383.389738) (xy 374.953133 -383.324356) (xy 374.976805 -383.261352)
			(xy 375.007839 -383.201629) (xy 375.045788 -383.146044) (xy 375.067576 -383.120392) (xy 375.073356 -383.113235)
			(xy 375.079881 -383.096054) (xy 375.080276 -383.086864) (xy 375.080276 -382.593342) (xy 375.079851 -382.584156)
			(xy 375.073348 -382.566971) (xy 375.067576 -382.559814) (xy 375.045777 -382.53417) (xy 375.007826 -382.478584)
			(xy 374.976792 -382.418859) (xy 374.953118 -382.355853) (xy 374.937144 -382.29047) (xy 374.9291 -382.223646)
			(xy 345.250798 -382.223646) (xy 345.242755 -382.290467) (xy 345.226782 -382.355849) (xy 345.20311 -382.418853)
			(xy 345.172077 -382.478576) (xy 345.134128 -382.534162) (xy 345.11234 -382.559814) (xy 345.106548 -382.566962)
			(xy 345.100032 -382.584151) (xy 345.09964 -382.593342) (xy 345.09964 -383.086864) (xy 345.100081 -383.096048)
			(xy 345.106575 -383.113232) (xy 345.11234 -383.120392) (xy 345.134144 -383.146031) (xy 345.172094 -383.201619)
			(xy 345.203127 -383.261344) (xy 345.226566 -383.323727) (xy 346.329188 -383.323727) (xy 346.329192 -383.256419)
			(xy 346.33724 -383.189593) (xy 346.353218 -383.124208) (xy 346.376897 -383.061202) (xy 346.407937 -383.001478)
			(xy 346.445893 -382.945892) (xy 346.467684 -382.92024) (xy 346.473487 -382.913099) (xy 346.479998 -382.895905)
			(xy 346.480384 -382.886712) (xy 346.480384 -382.728724) (xy 346.480841 -382.718573) (xy 346.488625 -382.699825)
			(xy 346.503011 -382.685501) (xy 346.521794 -382.677797) (xy 346.531946 -382.677416) (xy 347.248226 -382.677416)
			(xy 347.258351 -382.677904) (xy 347.277069 -382.685636) (xy 347.291423 -382.699921) (xy 347.299246 -382.718601)
			(xy 347.299788 -382.728724) (xy 347.299788 -382.886712) (xy 347.300195 -382.895899) (xy 347.306711 -382.913084)
			(xy 347.312488 -382.92024) (xy 347.33424 -382.945922) (xy 347.372188 -383.001504) (xy 347.403221 -383.061224)
			(xy 347.426895 -383.124225) (xy 347.442869 -383.189603) (xy 347.450916 -383.256422) (xy 347.450919 -383.323724)
			(xy 347.442879 -383.390543) (xy 347.426911 -383.455923) (xy 347.403243 -383.518926) (xy 347.372216 -383.578649)
			(xy 347.334273 -383.634236) (xy 347.312488 -383.659888) (xy 347.30667 -383.667018) (xy 347.300169 -383.68422)
			(xy 347.299788 -383.693416) (xy 347.299788 -384.186684) (xy 347.300209 -384.19587) (xy 347.306715 -384.213054)
			(xy 347.312488 -384.220212) (xy 347.33431 -384.245835) (xy 347.372256 -384.301427) (xy 347.403286 -384.361154)
			(xy 347.426956 -384.424163) (xy 347.442926 -384.489548) (xy 347.450967 -384.556373) (xy 347.450963 -384.623681)
			(xy 347.442916 -384.690505) (xy 347.42694 -384.755889) (xy 347.403264 -384.818895) (xy 347.372228 -384.87862)
			(xy 347.334277 -384.934207) (xy 347.312488 -384.95986) (xy 347.306682 -384.966999) (xy 347.300173 -384.984194)
			(xy 347.299788 -384.993388) (xy 347.299788 -385.151376) (xy 347.299359 -385.16153) (xy 347.291569 -385.180284)
			(xy 347.277174 -385.194609) (xy 347.258382 -385.202307) (xy 347.248226 -385.202684) (xy 346.531946 -385.202684)
			(xy 346.521825 -385.202136) (xy 346.50311 -385.194428) (xy 346.488753 -385.180161) (xy 346.480928 -385.161494)
			(xy 346.480384 -385.151376) (xy 346.480384 -384.993388) (xy 346.479983 -384.9842) (xy 346.473463 -384.967015)
			(xy 346.467684 -384.95986) (xy 346.44593 -384.934179) (xy 346.407977 -384.878598) (xy 346.37694 -384.818879)
			(xy 346.353263 -384.755878) (xy 346.337287 -384.690499) (xy 346.329239 -384.623679) (xy 346.329236 -384.556376)
			(xy 346.337277 -384.489555) (xy 346.353247 -384.424174) (xy 346.376918 -384.361171) (xy 346.40795 -384.301448)
			(xy 346.445897 -384.245864) (xy 346.467684 -384.220212) (xy 346.473499 -384.213079) (xy 346.480003 -384.195879)
			(xy 346.480384 -384.186684) (xy 346.480384 -383.693416) (xy 346.47997 -383.684229) (xy 346.473459 -383.667045)
			(xy 346.467684 -383.659888) (xy 346.44586 -383.634266) (xy 346.407909 -383.578676) (xy 346.376875 -383.518949)
			(xy 346.353202 -383.45594) (xy 346.33723 -383.390554) (xy 346.329188 -383.323727) (xy 345.226566 -383.323727)
			(xy 345.2268 -383.32435) (xy 345.242773 -383.389734) (xy 345.250816 -383.456559) (xy 345.250814 -383.523865)
			(xy 345.242768 -383.590689) (xy 345.226793 -383.656073) (xy 345.203118 -383.719078) (xy 345.172081 -383.778802)
			(xy 345.134129 -383.834388) (xy 345.11234 -383.86004) (xy 345.106537 -383.86718) (xy 345.100028 -383.884375)
			(xy 345.09964 -383.893568) (xy 345.09964 -384.051556) (xy 345.099143 -384.061702) (xy 345.09137 -384.080446)
			(xy 345.076996 -384.094769) (xy 345.058226 -384.102478) (xy 345.048078 -384.102864) (xy 344.331798 -384.102864)
			(xy 344.321672 -384.102375) (xy 344.302951 -384.094647) (xy 344.288595 -384.080362) (xy 344.280775 -384.06168)
			(xy 344.280236 -384.051556) (xy 344.280236 -383.893568) (xy 344.279833 -383.88438) (xy 344.273313 -383.867196)
			(xy 344.267536 -383.86004) (xy 344.245764 -383.834375) (xy 344.207815 -383.77879) (xy 344.176781 -383.719068)
			(xy 344.153108 -383.656066) (xy 344.137134 -383.590685) (xy 344.129089 -383.523864) (xy 344.129087 -383.45656)
			(xy 344.13713 -383.389739) (xy 344.153101 -383.324358) (xy 344.176772 -383.261354) (xy 344.207803 -383.201631)
			(xy 344.24575 -383.146044) (xy 344.267536 -383.120392) (xy 344.273323 -383.11324) (xy 344.279843 -383.096055)
			(xy 344.280236 -383.086864) (xy 344.280236 -382.593342) (xy 344.279797 -382.584158) (xy 344.273303 -382.566974)
			(xy 344.267536 -382.559814) (xy 344.245738 -382.53417) (xy 344.20779 -382.478582) (xy 344.176757 -382.418858)
			(xy 344.153085 -382.355852) (xy 344.137113 -382.290469) (xy 344.12907 -382.223645) (xy 340.851007 -382.223645)
			(xy 340.842964 -382.290467) (xy 340.826992 -382.355848) (xy 340.80332 -382.418853) (xy 340.772287 -382.478576)
			(xy 340.734339 -382.534162) (xy 340.712552 -382.559814) (xy 340.706761 -382.566963) (xy 340.700244 -382.584151)
			(xy 340.699852 -382.593342) (xy 340.699852 -383.086864) (xy 340.70029 -383.096048) (xy 340.706785 -383.113232)
			(xy 340.712552 -383.120392) (xy 340.734356 -383.146031) (xy 340.772305 -383.201619) (xy 340.803338 -383.261344)
			(xy 340.826798 -383.323786) (xy 341.928893 -383.323786) (xy 341.928896 -383.25636) (xy 341.936975 -383.189419)
			(xy 341.953015 -383.123928) (xy 341.976783 -383.06083) (xy 342.007937 -383.001032) (xy 342.04603 -382.945397)
			(xy 342.067896 -382.919732) (xy 342.073703 -382.912594) (xy 342.080212 -382.895398) (xy 342.080596 -382.886204)
			(xy 342.080596 -382.728724) (xy 342.081035 -382.718604) (xy 342.088775 -382.699901) (xy 342.103084 -382.685586)
			(xy 342.121784 -382.677839) (xy 342.131904 -382.677416) (xy 342.848184 -382.677416) (xy 342.858307 -382.677829)
			(xy 342.877014 -382.685575) (xy 342.891329 -382.699893) (xy 342.899072 -382.7186) (xy 342.899492 -382.728724)
			(xy 342.899492 -382.886204) (xy 342.899902 -382.895391) (xy 342.906416 -382.912575) (xy 342.912192 -382.919732)
			(xy 342.934021 -382.945426) (xy 342.972111 -383.001056) (xy 343.003264 -383.060849) (xy 343.02703 -383.123942)
			(xy 343.043069 -383.189427) (xy 343.051148 -383.256362) (xy 343.051151 -383.323783) (xy 343.043078 -383.390719)
			(xy 343.027046 -383.456207) (xy 343.003286 -383.519302) (xy 342.972139 -383.579097) (xy 342.934054 -383.634731)
			(xy 342.912192 -383.660396) (xy 342.906414 -383.667554) (xy 342.899888 -383.684735) (xy 342.899492 -383.693924)
			(xy 342.899492 -384.186176) (xy 342.899916 -384.195362) (xy 342.90642 -384.212546) (xy 342.912192 -384.219704)
			(xy 342.934092 -384.24534) (xy 342.97218 -384.300978) (xy 343.003329 -384.360779) (xy 343.027092 -384.423879)
			(xy 343.043125 -384.489372) (xy 343.051198 -384.556314) (xy 343.051195 -384.62374) (xy 343.043115 -384.690681)
			(xy 343.027076 -384.756172) (xy 343.003307 -384.819271) (xy 342.972152 -384.879068) (xy 342.934058 -384.934703)
			(xy 342.912192 -384.960368) (xy 342.906383 -384.967504) (xy 342.899876 -384.984702) (xy 342.899492 -384.993896)
			(xy 342.899492 -385.151376) (xy 342.899064 -385.161498) (xy 342.891323 -385.180203) (xy 342.877009 -385.194518)
			(xy 342.858306 -385.202263) (xy 342.848184 -385.202684) (xy 342.131904 -385.202684) (xy 342.12178 -385.20228)
			(xy 342.103073 -385.194531) (xy 342.088758 -385.18021) (xy 342.081016 -385.1615) (xy 342.080596 -385.151376)
			(xy 342.080596 -384.993896) (xy 342.080189 -384.984709) (xy 342.073673 -384.967524) (xy 342.067896 -384.960368)
			(xy 342.046068 -384.934674) (xy 342.007978 -384.879043) (xy 341.976826 -384.819251) (xy 341.95306 -384.756158)
			(xy 341.937022 -384.690672) (xy 341.928943 -384.623737) (xy 341.92894 -384.556317) (xy 341.937012 -384.489381)
			(xy 341.953044 -384.423894) (xy 341.976804 -384.360799) (xy 342.00795 -384.301003) (xy 342.046034 -384.245369)
			(xy 342.067896 -384.219704) (xy 342.073673 -384.212545) (xy 342.080199 -384.195365) (xy 342.080596 -384.186176)
			(xy 342.080596 -383.693924) (xy 342.080175 -383.684738) (xy 342.073669 -383.667553) (xy 342.067896 -383.660396)
			(xy 342.045997 -383.63476) (xy 342.007909 -383.579121) (xy 341.976761 -383.519321) (xy 341.952999 -383.45622)
			(xy 341.936966 -383.390728) (xy 341.928893 -383.323786) (xy 340.826798 -383.323786) (xy 340.82701 -383.324351)
			(xy 340.842982 -383.389735) (xy 340.851025 -383.456559) (xy 340.851024 -383.523865) (xy 340.842978 -383.590689)
			(xy 340.827003 -383.656072) (xy 340.803328 -383.719078) (xy 340.772292 -383.778802) (xy 340.734341 -383.834388)
			(xy 340.712552 -383.86004) (xy 340.70675 -383.867181) (xy 340.70024 -383.884375) (xy 340.699852 -383.893568)
			(xy 340.699852 -384.051556) (xy 340.699343 -384.061701) (xy 340.691572 -384.080442) (xy 340.677202 -384.094765)
			(xy 340.658436 -384.102476) (xy 340.64829 -384.102864) (xy 339.93201 -384.102864) (xy 339.921884 -384.102365)
			(xy 339.903164 -384.094642) (xy 339.888808 -384.080359) (xy 339.880987 -384.061679) (xy 339.880448 -384.051556)
			(xy 339.880448 -383.893568) (xy 339.880042 -383.884381) (xy 339.873524 -383.867197) (xy 339.867748 -383.86004)
			(xy 339.845976 -383.834375) (xy 339.808026 -383.778791) (xy 339.776992 -383.719069) (xy 339.753318 -383.656066)
			(xy 339.737343 -383.590685) (xy 339.729298 -383.523864) (xy 339.729296 -383.45656) (xy 339.737339 -383.389738)
			(xy 339.75331 -383.324357) (xy 339.776982 -383.261353) (xy 339.808014 -383.20163) (xy 339.845961 -383.146044)
			(xy 339.867748 -383.120392) (xy 339.873536 -383.113241) (xy 339.880055 -383.096055) (xy 339.880448 -383.086864)
			(xy 339.880448 -382.593342) (xy 339.880007 -382.584158) (xy 339.873513 -382.566974) (xy 339.867748 -382.559814)
			(xy 339.84595 -382.53417) (xy 339.808001 -382.478583) (xy 339.776968 -382.418858) (xy 339.753295 -382.355852)
			(xy 339.737322 -382.290469) (xy 339.729279 -382.223645) (xy 336.45124 -382.223645) (xy 336.45124 -382.223704)
			(xy 336.443164 -382.290643) (xy 336.427128 -382.356132) (xy 336.403363 -382.419228) (xy 336.372211 -382.479024)
			(xy 336.334121 -382.534658) (xy 336.312256 -382.560322) (xy 336.306462 -382.567469) (xy 336.299947 -382.584658)
			(xy 336.299556 -382.59385) (xy 336.299556 -383.086356) (xy 336.299997 -383.09554) (xy 336.306491 -383.112724)
			(xy 336.312256 -383.119884) (xy 336.334137 -383.145536) (xy 336.372228 -383.201171) (xy 336.403381 -383.260969)
			(xy 336.427018 -383.323726) (xy 337.529124 -383.323726) (xy 337.529128 -383.256419) (xy 337.537175 -383.189595)
			(xy 337.55315 -383.124211) (xy 337.576825 -383.061205) (xy 337.607861 -383.001481) (xy 337.645811 -382.945893)
			(xy 337.6676 -382.92024) (xy 337.673405 -382.9131) (xy 337.679914 -382.895906) (xy 337.6803 -382.886712)
			(xy 337.6803 -382.728724) (xy 337.680741 -382.718571) (xy 337.688529 -382.699819) (xy 337.70292 -382.685495)
			(xy 337.721708 -382.677795) (xy 337.731862 -382.677416) (xy 338.448142 -382.677416) (xy 338.458268 -382.677891)
			(xy 338.476986 -382.685629) (xy 338.49134 -382.699918) (xy 338.499162 -382.7186) (xy 338.499704 -382.728724)
			(xy 338.499704 -382.886712) (xy 338.500108 -382.8959) (xy 338.506626 -382.913084) (xy 338.512404 -382.92024)
			(xy 338.534155 -382.945922) (xy 338.572102 -383.001505) (xy 338.603135 -383.061225) (xy 338.626808 -383.124225)
			(xy 338.642782 -383.189604) (xy 338.650828 -383.256422) (xy 338.650831 -383.323724) (xy 338.642791 -383.390543)
			(xy 338.626824 -383.455923) (xy 338.603157 -383.518926) (xy 338.57213 -383.578648) (xy 338.534188 -383.634235)
			(xy 338.512404 -383.659888) (xy 338.506588 -383.66702) (xy 338.500085 -383.68422) (xy 338.499704 -383.693416)
			(xy 338.499704 -384.186684) (xy 338.500121 -384.19587) (xy 338.50663 -384.213055) (xy 338.512404 -384.220212)
			(xy 338.534226 -384.245836) (xy 338.572171 -384.301427) (xy 338.6032 -384.361155) (xy 338.626869 -384.424163)
			(xy 338.642838 -384.489548) (xy 338.650879 -384.556374) (xy 338.650875 -384.623681) (xy 338.642828 -384.690505)
			(xy 338.626853 -384.755889) (xy 338.603178 -384.818894) (xy 338.572143 -384.878619) (xy 338.534193 -384.934207)
			(xy 338.512404 -384.95986) (xy 338.5066 -384.967) (xy 338.50009 -384.984194) (xy 338.499704 -384.993388)
			(xy 338.499704 -385.151376) (xy 338.499259 -385.161528) (xy 338.491472 -385.180279) (xy 338.477082 -385.194603)
			(xy 338.458296 -385.202305) (xy 338.448142 -385.202684) (xy 337.731862 -385.202684) (xy 337.721736 -385.202205)
			(xy 337.703018 -385.194469) (xy 337.688664 -385.180181) (xy 337.680842 -385.1615) (xy 337.6803 -385.151376)
			(xy 337.6803 -384.993388) (xy 337.679895 -384.9842) (xy 337.673378 -384.967016) (xy 337.6676 -384.95986)
			(xy 337.645849 -384.934178) (xy 337.607901 -384.878595) (xy 337.576869 -384.818875) (xy 337.553196 -384.755875)
			(xy 337.537221 -384.690497) (xy 337.529175 -384.623678) (xy 337.529172 -384.556376) (xy 337.537212 -384.489557)
			(xy 337.55318 -384.424177) (xy 337.576847 -384.361174) (xy 337.607874 -384.301451) (xy 337.645816 -384.245865)
			(xy 337.6676 -384.220212) (xy 337.673416 -384.213081) (xy 337.679919 -384.19588) (xy 337.6803 -384.186684)
			(xy 337.6803 -383.693416) (xy 337.679882 -383.68423) (xy 337.673374 -383.667045) (xy 337.6676 -383.659888)
			(xy 337.645778 -383.634264) (xy 337.607833 -383.578673) (xy 337.576803 -383.518945) (xy 337.553134 -383.455937)
			(xy 337.537165 -383.390552) (xy 337.529124 -383.323726) (xy 336.427018 -383.323726) (xy 336.427146 -383.324067)
			(xy 336.443182 -383.389559) (xy 336.451257 -383.456499) (xy 336.451256 -383.523925) (xy 336.443177 -383.590865)
			(xy 336.427139 -383.656356) (xy 336.403371 -383.719453) (xy 336.372216 -383.77925) (xy 336.334122 -383.834883)
			(xy 336.312256 -383.860548) (xy 336.306451 -383.867687) (xy 336.299943 -383.884882) (xy 336.299556 -383.894076)
			(xy 336.299556 -384.051556) (xy 336.29898 -384.061655) (xy 336.291267 -384.080321) (xy 336.276999 -384.094616)
			(xy 336.258346 -384.102362) (xy 336.248248 -384.102864) (xy 335.531968 -384.102864) (xy 335.521839 -384.102509)
			(xy 335.503128 -384.094744) (xy 335.488813 -384.080408) (xy 335.481076 -384.061686) (xy 335.48066 -384.051556)
			(xy 335.48066 -383.894076) (xy 335.480248 -383.884889) (xy 335.473734 -383.867706) (xy 335.46796 -383.860548)
			(xy 335.446113 -383.834869) (xy 335.408027 -383.779236) (xy 335.376877 -383.719441) (xy 335.353114 -383.656346)
			(xy 335.337079 -383.590859) (xy 335.329002 -383.523923) (xy 335.329001 -383.456501) (xy 335.337074 -383.389565)
			(xy 335.353107 -383.324077) (xy 335.376868 -383.260981) (xy 335.408014 -383.201185) (xy 335.446098 -383.14555)
			(xy 335.46796 -383.119884) (xy 335.473753 -383.112737) (xy 335.480268 -383.095548) (xy 335.48066 -383.086356)
			(xy 335.48066 -382.59385) (xy 335.480213 -382.584667) (xy 335.473723 -382.567483) (xy 335.46796 -382.560322)
			(xy 335.446088 -382.534664) (xy 335.408002 -382.479028) (xy 335.376854 -382.41923) (xy 335.353092 -382.356132)
			(xy 335.337058 -382.290643) (xy 335.328984 -382.223704) (xy 332.050913 -382.223704) (xy 332.042877 -382.290466)
			(xy 332.026905 -382.355848) (xy 332.003234 -382.418852) (xy 331.972202 -382.478575) (xy 331.934255 -382.534162)
			(xy 331.912468 -382.559814) (xy 331.906679 -382.566964) (xy 331.90016 -382.584151) (xy 331.899768 -382.593342)
			(xy 331.899768 -383.086864) (xy 331.900203 -383.096048) (xy 331.9067 -383.113233) (xy 331.912468 -383.120392)
			(xy 331.934271 -383.146031) (xy 331.972219 -383.20162) (xy 332.003251 -383.261345) (xy 332.026711 -383.323786)
			(xy 333.128805 -383.323786) (xy 333.128808 -383.25636) (xy 333.136888 -383.189419) (xy 333.152927 -383.123927)
			(xy 333.176696 -383.060829) (xy 333.207852 -383.001032) (xy 333.245945 -382.945397) (xy 333.267812 -382.919732)
			(xy 333.273621 -382.912596) (xy 333.280128 -382.895398) (xy 333.280512 -382.886204) (xy 333.280512 -382.728724)
			(xy 333.280936 -382.718602) (xy 333.288678 -382.699896) (xy 333.302993 -382.685581) (xy 333.321698 -382.677837)
			(xy 333.33182 -382.677416) (xy 334.0481 -382.677416) (xy 334.058224 -382.677816) (xy 334.076931 -382.685568)
			(xy 334.091246 -382.699889) (xy 334.098988 -382.718599) (xy 334.099408 -382.728724) (xy 334.099408 -382.886204)
			(xy 334.099815 -382.895392) (xy 334.106331 -382.912576) (xy 334.112108 -382.919732) (xy 334.133936 -382.945427)
			(xy 334.172026 -383.001057) (xy 334.203177 -383.060849) (xy 334.226943 -383.123942) (xy 334.242981 -383.189428)
			(xy 334.25106 -383.256363) (xy 334.251063 -383.323783) (xy 334.242991 -383.390719) (xy 334.226959 -383.456206)
			(xy 334.2032 -383.519301) (xy 334.172053 -383.579096) (xy 334.13397 -383.634731) (xy 334.112108 -383.660396)
			(xy 334.106332 -383.667556) (xy 334.099805 -383.684735) (xy 334.099408 -383.693924) (xy 334.099408 -384.186176)
			(xy 334.099828 -384.195362) (xy 334.106335 -384.212547) (xy 334.112108 -384.219704) (xy 334.134007 -384.24534)
			(xy 334.172094 -384.300979) (xy 334.203243 -384.360779) (xy 334.227005 -384.42388) (xy 334.243037 -384.489373)
			(xy 334.25111 -384.556314) (xy 334.251107 -384.62374) (xy 334.243028 -384.690681) (xy 334.226989 -384.756172)
			(xy 334.203221 -384.81927) (xy 334.172066 -384.879067) (xy 334.133974 -384.934703) (xy 334.112108 -384.960368)
			(xy 334.106301 -384.967506) (xy 334.099792 -384.984702) (xy 334.099408 -384.993896) (xy 334.099408 -385.151376)
			(xy 334.098965 -385.161496) (xy 334.091226 -385.180198) (xy 334.076918 -385.194512) (xy 334.05822 -385.20226)
			(xy 334.0481 -385.202684) (xy 333.33182 -385.202684) (xy 333.321697 -385.202267) (xy 333.302991 -385.194523)
			(xy 333.288675 -385.180206) (xy 333.280932 -385.161499) (xy 333.280512 -385.151376) (xy 333.280512 -384.993896)
			(xy 333.280101 -384.984709) (xy 333.273587 -384.967525) (xy 333.267812 -384.960368) (xy 333.245983 -384.934674)
			(xy 333.207892 -384.879044) (xy 333.176739 -384.819252) (xy 333.152973 -384.756158) (xy 333.136934 -384.690673)
			(xy 333.128855 -384.623738) (xy 333.128852 -384.556316) (xy 333.136925 -384.48938) (xy 333.152957 -384.423893)
			(xy 333.176717 -384.360798) (xy 333.207865 -384.301003) (xy 333.24595 -384.245369) (xy 333.267812 -384.219704)
			(xy 333.273591 -384.212546) (xy 333.280116 -384.195365) (xy 333.280512 -384.186176) (xy 333.280512 -383.693924)
			(xy 333.280088 -383.684738) (xy 333.273583 -383.667554) (xy 333.267812 -383.660396) (xy 333.245912 -383.63476)
			(xy 333.207824 -383.579122) (xy 333.176674 -383.519322) (xy 333.152911 -383.456221) (xy 333.136878 -383.390728)
			(xy 333.128805 -383.323786) (xy 332.026711 -383.323786) (xy 332.026923 -383.324351) (xy 332.042895 -383.389735)
			(xy 332.050937 -383.456559) (xy 332.050936 -383.523865) (xy 332.04289 -383.590689) (xy 332.026916 -383.656072)
			(xy 332.003242 -383.719077) (xy 331.972207 -383.778801) (xy 331.934257 -383.834388) (xy 331.912468 -383.86004)
			(xy 331.906668 -383.867183) (xy 331.900156 -383.884375) (xy 331.899768 -383.893568) (xy 331.899768 -384.051556)
			(xy 331.899342 -384.061711) (xy 331.891555 -384.080469) (xy 331.877159 -384.094795) (xy 331.858363 -384.10249)
			(xy 331.848206 -384.102864) (xy 331.131926 -384.102864) (xy 331.121801 -384.102352) (xy 331.103082 -384.094634)
			(xy 331.088724 -384.080355) (xy 331.080904 -384.061678) (xy 331.080364 -384.051556) (xy 331.080364 -383.893568)
			(xy 331.079955 -383.884381) (xy 331.073439 -383.867198) (xy 331.067664 -383.86004) (xy 331.045891 -383.834375)
			(xy 331.00794 -383.778791) (xy 330.976905 -383.71907) (xy 330.95323 -383.656067) (xy 330.937256 -383.590686)
			(xy 330.92921 -383.523864) (xy 330.929208 -383.45656) (xy 330.937251 -383.389738) (xy 330.953223 -383.324356)
			(xy 330.976895 -383.261352) (xy 331.007928 -383.20163) (xy 331.045877 -383.146044) (xy 331.067664 -383.120392)
			(xy 331.073454 -383.113243) (xy 331.079971 -383.096055) (xy 331.080364 -383.086864) (xy 331.080364 -382.593342)
			(xy 331.079919 -382.584159) (xy 331.073428 -382.566975) (xy 331.067664 -382.559814) (xy 331.045866 -382.53417)
			(xy 331.007916 -382.478583) (xy 330.976881 -382.418859) (xy 330.953208 -382.355853) (xy 330.937235 -382.29047)
			(xy 330.929191 -382.223646) (xy 301.250888 -382.223646) (xy 301.250888 -382.223704) (xy 301.242813 -382.290641)
			(xy 301.226779 -382.356129) (xy 301.203017 -382.419226) (xy 301.171869 -382.479022) (xy 301.133783 -382.534656)
			(xy 301.11192 -382.560322) (xy 301.106134 -382.567475) (xy 301.099612 -382.584659) (xy 301.09922 -382.59385)
			(xy 301.09922 -383.086356) (xy 301.099647 -383.095542) (xy 301.106148 -383.112726) (xy 301.11192 -383.119884)
			(xy 301.133799 -383.145537) (xy 301.171886 -383.201173) (xy 301.203035 -383.260972) (xy 301.22669 -383.323786)
			(xy 302.328775 -383.323786) (xy 302.328778 -383.25636) (xy 302.336857 -383.18942) (xy 302.352895 -383.123929)
			(xy 302.376662 -383.060831) (xy 302.407816 -383.001033) (xy 302.445907 -382.945398) (xy 302.467772 -382.919732)
			(xy 302.473589 -382.912601) (xy 302.480089 -382.895399) (xy 302.480472 -382.886204) (xy 302.480472 -382.728724)
			(xy 302.480935 -382.718606) (xy 302.48867 -382.699909) (xy 302.502972 -382.685595) (xy 302.521663 -382.677843)
			(xy 302.53178 -382.677416) (xy 303.24806 -382.677416) (xy 303.258182 -382.677849) (xy 303.276888 -382.685587)
			(xy 303.291204 -382.699899) (xy 303.298948 -382.718602) (xy 303.299368 -382.728724) (xy 303.299368 -382.886204)
			(xy 303.299783 -382.89539) (xy 303.306294 -382.912575) (xy 303.312068 -382.919732) (xy 303.333898 -382.945426)
			(xy 303.37199 -383.001056) (xy 303.403144 -383.060847) (xy 303.426911 -383.123941) (xy 303.44295 -383.189427)
			(xy 303.451029 -383.256362) (xy 303.451033 -383.323784) (xy 303.44296 -383.39072) (xy 303.426927 -383.456208)
			(xy 303.403166 -383.519303) (xy 303.372017 -383.579098) (xy 303.333931 -383.634731) (xy 303.312068 -383.660396)
			(xy 303.306286 -383.667552) (xy 303.299764 -383.684734) (xy 303.299368 -383.693924) (xy 303.299368 -384.186176)
			(xy 303.299797 -384.195361) (xy 303.306299 -384.212545) (xy 303.312068 -384.219704) (xy 303.333968 -384.24534)
			(xy 303.372058 -384.300978) (xy 303.403209 -384.360778) (xy 303.426973 -384.423878) (xy 303.443007 -384.489371)
			(xy 303.45108 -384.556313) (xy 303.451077 -384.623741) (xy 303.442997 -384.690682) (xy 303.426957 -384.756173)
			(xy 303.403187 -384.819272) (xy 303.37203 -384.879069) (xy 303.333935 -384.934703) (xy 303.312068 -384.960368)
			(xy 303.306256 -384.967502) (xy 303.299751 -384.984701) (xy 303.299368 -384.993896) (xy 303.299368 -385.151376)
			(xy 303.298964 -385.161501) (xy 303.291218 -385.18021) (xy 303.276897 -385.194527) (xy 303.258185 -385.202267)
			(xy 303.24806 -385.202684) (xy 302.53178 -385.202684) (xy 302.521654 -385.2023) (xy 302.502947 -385.194542)
			(xy 302.488633 -385.180216) (xy 302.480891 -385.161502) (xy 302.480472 -385.151376) (xy 302.480472 -384.993896)
			(xy 302.48007 -384.984708) (xy 302.473551 -384.967523) (xy 302.467772 -384.960368) (xy 302.445944 -384.934673)
			(xy 302.407856 -384.879042) (xy 302.376706 -384.81925) (xy 302.352941 -384.756157) (xy 302.336904 -384.690672)
			(xy 302.328825 -384.623737) (xy 302.328822 -384.556317) (xy 302.336894 -384.489382) (xy 302.352925 -384.423895)
			(xy 302.376684 -384.3608) (xy 302.407829 -384.301004) (xy 302.445911 -384.24537) (xy 302.467772 -384.219704)
			(xy 302.473558 -384.212552) (xy 302.480077 -384.195366) (xy 302.480472 -384.186176) (xy 302.480472 -383.693924)
			(xy 302.480057 -383.684737) (xy 302.473547 -383.667552) (xy 302.467772 -383.660396) (xy 302.445874 -383.634759)
			(xy 302.407788 -383.57912) (xy 302.37664 -383.51932) (xy 302.352879 -383.456219) (xy 302.336847 -383.390727)
			(xy 302.328775 -383.323786) (xy 301.22669 -383.323786) (xy 301.226797 -383.32407) (xy 301.242831 -383.38956)
			(xy 301.250905 -383.4565) (xy 301.250904 -383.523924) (xy 301.242827 -383.590863) (xy 301.22679 -383.656353)
			(xy 301.203025 -383.71945) (xy 301.171874 -383.779247) (xy 301.133784 -383.834882) (xy 301.11192 -383.860548)
			(xy 301.106123 -383.867693) (xy 301.099608 -383.884884) (xy 301.09922 -383.894076) (xy 301.09922 -384.051556)
			(xy 301.098748 -384.061673) (xy 301.091018 -384.080372) (xy 301.076719 -384.094687) (xy 301.058029 -384.102437)
			(xy 301.047912 -384.102864) (xy 300.331632 -384.102864) (xy 300.321507 -384.102457) (xy 300.302797 -384.094713)
			(xy 300.28848 -384.080393) (xy 300.28074 -384.061681) (xy 300.280324 -384.051556) (xy 300.280324 -383.894076)
			(xy 300.27992 -383.884888) (xy 300.273402 -383.867704) (xy 300.267624 -383.860548) (xy 300.245775 -383.83487)
			(xy 300.207684 -383.779238) (xy 300.176531 -383.719444) (xy 300.152765 -383.656349) (xy 300.136728 -383.590861)
			(xy 300.12865 -383.523923) (xy 300.128649 -383.456501) (xy 300.136724 -383.389563) (xy 300.152758 -383.324074)
			(xy 300.176522 -383.260978) (xy 300.207672 -383.201183) (xy 300.24576 -383.145549) (xy 300.267624 -383.119884)
			(xy 300.273413 -383.112733) (xy 300.279931 -383.095547) (xy 300.280324 -383.086356) (xy 300.280324 -382.59385)
			(xy 300.279884 -382.584666) (xy 300.273391 -382.567482) (xy 300.267624 -382.560322) (xy 300.245749 -382.534665)
			(xy 300.207659 -382.47903) (xy 300.176508 -382.419233) (xy 300.152743 -382.356135) (xy 300.136708 -382.290645)
			(xy 300.128632 -382.223705) (xy 296.851097 -382.223705) (xy 296.843022 -382.290641) (xy 296.826989 -382.356129)
			(xy 296.803227 -382.419225) (xy 296.77208 -382.479021) (xy 296.733994 -382.534656) (xy 296.712132 -382.560322)
			(xy 296.706335 -382.567467) (xy 296.699823 -382.584658) (xy 296.699432 -382.59385) (xy 296.699432 -383.086356)
			(xy 296.699878 -383.095539) (xy 296.706368 -383.112723) (xy 296.712132 -383.119884) (xy 296.734011 -383.145537)
			(xy 296.772097 -383.201174) (xy 296.803245 -383.260972) (xy 296.826877 -383.323727) (xy 297.928982 -383.323727)
			(xy 297.928985 -383.256419) (xy 297.937033 -383.189593) (xy 297.953011 -383.124208) (xy 297.97669 -383.061202)
			(xy 298.007729 -383.001478) (xy 298.045685 -382.945891) (xy 298.067476 -382.92024) (xy 298.073278 -382.913098)
			(xy 298.07979 -382.895905) (xy 298.080176 -382.886712) (xy 298.080176 -382.728724) (xy 298.080641 -382.718574)
			(xy 298.088424 -382.699827) (xy 298.102807 -382.685504) (xy 298.121587 -382.677799) (xy 298.131738 -382.677416)
			(xy 298.848018 -382.677416) (xy 298.858143 -382.677911) (xy 298.87686 -382.68564) (xy 298.891215 -382.699923)
			(xy 298.899038 -382.718602) (xy 298.89958 -382.728724) (xy 298.89958 -382.886712) (xy 298.899989 -382.895899)
			(xy 298.906504 -382.913083) (xy 298.91228 -382.92024) (xy 298.934031 -382.945922) (xy 298.97198 -383.001504)
			(xy 299.003014 -383.061224) (xy 299.026688 -383.124225) (xy 299.042663 -383.189603) (xy 299.050709 -383.256422)
			(xy 299.050713 -383.323724) (xy 299.042672 -383.390544) (xy 299.026704 -383.455924) (xy 299.003036 -383.518926)
			(xy 298.972008 -383.578649) (xy 298.934065 -383.634235) (xy 298.91228 -383.659888) (xy 298.906461 -383.667017)
			(xy 298.89996 -383.68422) (xy 298.89958 -383.693416) (xy 298.89958 -384.186684) (xy 298.900003 -384.19587)
			(xy 298.906508 -384.213054) (xy 298.91228 -384.220212) (xy 298.934103 -384.245835) (xy 298.972049 -384.301426)
			(xy 299.00308 -384.361154) (xy 299.02675 -384.424162) (xy 299.04272 -384.489548) (xy 299.050761 -384.556373)
			(xy 299.050757 -384.623681) (xy 299.04271 -384.690506) (xy 299.026734 -384.75589) (xy 299.003058 -384.818895)
			(xy 298.972021 -384.87862) (xy 298.934069 -384.934208) (xy 298.91228 -384.95986) (xy 298.906473 -384.966998)
			(xy 298.899965 -384.984194) (xy 298.89958 -384.993388) (xy 298.89958 -385.151376) (xy 298.899159 -385.161531)
			(xy 298.891367 -385.180287) (xy 298.87697 -385.194612) (xy 298.858175 -385.202309) (xy 298.848018 -385.202684)
			(xy 298.131738 -385.202684) (xy 298.121617 -385.202143) (xy 298.102901 -385.194432) (xy 298.088544 -385.180162)
			(xy 298.08072 -385.161494) (xy 298.080176 -385.151376) (xy 298.080176 -384.993388) (xy 298.079777 -384.9842)
			(xy 298.073256 -384.967015) (xy 298.067476 -384.95986) (xy 298.045723 -384.934179) (xy 298.00777 -384.878598)
			(xy 297.976733 -384.818878) (xy 297.953057 -384.755878) (xy 297.93708 -384.690499) (xy 297.929033 -384.623679)
			(xy 297.92903 -384.556376) (xy 297.937071 -384.489555) (xy 297.953041 -384.424174) (xy 297.976711 -384.361171)
			(xy 298.007742 -384.301449) (xy 298.045689 -384.245864) (xy 298.067476 -384.220212) (xy 298.07329 -384.213079)
			(xy 298.079795 -384.195879) (xy 298.080176 -384.186684) (xy 298.080176 -383.693416) (xy 298.079764 -383.684229)
			(xy 298.073252 -383.667044) (xy 298.067476 -383.659888) (xy 298.045651 -383.634266) (xy 298.007701 -383.578676)
			(xy 297.976668 -383.518948) (xy 297.952995 -383.45594) (xy 297.937024 -383.390554) (xy 297.928982 -383.323727)
			(xy 296.826877 -383.323727) (xy 296.827007 -383.324071) (xy 296.84304 -383.389561) (xy 296.851114 -383.4565)
			(xy 296.851113 -383.523924) (xy 296.843036 -383.590863) (xy 296.827 -383.656352) (xy 296.803235 -383.71945)
			(xy 296.772084 -383.779247) (xy 296.733996 -383.834882) (xy 296.712132 -383.860548) (xy 296.706324 -383.867685)
			(xy 296.699818 -383.884882) (xy 296.699432 -383.894076) (xy 296.699432 -384.051556) (xy 296.698949 -384.061672)
			(xy 296.691221 -384.080368) (xy 296.676925 -384.094683) (xy 296.658239 -384.102435) (xy 296.648124 -384.102864)
			(xy 295.931844 -384.102864) (xy 295.92172 -384.102447) (xy 295.90301 -384.094707) (xy 295.888693 -384.08039)
			(xy 295.880953 -384.06168) (xy 295.880536 -384.051556) (xy 295.880536 -383.894076) (xy 295.880129 -383.884889)
			(xy 295.873612 -383.867705) (xy 295.867836 -383.860548) (xy 295.845986 -383.83487) (xy 295.807895 -383.779238)
			(xy 295.776742 -383.719444) (xy 295.752975 -383.656349) (xy 295.736937 -383.590861) (xy 295.728859 -383.523924)
			(xy 295.728858 -383.4565) (xy 295.736933 -383.389563) (xy 295.752968 -383.324074) (xy 295.776732 -383.260978)
			(xy 295.807883 -383.201182) (xy 295.845972 -383.145549) (xy 295.867836 -383.119884) (xy 295.873626 -383.112735)
			(xy 295.880144 -383.095547) (xy 295.880536 -383.086356) (xy 295.880536 -382.59385) (xy 295.880094 -382.584666)
			(xy 295.873601 -382.567482) (xy 295.867836 -382.560322) (xy 295.845961 -382.534665) (xy 295.80787 -382.479031)
			(xy 295.776718 -382.419233) (xy 295.752953 -382.356135) (xy 295.736917 -382.290645) (xy 295.728841 -382.223705)
			(xy 292.450794 -382.223705) (xy 292.442758 -382.290467) (xy 292.426786 -382.355849) (xy 292.403113 -382.418853)
			(xy 292.37208 -382.478576) (xy 292.334131 -382.534162) (xy 292.312344 -382.559814) (xy 292.306552 -382.566962)
			(xy 292.300036 -382.584151) (xy 292.299644 -382.593342) (xy 292.299644 -383.086864) (xy 292.300084 -383.096048)
			(xy 292.306578 -383.113232) (xy 292.312344 -383.120392) (xy 292.334148 -383.146031) (xy 292.372098 -383.201619)
			(xy 292.403131 -383.261344) (xy 292.426592 -383.323786) (xy 293.528687 -383.323786) (xy 293.52869 -383.25636)
			(xy 293.536769 -383.189419) (xy 293.552808 -383.123928) (xy 293.576576 -383.06083) (xy 293.60773 -383.001033)
			(xy 293.645822 -382.945397) (xy 293.667688 -382.919732) (xy 293.673495 -382.912594) (xy 293.680004 -382.895398)
			(xy 293.680388 -382.886204) (xy 293.680388 -382.728724) (xy 293.680835 -382.718605) (xy 293.688573 -382.699904)
			(xy 293.70288 -382.685589) (xy 293.721577 -382.677841) (xy 293.731696 -382.677416) (xy 294.447976 -382.677416)
			(xy 294.458099 -382.677836) (xy 294.476805 -382.685579) (xy 294.491121 -382.699895) (xy 294.498864 -382.718601)
			(xy 294.499284 -382.728724) (xy 294.499284 -382.886204) (xy 294.499696 -382.895391) (xy 294.506209 -382.912575)
			(xy 294.511984 -382.919732) (xy 294.533813 -382.945426) (xy 294.571904 -383.001056) (xy 294.603057 -383.060848)
			(xy 294.626824 -383.123941) (xy 294.642863 -383.189427) (xy 294.650942 -383.256362) (xy 294.650945 -383.323784)
			(xy 294.642872 -383.39072) (xy 294.62684 -383.456207) (xy 294.603079 -383.519302) (xy 294.571932 -383.579097)
			(xy 294.533846 -383.634731) (xy 294.511984 -383.660396) (xy 294.506205 -383.667553) (xy 294.49968 -383.684735)
			(xy 294.499284 -383.693924) (xy 294.499284 -384.186176) (xy 294.499709 -384.195361) (xy 294.506213 -384.212546)
			(xy 294.511984 -384.219704) (xy 294.533884 -384.24534) (xy 294.571973 -384.300978) (xy 294.603123 -384.360778)
			(xy 294.626885 -384.423879) (xy 294.642919 -384.489372) (xy 294.650992 -384.556314) (xy 294.650989 -384.62374)
			(xy 294.642909 -384.690681) (xy 294.626869 -384.756173) (xy 294.603101 -384.819271) (xy 294.571945 -384.879068)
			(xy 294.533851 -384.934703) (xy 294.511984 -384.960368) (xy 294.506174 -384.967504) (xy 294.499668 -384.984702)
			(xy 294.499284 -384.993896) (xy 294.499284 -385.151376) (xy 294.498864 -385.161499) (xy 294.491121 -385.180205)
			(xy 294.476805 -385.194521) (xy 294.458099 -385.202264) (xy 294.447976 -385.202684) (xy 293.731696 -385.202684)
			(xy 293.721571 -385.202287) (xy 293.702865 -385.194534) (xy 293.68855 -385.180212) (xy 293.680808 -385.161501)
			(xy 293.680388 -385.151376) (xy 293.680388 -384.993896) (xy 293.679982 -384.984708) (xy 293.673466 -384.967524)
			(xy 293.667688 -384.960368) (xy 293.64586 -384.934673) (xy 293.607771 -384.879043) (xy 293.576619 -384.819251)
			(xy 293.552854 -384.756158) (xy 293.536816 -384.690672) (xy 293.528737 -384.623737) (xy 293.528734 -384.556317)
			(xy 293.536806 -384.489381) (xy 293.552838 -384.423894) (xy 293.576597 -384.360799) (xy 293.607743 -384.301004)
			(xy 293.645827 -384.245369) (xy 293.667688 -384.219704) (xy 293.673464 -384.212544) (xy 293.679991 -384.195365)
			(xy 293.680388 -384.186176) (xy 293.680388 -383.693924) (xy 293.679969 -383.684738) (xy 293.673462 -383.667553)
			(xy 293.667688 -383.660396) (xy 293.645789 -383.63476) (xy 293.607702 -383.579121) (xy 293.576554 -383.51932)
			(xy 293.552792 -383.45622) (xy 293.53676 -383.390727) (xy 293.528687 -383.323786) (xy 292.426592 -383.323786)
			(xy 292.426804 -383.32435) (xy 292.442776 -383.389734) (xy 292.450819 -383.456559) (xy 292.450818 -383.523865)
			(xy 292.442772 -383.590689) (xy 292.426797 -383.656073) (xy 292.403121 -383.719078) (xy 292.372085 -383.778802)
			(xy 292.334133 -383.834388) (xy 292.312344 -383.86004) (xy 292.306541 -383.86718) (xy 292.300032 -383.884375)
			(xy 292.299644 -383.893568) (xy 292.299644 -384.051556) (xy 292.299149 -384.06167) (xy 292.291423 -384.080364)
			(xy 292.277132 -384.094679) (xy 292.258449 -384.102433) (xy 292.248336 -384.102864) (xy 291.531802 -384.102864)
			(xy 291.521676 -384.102372) (xy 291.502956 -384.094645) (xy 291.488599 -384.080361) (xy 291.480779 -384.06168)
			(xy 291.48024 -384.051556) (xy 291.48024 -383.893568) (xy 291.479836 -383.88438) (xy 291.473317 -383.867197)
			(xy 291.46754 -383.86004) (xy 291.445768 -383.834375) (xy 291.407819 -383.77879) (xy 291.376785 -383.719068)
			(xy 291.353111 -383.656066) (xy 291.337137 -383.590685) (xy 291.329092 -383.523864) (xy 291.32909 -383.45656)
			(xy 291.337133 -383.389739) (xy 291.353104 -383.324357) (xy 291.376775 -383.261354) (xy 291.407806 -383.20163)
			(xy 291.445753 -383.146044) (xy 291.46754 -383.120392) (xy 291.473328 -383.113241) (xy 291.479847 -383.096055)
			(xy 291.48024 -383.086864) (xy 291.48024 -382.593342) (xy 291.4798 -382.584158) (xy 291.473306 -382.566974)
			(xy 291.46754 -382.559814) (xy 291.445742 -382.53417) (xy 291.407794 -382.478582) (xy 291.376761 -382.418858)
			(xy 291.353088 -382.355852) (xy 291.337116 -382.290469) (xy 291.329073 -382.223645) (xy 288.051034 -382.223645)
			(xy 288.051034 -382.223704) (xy 288.042958 -382.290643) (xy 288.026922 -382.356132) (xy 288.003157 -382.419229)
			(xy 287.972004 -382.479024) (xy 287.933913 -382.534658) (xy 287.912048 -382.560322) (xy 287.906253 -382.567468)
			(xy 287.899739 -382.584658) (xy 287.899348 -382.59385) (xy 287.899348 -383.086356) (xy 287.899791 -383.095539)
			(xy 287.906283 -383.112723) (xy 287.912048 -383.119884) (xy 287.93393 -383.145535) (xy 287.972021 -383.201171)
			(xy 288.003174 -383.260968) (xy 288.026812 -383.323727) (xy 289.128894 -383.323727) (xy 289.128898 -383.256418)
			(xy 289.136946 -383.189593) (xy 289.152924 -383.124208) (xy 289.176604 -383.061202) (xy 289.207644 -383.001477)
			(xy 289.245601 -382.945891) (xy 289.267392 -382.92024) (xy 289.273196 -382.9131) (xy 289.279706 -382.895905)
			(xy 289.280092 -382.886712) (xy 289.280092 -382.728724) (xy 289.280535 -382.718604) (xy 289.288274 -382.699902)
			(xy 289.302582 -382.685588) (xy 289.32128 -382.67784) (xy 289.3314 -382.677416) (xy 290.047934 -382.677416)
			(xy 290.05806 -382.677898) (xy 290.076777 -382.685632) (xy 290.091132 -382.69992) (xy 290.098954 -382.7186)
			(xy 290.099496 -382.728724) (xy 290.099496 -382.886712) (xy 290.099901 -382.8959) (xy 290.106419 -382.913084)
			(xy 290.112196 -382.92024) (xy 290.133947 -382.945922) (xy 290.171895 -383.001505) (xy 290.202928 -383.061225)
			(xy 290.226601 -383.124225) (xy 290.242576 -383.189603) (xy 290.250622 -383.256422) (xy 290.250625 -383.323724)
			(xy 290.242585 -383.390543) (xy 290.226617 -383.455923) (xy 290.20295 -383.518926) (xy 290.171923 -383.578649)
			(xy 290.133981 -383.634235) (xy 290.112196 -383.659888) (xy 290.106379 -383.667019) (xy 290.099877 -383.68422)
			(xy 290.099496 -383.693416) (xy 290.099496 -384.186684) (xy 290.099915 -384.19587) (xy 290.106423 -384.213055)
			(xy 290.112196 -384.220212) (xy 290.134018 -384.245836) (xy 290.171963 -384.301427) (xy 290.202993 -384.361155)
			(xy 290.226662 -384.424163) (xy 290.242632 -384.489548) (xy 290.250673 -384.556373) (xy 290.250669 -384.623681)
			(xy 290.242622 -384.690505) (xy 290.226646 -384.755889) (xy 290.202971 -384.818895) (xy 290.171936 -384.87862)
			(xy 290.133985 -384.934207) (xy 290.112196 -384.95986) (xy 290.106391 -384.966999) (xy 290.099881 -384.984194)
			(xy 290.099496 -384.993388) (xy 290.099496 -385.151376) (xy 290.099064 -385.161497) (xy 290.091323 -385.180201)
			(xy 290.077011 -385.194517) (xy 290.058309 -385.202262) (xy 290.048188 -385.202684) (xy 289.331654 -385.202684)
			(xy 289.321527 -385.202212) (xy 289.30281 -385.194473) (xy 289.288456 -385.180183) (xy 289.280634 -385.1615)
			(xy 289.280092 -385.151376) (xy 289.280092 -384.993388) (xy 289.279689 -384.9842) (xy 289.273171 -384.967016)
			(xy 289.267392 -384.95986) (xy 289.245638 -384.934179) (xy 289.207685 -384.878598) (xy 289.176647 -384.818879)
			(xy 289.15297 -384.755878) (xy 289.136993 -384.690499) (xy 289.128945 -384.623679) (xy 289.128942 -384.556375)
			(xy 289.136983 -384.489554) (xy 289.152954 -384.424174) (xy 289.176625 -384.36117) (xy 289.207657 -384.301448)
			(xy 289.245605 -384.245863) (xy 289.267392 -384.220212) (xy 289.273208 -384.21308) (xy 289.279711 -384.195879)
			(xy 289.280092 -384.186684) (xy 289.280092 -383.693416) (xy 289.279676 -383.684229) (xy 289.273167 -383.667045)
			(xy 289.267392 -383.659888) (xy 289.245567 -383.634266) (xy 289.207616 -383.578676) (xy 289.176581 -383.518949)
			(xy 289.152908 -383.45594) (xy 289.136936 -383.390554) (xy 289.128894 -383.323727) (xy 288.026812 -383.323727)
			(xy 288.02694 -383.324067) (xy 288.042976 -383.389558) (xy 288.051051 -383.456499) (xy 288.05105 -383.523925)
			(xy 288.042971 -383.590865) (xy 288.026933 -383.656356) (xy 288.003164 -383.719454) (xy 287.972009 -383.77925)
			(xy 287.933915 -383.834884) (xy 287.912048 -383.860548) (xy 287.906242 -383.867686) (xy 287.899734 -383.884882)
			(xy 287.899348 -383.894076) (xy 287.899348 -384.051556) (xy 287.898849 -384.06167) (xy 287.891124 -384.080363)
			(xy 287.876834 -384.094677) (xy 287.858153 -384.102432) (xy 287.84804 -384.102864) (xy 287.13176 -384.102864)
			(xy 287.12163 -384.102516) (xy 287.102919 -384.094748) (xy 287.088605 -384.08041) (xy 287.080868 -384.061686)
			(xy 287.080452 -384.051556) (xy 287.080452 -383.894076) (xy 287.080042 -383.884889) (xy 287.073527 -383.867705)
			(xy 287.067752 -383.860548) (xy 287.045902 -383.834871) (xy 287.007809 -383.779239) (xy 286.976655 -383.719445)
			(xy 286.952888 -383.65635) (xy 286.936849 -383.590862) (xy 286.928772 -383.523924) (xy 286.92877 -383.4565)
			(xy 286.936845 -383.389562) (xy 286.952881 -383.324073) (xy 286.976645 -383.260977) (xy 287.007797 -383.201182)
			(xy 287.045887 -383.145548) (xy 287.067752 -383.119884) (xy 287.073544 -383.112736) (xy 287.08006 -383.095547)
			(xy 287.080452 -383.086356) (xy 287.080452 -382.59385) (xy 287.080006 -382.584667) (xy 287.073516 -382.567483)
			(xy 287.067752 -382.560322) (xy 287.045876 -382.534666) (xy 287.007785 -382.479031) (xy 286.976631 -382.419234)
			(xy 286.952865 -382.356136) (xy 286.936829 -382.290645) (xy 286.928753 -382.223705) (xy 262.274304 -382.223705)
			(xy 262.274304 -385.608376) (xy 454.303373 -385.608376) (xy 454.303373 -385.479236) (xy 454.311323 -385.350341)
			(xy 454.327193 -385.222181) (xy 454.350922 -385.09524) (xy 454.382421 -384.970001) (xy 454.42157 -384.846938)
			(xy 454.468221 -384.726519) (xy 454.522196 -384.6092) (xy 454.583291 -384.495426) (xy 454.651274 -384.385629)
			(xy 454.725888 -384.280226) (xy 454.806849 -384.179616) (xy 454.893849 -384.084181) (xy 454.98656 -383.994282)
			(xy 455.08463 -383.910261) (xy 455.187685 -383.832437) (xy 455.295336 -383.761105) (xy 455.407175 -383.696535)
			(xy 455.522776 -383.638973) (xy 455.641701 -383.588636) (xy 455.7635 -383.545716) (xy 455.88771 -383.510375)
			(xy 456.013859 -383.482748) (xy 456.141471 -383.462939) (xy 456.27006 -383.451023) (xy 456.399138 -383.447047)
			(xy 456.528216 -383.451023) (xy 456.656805 -383.462939) (xy 456.784417 -383.482748) (xy 456.910566 -383.510375)
			(xy 457.034776 -383.545716) (xy 457.156575 -383.588636) (xy 457.2755 -383.638973) (xy 457.391101 -383.696535)
			(xy 457.50294 -383.761105) (xy 457.610591 -383.832437) (xy 457.713646 -383.910261) (xy 457.811716 -383.994282)
			(xy 457.904427 -384.084181) (xy 457.991427 -384.179616) (xy 458.072388 -384.280226) (xy 458.147002 -384.385629)
			(xy 458.214985 -384.495426) (xy 458.27608 -384.6092) (xy 458.330055 -384.726519) (xy 458.376706 -384.846938)
			(xy 458.415855 -384.970001) (xy 458.447354 -385.09524) (xy 458.471083 -385.222181) (xy 458.486953 -385.350341)
			(xy 458.494903 -385.479236) (xy 458.4954 -385.543806) (xy 458.494903 -385.608376) (xy 458.486953 -385.737271)
			(xy 458.471083 -385.865431) (xy 458.447354 -385.992372) (xy 458.415855 -386.117611) (xy 458.376706 -386.240674)
			(xy 458.330055 -386.361093) (xy 458.27608 -386.478412) (xy 458.214985 -386.592186) (xy 458.147002 -386.701983)
			(xy 458.072388 -386.807386) (xy 457.991427 -386.907996) (xy 457.904427 -387.003431) (xy 457.811716 -387.09333)
			(xy 457.713646 -387.177351) (xy 457.610591 -387.255175) (xy 457.50294 -387.326507) (xy 457.391101 -387.391077)
			(xy 457.2755 -387.448639) (xy 457.156575 -387.498976) (xy 457.034776 -387.541896) (xy 456.910566 -387.577237)
			(xy 456.784417 -387.604864) (xy 456.656805 -387.624673) (xy 456.528216 -387.636589) (xy 456.399138 -387.640566)
			(xy 456.27006 -387.636589) (xy 456.141471 -387.624673) (xy 456.013859 -387.604864) (xy 455.88771 -387.577237)
			(xy 455.7635 -387.541896) (xy 455.641701 -387.498976) (xy 455.522776 -387.448639) (xy 455.407175 -387.391077)
			(xy 455.295336 -387.326507) (xy 455.187685 -387.255175) (xy 455.08463 -387.177351) (xy 454.98656 -387.09333)
			(xy 454.893849 -387.003431) (xy 454.806849 -386.907996) (xy 454.725888 -386.807386) (xy 454.651274 -386.701983)
			(xy 454.583291 -386.592186) (xy 454.522196 -386.478412) (xy 454.468221 -386.361093) (xy 454.42157 -386.240674)
			(xy 454.382421 -386.117611) (xy 454.350922 -385.992372) (xy 454.327193 -385.865431) (xy 454.311323 -385.737271)
			(xy 454.303373 -385.608376) (xy 262.274304 -385.608376) (xy 262.274304 -387.892798) (xy 262.273903 -387.902871)
			(xy 262.266168 -387.92147) (xy 262.259318 -387.928866) (xy 259.197602 -390.990582) (xy 259.190193 -390.997411)
			(xy 259.171601 -391.005138) (xy 259.161534 -391.005568) (xy 245.155466 -391.005568) (xy 245.143121 -391.006101)
			(xy 245.120249 -391.015389) (xy 245.111016 -391.023602) (xy 245.110508 -391.02411) (xy 244.084602 -392.050016)
			(xy 244.076151 -392.059207) (xy 244.066584 -392.082246) (xy 244.06606 -392.09472) (xy 244.06606 -397.823885)
			(xy 286.928734 -397.823885) (xy 286.928737 -397.756458) (xy 286.936817 -397.689516) (xy 286.952859 -397.624024)
			(xy 286.976629 -397.560925) (xy 287.007787 -397.501128) (xy 287.045884 -397.445494) (xy 287.067752 -397.41983)
			(xy 287.073567 -397.412698) (xy 287.080069 -397.395497) (xy 287.080452 -397.386302) (xy 287.080452 -396.89405)
			(xy 287.080006 -396.884867) (xy 287.073516 -396.867683) (xy 287.067752 -396.860522) (xy 287.045876 -396.834866)
			(xy 287.007785 -396.779231) (xy 286.976631 -396.719434) (xy 286.952865 -396.656336) (xy 286.936829 -396.590845)
			(xy 286.928753 -396.523905) (xy 286.928754 -396.45648) (xy 286.936832 -396.38954) (xy 286.95287 -396.32405)
			(xy 286.976638 -396.260952) (xy 287.007792 -396.201156) (xy 287.045886 -396.145522) (xy 287.067752 -396.119858)
			(xy 287.073555 -396.112718) (xy 287.080065 -396.095523) (xy 287.080452 -396.08633) (xy 287.080452 -395.92885)
			(xy 287.080968 -395.918725) (xy 287.088682 -395.900003) (xy 287.102959 -395.885644) (xy 287.121638 -395.877825)
			(xy 287.13176 -395.877288) (xy 287.84804 -395.877288) (xy 287.858195 -395.877689) (xy 287.876946 -395.885495)
			(xy 287.891268 -395.899898) (xy 287.898968 -395.918693) (xy 287.899348 -395.92885) (xy 287.899348 -396.08633)
			(xy 287.899755 -396.095517) (xy 287.906272 -396.112701) (xy 287.912048 -396.119858) (xy 287.933904 -396.14553)
			(xy 287.971996 -396.201163) (xy 288.00315 -396.260957) (xy 288.026917 -396.324053) (xy 288.042955 -396.389542)
			(xy 288.051033 -396.456481) (xy 288.051034 -396.523904) (xy 288.042958 -396.590843) (xy 288.026922 -396.656332)
			(xy 288.003157 -396.719429) (xy 287.972004 -396.779224) (xy 287.933913 -396.834858) (xy 287.912048 -396.860522)
			(xy 287.906253 -396.867668) (xy 287.899739 -396.884858) (xy 287.899348 -396.89405) (xy 287.899348 -397.386302)
			(xy 287.899769 -397.395488) (xy 287.906276 -397.412672) (xy 287.912048 -397.41983) (xy 287.933876 -397.445525)
			(xy 287.97197 -397.501154) (xy 288.000733 -397.556355) (xy 289.128926 -397.556355) (xy 289.13697 -397.489532)
			(xy 289.152943 -397.42415) (xy 289.176617 -397.361145) (xy 289.207652 -397.301423) (xy 289.245603 -397.245837)
			(xy 289.267392 -397.220186) (xy 289.273176 -397.213032) (xy 289.279698 -397.195848) (xy 289.280092 -397.186658)
			(xy 289.280092 -397.028924) (xy 289.280541 -397.018772) (xy 289.288327 -397.000022) (xy 289.302715 -396.985698)
			(xy 289.321501 -396.977996) (xy 289.331654 -396.977616) (xy 290.047934 -396.977616) (xy 290.05806 -396.978098)
			(xy 290.076777 -396.985832) (xy 290.091132 -397.00012) (xy 290.098954 -397.0188) (xy 290.099496 -397.028924)
			(xy 290.099496 -397.186658) (xy 290.099927 -397.195843) (xy 290.106426 -397.213027) (xy 290.112196 -397.220186)
			(xy 290.133992 -397.245831) (xy 290.171939 -397.301419) (xy 290.20297 -397.361144) (xy 290.22664 -397.424149)
			(xy 290.242612 -397.489532) (xy 290.250654 -397.556355) (xy 290.250653 -397.62366) (xy 290.242609 -397.690483)
			(xy 290.226636 -397.755865) (xy 290.202963 -397.81887) (xy 290.200388 -397.823825) (xy 291.329053 -397.823825)
			(xy 291.329057 -397.756517) (xy 291.337105 -397.689692) (xy 291.353082 -397.624308) (xy 291.376759 -397.561302)
			(xy 291.407796 -397.501577) (xy 291.44575 -397.44599) (xy 291.46754 -397.420338) (xy 291.47335 -397.413203)
			(xy 291.479856 -397.396004) (xy 291.48024 -397.38681) (xy 291.48024 -396.893542) (xy 291.4798 -396.884358)
			(xy 291.473306 -396.867174) (xy 291.46754 -396.860014) (xy 291.445742 -396.83437) (xy 291.407794 -396.778782)
			(xy 291.376761 -396.719058) (xy 291.353088 -396.656052) (xy 291.337116 -396.590669) (xy 291.329073 -396.523845)
			(xy 291.329074 -396.45654) (xy 291.337119 -396.389716) (xy 291.353093 -396.324333) (xy 291.376767 -396.261328)
			(xy 291.407801 -396.201605) (xy 291.445751 -396.146018) (xy 291.46754 -396.120366) (xy 291.473339 -396.113222)
			(xy 291.479851 -396.096031) (xy 291.48024 -396.086838) (xy 291.48024 -395.92885) (xy 291.480705 -395.918681)
			(xy 291.488474 -395.899887) (xy 291.502847 -395.885501) (xy 291.521634 -395.877714) (xy 291.531802 -395.877288)
			(xy 292.248082 -395.877288) (xy 292.258259 -395.87768) (xy 292.277063 -395.885468) (xy 292.29145 -395.899864)
			(xy 292.299227 -395.918673) (xy 292.299644 -395.92885) (xy 292.299644 -396.086838) (xy 292.300049 -396.096026)
			(xy 292.306568 -396.113209) (xy 292.312344 -396.120366) (xy 292.334122 -396.146026) (xy 292.372072 -396.201611)
			(xy 292.403107 -396.261333) (xy 292.426781 -396.324337) (xy 292.442755 -396.389718) (xy 292.450801 -396.45654)
			(xy 292.450801 -396.523845) (xy 292.442758 -396.590667) (xy 292.426786 -396.656049) (xy 292.403113 -396.719053)
			(xy 292.37208 -396.778776) (xy 292.334131 -396.834362) (xy 292.312344 -396.860014) (xy 292.306552 -396.867162)
			(xy 292.300036 -396.884351) (xy 292.299644 -396.893542) (xy 292.299644 -397.38681) (xy 292.300062 -397.395996)
			(xy 292.306572 -397.41318) (xy 292.312344 -397.420338) (xy 292.334095 -397.446021) (xy 292.372046 -397.501602)
			(xy 292.40047 -397.556296) (xy 293.528718 -397.556296) (xy 293.536793 -397.489359) (xy 293.552827 -397.42387)
			(xy 293.576589 -397.360774) (xy 293.607738 -397.300978) (xy 293.645825 -397.245343) (xy 293.667688 -397.219678)
			(xy 293.673475 -397.212526) (xy 293.679996 -397.195341) (xy 293.680388 -397.18615) (xy 293.680388 -397.028924)
			(xy 293.680835 -397.018805) (xy 293.688573 -397.000104) (xy 293.70288 -396.985789) (xy 293.721577 -396.978041)
			(xy 293.731696 -396.977616) (xy 294.447976 -396.977616) (xy 294.458099 -396.978036) (xy 294.476805 -396.985779)
			(xy 294.491121 -397.000095) (xy 294.498864 -397.018801) (xy 294.499284 -397.028924) (xy 294.499284 -397.18615)
			(xy 294.499722 -397.195334) (xy 294.506217 -397.212519) (xy 294.511984 -397.219678) (xy 294.533858 -397.245335)
			(xy 294.571948 -397.30097) (xy 294.603099 -397.360767) (xy 294.626863 -397.423865) (xy 294.642899 -397.489356)
			(xy 294.650974 -397.556295) (xy 294.650973 -397.62372) (xy 294.642896 -397.690659) (xy 294.626859 -397.756149)
			(xy 294.603093 -397.819246) (xy 294.600676 -397.823885) (xy 295.728821 -397.823885) (xy 295.728825 -397.756458)
			(xy 295.736905 -397.689516) (xy 295.752946 -397.624025) (xy 295.776716 -397.560926) (xy 295.807873 -397.501129)
			(xy 295.845969 -397.445495) (xy 295.867836 -397.41983) (xy 295.873649 -397.412697) (xy 295.880153 -397.395497)
			(xy 295.880536 -397.386302) (xy 295.880536 -396.89405) (xy 295.880094 -396.884866) (xy 295.873601 -396.867682)
			(xy 295.867836 -396.860522) (xy 295.845961 -396.834865) (xy 295.80787 -396.779231) (xy 295.776718 -396.719433)
			(xy 295.752953 -396.656335) (xy 295.736917 -396.590845) (xy 295.728841 -396.523905) (xy 295.728842 -396.45648)
			(xy 295.73692 -396.38954) (xy 295.752957 -396.32405) (xy 295.776724 -396.260953) (xy 295.807878 -396.201157)
			(xy 295.84597 -396.145523) (xy 295.867836 -396.119858) (xy 295.873637 -396.112716) (xy 295.880148 -396.095523)
			(xy 295.880536 -396.08633) (xy 295.880536 -395.92885) (xy 295.881067 -395.918727) (xy 295.888778 -395.900008)
			(xy 295.903051 -395.88565) (xy 295.921724 -395.877828) (xy 295.931844 -395.877288) (xy 296.648124 -395.877288)
			(xy 296.658278 -395.877702) (xy 296.677029 -395.885503) (xy 296.691351 -395.899902) (xy 296.699052 -395.918694)
			(xy 296.699432 -395.92885) (xy 296.699432 -396.08633) (xy 296.699843 -396.095517) (xy 296.706358 -396.1127)
			(xy 296.712132 -396.119858) (xy 296.733985 -396.145532) (xy 296.772072 -396.201166) (xy 296.803221 -396.260961)
			(xy 296.826985 -396.324057) (xy 296.84302 -396.389545) (xy 296.851096 -396.456481) (xy 296.851097 -396.523904)
			(xy 296.843022 -396.590841) (xy 296.826989 -396.656329) (xy 296.803227 -396.719425) (xy 296.77208 -396.779221)
			(xy 296.733994 -396.834856) (xy 296.712132 -396.860522) (xy 296.706335 -396.867667) (xy 296.699823 -396.884858)
			(xy 296.699432 -396.89405) (xy 296.699432 -397.386302) (xy 296.699856 -397.395487) (xy 296.706362 -397.412671)
			(xy 296.712132 -397.41983) (xy 296.733958 -397.445527) (xy 296.772045 -397.501157) (xy 296.800802 -397.556355)
			(xy 297.929014 -397.556355) (xy 297.937057 -397.489532) (xy 297.95303 -397.42415) (xy 297.976704 -397.361146)
			(xy 298.007738 -397.301423) (xy 298.045688 -397.245838) (xy 298.067476 -397.220186) (xy 298.073258 -397.21303)
			(xy 298.079782 -397.195848) (xy 298.080176 -397.186658) (xy 298.080176 -397.028924) (xy 298.080641 -397.018774)
			(xy 298.088424 -397.000027) (xy 298.102807 -396.985704) (xy 298.121587 -396.977999) (xy 298.131738 -396.977616)
			(xy 298.848018 -396.977616) (xy 298.858143 -396.978111) (xy 298.87686 -396.98584) (xy 298.891215 -397.000123)
			(xy 298.899038 -397.018802) (xy 298.89958 -397.028924) (xy 298.89958 -397.186658) (xy 298.900015 -397.195842)
			(xy 298.906512 -397.213027) (xy 298.91228 -397.220186) (xy 298.934077 -397.24583) (xy 298.972024 -397.301418)
			(xy 299.003056 -397.361143) (xy 299.026728 -397.424149) (xy 299.042699 -397.489532) (xy 299.050742 -397.556355)
			(xy 299.050741 -397.62366) (xy 299.042697 -397.690483) (xy 299.026723 -397.755866) (xy 299.00305 -397.818871)
			(xy 299.000445 -397.823885) (xy 300.128612 -397.823885) (xy 300.128616 -397.756458) (xy 300.136696 -397.689517)
			(xy 300.152736 -397.624025) (xy 300.176506 -397.560927) (xy 300.207662 -397.501129) (xy 300.245757 -397.445495)
			(xy 300.267624 -397.41983) (xy 300.273436 -397.412696) (xy 300.27994 -397.395497) (xy 300.280324 -397.386302)
			(xy 300.280324 -396.89405) (xy 300.279884 -396.884866) (xy 300.273391 -396.867682) (xy 300.267624 -396.860522)
			(xy 300.245749 -396.834865) (xy 300.207659 -396.77923) (xy 300.176508 -396.719433) (xy 300.152743 -396.656335)
			(xy 300.136708 -396.590845) (xy 300.128632 -396.523905) (xy 300.128633 -396.45648) (xy 300.13671 -396.389541)
			(xy 300.152748 -396.324051) (xy 300.176514 -396.260953) (xy 300.207667 -396.201157) (xy 300.245759 -396.145523)
			(xy 300.267624 -396.119858) (xy 300.273424 -396.112715) (xy 300.279936 -396.095523) (xy 300.280324 -396.08633)
			(xy 300.280324 -395.92885) (xy 300.280867 -395.918728) (xy 300.288576 -395.900011) (xy 300.302845 -395.885654)
			(xy 300.321514 -395.87783) (xy 300.331632 -395.877288) (xy 301.047912 -395.877288) (xy 301.058065 -395.877711)
			(xy 301.076816 -395.885509) (xy 301.091138 -395.899904) (xy 301.09884 -395.918694) (xy 301.09922 -395.92885)
			(xy 301.09922 -396.08633) (xy 301.099611 -396.095519) (xy 301.106138 -396.112704) (xy 301.11192 -396.119858)
			(xy 301.133773 -396.145532) (xy 301.171861 -396.201165) (xy 301.203011 -396.260961) (xy 301.226775 -396.324056)
			(xy 301.242811 -396.389544) (xy 301.250887 -396.456481) (xy 301.250888 -396.523904) (xy 301.242813 -396.590841)
			(xy 301.226779 -396.656329) (xy 301.203017 -396.719426) (xy 301.171869 -396.779222) (xy 301.133783 -396.834856)
			(xy 301.11192 -396.860522) (xy 301.106134 -396.867675) (xy 301.099612 -396.884859) (xy 301.09922 -396.89405)
			(xy 301.09922 -397.386302) (xy 301.099625 -397.39549) (xy 301.106142 -397.412674) (xy 301.11192 -397.41983)
			(xy 301.133746 -397.445526) (xy 301.171834 -397.501157) (xy 301.200562 -397.556296) (xy 302.328806 -397.556296)
			(xy 302.336881 -397.489359) (xy 302.352914 -397.423871) (xy 302.376676 -397.360775) (xy 302.407824 -397.300979)
			(xy 302.44591 -397.245344) (xy 302.467772 -397.219678) (xy 302.473569 -397.212534) (xy 302.480081 -397.195342)
			(xy 302.480472 -397.18615) (xy 302.480472 -397.028924) (xy 302.480935 -397.018806) (xy 302.48867 -397.000109)
			(xy 302.502972 -396.985795) (xy 302.521663 -396.978043) (xy 302.53178 -396.977616) (xy 303.24806 -396.977616)
			(xy 303.258182 -396.978049) (xy 303.276888 -396.985787) (xy 303.291204 -397.000099) (xy 303.298948 -397.018802)
			(xy 303.299368 -397.028924) (xy 303.299368 -397.18615) (xy 303.299809 -397.195334) (xy 303.306302 -397.212518)
			(xy 303.312068 -397.219678) (xy 303.333943 -397.245335) (xy 303.372033 -397.30097) (xy 303.403185 -397.360767)
			(xy 303.426951 -397.423865) (xy 303.442986 -397.489355) (xy 303.451062 -397.556295) (xy 303.451061 -397.62372)
			(xy 303.442984 -397.69066) (xy 303.426946 -397.75615) (xy 303.403179 -397.819247) (xy 303.372026 -397.879043)
			(xy 303.333934 -397.934677) (xy 303.312068 -397.960342) (xy 303.306267 -397.967484) (xy 303.299756 -397.984677)
			(xy 303.299368 -397.99387) (xy 303.299368 -398.486376) (xy 303.299797 -398.495561) (xy 303.306299 -398.512745)
			(xy 303.312068 -398.519904) (xy 303.333968 -398.54554) (xy 303.372058 -398.601178) (xy 303.403209 -398.660978)
			(xy 303.426973 -398.724078) (xy 303.443007 -398.789571) (xy 303.45108 -398.856513) (xy 303.451077 -398.923941)
			(xy 303.442997 -398.990882) (xy 303.426957 -399.056373) (xy 303.403187 -399.119472) (xy 303.37203 -399.179269)
			(xy 303.333935 -399.234903) (xy 303.312068 -399.260568) (xy 303.306256 -399.267702) (xy 303.299751 -399.284901)
			(xy 303.299368 -399.294096) (xy 303.299368 -399.451576) (xy 303.298964 -399.461701) (xy 303.291218 -399.48041)
			(xy 303.276897 -399.494727) (xy 303.258185 -399.502467) (xy 303.24806 -399.502884) (xy 302.53178 -399.502884)
			(xy 302.521654 -399.5025) (xy 302.502947 -399.494742) (xy 302.488633 -399.480416) (xy 302.480891 -399.461702)
			(xy 302.480472 -399.451576) (xy 302.480472 -399.294096) (xy 302.48007 -399.284908) (xy 302.473551 -399.267723)
			(xy 302.467772 -399.260568) (xy 302.445944 -399.234873) (xy 302.407856 -399.179242) (xy 302.376706 -399.11945)
			(xy 302.352941 -399.056357) (xy 302.336904 -398.990872) (xy 302.328825 -398.923937) (xy 302.328822 -398.856517)
			(xy 302.336894 -398.789582) (xy 302.352925 -398.724095) (xy 302.376684 -398.661) (xy 302.407829 -398.601204)
			(xy 302.445911 -398.54557) (xy 302.467772 -398.519904) (xy 302.473558 -398.512752) (xy 302.480077 -398.495566)
			(xy 302.480472 -398.486376) (xy 302.480472 -397.99387) (xy 302.480082 -397.98468) (xy 302.473555 -397.967496)
			(xy 302.467772 -397.960342) (xy 302.445919 -397.934668) (xy 302.407832 -397.879034) (xy 302.376682 -397.819239)
			(xy 302.352919 -397.756143) (xy 302.336883 -397.690656) (xy 302.328807 -397.623719) (xy 302.328806 -397.556296)
			(xy 301.200562 -397.556296) (xy 301.202986 -397.560949) (xy 301.226751 -397.624042) (xy 301.242789 -397.689527)
			(xy 301.250867 -397.756461) (xy 301.250871 -397.823882) (xy 301.242799 -397.890817) (xy 301.226768 -397.956304)
			(xy 301.203009 -398.019399) (xy 301.171864 -398.079194) (xy 301.133781 -398.134828) (xy 301.11192 -398.160494)
			(xy 301.106146 -398.167655) (xy 301.099617 -398.184833) (xy 301.09922 -398.194022) (xy 301.09922 -398.351502)
			(xy 301.098774 -398.361634) (xy 301.091038 -398.380362) (xy 301.076739 -398.39472) (xy 301.058042 -398.402532)
			(xy 301.047912 -398.403064) (xy 300.331632 -398.403064) (xy 300.321475 -398.402652) (xy 300.302717 -398.39486)
			(xy 300.288391 -398.38046) (xy 300.280696 -398.361661) (xy 300.280324 -398.351502) (xy 300.280324 -398.194022)
			(xy 300.279898 -398.184837) (xy 300.273395 -398.167652) (xy 300.267624 -398.160494) (xy 300.245722 -398.13486)
			(xy 300.207633 -398.079222) (xy 300.176482 -398.019421) (xy 300.152719 -397.95632) (xy 300.136686 -397.890827)
			(xy 300.128612 -397.823885) (xy 299.000445 -397.823885) (xy 298.972017 -397.878595) (xy 298.934068 -397.934182)
			(xy 298.91228 -397.959834) (xy 298.906484 -397.96698) (xy 298.89997 -397.98417) (xy 298.89958 -397.993362)
			(xy 298.89958 -398.486884) (xy 298.900003 -398.49607) (xy 298.906508 -398.513254) (xy 298.91228 -398.520412)
			(xy 298.934103 -398.546035) (xy 298.972049 -398.601626) (xy 299.00308 -398.661354) (xy 299.02675 -398.724362)
			(xy 299.04272 -398.789748) (xy 299.050761 -398.856573) (xy 299.050757 -398.923881) (xy 299.04271 -398.990706)
			(xy 299.026734 -399.05609) (xy 299.003058 -399.119095) (xy 298.972021 -399.17882) (xy 298.934069 -399.234408)
			(xy 298.91228 -399.26006) (xy 298.906473 -399.267198) (xy 298.899965 -399.284394) (xy 298.89958 -399.293588)
			(xy 298.89958 -399.451576) (xy 298.899159 -399.461731) (xy 298.891367 -399.480487) (xy 298.87697 -399.494812)
			(xy 298.858175 -399.502509) (xy 298.848018 -399.502884) (xy 298.131738 -399.502884) (xy 298.121617 -399.502343)
			(xy 298.102901 -399.494632) (xy 298.088544 -399.480362) (xy 298.08072 -399.461694) (xy 298.080176 -399.451576)
			(xy 298.080176 -399.293588) (xy 298.079777 -399.2844) (xy 298.073256 -399.267215) (xy 298.067476 -399.26006)
			(xy 298.045723 -399.234379) (xy 298.00777 -399.178798) (xy 297.976733 -399.119078) (xy 297.953057 -399.056078)
			(xy 297.93708 -398.990699) (xy 297.929033 -398.923879) (xy 297.92903 -398.856576) (xy 297.937071 -398.789755)
			(xy 297.953041 -398.724374) (xy 297.976711 -398.661371) (xy 298.007742 -398.601649) (xy 298.045689 -398.546064)
			(xy 298.067476 -398.520412) (xy 298.07329 -398.513279) (xy 298.079795 -398.496079) (xy 298.080176 -398.486884)
			(xy 298.080176 -397.993362) (xy 298.079789 -397.984172) (xy 298.07326 -397.966988) (xy 298.067476 -397.959834)
			(xy 298.045697 -397.934174) (xy 298.007746 -397.87859) (xy 297.97671 -397.818868) (xy 297.953035 -397.755864)
			(xy 297.93706 -397.690482) (xy 297.929015 -397.62366) (xy 297.929014 -397.556355) (xy 296.800802 -397.556355)
			(xy 296.803196 -397.56095) (xy 296.826961 -397.624042) (xy 296.842998 -397.689527) (xy 296.851076 -397.756461)
			(xy 296.85108 -397.823881) (xy 296.843008 -397.890817) (xy 296.826978 -397.956303) (xy 296.803219 -398.019398)
			(xy 296.772075 -398.079194) (xy 296.733993 -398.134828) (xy 296.712132 -398.160494) (xy 296.706347 -398.167647)
			(xy 296.699827 -398.184832) (xy 296.699432 -398.194022) (xy 296.699432 -398.351502) (xy 296.698974 -398.361632)
			(xy 296.691241 -398.380359) (xy 296.676945 -398.394716) (xy 296.658252 -398.40253) (xy 296.648124 -398.403064)
			(xy 295.931844 -398.403064) (xy 295.921688 -398.402642) (xy 295.90293 -398.394854) (xy 295.888604 -398.380456)
			(xy 295.880909 -398.36166) (xy 295.880536 -398.351502) (xy 295.880536 -398.194022) (xy 295.880107 -398.184837)
			(xy 295.873606 -398.167653) (xy 295.867836 -398.160494) (xy 295.845933 -398.13486) (xy 295.807843 -398.079222)
			(xy 295.776692 -398.019422) (xy 295.752929 -397.956321) (xy 295.736895 -397.890827) (xy 295.728821 -397.823885)
			(xy 294.600676 -397.823885) (xy 294.57194 -397.879043) (xy 294.533849 -397.934677) (xy 294.511984 -397.960342)
			(xy 294.506185 -397.967486) (xy 294.499672 -397.984677) (xy 294.499284 -397.99387) (xy 294.499284 -398.486376)
			(xy 294.499709 -398.495561) (xy 294.506213 -398.512746) (xy 294.511984 -398.519904) (xy 294.533884 -398.54554)
			(xy 294.571973 -398.601178) (xy 294.603123 -398.660978) (xy 294.626885 -398.724079) (xy 294.642919 -398.789572)
			(xy 294.650992 -398.856514) (xy 294.650989 -398.92394) (xy 294.642909 -398.990881) (xy 294.626869 -399.056373)
			(xy 294.603101 -399.119471) (xy 294.571945 -399.179268) (xy 294.533851 -399.234903) (xy 294.511984 -399.260568)
			(xy 294.506174 -399.267704) (xy 294.499668 -399.284902) (xy 294.499284 -399.294096) (xy 294.499284 -399.451576)
			(xy 294.498864 -399.461699) (xy 294.491121 -399.480405) (xy 294.476805 -399.494721) (xy 294.458099 -399.502464)
			(xy 294.447976 -399.502884) (xy 293.731696 -399.502884) (xy 293.721571 -399.502487) (xy 293.702865 -399.494734)
			(xy 293.68855 -399.480412) (xy 293.680808 -399.461701) (xy 293.680388 -399.451576) (xy 293.680388 -399.294096)
			(xy 293.679982 -399.284908) (xy 293.673466 -399.267724) (xy 293.667688 -399.260568) (xy 293.64586 -399.234873)
			(xy 293.607771 -399.179243) (xy 293.576619 -399.119451) (xy 293.552854 -399.056358) (xy 293.536816 -398.990872)
			(xy 293.528737 -398.923937) (xy 293.528734 -398.856517) (xy 293.536806 -398.789581) (xy 293.552838 -398.724094)
			(xy 293.576597 -398.660999) (xy 293.607743 -398.601204) (xy 293.645827 -398.545569) (xy 293.667688 -398.519904)
			(xy 293.673464 -398.512744) (xy 293.679991 -398.495565) (xy 293.680388 -398.486376) (xy 293.680388 -397.99387)
			(xy 293.679995 -397.984681) (xy 293.673469 -397.967497) (xy 293.667688 -397.960342) (xy 293.645834 -397.934668)
			(xy 293.607746 -397.879035) (xy 293.576596 -397.81924) (xy 293.552831 -397.756144) (xy 293.536796 -397.690656)
			(xy 293.528719 -397.623719) (xy 293.528718 -397.556296) (xy 292.40047 -397.556296) (xy 292.403082 -397.561322)
			(xy 292.426757 -397.624322) (xy 292.442733 -397.689701) (xy 292.450781 -397.75652) (xy 292.450784 -397.823823)
			(xy 292.442744 -397.890643) (xy 292.426774 -397.956023) (xy 292.403105 -398.019026) (xy 292.372075 -398.078748)
			(xy 292.33413 -398.134334) (xy 292.312344 -398.159986) (xy 292.306522 -398.167113) (xy 292.300024 -398.184318)
			(xy 292.299644 -398.193514) (xy 292.299644 -398.351502) (xy 292.299237 -398.361676) (xy 292.291448 -398.380474)
			(xy 292.277057 -398.39486) (xy 292.258256 -398.402641) (xy 292.248082 -398.403064) (xy 291.531802 -398.403064)
			(xy 291.521645 -398.402565) (xy 291.502876 -398.394792) (xy 291.488511 -398.380427) (xy 291.480736 -398.361659)
			(xy 291.48024 -398.351502) (xy 291.48024 -398.193514) (xy 291.479814 -398.184329) (xy 291.473311 -398.167145)
			(xy 291.46754 -398.159986) (xy 291.445715 -398.134365) (xy 291.407767 -398.078774) (xy 291.376735 -398.019046)
			(xy 291.353065 -397.956037) (xy 291.337094 -397.890651) (xy 291.329053 -397.823825) (xy 290.200388 -397.823825)
			(xy 290.171931 -397.878594) (xy 290.133983 -397.934181) (xy 290.112196 -397.959834) (xy 290.106402 -397.966981)
			(xy 290.099886 -397.98417) (xy 290.099496 -397.993362) (xy 290.099496 -398.486884) (xy 290.099915 -398.49607)
			(xy 290.106423 -398.513255) (xy 290.112196 -398.520412) (xy 290.134018 -398.546036) (xy 290.171963 -398.601627)
			(xy 290.202993 -398.661355) (xy 290.226662 -398.724363) (xy 290.242632 -398.789748) (xy 290.250673 -398.856573)
			(xy 290.250669 -398.923881) (xy 290.242622 -398.990705) (xy 290.226646 -399.056089) (xy 290.202971 -399.119095)
			(xy 290.171936 -399.17882) (xy 290.133985 -399.234407) (xy 290.112196 -399.26006) (xy 290.106391 -399.267199)
			(xy 290.099881 -399.284394) (xy 290.099496 -399.293588) (xy 290.099496 -399.451576) (xy 290.099059 -399.461729)
			(xy 290.09127 -399.480482) (xy 290.076878 -399.494806) (xy 290.058089 -399.502506) (xy 290.047934 -399.502884)
			(xy 289.331654 -399.502884) (xy 289.321527 -399.502412) (xy 289.30281 -399.494673) (xy 289.288456 -399.480383)
			(xy 289.280634 -399.4617) (xy 289.280092 -399.451576) (xy 289.280092 -399.293588) (xy 289.279689 -399.2844)
			(xy 289.273171 -399.267216) (xy 289.267392 -399.26006) (xy 289.245638 -399.234379) (xy 289.207685 -399.178798)
			(xy 289.176647 -399.119079) (xy 289.15297 -399.056078) (xy 289.136993 -398.990699) (xy 289.128945 -398.923879)
			(xy 289.128942 -398.856575) (xy 289.136983 -398.789754) (xy 289.152954 -398.724374) (xy 289.176625 -398.66137)
			(xy 289.207657 -398.601648) (xy 289.245605 -398.546063) (xy 289.267392 -398.520412) (xy 289.273208 -398.51328)
			(xy 289.279711 -398.496079) (xy 289.280092 -398.486884) (xy 289.280092 -397.993362) (xy 289.279702 -397.984173)
			(xy 289.273175 -397.966988) (xy 289.267392 -397.959834) (xy 289.245612 -397.934174) (xy 289.20766 -397.87859)
			(xy 289.176623 -397.818868) (xy 289.152948 -397.755865) (xy 289.136972 -397.690483) (xy 289.128927 -397.62366)
			(xy 289.128926 -397.556355) (xy 288.000733 -397.556355) (xy 288.003125 -397.560946) (xy 288.026894 -397.624039)
			(xy 288.042933 -397.689525) (xy 288.051013 -397.756461) (xy 288.051016 -397.823882) (xy 288.042944 -397.890819)
			(xy 288.026911 -397.956307) (xy 288.003148 -398.019402) (xy 287.971999 -398.079197) (xy 287.933912 -398.13483)
			(xy 287.912048 -398.160494) (xy 287.906265 -398.167649) (xy 287.899744 -398.184832) (xy 287.899348 -398.194022)
			(xy 287.899348 -398.351502) (xy 287.898875 -398.36163) (xy 287.891144 -398.380354) (xy 287.876853 -398.39471)
			(xy 287.858166 -398.402527) (xy 287.84804 -398.403064) (xy 287.13176 -398.403064) (xy 287.121599 -398.40271)
			(xy 287.102839 -398.394895) (xy 287.088515 -398.380477) (xy 287.080824 -398.361666) (xy 287.080452 -398.351502)
			(xy 287.080452 -398.194022) (xy 287.08002 -398.184837) (xy 287.07352 -398.167653) (xy 287.067752 -398.160494)
			(xy 287.045849 -398.13486) (xy 287.007758 -398.079223) (xy 286.976606 -398.019423) (xy 286.952842 -397.956321)
			(xy 286.936807 -397.890828) (xy 286.928734 -397.823885) (xy 244.06606 -397.823885) (xy 244.06606 -399.830544)
			(xy 244.065668 -399.840617) (xy 244.057925 -399.859215) (xy 244.051074 -399.866612) (xy 243.052346 -400.865594)
			(xy 243.044923 -400.872406) (xy 243.026341 -400.880142) (xy 243.016278 -400.88058) (xy 238.99114 -400.88058)
			(xy 238.978794 -400.881097) (xy 238.955921 -400.890396) (xy 238.94669 -400.898614) (xy 238.946182 -400.899122)
			(xy 238.121507 -401.723797) (xy 286.928745 -401.723797) (xy 286.928747 -401.65637) (xy 286.936826 -401.58943)
			(xy 286.952865 -401.523939) (xy 286.976634 -401.460841) (xy 287.00779 -401.401044) (xy 287.045885 -401.34541)
			(xy 287.067752 -401.319746) (xy 287.07356 -401.312609) (xy 287.080067 -401.295412) (xy 287.080452 -401.286218)
			(xy 287.080452 -400.793966) (xy 287.080046 -400.784779) (xy 287.073528 -400.767595) (xy 287.067752 -400.760438)
			(xy 287.045892 -400.734769) (xy 287.0078 -400.679136) (xy 286.976646 -400.619341) (xy 286.952879 -400.556244)
			(xy 286.936842 -400.490755) (xy 286.928764 -400.423817) (xy 286.928764 -400.356392) (xy 286.93684 -400.289454)
			(xy 286.952876 -400.223964) (xy 286.976642 -400.160867) (xy 287.007795 -400.101072) (xy 287.045887 -400.045438)
			(xy 287.067752 -400.019774) (xy 287.073549 -400.012629) (xy 287.080062 -399.995438) (xy 287.080452 -399.986246)
			(xy 287.080452 -399.828766) (xy 287.080899 -399.818636) (xy 287.08864 -399.799911) (xy 287.102939 -399.785556)
			(xy 287.121632 -399.77774) (xy 287.13176 -399.777204) (xy 287.84804 -399.777204) (xy 287.858197 -399.777589)
			(xy 287.876951 -399.785399) (xy 287.891273 -399.799806) (xy 287.898971 -399.818606) (xy 287.899348 -399.828766)
			(xy 287.899348 -399.986246) (xy 287.899796 -399.995429) (xy 287.906285 -400.012613) (xy 287.912048 -400.019774)
			(xy 287.93392 -400.045433) (xy 287.972012 -400.101068) (xy 288.003165 -400.160864) (xy 288.026931 -400.223962)
			(xy 288.042968 -400.289452) (xy 288.051044 -400.356392) (xy 288.051043 -400.423817) (xy 288.042966 -400.490757)
			(xy 288.026928 -400.556247) (xy 288.003161 -400.619344) (xy 287.972007 -400.67914) (xy 287.933914 -400.734774)
			(xy 287.912048 -400.760438) (xy 287.906246 -400.767579) (xy 287.899736 -400.784773) (xy 287.899348 -400.793966)
			(xy 287.899348 -401.286218) (xy 287.899761 -401.295405) (xy 287.906274 -401.312588) (xy 287.912048 -401.319746)
			(xy 287.933892 -401.345428) (xy 287.971985 -401.401059) (xy 288.00314 -401.460852) (xy 288.026907 -401.523947)
			(xy 288.042946 -401.589435) (xy 288.051024 -401.656372) (xy 288.051026 -401.723795) (xy 288.042952 -401.790733)
			(xy 288.026917 -401.856221) (xy 288.003153 -401.919317) (xy 287.972002 -401.979113) (xy 287.933912 -402.034746)
			(xy 287.912048 -402.06041) (xy 287.906258 -402.06756) (xy 287.899741 -402.084747) (xy 287.899348 -402.093938)
			(xy 287.899348 -402.251418) (xy 287.898888 -402.261547) (xy 287.891152 -402.280271) (xy 287.876858 -402.294627)
			(xy 287.858167 -402.302444) (xy 287.84804 -402.30298) (xy 287.13176 -402.30298) (xy 287.121601 -402.302611)
			(xy 287.102844 -402.294798) (xy 287.088521 -402.280385) (xy 287.080826 -402.26158) (xy 287.080452 -402.251418)
			(xy 287.080452 -402.093938) (xy 287.080012 -402.084754) (xy 287.073518 -402.06757) (xy 287.067752 -402.06041)
			(xy 287.045865 -402.034763) (xy 287.007773 -401.979127) (xy 286.97662 -401.919329) (xy 286.952855 -401.85623)
			(xy 286.93682 -401.790738) (xy 286.928745 -401.723797) (xy 238.121507 -401.723797) (xy 237.044738 -402.800566)
			(xy 237.036256 -402.809732) (xy 237.030424 -402.823819) (xy 289.128886 -402.823819) (xy 289.12889 -402.756509)
			(xy 289.13694 -402.689682) (xy 289.15292 -402.624297) (xy 289.1766 -402.56129) (xy 289.207642 -402.501565)
			(xy 289.2456 -402.445979) (xy 289.267392 -402.420328) (xy 289.273201 -402.413191) (xy 289.279708 -402.395994)
			(xy 289.280092 -402.3868) (xy 289.280092 -401.893532) (xy 289.279668 -401.884346) (xy 289.273164 -401.867162)
			(xy 289.267392 -401.860004) (xy 289.245583 -401.834369) (xy 289.207631 -401.778781) (xy 289.176596 -401.719056)
			(xy 289.152922 -401.656049) (xy 289.136949 -401.590664) (xy 289.128906 -401.523839) (xy 289.128907 -401.456531)
			(xy 289.136954 -401.389706) (xy 289.152931 -401.324322) (xy 289.176608 -401.261317) (xy 289.207647 -401.201593)
			(xy 289.245601 -401.146007) (xy 289.267392 -401.120356) (xy 289.273189 -401.113211) (xy 289.279704 -401.09602)
			(xy 289.280092 -401.086828) (xy 289.280092 -400.92884) (xy 289.280554 -400.918689) (xy 289.288335 -400.89994)
			(xy 289.30272 -400.885615) (xy 289.321502 -400.877913) (xy 289.331654 -400.877532) (xy 290.047934 -400.877532)
			(xy 290.058062 -400.877998) (xy 290.076782 -400.885736) (xy 290.091137 -400.900028) (xy 290.098957 -400.918714)
			(xy 290.099496 -400.92884) (xy 290.099496 -401.086828) (xy 290.099893 -401.096017) (xy 290.106416 -401.113201)
			(xy 290.112196 -401.120356) (xy 290.133963 -401.146025) (xy 290.17191 -401.20161) (xy 290.202942 -401.261331)
			(xy 290.226615 -401.324334) (xy 290.242588 -401.389713) (xy 290.250633 -401.456534) (xy 290.250635 -401.523836)
			(xy 290.242593 -401.590657) (xy 290.226624 -401.656038) (xy 290.202955 -401.719041) (xy 290.200515 -401.723737)
			(xy 291.329064 -401.723737) (xy 291.329066 -401.65643) (xy 291.337113 -401.589606) (xy 291.353088 -401.524222)
			(xy 291.376763 -401.461217) (xy 291.407799 -401.401493) (xy 291.445751 -401.345906) (xy 291.46754 -401.320254)
			(xy 291.473344 -401.313114) (xy 291.479853 -401.295919) (xy 291.48024 -401.286726) (xy 291.48024 -400.793458)
			(xy 291.479841 -400.78427) (xy 291.473319 -400.767086) (xy 291.46754 -400.75993) (xy 291.445758 -400.734273)
			(xy 291.407809 -400.678687) (xy 291.376776 -400.618964) (xy 291.353103 -400.55596) (xy 291.337129 -400.490579)
			(xy 291.329085 -400.423757) (xy 291.329084 -400.356452) (xy 291.337128 -400.28963) (xy 291.3531 -400.224248)
			(xy 291.376772 -400.161244) (xy 291.407805 -400.101521) (xy 291.445753 -400.045934) (xy 291.46754 -400.020282)
			(xy 291.473332 -400.013134) (xy 291.479848 -399.995945) (xy 291.48024 -399.986754) (xy 291.48024 -399.828766)
			(xy 291.480706 -399.818606) (xy 291.488492 -399.799835) (xy 291.502866 -399.785471) (xy 291.521641 -399.777698)
			(xy 291.531802 -399.777204) (xy 292.248082 -399.777204) (xy 292.258234 -399.777747) (xy 292.276997 -399.785509)
			(xy 292.291361 -399.79986) (xy 292.299143 -399.818614) (xy 292.299644 -399.828766) (xy 292.299644 -399.986754)
			(xy 292.300089 -399.995937) (xy 292.30658 -400.013121) (xy 292.312344 -400.020282) (xy 292.334138 -400.045929)
			(xy 292.372088 -400.101516) (xy 292.403122 -400.16124) (xy 292.426795 -400.224245) (xy 292.442768 -400.289628)
			(xy 292.450812 -400.356452) (xy 292.450811 -400.423757) (xy 292.442766 -400.490581) (xy 292.426792 -400.555963)
			(xy 292.403118 -400.618968) (xy 292.372083 -400.678692) (xy 292.334132 -400.734278) (xy 292.312344 -400.75993)
			(xy 292.306545 -400.767073) (xy 292.300033 -400.784266) (xy 292.299644 -400.793458) (xy 292.299644 -401.286726)
			(xy 292.300054 -401.295913) (xy 292.306569 -401.313097) (xy 292.312344 -401.320254) (xy 292.33411 -401.345924)
			(xy 292.372061 -401.401507) (xy 292.403096 -401.461228) (xy 292.426771 -401.524231) (xy 292.442746 -401.589611)
			(xy 292.450792 -401.656432) (xy 292.450794 -401.723735) (xy 292.442752 -401.790557) (xy 292.426781 -401.855938)
			(xy 292.40311 -401.918941) (xy 292.372078 -401.978664) (xy 292.334131 -402.03425) (xy 292.312344 -402.059902)
			(xy 292.306557 -402.067054) (xy 292.300038 -402.084239) (xy 292.299644 -402.09343) (xy 292.299644 -402.251418)
			(xy 292.299181 -402.261579) (xy 292.291397 -402.280352) (xy 292.277022 -402.294718) (xy 292.258244 -402.302488)
			(xy 292.248082 -402.30298) (xy 291.531802 -402.30298) (xy 291.521647 -402.302465) (xy 291.502881 -402.294695)
			(xy 291.488516 -402.280336) (xy 291.480739 -402.261573) (xy 291.48024 -402.251418) (xy 291.48024 -402.09343)
			(xy 291.479806 -402.084246) (xy 291.473308 -402.067061) (xy 291.46754 -402.059902) (xy 291.44573 -402.034268)
			(xy 291.407782 -401.978679) (xy 291.37675 -401.918953) (xy 291.353078 -401.855946) (xy 291.337107 -401.790561)
			(xy 291.329064 -401.723737) (xy 290.200515 -401.723737) (xy 290.171926 -401.778764) (xy 290.133981 -401.834351)
			(xy 290.112196 -401.860004) (xy 290.106415 -401.86716) (xy 290.099891 -401.884342) (xy 290.099496 -401.893532)
			(xy 290.099496 -402.3868) (xy 290.099907 -402.395987) (xy 290.10642 -402.413171) (xy 290.112196 -402.420328)
			(xy 290.133935 -402.44602) (xy 290.171883 -402.501601) (xy 290.202916 -402.56132) (xy 290.22659 -402.624319)
			(xy 290.242566 -402.689696) (xy 290.250613 -402.756514) (xy 290.250617 -402.823814) (xy 290.250609 -402.823878)
			(xy 293.528678 -402.823878) (xy 293.528683 -402.75645) (xy 293.536763 -402.689509) (xy 293.552803 -402.624017)
			(xy 293.576572 -402.560919) (xy 293.607728 -402.501121) (xy 293.645822 -402.445485) (xy 293.667688 -402.41982)
			(xy 293.6735 -402.412685) (xy 293.680006 -402.395487) (xy 293.680388 -402.386292) (xy 293.680388 -401.89404)
			(xy 293.679961 -401.884854) (xy 293.67346 -401.86767) (xy 293.667688 -401.860512) (xy 293.645805 -401.834863)
			(xy 293.607717 -401.779226) (xy 293.576568 -401.719427) (xy 293.552806 -401.656328) (xy 293.536772 -401.590837)
			(xy 293.528698 -401.523897) (xy 293.5287 -401.456472) (xy 293.536777 -401.389533) (xy 293.552815 -401.324043)
			(xy 293.576581 -401.260945) (xy 293.607733 -401.201149) (xy 293.645823 -401.145513) (xy 293.667688 -401.119848)
			(xy 293.673488 -401.112705) (xy 293.680001 -401.095513) (xy 293.680388 -401.08632) (xy 293.680388 -400.92884)
			(xy 293.680849 -400.918722) (xy 293.688581 -400.900021) (xy 293.702884 -400.885706) (xy 293.721578 -400.877957)
			(xy 293.731696 -400.877532) (xy 294.447976 -400.877532) (xy 294.458101 -400.877936) (xy 294.47681 -400.885682)
			(xy 294.491127 -400.900003) (xy 294.498867 -400.918715) (xy 294.499284 -400.92884) (xy 294.499284 -401.08632)
			(xy 294.499688 -401.095508) (xy 294.506206 -401.112692) (xy 294.511984 -401.119848) (xy 294.533829 -401.145529)
			(xy 294.571919 -401.201161) (xy 294.603072 -401.260955) (xy 294.626838 -401.32405) (xy 294.642875 -401.389537)
			(xy 294.650953 -401.456474) (xy 294.650955 -401.523896) (xy 294.64288 -401.590833) (xy 294.626847 -401.656322)
			(xy 294.603084 -401.719418) (xy 294.600803 -401.723797) (xy 295.728833 -401.723797) (xy 295.728835 -401.65637)
			(xy 295.736913 -401.58943) (xy 295.752952 -401.523939) (xy 295.77672 -401.460841) (xy 295.807876 -401.401045)
			(xy 295.845969 -401.345411) (xy 295.867836 -401.319746) (xy 295.873643 -401.312608) (xy 295.88015 -401.295412)
			(xy 295.880536 -401.286218) (xy 295.880536 -400.793966) (xy 295.880134 -400.784778) (xy 295.873614 -400.767594)
			(xy 295.867836 -400.760438) (xy 295.845977 -400.734769) (xy 295.807885 -400.679135) (xy 295.776732 -400.61934)
			(xy 295.752966 -400.556244) (xy 295.736929 -400.490755) (xy 295.728852 -400.423816) (xy 295.728852 -400.356393)
			(xy 295.736928 -400.289454) (xy 295.752964 -400.223965) (xy 295.776729 -400.160868) (xy 295.807881 -400.101072)
			(xy 295.845971 -400.045439) (xy 295.867836 -400.019774) (xy 295.873631 -400.012628) (xy 295.880146 -399.995438)
			(xy 295.880536 -399.986246) (xy 295.880536 -399.828766) (xy 295.880999 -399.818638) (xy 295.888737 -399.799916)
			(xy 295.90303 -399.785561) (xy 295.921718 -399.777743) (xy 295.931844 -399.777204) (xy 296.648124 -399.777204)
			(xy 296.65828 -399.777602) (xy 296.677034 -399.785406) (xy 296.691357 -399.79981) (xy 296.699055 -399.818608)
			(xy 296.699432 -399.828766) (xy 296.699432 -399.986246) (xy 296.699883 -399.995429) (xy 296.70637 -400.012613)
			(xy 296.712132 -400.019774) (xy 296.734001 -400.045435) (xy 296.772087 -400.101071) (xy 296.803236 -400.160868)
			(xy 296.826998 -400.223965) (xy 296.843032 -400.289455) (xy 296.851107 -400.356393) (xy 296.851107 -400.423816)
			(xy 296.843031 -400.490754) (xy 296.826996 -400.556243) (xy 296.803232 -400.61934) (xy 296.772083 -400.679137)
			(xy 296.733995 -400.734772) (xy 296.712132 -400.760438) (xy 296.706329 -400.767578) (xy 296.69982 -400.784773)
			(xy 296.699432 -400.793966) (xy 296.699432 -401.286218) (xy 296.699849 -401.295404) (xy 296.70636 -401.312588)
			(xy 296.712132 -401.319746) (xy 296.733973 -401.34543) (xy 296.77206 -401.401062) (xy 296.80321 -401.460856)
			(xy 296.826974 -401.523951) (xy 296.84301 -401.589437) (xy 296.851088 -401.656373) (xy 296.85109 -401.723794)
			(xy 296.843016 -401.79073) (xy 296.826984 -401.856218) (xy 296.803224 -401.919314) (xy 296.772078 -401.979109)
			(xy 296.733994 -402.034744) (xy 296.712132 -402.06041) (xy 296.70634 -402.067558) (xy 296.699825 -402.084747)
			(xy 296.699432 -402.093938) (xy 296.699432 -402.251418) (xy 296.698988 -402.261549) (xy 296.691249 -402.280276)
			(xy 296.676949 -402.294633) (xy 296.658253 -402.302447) (xy 296.648124 -402.30298) (xy 295.931844 -402.30298)
			(xy 295.92169 -402.302542) (xy 295.902935 -402.294757) (xy 295.888609 -402.280365) (xy 295.880912 -402.261574)
			(xy 295.880536 -402.251418) (xy 295.880536 -402.093938) (xy 295.880099 -402.084754) (xy 295.873603 -402.06757)
			(xy 295.867836 -402.06041) (xy 295.845949 -402.034763) (xy 295.807859 -401.979127) (xy 295.776707 -401.919328)
			(xy 295.752942 -401.856229) (xy 295.736907 -401.790737) (xy 295.728833 -401.723797) (xy 294.600803 -401.723797)
			(xy 294.571935 -401.779213) (xy 294.533847 -401.834847) (xy 294.511984 -401.860512) (xy 294.506198 -401.867665)
			(xy 294.499678 -401.88485) (xy 294.499284 -401.89404) (xy 294.499284 -402.386292) (xy 294.499702 -402.395478)
			(xy 294.506211 -402.412662) (xy 294.511984 -402.41982) (xy 294.533801 -402.445524) (xy 294.571893 -402.501152)
			(xy 294.603046 -402.560943) (xy 294.626814 -402.624035) (xy 294.642853 -402.68952) (xy 294.650933 -402.756454)
			(xy 294.650937 -402.823819) (xy 297.928973 -402.823819) (xy 297.928978 -402.756509) (xy 297.937027 -402.689683)
			(xy 297.953006 -402.624297) (xy 297.976686 -402.561291) (xy 298.007727 -402.501566) (xy 298.045684 -402.445979)
			(xy 298.067476 -402.420328) (xy 298.073283 -402.41319) (xy 298.079792 -402.395994) (xy 298.080176 -402.3868)
			(xy 298.080176 -401.893532) (xy 298.079756 -401.884346) (xy 298.07325 -401.867161) (xy 298.067476 -401.860004)
			(xy 298.045668 -401.834368) (xy 298.007717 -401.77878) (xy 297.976683 -401.719055) (xy 297.953009 -401.656048)
			(xy 297.937037 -401.590664) (xy 297.928993 -401.523839) (xy 297.928995 -401.456531) (xy 297.937042 -401.389707)
			(xy 297.953018 -401.324323) (xy 297.976695 -401.261318) (xy 298.007732 -401.201594) (xy 298.045686 -401.146008)
			(xy 298.067476 -401.120356) (xy 298.073271 -401.113209) (xy 298.079787 -401.09602) (xy 298.080176 -401.086828)
			(xy 298.080176 -400.92884) (xy 298.080654 -400.918691) (xy 298.088432 -400.899945) (xy 298.102811 -400.885621)
			(xy 298.121588 -400.877915) (xy 298.131738 -400.877532) (xy 298.848018 -400.877532) (xy 298.858145 -400.878011)
			(xy 298.876865 -400.885744) (xy 298.89122 -400.900032) (xy 298.89904 -400.918716) (xy 298.89958 -400.92884)
			(xy 298.89958 -401.086828) (xy 298.899981 -401.096016) (xy 298.906502 -401.1132) (xy 298.91228 -401.120356)
			(xy 298.934048 -401.146024) (xy 298.971996 -401.201609) (xy 299.003029 -401.261331) (xy 299.026702 -401.324333)
			(xy 299.042676 -401.389713) (xy 299.050721 -401.456533) (xy 299.050723 -401.523837) (xy 299.042681 -401.590657)
			(xy 299.026711 -401.656038) (xy 299.003041 -401.719042) (xy 299.000571 -401.723796) (xy 300.128624 -401.723796)
			(xy 300.128626 -401.656371) (xy 300.136704 -401.58943) (xy 300.152743 -401.52394) (xy 300.17651 -401.460842)
			(xy 300.207665 -401.401045) (xy 300.245758 -401.345411) (xy 300.267624 -401.319746) (xy 300.273429 -401.312607)
			(xy 300.279938 -401.295412) (xy 300.280324 -401.286218) (xy 300.280324 -400.793966) (xy 300.279925 -400.784778)
			(xy 300.273403 -400.767594) (xy 300.267624 -400.760438) (xy 300.245765 -400.734768) (xy 300.207675 -400.679135)
			(xy 300.176522 -400.61934) (xy 300.152757 -400.556243) (xy 300.13672 -400.490755) (xy 300.128643 -400.423816)
			(xy 300.128643 -400.356393) (xy 300.136719 -400.289454) (xy 300.152754 -400.223965) (xy 300.176519 -400.160869)
			(xy 300.20767 -400.101073) (xy 300.24576 -400.045439) (xy 300.267624 -400.019774) (xy 300.273417 -400.012626)
			(xy 300.279933 -399.995438) (xy 300.280324 -399.986246) (xy 300.280324 -399.828766) (xy 300.280798 -399.818639)
			(xy 300.288534 -399.79992) (xy 300.302824 -399.785566) (xy 300.321507 -399.777745) (xy 300.331632 -399.777204)
			(xy 301.047912 -399.777204) (xy 301.058067 -399.777612) (xy 301.076821 -399.785412) (xy 301.091144 -399.799813)
			(xy 301.098843 -399.818608) (xy 301.09922 -399.828766) (xy 301.09922 -399.986246) (xy 301.099652 -399.995431)
			(xy 301.10615 -400.012616) (xy 301.11192 -400.019774) (xy 301.133789 -400.045435) (xy 301.171876 -400.10107)
			(xy 301.203026 -400.160867) (xy 301.226789 -400.223965) (xy 301.242823 -400.289454) (xy 301.250898 -400.356393)
			(xy 301.250898 -400.423816) (xy 301.242821 -400.490755) (xy 301.226786 -400.556244) (xy 301.203022 -400.619341)
			(xy 301.171872 -400.679137) (xy 301.133784 -400.734772) (xy 301.11192 -400.760438) (xy 301.106127 -400.767586)
			(xy 301.09961 -400.784774) (xy 301.09922 -400.793966) (xy 301.09922 -401.286218) (xy 301.099617 -401.295407)
			(xy 301.106139 -401.312591) (xy 301.11192 -401.319746) (xy 301.133762 -401.345429) (xy 301.17185 -401.401062)
			(xy 301.203 -401.460856) (xy 301.226765 -401.52395) (xy 301.242801 -401.589437) (xy 301.250878 -401.656373)
			(xy 301.25088 -401.723794) (xy 301.242807 -401.790731) (xy 301.226775 -401.856218) (xy 301.203014 -401.919314)
			(xy 301.171867 -401.97911) (xy 301.133782 -402.034744) (xy 301.11192 -402.06041) (xy 301.106139 -402.067566)
			(xy 301.099614 -402.084748) (xy 301.09922 -402.093938) (xy 301.09922 -402.251418) (xy 301.098787 -402.261551)
			(xy 301.091046 -402.28028) (xy 301.076743 -402.294637) (xy 301.058043 -402.302449) (xy 301.047912 -402.30298)
			(xy 300.331632 -402.30298) (xy 300.321477 -402.302552) (xy 300.302722 -402.294763) (xy 300.288396 -402.280368)
			(xy 300.280699 -402.261575) (xy 300.280324 -402.251418) (xy 300.280324 -402.093938) (xy 300.27989 -402.084753)
			(xy 300.273392 -402.067569) (xy 300.267624 -402.06041) (xy 300.245738 -402.034763) (xy 300.207648 -401.979126)
			(xy 300.176497 -401.919328) (xy 300.152733 -401.856229) (xy 300.136698 -401.790737) (xy 300.128624 -401.723796)
			(xy 299.000571 -401.723796) (xy 298.972011 -401.778765) (xy 298.934066 -401.834352) (xy 298.91228 -401.860004)
			(xy 298.906497 -401.867159) (xy 298.899975 -401.884342) (xy 298.89958 -401.893532) (xy 298.89958 -402.3868)
			(xy 298.899994 -402.395987) (xy 298.906505 -402.413171) (xy 298.91228 -402.420328) (xy 298.93402 -402.446019)
			(xy 298.971969 -402.501601) (xy 299.003003 -402.561319) (xy 299.026678 -402.624318) (xy 299.042653 -402.689696)
			(xy 299.050701 -402.756513) (xy 299.050705 -402.823814) (xy 299.050697 -402.823877) (xy 302.328766 -402.823877)
			(xy 302.328771 -402.75645) (xy 302.336851 -402.689509) (xy 302.35289 -402.624018) (xy 302.376659 -402.560919)
			(xy 302.407814 -402.501122) (xy 302.445906 -402.445486) (xy 302.467772 -402.41982) (xy 302.473594 -402.412693)
			(xy 302.480091 -402.395488) (xy 302.480472 -402.386292) (xy 302.480472 -401.89404) (xy 302.480049 -401.884854)
			(xy 302.473545 -401.867669) (xy 302.467772 -401.860512) (xy 302.445889 -401.834863) (xy 302.407803 -401.779225)
			(xy 302.376655 -401.719426) (xy 302.352893 -401.656328) (xy 302.33686 -401.590837) (xy 302.328786 -401.523897)
			(xy 302.328788 -401.456473) (xy 302.336865 -401.389534) (xy 302.352902 -401.324044) (xy 302.376667 -401.260946)
			(xy 302.407819 -401.201149) (xy 302.445908 -401.145514) (xy 302.467772 -401.119848) (xy 302.473582 -401.112713)
			(xy 302.480087 -401.095514) (xy 302.480472 -401.08632) (xy 302.480472 -400.92884) (xy 302.480948 -400.918724)
			(xy 302.488678 -400.900026) (xy 302.502976 -400.885712) (xy 302.521664 -400.87796) (xy 302.53178 -400.877532)
			(xy 303.24806 -400.877532) (xy 303.258184 -400.87795) (xy 303.276893 -400.885691) (xy 303.291209 -400.900007)
			(xy 303.29895 -400.918716) (xy 303.299368 -400.92884) (xy 303.299368 -401.08632) (xy 303.299776 -401.095507)
			(xy 303.306292 -401.112691) (xy 303.312068 -401.119848) (xy 303.333913 -401.145529) (xy 303.372005 -401.20116)
			(xy 303.403158 -401.260954) (xy 303.426925 -401.324049) (xy 303.442963 -401.389537) (xy 303.451041 -401.456474)
			(xy 303.451043 -401.523896) (xy 303.442968 -401.590834) (xy 303.426934 -401.656322) (xy 303.40317 -401.719418)
			(xy 303.37202 -401.779214) (xy 303.333932 -401.834847) (xy 303.312068 -401.860512) (xy 303.30628 -401.867663)
			(xy 303.299761 -401.884849) (xy 303.299368 -401.89404) (xy 303.299368 -402.386292) (xy 303.299789 -402.395478)
			(xy 303.306296 -402.412662) (xy 303.312068 -402.41982) (xy 303.333886 -402.445524) (xy 303.371978 -402.501152)
			(xy 303.403133 -402.560942) (xy 303.426901 -402.624034) (xy 303.442941 -402.689519) (xy 303.451021 -402.756454)
			(xy 303.451025 -402.823874) (xy 303.442954 -402.89081) (xy 303.426922 -402.956297) (xy 303.403162 -403.019392)
			(xy 303.372015 -403.079186) (xy 303.33393 -403.134819) (xy 303.312068 -403.160484) (xy 303.306249 -403.167613)
			(xy 303.299749 -403.184816) (xy 303.299368 -403.194012) (xy 303.299368 -403.351492) (xy 303.298977 -403.361618)
			(xy 303.291225 -403.380328) (xy 303.276901 -403.394643) (xy 303.258186 -403.402383) (xy 303.24806 -403.4028)
			(xy 302.53178 -403.4028) (xy 302.52167 -403.402331) (xy 302.502991 -403.394587) (xy 302.488697 -403.380285)
			(xy 302.480963 -403.361602) (xy 302.480472 -403.351492) (xy 302.480472 -403.194012) (xy 302.480062 -403.184825)
			(xy 302.473549 -403.16764) (xy 302.467772 -403.160484) (xy 302.445862 -403.134857) (xy 302.407776 -403.079216)
			(xy 302.376629 -403.019415) (xy 302.352869 -402.956313) (xy 302.336838 -402.890819) (xy 302.328766 -402.823877)
			(xy 299.050697 -402.823877) (xy 299.042666 -402.890633) (xy 299.026699 -402.956013) (xy 299.003032 -403.019015)
			(xy 298.972006 -403.078737) (xy 298.934064 -403.134323) (xy 298.91228 -403.159976) (xy 298.906466 -403.167109)
			(xy 298.899963 -403.184309) (xy 298.89958 -403.193504) (xy 298.89958 -403.351492) (xy 298.899171 -403.361648)
			(xy 298.891375 -403.380404) (xy 298.876974 -403.394729) (xy 298.858176 -403.402425) (xy 298.848018 -403.4028)
			(xy 298.131738 -403.4028) (xy 298.121619 -403.402243) (xy 298.102906 -403.394535) (xy 298.08855 -403.380271)
			(xy 298.080722 -403.361608) (xy 298.080176 -403.351492) (xy 298.080176 -403.193504) (xy 298.079769 -403.184316)
			(xy 298.073254 -403.167132) (xy 298.067476 -403.159976) (xy 298.04564 -403.134363) (xy 298.00769 -403.078772)
			(xy 297.976657 -403.019043) (xy 297.952985 -402.956034) (xy 297.937014 -402.890646) (xy 297.928973 -402.823819)
			(xy 294.650937 -402.823819) (xy 294.650937 -402.823874) (xy 294.642866 -402.890809) (xy 294.626835 -402.956296)
			(xy 294.603076 -403.019391) (xy 294.57193 -403.079186) (xy 294.533846 -403.134819) (xy 294.511984 -403.160484)
			(xy 294.506167 -403.167615) (xy 294.499665 -403.184816) (xy 294.499284 -403.194012) (xy 294.499284 -403.351492)
			(xy 294.498877 -403.361616) (xy 294.491129 -403.380322) (xy 294.476809 -403.394638) (xy 294.4581 -403.40238)
			(xy 294.447976 -403.4028) (xy 293.731696 -403.4028) (xy 293.721573 -403.402387) (xy 293.70287 -403.394638)
			(xy 293.688556 -403.38032) (xy 293.68081 -403.361615) (xy 293.680388 -403.351492) (xy 293.680388 -403.194012)
			(xy 293.679975 -403.184825) (xy 293.673464 -403.167641) (xy 293.667688 -403.160484) (xy 293.645777 -403.134857)
			(xy 293.607691 -403.079217) (xy 293.576543 -403.019415) (xy 293.552782 -402.956314) (xy 293.53675 -402.89082)
			(xy 293.528678 -402.823878) (xy 290.250609 -402.823878) (xy 290.242579 -402.890633) (xy 290.226612 -402.956012)
			(xy 290.202946 -403.019014) (xy 290.17192 -403.078737) (xy 290.133979 -403.134323) (xy 290.112196 -403.159976)
			(xy 290.106384 -403.16711) (xy 290.099879 -403.184309) (xy 290.099496 -403.193504) (xy 290.099496 -403.351492)
			(xy 290.099072 -403.361646) (xy 290.091278 -403.380399) (xy 290.076882 -403.394723) (xy 290.05809 -403.402422)
			(xy 290.047934 -403.4028) (xy 289.331654 -403.4028) (xy 289.321529 -403.402312) (xy 289.302815 -403.394577)
			(xy 289.288461 -403.380292) (xy 289.280637 -403.361614) (xy 289.280092 -403.351492) (xy 289.280092 -403.193504)
			(xy 289.279682 -403.184317) (xy 289.273168 -403.167132) (xy 289.267392 -403.159976) (xy 289.245556 -403.134363)
			(xy 289.207605 -403.078772) (xy 289.176571 -403.019044) (xy 289.152898 -402.956034) (xy 289.136927 -402.890647)
			(xy 289.128886 -402.823819) (xy 237.030424 -402.823819) (xy 237.026709 -402.832791) (xy 237.026196 -402.84527)
			(xy 237.026196 -405.623708) (xy 286.928756 -405.623708) (xy 286.928757 -405.556283) (xy 286.936834 -405.489343)
			(xy 286.952872 -405.423853) (xy 286.976639 -405.360756) (xy 287.007793 -405.30096) (xy 287.045886 -405.245326)
			(xy 287.067752 -405.219662) (xy 287.073554 -405.212521) (xy 287.080064 -405.195327) (xy 287.080452 -405.186134)
			(xy 287.080452 -404.693882) (xy 287.080039 -404.684695) (xy 287.073526 -404.667512) (xy 287.067752 -404.660354)
			(xy 287.045908 -404.634672) (xy 287.007815 -404.579041) (xy 286.97666 -404.519248) (xy 286.952893 -404.456153)
			(xy 286.936854 -404.390665) (xy 286.928776 -404.323728) (xy 286.928774 -404.256305) (xy 286.936848 -404.189367)
			(xy 286.952883 -404.123879) (xy 286.976647 -404.060783) (xy 287.007798 -404.000987) (xy 287.045888 -403.945354)
			(xy 287.067752 -403.91969) (xy 287.073542 -403.91254) (xy 287.080059 -403.895353) (xy 287.080452 -403.886162)
			(xy 287.080452 -403.728682) (xy 287.080912 -403.718553) (xy 287.088648 -403.699829) (xy 287.102942 -403.685473)
			(xy 287.121633 -403.677656) (xy 287.13176 -403.67712) (xy 287.84804 -403.67712) (xy 287.858199 -403.677489)
			(xy 287.876956 -403.685302) (xy 287.891279 -403.699715) (xy 287.898974 -403.71852) (xy 287.899348 -403.728682)
			(xy 287.899348 -403.886162) (xy 287.899788 -403.895346) (xy 287.906282 -403.91253) (xy 287.912048 -403.91969)
			(xy 287.933935 -403.945337) (xy 287.972027 -404.000973) (xy 288.00318 -404.060771) (xy 288.026945 -404.12387)
			(xy 288.04298 -404.189362) (xy 288.051055 -404.256303) (xy 288.051053 -404.32373) (xy 288.042974 -404.39067)
			(xy 288.026935 -404.456161) (xy 288.003166 -404.519259) (xy 287.97201 -404.579056) (xy 287.933915 -404.63469)
			(xy 287.912048 -404.660354) (xy 287.90624 -404.667491) (xy 287.899733 -404.684688) (xy 287.899348 -404.693882)
			(xy 287.899348 -405.186134) (xy 287.899754 -405.195321) (xy 287.906272 -405.212505) (xy 287.912048 -405.219662)
			(xy 287.933908 -405.245331) (xy 287.972 -405.300964) (xy 288.003154 -405.360759) (xy 288.026921 -405.423856)
			(xy 288.042958 -405.489345) (xy 288.051036 -405.556283) (xy 288.051036 -405.623708) (xy 288.04296 -405.690646)
			(xy 288.026924 -405.756136) (xy 288.003158 -405.819233) (xy 287.972005 -405.879028) (xy 287.933913 -405.934662)
			(xy 287.912048 -405.960326) (xy 287.906251 -405.967471) (xy 287.899738 -405.984662) (xy 287.899348 -405.993854)
			(xy 287.899348 -406.151334) (xy 287.898901 -406.161464) (xy 287.89116 -406.180189) (xy 287.876861 -406.194544)
			(xy 287.858168 -406.20236) (xy 287.84804 -406.202896) (xy 287.13176 -406.202896) (xy 287.121603 -406.202511)
			(xy 287.102849 -406.194701) (xy 287.088527 -406.180294) (xy 287.080829 -406.161494) (xy 287.080452 -406.151334)
			(xy 287.080452 -405.993854) (xy 287.080004 -405.984671) (xy 287.073515 -405.967487) (xy 287.067752 -405.960326)
			(xy 287.04588 -405.934667) (xy 287.007788 -405.879032) (xy 286.976635 -405.819236) (xy 286.952869 -405.756138)
			(xy 286.936832 -405.690648) (xy 286.928756 -405.623708) (xy 237.026196 -405.623708) (xy 237.026196 -406.72373)
			(xy 289.128897 -406.72373) (xy 289.1289 -406.656422) (xy 289.136948 -406.589596) (xy 289.152926 -406.524211)
			(xy 289.176605 -406.461205) (xy 289.207645 -406.401481) (xy 289.245601 -406.345895) (xy 289.267392 -406.320244)
			(xy 289.273194 -406.313103) (xy 289.279706 -406.295909) (xy 289.280092 -406.286716) (xy 289.280092 -405.793448)
			(xy 289.279661 -405.784263) (xy 289.273162 -405.767078) (xy 289.267392 -405.75992) (xy 289.245599 -405.734272)
			(xy 289.207647 -405.678686) (xy 289.176611 -405.618962) (xy 289.152936 -405.555957) (xy 289.136961 -405.490574)
			(xy 289.128917 -405.42375) (xy 289.128917 -405.356444) (xy 289.136962 -405.28962) (xy 289.152937 -405.224237)
			(xy 289.176613 -405.161232) (xy 289.20765 -405.101509) (xy 289.245602 -405.045923) (xy 289.267392 -405.020272)
			(xy 289.273182 -405.013122) (xy 289.279701 -404.995935) (xy 289.280092 -404.986744) (xy 289.280092 -404.828756)
			(xy 289.280486 -404.8186) (xy 289.288294 -404.799848) (xy 289.302699 -404.785527) (xy 289.321496 -404.777827)
			(xy 289.331654 -404.777448) (xy 290.047934 -404.777448) (xy 290.058064 -404.777899) (xy 290.076787 -404.785639)
			(xy 290.091143 -404.799936) (xy 290.098959 -404.818628) (xy 290.099496 -404.828756) (xy 290.099496 -404.986744)
			(xy 290.099886 -404.995933) (xy 290.106414 -405.013117) (xy 290.112196 -405.020272) (xy 290.133979 -405.045928)
			(xy 290.171925 -405.101515) (xy 290.202957 -405.161238) (xy 290.226628 -405.224242) (xy 290.242601 -405.289623)
			(xy 290.250644 -405.356445) (xy 290.250645 -405.423749) (xy 290.242602 -405.490571) (xy 290.22663 -405.555952)
			(xy 290.202959 -405.618957) (xy 290.200522 -405.623648) (xy 291.329076 -405.623648) (xy 291.329076 -405.556343)
			(xy 291.337121 -405.48952) (xy 291.353095 -405.424137) (xy 291.376768 -405.361132) (xy 291.407802 -405.301409)
			(xy 291.445752 -405.245822) (xy 291.46754 -405.22017) (xy 291.473337 -405.213025) (xy 291.47985 -405.195834)
			(xy 291.48024 -405.186642) (xy 291.48024 -404.693374) (xy 291.479833 -404.684187) (xy 291.473316 -404.667003)
			(xy 291.46754 -404.659846) (xy 291.445774 -404.634176) (xy 291.407825 -404.578592) (xy 291.37679 -404.518871)
			(xy 291.353116 -404.455869) (xy 291.337142 -404.390489) (xy 291.329096 -404.323668) (xy 291.329094 -404.256365)
			(xy 291.337136 -404.189544) (xy 291.353106 -404.124163) (xy 291.376777 -404.061159) (xy 291.407808 -404.001436)
			(xy 291.445754 -403.94585) (xy 291.46754 -403.920198) (xy 291.473325 -403.913045) (xy 291.479846 -403.89586)
			(xy 291.48024 -403.88667) (xy 291.48024 -403.728682) (xy 291.480718 -403.718523) (xy 291.488499 -403.699753)
			(xy 291.50287 -403.685388) (xy 291.521643 -403.677615) (xy 291.531802 -403.67712) (xy 292.248082 -403.67712)
			(xy 292.258236 -403.677648) (xy 292.277002 -403.685413) (xy 292.291367 -403.699768) (xy 292.299145 -403.718528)
			(xy 292.299644 -403.728682) (xy 292.299644 -403.88667) (xy 292.300081 -403.895854) (xy 292.306577 -403.913038)
			(xy 292.312344 -403.920198) (xy 292.334154 -403.945832) (xy 292.372103 -404.001421) (xy 292.403137 -404.061147)
			(xy 292.426809 -404.124153) (xy 292.442781 -404.189538) (xy 292.450824 -404.256363) (xy 292.450822 -404.32367)
			(xy 292.442775 -404.390495) (xy 292.426799 -404.455878) (xy 292.403123 -404.518884) (xy 292.372086 -404.578608)
			(xy 292.334134 -404.634194) (xy 292.312344 -404.659846) (xy 292.306539 -404.666985) (xy 292.300031 -404.68418)
			(xy 292.299644 -404.693374) (xy 292.299644 -405.186642) (xy 292.300047 -405.19583) (xy 292.306567 -405.213013)
			(xy 292.312344 -405.22017) (xy 292.334126 -405.245827) (xy 292.372076 -405.301412) (xy 292.403111 -405.361135)
			(xy 292.426785 -405.424139) (xy 292.442758 -405.489521) (xy 292.450803 -405.556343) (xy 292.450804 -405.623648)
			(xy 292.44276 -405.69047) (xy 292.426787 -405.755852) (xy 292.403114 -405.818857) (xy 292.372081 -405.87858)
			(xy 292.334132 -405.934166) (xy 292.312344 -405.959818) (xy 292.30655 -405.966965) (xy 292.300035 -405.984154)
			(xy 292.299644 -405.993346) (xy 292.299644 -406.151334) (xy 292.299194 -406.161496) (xy 292.291405 -406.18027)
			(xy 292.277026 -406.194634) (xy 292.258245 -406.202404) (xy 292.248082 -406.202896) (xy 291.531802 -406.202896)
			(xy 291.521649 -406.202366) (xy 291.502886 -406.194598) (xy 291.488522 -406.180244) (xy 291.480741 -406.161487)
			(xy 291.48024 -406.151334) (xy 291.48024 -405.993346) (xy 291.479799 -405.984162) (xy 291.473306 -405.966978)
			(xy 291.46754 -405.959818) (xy 291.445746 -405.934171) (xy 291.407797 -405.878584) (xy 291.376764 -405.818859)
			(xy 291.353092 -405.755854) (xy 291.337119 -405.690471) (xy 291.329076 -405.623648) (xy 290.200522 -405.623648)
			(xy 290.171928 -405.67868) (xy 290.133982 -405.734267) (xy 290.112196 -405.75992) (xy 290.106408 -405.767071)
			(xy 290.099888 -405.784257) (xy 290.099496 -405.793448) (xy 290.099496 -406.286716) (xy 290.099899 -406.295904)
			(xy 290.106418 -406.313088) (xy 290.112196 -406.320244) (xy 290.133951 -406.345922) (xy 290.171899 -406.401506)
			(xy 290.202931 -406.461226) (xy 290.226605 -406.524227) (xy 290.242579 -406.589606) (xy 290.250625 -406.656425)
			(xy 290.250628 -406.723727) (xy 290.250621 -406.723789) (xy 293.52869 -406.723789) (xy 293.528692 -406.656363)
			(xy 293.536771 -406.589423) (xy 293.55281 -406.523932) (xy 293.576577 -406.460834) (xy 293.607731 -406.401037)
			(xy 293.645823 -406.345401) (xy 293.667688 -406.319736) (xy 293.673493 -406.312597) (xy 293.680003 -406.295402)
			(xy 293.680388 -406.286208) (xy 293.680388 -405.793956) (xy 293.680002 -405.784766) (xy 293.673472 -405.767582)
			(xy 293.667688 -405.760428) (xy 293.645821 -405.734766) (xy 293.607733 -405.679131) (xy 293.576583 -405.619334)
			(xy 293.552819 -405.556237) (xy 293.536785 -405.490747) (xy 293.528709 -405.423809) (xy 293.52871 -405.356385)
			(xy 293.536786 -405.289447) (xy 293.552821 -405.223958) (xy 293.576585 -405.160861) (xy 293.607736 -405.101064)
			(xy 293.645824 -405.045429) (xy 293.667688 -405.019764) (xy 293.673481 -405.012616) (xy 293.679998 -404.995428)
			(xy 293.680388 -404.986236) (xy 293.680388 -404.828756) (xy 293.680849 -404.818646) (xy 293.688599 -404.799969)
			(xy 293.702903 -404.785676) (xy 293.721586 -404.777941) (xy 293.731696 -404.777448) (xy 294.447976 -404.777448)
			(xy 294.458077 -404.778003) (xy 294.476745 -404.785723) (xy 294.491038 -404.799998) (xy 294.498783 -404.818656)
			(xy 294.499284 -404.828756) (xy 294.499284 -404.986236) (xy 294.49968 -404.995425) (xy 294.506204 -405.012609)
			(xy 294.511984 -405.019764) (xy 294.533845 -405.045432) (xy 294.571934 -405.101066) (xy 294.603086 -405.160862)
			(xy 294.626851 -405.223958) (xy 294.642888 -405.289447) (xy 294.650964 -405.356385) (xy 294.650964 -405.423809)
			(xy 294.642889 -405.490747) (xy 294.626853 -405.556236) (xy 294.603089 -405.619333) (xy 294.60081 -405.623708)
			(xy 295.728844 -405.623708) (xy 295.728845 -405.556283) (xy 295.736922 -405.489344) (xy 295.752959 -405.423854)
			(xy 295.776725 -405.360757) (xy 295.807879 -405.30096) (xy 295.84597 -405.245327) (xy 295.867836 -405.219662)
			(xy 295.873636 -405.212519) (xy 295.880148 -405.195327) (xy 295.880536 -405.186134) (xy 295.880536 -404.693882)
			(xy 295.880126 -404.684695) (xy 295.873611 -404.667511) (xy 295.867836 -404.660354) (xy 295.845992 -404.634672)
			(xy 295.807901 -404.57904) (xy 295.776747 -404.519247) (xy 295.75298 -404.456152) (xy 295.736942 -404.390665)
			(xy 295.728864 -404.323728) (xy 295.728862 -404.256305) (xy 295.736936 -404.189368) (xy 295.75297 -404.123879)
			(xy 295.776733 -404.060783) (xy 295.807884 -404.000988) (xy 295.845972 -403.945355) (xy 295.867836 -403.91969)
			(xy 295.873624 -403.912539) (xy 295.880143 -403.895353) (xy 295.880536 -403.886162) (xy 295.880536 -403.728682)
			(xy 295.881011 -403.718555) (xy 295.888744 -403.699834) (xy 295.903034 -403.685478) (xy 295.921719 -403.677659)
			(xy 295.931844 -403.67712) (xy 296.648124 -403.67712) (xy 296.658282 -403.677502) (xy 296.677039 -403.685309)
			(xy 296.691362 -403.699718) (xy 296.699058 -403.718521) (xy 296.699432 -403.728682) (xy 296.699432 -403.886162)
			(xy 296.699876 -403.895345) (xy 296.706368 -403.912529) (xy 296.712132 -403.91969) (xy 296.734016 -403.945338)
			(xy 296.772102 -404.000976) (xy 296.80325 -404.060775) (xy 296.827012 -404.123874) (xy 296.843045 -404.189364)
			(xy 296.851118 -404.256304) (xy 296.851117 -404.323729) (xy 296.843039 -404.390668) (xy 296.827002 -404.456158)
			(xy 296.803237 -404.519256) (xy 296.772085 -404.579053) (xy 296.733996 -404.634688) (xy 296.712132 -404.660354)
			(xy 296.706322 -404.667489) (xy 296.699817 -404.684688) (xy 296.699432 -404.693882) (xy 296.699432 -405.186134)
			(xy 296.699841 -405.195321) (xy 296.706357 -405.212505) (xy 296.712132 -405.219662) (xy 296.733989 -405.245333)
			(xy 296.772076 -405.300967) (xy 296.803225 -405.360763) (xy 296.826988 -405.423859) (xy 296.843023 -405.489347)
			(xy 296.851099 -405.556284) (xy 296.851099 -405.623707) (xy 296.843025 -405.690644) (xy 296.826991 -405.756132)
			(xy 296.803229 -405.819229) (xy 296.77208 -405.879025) (xy 296.733994 -405.93466) (xy 296.712132 -405.960326)
			(xy 296.706334 -405.96747) (xy 296.699822 -405.984662) (xy 296.699432 -405.993854) (xy 296.699432 -406.151334)
			(xy 296.699001 -406.161466) (xy 296.691256 -406.180194) (xy 296.676953 -406.19455) (xy 296.658254 -406.202363)
			(xy 296.648124 -406.202896) (xy 295.931844 -406.202896) (xy 295.921692 -406.202442) (xy 295.90294 -406.19466)
			(xy 295.888615 -406.180273) (xy 295.880915 -406.161487) (xy 295.880536 -406.151334) (xy 295.880536 -405.993854)
			(xy 295.880092 -405.984671) (xy 295.873601 -405.967486) (xy 295.867836 -405.960326) (xy 295.845965 -405.934666)
			(xy 295.807874 -405.879032) (xy 295.776722 -405.819235) (xy 295.752956 -405.756137) (xy 295.73692 -405.690647)
			(xy 295.728844 -405.623708) (xy 294.60081 -405.623708) (xy 294.571938 -405.679129) (xy 294.533848 -405.734763)
			(xy 294.511984 -405.760428) (xy 294.506191 -405.767576) (xy 294.499675 -405.784764) (xy 294.499284 -405.793956)
			(xy 294.499284 -406.286208) (xy 294.499694 -406.295395) (xy 294.506208 -406.312579) (xy 294.511984 -406.319736)
			(xy 294.533817 -406.345427) (xy 294.571908 -406.401057) (xy 294.603061 -406.46085) (xy 294.626827 -406.523943)
			(xy 294.642866 -406.58943) (xy 294.650944 -406.656365) (xy 294.650947 -406.72373) (xy 297.928985 -406.72373)
			(xy 297.928988 -406.656422) (xy 297.937036 -406.589596) (xy 297.953013 -406.524212) (xy 297.976691 -406.461206)
			(xy 298.00773 -406.401482) (xy 298.045685 -406.345896) (xy 298.067476 -406.320244) (xy 298.073276 -406.313101)
			(xy 298.079789 -406.295909) (xy 298.080176 -406.286716) (xy 298.080176 -405.793448) (xy 298.079748 -405.784263)
			(xy 298.073247 -405.767078) (xy 298.067476 -405.75992) (xy 298.045683 -405.734272) (xy 298.007732 -405.678685)
			(xy 297.976697 -405.618962) (xy 297.953023 -405.555957) (xy 297.937049 -405.490574) (xy 297.929005 -405.42375)
			(xy 297.929005 -405.356444) (xy 297.93705 -405.28962) (xy 297.953025 -405.224238) (xy 297.9767 -405.161233)
			(xy 298.007735 -405.101509) (xy 298.045687 -405.045924) (xy 298.067476 -405.020272) (xy 298.073264 -405.013121)
			(xy 298.079785 -404.995935) (xy 298.080176 -404.986744) (xy 298.080176 -404.828756) (xy 298.080585 -404.818602)
			(xy 298.088391 -404.799853) (xy 298.102791 -404.785532) (xy 298.121582 -404.77783) (xy 298.131738 -404.777448)
			(xy 298.848018 -404.777448) (xy 298.858147 -404.777912) (xy 298.87687 -404.785647) (xy 298.891226 -404.79994)
			(xy 298.899043 -404.818629) (xy 298.89958 -404.828756) (xy 298.89958 -404.986744) (xy 298.899973 -404.995933)
			(xy 298.906499 -405.013117) (xy 298.91228 -405.020272) (xy 298.934063 -405.045928) (xy 298.972011 -405.101514)
			(xy 299.003043 -405.161237) (xy 299.026716 -405.224241) (xy 299.042688 -405.289623) (xy 299.050732 -405.356445)
			(xy 299.050733 -405.423749) (xy 299.042689 -405.490571) (xy 299.026717 -405.555953) (xy 299.003046 -405.618957)
			(xy 299.000577 -405.623708) (xy 300.128635 -405.623708) (xy 300.128635 -405.556283) (xy 300.136712 -405.489344)
			(xy 300.152749 -405.423854) (xy 300.176515 -405.360757) (xy 300.207668 -405.300961) (xy 300.245759 -405.245327)
			(xy 300.267624 -405.219662) (xy 300.273422 -405.212518) (xy 300.279935 -405.195326) (xy 300.280324 -405.186134)
			(xy 300.280324 -404.693882) (xy 300.279917 -404.684695) (xy 300.273401 -404.66751) (xy 300.267624 -404.660354)
			(xy 300.245781 -404.634671) (xy 300.20769 -404.57904) (xy 300.176537 -404.519246) (xy 300.15277 -404.456152)
			(xy 300.136733 -404.390664) (xy 300.128655 -404.323728) (xy 300.128653 -404.256305) (xy 300.136727 -404.189368)
			(xy 300.152761 -404.12388) (xy 300.176523 -404.060784) (xy 300.207673 -404.000989) (xy 300.245761 -403.945355)
			(xy 300.267624 -403.91969) (xy 300.27341 -403.912538) (xy 300.27993 -403.895352) (xy 300.280324 -403.886162)
			(xy 300.280324 -403.728682) (xy 300.280811 -403.718556) (xy 300.288542 -403.699837) (xy 300.302828 -403.685482)
			(xy 300.321509 -403.677661) (xy 300.331632 -403.67712) (xy 301.047912 -403.67712) (xy 301.058069 -403.677512)
			(xy 301.076826 -403.685315) (xy 301.09115 -403.699721) (xy 301.098846 -403.718522) (xy 301.09922 -403.728682)
			(xy 301.09922 -403.886162) (xy 301.099644 -403.895348) (xy 301.106147 -403.912533) (xy 301.11192 -403.91969)
			(xy 301.133805 -403.945338) (xy 301.171892 -404.000975) (xy 301.20304 -404.060774) (xy 301.226802 -404.123873)
			(xy 301.242836 -404.189364) (xy 301.250909 -404.256304) (xy 301.250907 -404.323729) (xy 301.24283 -404.390668)
			(xy 301.226793 -404.456158) (xy 301.203027 -404.519256) (xy 301.171875 -404.579053) (xy 301.133785 -404.634688)
			(xy 301.11192 -404.660354) (xy 301.10612 -404.667497) (xy 301.099607 -404.684689) (xy 301.09922 -404.693882)
			(xy 301.09922 -405.186134) (xy 301.099609 -405.195323) (xy 301.106137 -405.212508) (xy 301.11192 -405.219662)
			(xy 301.133777 -405.245332) (xy 301.171865 -405.300967) (xy 301.203015 -405.360762) (xy 301.226778 -405.423859)
			(xy 301.242814 -405.489347) (xy 301.25089 -405.556284) (xy 301.25089 -405.623707) (xy 301.242815 -405.690644)
			(xy 301.226781 -405.756133) (xy 301.203018 -405.819229) (xy 301.17187 -405.879026) (xy 301.133783 -405.93466)
			(xy 301.11192 -405.960326) (xy 301.106132 -405.967478) (xy 301.099612 -405.984663) (xy 301.09922 -405.993854)
			(xy 301.09922 -406.151334) (xy 301.0988 -406.161468) (xy 301.091054 -406.180197) (xy 301.076747 -406.194554)
			(xy 301.058044 -406.202365) (xy 301.047912 -406.202896) (xy 300.331632 -406.202896) (xy 300.321479 -406.202452)
			(xy 300.302727 -406.194667) (xy 300.288402 -406.180276) (xy 300.280702 -406.161488) (xy 300.280324 -406.151334)
			(xy 300.280324 -405.993854) (xy 300.279882 -405.98467) (xy 300.27339 -405.967486) (xy 300.267624 -405.960326)
			(xy 300.245753 -405.934666) (xy 300.207663 -405.879031) (xy 300.176511 -405.819235) (xy 300.152747 -405.756137)
			(xy 300.136711 -405.690647) (xy 300.128635 -405.623708) (xy 299.000577 -405.623708) (xy 298.972014 -405.678681)
			(xy 298.934067 -405.734268) (xy 298.91228 -405.75992) (xy 298.90649 -405.76707) (xy 298.899972 -405.784257)
			(xy 298.89958 -405.793448) (xy 298.89958 -406.286716) (xy 298.899987 -406.295903) (xy 298.906503 -406.313088)
			(xy 298.91228 -406.320244) (xy 298.934035 -406.345922) (xy 298.971984 -406.401506) (xy 299.003018 -406.461226)
			(xy 299.026691 -406.524227) (xy 299.042666 -406.589606) (xy 299.050712 -406.656425) (xy 299.050715 -406.723727)
			(xy 299.050708 -406.723789) (xy 302.328777 -406.723789) (xy 302.32878 -406.656363) (xy 302.336859 -406.589423)
			(xy 302.352897 -406.523933) (xy 302.376664 -406.460835) (xy 302.407816 -406.401037) (xy 302.445907 -406.345402)
			(xy 302.467772 -406.319736) (xy 302.473587 -406.312604) (xy 302.480089 -406.295403) (xy 302.480472 -406.286208)
			(xy 302.480472 -405.793956) (xy 302.480089 -405.784766) (xy 302.473557 -405.767581) (xy 302.467772 -405.760428)
			(xy 302.445905 -405.734766) (xy 302.407818 -405.67913) (xy 302.376669 -405.619333) (xy 302.352907 -405.556236)
			(xy 302.336872 -405.490747) (xy 302.328797 -405.423809) (xy 302.328798 -405.356385) (xy 302.336873 -405.289447)
			(xy 302.352908 -405.223958) (xy 302.376672 -405.160861) (xy 302.407821 -405.101065) (xy 302.445909 -405.04543)
			(xy 302.467772 -405.019764) (xy 302.473575 -405.012624) (xy 302.480084 -404.995429) (xy 302.480472 -404.986236)
			(xy 302.480472 -404.828756) (xy 302.480948 -404.818648) (xy 302.488695 -404.799974) (xy 302.502994 -404.785682)
			(xy 302.521672 -404.777944) (xy 302.53178 -404.777448) (xy 303.24806 -404.777448) (xy 303.25816 -404.778017)
			(xy 303.276827 -404.785732) (xy 303.291121 -404.800002) (xy 303.298867 -404.818657) (xy 303.299368 -404.828756)
			(xy 303.299368 -404.986236) (xy 303.299768 -404.995424) (xy 303.30629 -405.012608) (xy 303.312068 -405.019764)
			(xy 303.333929 -405.045432) (xy 303.37202 -405.101065) (xy 303.403173 -405.160861) (xy 303.426939 -405.223957)
			(xy 303.442975 -405.289447) (xy 303.451052 -405.356385) (xy 303.451052 -405.423809) (xy 303.442976 -405.490748)
			(xy 303.42694 -405.556237) (xy 303.403175 -405.619334) (xy 303.372023 -405.67913) (xy 303.333933 -405.734763)
			(xy 303.312068 -405.760428) (xy 303.306273 -405.767574) (xy 303.299758 -405.784764) (xy 303.299368 -405.793956)
			(xy 303.299368 -406.286208) (xy 303.299781 -406.295395) (xy 303.306294 -406.312579) (xy 303.312068 -406.319736)
			(xy 303.333902 -406.345427) (xy 303.371993 -406.401057) (xy 303.403147 -406.460849) (xy 303.426915 -406.523943)
			(xy 303.442953 -406.589429) (xy 303.451032 -406.656365) (xy 303.451035 -406.723787) (xy 303.442962 -406.790724)
			(xy 303.426929 -406.856211) (xy 303.403167 -406.919307) (xy 303.372018 -406.979102) (xy 303.333931 -407.034735)
			(xy 303.312068 -407.0604) (xy 303.306285 -407.067555) (xy 303.299763 -407.084738) (xy 303.299368 -407.093928)
			(xy 303.299368 -407.251408) (xy 303.29899 -407.261535) (xy 303.291233 -407.280245) (xy 303.276904 -407.29456)
			(xy 303.258187 -407.302299) (xy 303.24806 -407.302716) (xy 302.53178 -407.302716) (xy 302.521672 -407.302232)
			(xy 302.502996 -407.294491) (xy 302.488703 -407.280194) (xy 302.480966 -407.261516) (xy 302.480472 -407.251408)
			(xy 302.480472 -407.093928) (xy 302.480055 -407.084741) (xy 302.473547 -407.067557) (xy 302.467772 -407.0604)
			(xy 302.445878 -407.03476) (xy 302.407792 -406.979121) (xy 302.376644 -406.919321) (xy 302.352883 -406.856221)
			(xy 302.33685 -406.790729) (xy 302.328777 -406.723789) (xy 299.050708 -406.723789) (xy 299.042674 -406.790547)
			(xy 299.026705 -406.855927) (xy 299.003037 -406.91893) (xy 298.972009 -406.978653) (xy 298.934065 -407.034239)
			(xy 298.91228 -407.059892) (xy 298.906502 -407.06705) (xy 298.899977 -407.084231) (xy 298.89958 -407.09342)
			(xy 298.89958 -407.251408) (xy 298.899184 -407.261565) (xy 298.891382 -407.280321) (xy 298.876978 -407.294645)
			(xy 298.858177 -407.302341) (xy 298.848018 -407.302716) (xy 298.131738 -407.302716) (xy 298.121608 -407.302241)
			(xy 298.10288 -407.294517) (xy 298.088521 -407.280227) (xy 298.080708 -407.261535) (xy 298.080176 -407.251408)
			(xy 298.080176 -407.09342) (xy 298.079762 -407.084233) (xy 298.073252 -407.067048) (xy 298.067476 -407.059892)
			(xy 298.045656 -407.034266) (xy 298.007706 -406.978677) (xy 297.976672 -406.91895) (xy 297.952999 -406.855942)
			(xy 297.937027 -406.790556) (xy 297.928985 -406.72373) (xy 294.650947 -406.72373) (xy 294.650947 -406.723787)
			(xy 294.642874 -406.790723) (xy 294.626842 -406.856211) (xy 294.60308 -406.919306) (xy 294.571933 -406.979101)
			(xy 294.533847 -407.034735) (xy 294.511984 -407.0604) (xy 294.506203 -407.067556) (xy 294.49968 -407.084738)
			(xy 294.499284 -407.093928) (xy 294.499284 -407.251408) (xy 294.49889 -407.261533) (xy 294.491136 -407.28024)
			(xy 294.476813 -407.294554) (xy 294.458101 -407.302296) (xy 294.447976 -407.302716) (xy 293.731696 -407.302716)
			(xy 293.721589 -407.302218) (xy 293.702914 -407.294482) (xy 293.68862 -407.28019) (xy 293.680882 -407.261515)
			(xy 293.680388 -407.251408) (xy 293.680388 -407.093928) (xy 293.679967 -407.084742) (xy 293.673461 -407.067557)
			(xy 293.667688 -407.0604) (xy 293.645793 -407.03476) (xy 293.607706 -406.979122) (xy 293.576557 -406.919322)
			(xy 293.552796 -406.856222) (xy 293.536763 -406.79073) (xy 293.52869 -406.723789) (xy 290.250621 -406.723789)
			(xy 290.242587 -406.790547) (xy 290.226619 -406.855927) (xy 290.202951 -406.91893) (xy 290.171924 -406.978653)
			(xy 290.133981 -407.034239) (xy 290.112196 -407.059892) (xy 290.10642 -407.067052) (xy 290.099893 -407.084231)
			(xy 290.099496 -407.09342) (xy 290.099496 -407.251408) (xy 290.099085 -407.261563) (xy 290.091286 -407.280316)
			(xy 290.076886 -407.29464) (xy 290.058091 -407.302338) (xy 290.047934 -407.302716) (xy 289.331654 -407.302716)
			(xy 289.321519 -407.30231) (xy 289.302788 -407.294559) (xy 289.288432 -407.280248) (xy 289.280622 -407.261541)
			(xy 289.280092 -407.251408) (xy 289.280092 -407.09342) (xy 289.279674 -407.084234) (xy 289.273166 -407.067049)
			(xy 289.267392 -407.059892) (xy 289.245571 -407.034266) (xy 289.20762 -406.978677) (xy 289.176585 -406.918951)
			(xy 289.152912 -406.855943) (xy 289.136939 -406.790557) (xy 289.128897 -406.72373) (xy 237.026196 -406.72373)
			(xy 237.026196 -409.523887) (xy 286.928735 -409.523887) (xy 286.928738 -409.456459) (xy 286.936818 -409.389518)
			(xy 286.952859 -409.324026) (xy 286.97663 -409.260927) (xy 287.007788 -409.20113) (xy 287.045884 -409.145496)
			(xy 287.067752 -409.119832) (xy 287.073566 -409.1127) (xy 287.080069 -409.095499) (xy 287.080452 -409.086304)
			(xy 287.080452 -408.594052) (xy 287.080005 -408.584869) (xy 287.073516 -408.567685) (xy 287.067752 -408.560524)
			(xy 287.045878 -408.534866) (xy 287.007786 -408.479232) (xy 286.976633 -408.419435) (xy 286.952867 -408.356337)
			(xy 286.936831 -408.290847) (xy 286.928755 -408.223907) (xy 286.928755 -408.156481) (xy 286.936833 -408.089542)
			(xy 286.952871 -408.024051) (xy 286.976638 -407.960954) (xy 287.007793 -407.901158) (xy 287.045886 -407.845524)
			(xy 287.067752 -407.81986) (xy 287.073554 -407.812719) (xy 287.080064 -407.795525) (xy 287.080452 -407.786332)
			(xy 287.080452 -407.628852) (xy 287.080945 -407.618746) (xy 287.088689 -407.600076) (xy 287.102983 -407.585785)
			(xy 287.121654 -407.578043) (xy 287.13176 -407.577544) (xy 287.84804 -407.577544) (xy 287.858144 -407.578051)
			(xy 287.876813 -407.585791) (xy 287.891104 -407.600081) (xy 287.898847 -407.618748) (xy 287.899348 -407.628852)
			(xy 287.899348 -407.786332) (xy 287.899755 -407.795519) (xy 287.906272 -407.812703) (xy 287.912048 -407.81986)
			(xy 287.933906 -407.845531) (xy 287.971998 -407.901163) (xy 288.003152 -407.960958) (xy 288.026919 -408.024055)
			(xy 288.042957 -408.089543) (xy 288.051034 -408.156482) (xy 288.051035 -408.223906) (xy 288.042959 -408.290845)
			(xy 288.026923 -408.356334) (xy 288.003157 -408.419431) (xy 287.972004 -408.479226) (xy 287.933913 -408.53486)
			(xy 287.912048 -408.560524) (xy 287.906252 -408.56767) (xy 287.899739 -408.58486) (xy 287.899348 -408.594052)
			(xy 287.899348 -409.086304) (xy 287.899768 -409.09549) (xy 287.906276 -409.112674) (xy 287.912048 -409.119832)
			(xy 287.933878 -409.145526) (xy 287.971972 -409.201155) (xy 288.003127 -409.260947) (xy 288.026895 -409.32404)
			(xy 288.042935 -409.389526) (xy 288.051014 -409.456462) (xy 288.051018 -409.523884) (xy 288.042945 -409.590821)
			(xy 288.026911 -409.656308) (xy 288.003149 -409.719404) (xy 287.971999 -409.779199) (xy 287.933912 -409.834832)
			(xy 287.912048 -409.860496) (xy 287.906264 -409.86765) (xy 287.899743 -409.884834) (xy 287.899348 -409.894024)
			(xy 287.899348 -410.051504) (xy 287.898819 -410.061607) (xy 287.891089 -410.080276) (xy 287.876806 -410.094569)
			(xy 287.858143 -410.102312) (xy 287.84804 -410.102812) (xy 287.13176 -410.102812) (xy 287.12165 -410.102348)
			(xy 287.102973 -410.094599) (xy 287.08868 -410.080296) (xy 287.080945 -410.061614) (xy 287.080452 -410.051504)
			(xy 287.080452 -409.894024) (xy 287.080019 -409.884839) (xy 287.07352 -409.867655) (xy 287.067752 -409.860496)
			(xy 287.045851 -409.834861) (xy 287.00776 -409.779223) (xy 286.976608 -409.719423) (xy 286.952843 -409.656322)
			(xy 286.936809 -409.590829) (xy 286.928735 -409.523887) (xy 237.026196 -409.523887) (xy 237.026196 -410.623642)
			(xy 289.128908 -410.623642) (xy 289.12891 -410.556334) (xy 289.136956 -410.48951) (xy 289.152933 -410.424126)
			(xy 289.176609 -410.361121) (xy 289.207648 -410.301397) (xy 289.245602 -410.245811) (xy 289.267392 -410.22016)
			(xy 289.273187 -410.213014) (xy 289.279703 -410.195824) (xy 289.280092 -410.186632) (xy 289.280092 -409.693364)
			(xy 289.279701 -409.684175) (xy 289.273174 -409.66699) (xy 289.267392 -409.659836) (xy 289.245614 -409.634175)
			(xy 289.207662 -409.578591) (xy 289.176625 -409.518869) (xy 289.152949 -409.455866) (xy 289.136974 -409.390484)
			(xy 289.128928 -409.323662) (xy 289.128927 -409.256356) (xy 289.136971 -409.189534) (xy 289.152944 -409.124152)
			(xy 289.176618 -409.061147) (xy 289.207653 -409.001425) (xy 289.245603 -408.945839) (xy 289.267392 -408.920188)
			(xy 289.273175 -408.913033) (xy 289.279698 -408.89585) (xy 289.280092 -408.88666) (xy 289.280092 -408.728672)
			(xy 289.280498 -408.718517) (xy 289.288302 -408.699766) (xy 289.302703 -408.685443) (xy 289.321497 -408.677743)
			(xy 289.331654 -408.677364) (xy 290.047934 -408.677364) (xy 290.058066 -408.677799) (xy 290.076792 -408.685543)
			(xy 290.091148 -408.699845) (xy 290.098962 -408.718542) (xy 290.099496 -408.728672) (xy 290.099496 -408.88666)
			(xy 290.099926 -408.895845) (xy 290.106426 -408.91303) (xy 290.112196 -408.920188) (xy 290.133994 -408.945831)
			(xy 290.171941 -409.00142) (xy 290.202971 -409.061145) (xy 290.226642 -409.12415) (xy 290.242613 -409.189533)
			(xy 290.250656 -409.256356) (xy 290.250655 -409.323662) (xy 290.24261 -409.390484) (xy 290.226637 -409.455867)
			(xy 290.202964 -409.518872) (xy 290.200389 -409.523827) (xy 291.329055 -409.523827) (xy 291.329058 -409.456519)
			(xy 291.337106 -409.389694) (xy 291.353082 -409.32431) (xy 291.376759 -409.261304) (xy 291.407797 -409.201579)
			(xy 291.44575 -409.145992) (xy 291.46754 -409.12034) (xy 291.47335 -409.113204) (xy 291.479855 -409.096006)
			(xy 291.48024 -409.086812) (xy 291.48024 -408.593544) (xy 291.4798 -408.58436) (xy 291.473306 -408.567176)
			(xy 291.46754 -408.560016) (xy 291.445744 -408.53437) (xy 291.407796 -408.478783) (xy 291.376763 -408.419059)
			(xy 291.35309 -408.356053) (xy 291.337118 -408.29067) (xy 291.329074 -408.223847) (xy 291.329075 -408.156541)
			(xy 291.33712 -408.089718) (xy 291.353094 -408.024335) (xy 291.376767 -407.96133) (xy 291.407802 -407.901607)
			(xy 291.445752 -407.84602) (xy 291.46754 -407.820368) (xy 291.473338 -407.813224) (xy 291.479851 -407.796032)
			(xy 291.48024 -407.78684) (xy 291.48024 -407.628852) (xy 291.480583 -407.61869) (xy 291.488402 -407.599929)
			(xy 291.502823 -407.585606) (xy 291.521637 -407.577915) (xy 291.531802 -407.577544) (xy 292.248082 -407.577544)
			(xy 292.258208 -407.578041) (xy 292.27693 -407.585764) (xy 292.291287 -407.600047) (xy 292.299106 -407.618729)
			(xy 292.299644 -407.628852) (xy 292.299644 -407.78684) (xy 292.300048 -407.796028) (xy 292.306567 -407.813211)
			(xy 292.312344 -407.820368) (xy 292.334124 -407.846026) (xy 292.372074 -407.901612) (xy 292.403109 -407.961334)
			(xy 292.426783 -408.024338) (xy 292.442757 -408.089719) (xy 292.450802 -408.156542) (xy 292.450803 -408.223846)
			(xy 292.442759 -408.290669) (xy 292.426786 -408.356051) (xy 292.403114 -408.419055) (xy 292.372081 -408.478778)
			(xy 292.334132 -408.534364) (xy 292.312344 -408.560016) (xy 292.306551 -408.567164) (xy 292.300036 -408.584353)
			(xy 292.299644 -408.593544) (xy 292.299644 -409.086812) (xy 292.300061 -409.095998) (xy 292.306571 -409.113182)
			(xy 292.312344 -409.12034) (xy 292.334097 -409.146021) (xy 292.372048 -409.201603) (xy 292.403083 -409.261322)
			(xy 292.426759 -409.324323) (xy 292.442735 -409.389702) (xy 292.450782 -409.456522) (xy 292.450786 -409.523824)
			(xy 292.442745 -409.590645) (xy 292.426775 -409.656025) (xy 292.403106 -409.719028) (xy 292.372076 -409.77875)
			(xy 292.33413 -409.834336) (xy 292.312344 -409.859988) (xy 292.306521 -409.867114) (xy 292.300024 -409.884319)
			(xy 292.299644 -409.893516) (xy 292.299644 -410.051504) (xy 292.299182 -410.061653) (xy 292.291394 -410.080397)
			(xy 292.27701 -410.094718) (xy 292.258233 -410.102426) (xy 292.248082 -410.102812) (xy 291.531802 -410.102812)
			(xy 291.521682 -410.102273) (xy 291.502971 -410.094556) (xy 291.488616 -410.080286) (xy 291.480788 -410.061621)
			(xy 291.48024 -410.051504) (xy 291.48024 -409.893516) (xy 291.479813 -409.884331) (xy 291.47331 -409.867147)
			(xy 291.46754 -409.859988) (xy 291.445717 -409.834365) (xy 291.407769 -409.778774) (xy 291.376737 -409.719047)
			(xy 291.353066 -409.656039) (xy 291.337096 -409.590653) (xy 291.329055 -409.523827) (xy 290.200389 -409.523827)
			(xy 290.171931 -409.578596) (xy 290.133983 -409.634183) (xy 290.112196 -409.659836) (xy 290.106401 -409.666982)
			(xy 290.099886 -409.684172) (xy 290.099496 -409.693364) (xy 290.099496 -410.186632) (xy 290.099891 -410.195821)
			(xy 290.106415 -410.213005) (xy 290.112196 -410.22016) (xy 290.133967 -410.245826) (xy 290.171914 -410.301411)
			(xy 290.202946 -410.361133) (xy 290.226618 -410.424136) (xy 290.242591 -410.489516) (xy 290.250636 -410.556336)
			(xy 290.250638 -410.62364) (xy 290.250631 -410.6237) (xy 293.528701 -410.6237) (xy 293.528702 -410.556276)
			(xy 293.53678 -410.489336) (xy 293.552816 -410.423847) (xy 293.576582 -410.360749) (xy 293.607734 -410.300952)
			(xy 293.645824 -410.245317) (xy 293.667688 -410.219652) (xy 293.673486 -410.212508) (xy 293.68 -410.195317)
			(xy 293.680388 -410.186124) (xy 293.680388 -409.693872) (xy 293.679994 -409.684683) (xy 293.673469 -409.667499)
			(xy 293.667688 -409.660344) (xy 293.645836 -409.634669) (xy 293.607748 -409.579035) (xy 293.576597 -409.519241)
			(xy 293.552833 -409.456145) (xy 293.536797 -409.390657) (xy 293.52872 -409.32372) (xy 293.528719 -409.256298)
			(xy 293.536794 -409.189361) (xy 293.552828 -409.123872) (xy 293.57659 -409.060776) (xy 293.607739 -409.00098)
			(xy 293.645825 -408.945345) (xy 293.667688 -408.91968) (xy 293.673474 -408.912527) (xy 293.679995 -408.895343)
			(xy 293.680388 -408.886152) (xy 293.680388 -408.728672) (xy 293.680862 -408.718563) (xy 293.688606 -408.699886)
			(xy 293.702907 -408.685593) (xy 293.721587 -408.677857) (xy 293.731696 -408.677364) (xy 294.447976 -408.677364)
			(xy 294.458079 -408.677904) (xy 294.47675 -408.685627) (xy 294.491044 -408.699907) (xy 294.498786 -408.71857)
			(xy 294.499284 -408.728672) (xy 294.499284 -408.886152) (xy 294.499721 -408.895336) (xy 294.506216 -408.912521)
			(xy 294.511984 -408.91968) (xy 294.53386 -408.945335) (xy 294.57195 -409.000971) (xy 294.603101 -409.060768)
			(xy 294.626865 -409.123866) (xy 294.6429 -409.189357) (xy 294.650975 -409.256297) (xy 294.650974 -409.323721)
			(xy 294.642897 -409.390661) (xy 294.62686 -409.456151) (xy 294.603093 -409.519248) (xy 294.600676 -409.523887)
			(xy 295.728823 -409.523887) (xy 295.728826 -409.456459) (xy 295.736906 -409.389518) (xy 295.752947 -409.324026)
			(xy 295.776716 -409.260928) (xy 295.807873 -409.201131) (xy 295.845969 -409.145497) (xy 295.867836 -409.119832)
			(xy 295.873649 -409.112698) (xy 295.880153 -409.095499) (xy 295.880536 -409.086304) (xy 295.880536 -408.594052)
			(xy 295.880093 -408.584869) (xy 295.873601 -408.567684) (xy 295.867836 -408.560524) (xy 295.845963 -408.534866)
			(xy 295.807872 -408.479231) (xy 295.77672 -408.419434) (xy 295.752954 -408.356336) (xy 295.736918 -408.290846)
			(xy 295.728843 -408.223907) (xy 295.728843 -408.156481) (xy 295.736921 -408.089542) (xy 295.752958 -408.024052)
			(xy 295.776725 -407.960955) (xy 295.807878 -407.901159) (xy 295.84597 -407.845525) (xy 295.867836 -407.81986)
			(xy 295.873637 -407.812718) (xy 295.880148 -407.795525) (xy 295.880536 -407.786332) (xy 295.880536 -407.628852)
			(xy 295.880947 -407.618736) (xy 295.888707 -407.60005) (xy 295.903027 -407.585755) (xy 295.921727 -407.578029)
			(xy 295.931844 -407.577544) (xy 296.648124 -407.577544) (xy 296.658227 -407.578064) (xy 296.676895 -407.585799)
			(xy 296.691187 -407.600084) (xy 296.698931 -407.618749) (xy 296.699432 -407.628852) (xy 296.699432 -407.786332)
			(xy 296.699842 -407.795519) (xy 296.706357 -407.812703) (xy 296.712132 -407.81986) (xy 296.733987 -407.845532)
			(xy 296.772074 -407.901167) (xy 296.803223 -407.960962) (xy 296.826986 -408.024058) (xy 296.843021 -408.089546)
			(xy 296.851097 -408.156483) (xy 296.851098 -408.223905) (xy 296.843024 -408.290842) (xy 296.82699 -408.356331)
			(xy 296.803228 -408.419427) (xy 296.77208 -408.479223) (xy 296.733994 -408.534858) (xy 296.712132 -408.560524)
			(xy 296.706334 -408.567668) (xy 296.699822 -408.58486) (xy 296.699432 -408.594052) (xy 296.699432 -409.086304)
			(xy 296.699856 -409.095489) (xy 296.706362 -409.112673) (xy 296.712132 -409.119832) (xy 296.733959 -409.145527)
			(xy 296.772047 -409.201158) (xy 296.803198 -409.26095) (xy 296.826962 -409.324043) (xy 296.842999 -409.389528)
			(xy 296.851078 -409.456463) (xy 296.851081 -409.523883) (xy 296.843009 -409.590818) (xy 296.826978 -409.656305)
			(xy 296.80322 -409.7194) (xy 296.772075 -409.779196) (xy 296.733993 -409.83483) (xy 296.712132 -409.860496)
			(xy 296.706346 -409.867649) (xy 296.699827 -409.884834) (xy 296.699432 -409.894024) (xy 296.699432 -410.051504)
			(xy 296.698919 -410.061609) (xy 296.691186 -410.080281) (xy 296.676898 -410.094575) (xy 296.658229 -410.102315)
			(xy 296.648124 -410.102812) (xy 295.931844 -410.102812) (xy 295.921726 -410.102348) (xy 295.903026 -410.094617)
			(xy 295.88871 -410.080315) (xy 295.880961 -410.061622) (xy 295.880536 -410.051504) (xy 295.880536 -409.894024)
			(xy 295.880106 -409.884839) (xy 295.873605 -409.867655) (xy 295.867836 -409.860496) (xy 295.845935 -409.834861)
			(xy 295.807845 -409.779223) (xy 295.776694 -409.719423) (xy 295.752931 -409.656322) (xy 295.736896 -409.590829)
			(xy 295.728823 -409.523887) (xy 294.600676 -409.523887) (xy 294.57194 -409.579045) (xy 294.533849 -409.634679)
			(xy 294.511984 -409.660344) (xy 294.506184 -409.667487) (xy 294.499672 -409.684679) (xy 294.499284 -409.693872)
			(xy 294.499284 -410.186124) (xy 294.499686 -410.195312) (xy 294.506206 -410.212496) (xy 294.511984 -410.219652)
			(xy 294.533833 -410.24533) (xy 294.571923 -410.300962) (xy 294.603075 -410.360757) (xy 294.626841 -410.423852)
			(xy 294.642878 -410.489339) (xy 294.650956 -410.556277) (xy 294.650957 -410.623641) (xy 297.928996 -410.623641)
			(xy 297.928998 -410.556334) (xy 297.937044 -410.48951) (xy 297.95302 -410.424127) (xy 297.976696 -410.361121)
			(xy 298.007733 -410.301398) (xy 298.045686 -410.245812) (xy 298.067476 -410.22016) (xy 298.073269 -410.213012)
			(xy 298.079787 -410.195824) (xy 298.080176 -410.186632) (xy 298.080176 -409.693364) (xy 298.079788 -409.684174)
			(xy 298.07326 -409.66699) (xy 298.067476 -409.659836) (xy 298.045699 -409.634175) (xy 298.007747 -409.57859)
			(xy 297.976712 -409.518868) (xy 297.953037 -409.455865) (xy 297.937062 -409.390484) (xy 297.929016 -409.323661)
			(xy 297.929015 -409.256357) (xy 297.937058 -409.189534) (xy 297.953031 -409.124152) (xy 297.976704 -409.061148)
			(xy 298.007738 -409.001425) (xy 298.045688 -408.94584) (xy 298.067476 -408.920188) (xy 298.073257 -408.913032)
			(xy 298.079782 -408.89585) (xy 298.080176 -408.88666) (xy 298.080176 -408.728672) (xy 298.080598 -408.718519)
			(xy 298.088398 -408.699771) (xy 298.102794 -408.685449) (xy 298.121583 -408.677746) (xy 298.131738 -408.677364)
			(xy 298.848018 -408.677364) (xy 298.858149 -408.677812) (xy 298.876875 -408.68555) (xy 298.891232 -408.699849)
			(xy 298.899046 -408.718543) (xy 298.89958 -408.728672) (xy 298.89958 -408.88666) (xy 298.900014 -408.895845)
			(xy 298.906512 -408.913029) (xy 298.91228 -408.920188) (xy 298.934079 -408.945831) (xy 298.972026 -409.001419)
			(xy 299.003058 -409.061144) (xy 299.026729 -409.12415) (xy 299.042701 -409.189533) (xy 299.050744 -409.256356)
			(xy 299.050743 -409.323662) (xy 299.042698 -409.390485) (xy 299.026724 -409.455868) (xy 299.003051 -409.518873)
			(xy 299.000446 -409.523886) (xy 300.128614 -409.523886) (xy 300.128617 -409.456459) (xy 300.136697 -409.389518)
			(xy 300.152737 -409.324027) (xy 300.176506 -409.260928) (xy 300.207662 -409.201131) (xy 300.245757 -409.145497)
			(xy 300.267624 -409.119832) (xy 300.273435 -409.112697) (xy 300.27994 -409.095499) (xy 300.280324 -409.086304)
			(xy 300.280324 -408.594052) (xy 300.279883 -408.584868) (xy 300.27339 -408.567684) (xy 300.267624 -408.560524)
			(xy 300.245751 -408.534866) (xy 300.207661 -408.479231) (xy 300.17651 -408.419434) (xy 300.152745 -408.356336)
			(xy 300.136709 -408.290846) (xy 300.128634 -408.223906) (xy 300.128634 -408.156482) (xy 300.136711 -408.089542)
			(xy 300.152748 -408.024053) (xy 300.176514 -407.960955) (xy 300.207667 -407.901159) (xy 300.245759 -407.845525)
			(xy 300.267624 -407.81986) (xy 300.273423 -407.812717) (xy 300.279935 -407.795525) (xy 300.280324 -407.786332)
			(xy 300.280324 -407.628852) (xy 300.280747 -407.618737) (xy 300.288504 -407.600053) (xy 300.302821 -407.585759)
			(xy 300.321516 -407.578031) (xy 300.331632 -407.577544) (xy 301.047912 -407.577544) (xy 301.058015 -407.578074)
			(xy 301.076682 -407.585805) (xy 301.090975 -407.600088) (xy 301.098719 -407.61875) (xy 301.09922 -407.628852)
			(xy 301.09922 -407.786332) (xy 301.09961 -407.795521) (xy 301.106137 -407.812706) (xy 301.11192 -407.81986)
			(xy 301.133775 -407.845532) (xy 301.171863 -407.901166) (xy 301.203013 -407.960962) (xy 301.226777 -408.024057)
			(xy 301.242812 -408.089545) (xy 301.250888 -408.156483) (xy 301.250889 -408.223905) (xy 301.242814 -408.290843)
			(xy 301.22678 -408.356331) (xy 301.203018 -408.419427) (xy 301.171869 -408.479224) (xy 301.133783 -408.534858)
			(xy 301.11192 -408.560524) (xy 301.106133 -408.567676) (xy 301.099612 -408.584861) (xy 301.09922 -408.594052)
			(xy 301.09922 -409.086304) (xy 301.099624 -409.095492) (xy 301.106141 -409.112676) (xy 301.11192 -409.119832)
			(xy 301.133748 -409.145527) (xy 301.171836 -409.201158) (xy 301.202988 -409.26095) (xy 301.226753 -409.324043)
			(xy 301.24279 -409.389528) (xy 301.250869 -409.456463) (xy 301.250872 -409.523883) (xy 301.2428 -409.590819)
			(xy 301.226769 -409.656305) (xy 301.20301 -409.719401) (xy 301.171864 -409.779196) (xy 301.133781 -409.83483)
			(xy 301.11192 -409.860496) (xy 301.106145 -409.867657) (xy 301.099617 -409.884835) (xy 301.09922 -409.894024)
			(xy 301.09922 -410.051504) (xy 301.098719 -410.06161) (xy 301.090983 -410.080285) (xy 301.076692 -410.094579)
			(xy 301.058018 -410.102317) (xy 301.047912 -410.102812) (xy 300.331632 -410.102812) (xy 300.321513 -410.102358)
			(xy 300.302812 -410.094623) (xy 300.288497 -410.080318) (xy 300.280749 -410.061623) (xy 300.280324 -410.051504)
			(xy 300.280324 -409.894024) (xy 300.279897 -409.884839) (xy 300.273394 -409.867655) (xy 300.267624 -409.860496)
			(xy 300.245724 -409.83486) (xy 300.207635 -409.779222) (xy 300.176484 -409.719422) (xy 300.152721 -409.656321)
			(xy 300.136687 -409.590828) (xy 300.128614 -409.523886) (xy 299.000446 -409.523886) (xy 298.972017 -409.578597)
			(xy 298.934068 -409.634184) (xy 298.91228 -409.659836) (xy 298.906483 -409.666981) (xy 298.899969 -409.684172)
			(xy 298.89958 -409.693364) (xy 298.89958 -410.186632) (xy 298.899979 -410.19582) (xy 298.906501 -410.213004)
			(xy 298.91228 -410.22016) (xy 298.934052 -410.245825) (xy 298.972 -410.30141) (xy 299.003032 -410.361132)
			(xy 299.026705 -410.424135) (xy 299.042679 -410.489515) (xy 299.050724 -410.556336) (xy 299.050725 -410.62364)
			(xy 299.050718 -410.6237) (xy 302.328789 -410.6237) (xy 302.32879 -410.556276) (xy 302.336867 -410.489337)
			(xy 302.352904 -410.423847) (xy 302.376668 -410.36075) (xy 302.407819 -410.300953) (xy 302.445908 -410.245318)
			(xy 302.467772 -410.219652) (xy 302.47358 -410.212515) (xy 302.480086 -410.195318) (xy 302.480472 -410.186124)
			(xy 302.480472 -409.693872) (xy 302.480082 -409.684683) (xy 302.473555 -409.667498) (xy 302.467772 -409.660344)
			(xy 302.445921 -409.634669) (xy 302.407834 -409.579035) (xy 302.376684 -409.51924) (xy 302.35292 -409.456144)
			(xy 302.336885 -409.390657) (xy 302.328808 -409.32372) (xy 302.328807 -409.256298) (xy 302.336882 -409.189361)
			(xy 302.352915 -409.123873) (xy 302.376677 -409.060777) (xy 302.407824 -409.000981) (xy 302.44591 -408.945346)
			(xy 302.467772 -408.91968) (xy 302.473568 -408.912535) (xy 302.480081 -408.895344) (xy 302.480472 -408.886152)
			(xy 302.480472 -408.728672) (xy 302.480961 -408.718565) (xy 302.488703 -408.699891) (xy 302.502998 -408.685599)
			(xy 302.521673 -408.67786) (xy 302.53178 -408.677364) (xy 303.24806 -408.677364) (xy 303.258175 -408.677848)
			(xy 303.276871 -408.685576) (xy 303.291186 -408.699872) (xy 303.298939 -408.718557) (xy 303.299368 -408.728672)
			(xy 303.299368 -408.886152) (xy 303.299809 -408.895336) (xy 303.306302 -408.91252) (xy 303.312068 -408.91968)
			(xy 303.333945 -408.945335) (xy 303.372035 -409.00097) (xy 303.403187 -409.060768) (xy 303.426952 -409.123866)
			(xy 303.442988 -409.189356) (xy 303.451063 -409.256296) (xy 303.451062 -409.323722) (xy 303.442985 -409.390661)
			(xy 303.426947 -409.456151) (xy 303.40318 -409.519249) (xy 303.372026 -409.579045) (xy 303.333934 -409.634679)
			(xy 303.312068 -409.660344) (xy 303.306266 -409.667485) (xy 303.299755 -409.684679) (xy 303.299368 -409.693872)
			(xy 303.299368 -410.186124) (xy 303.299774 -410.195312) (xy 303.306291 -410.212495) (xy 303.312068 -410.219652)
			(xy 303.333917 -410.24533) (xy 303.372009 -410.300962) (xy 303.403162 -410.360756) (xy 303.426928 -410.423851)
			(xy 303.442966 -410.489339) (xy 303.451044 -410.556276) (xy 303.451045 -410.6237) (xy 303.44297 -410.690637)
			(xy 303.426935 -410.756126) (xy 303.403172 -410.819222) (xy 303.372021 -410.879018) (xy 303.333932 -410.934651)
			(xy 303.312068 -410.960316) (xy 303.306278 -410.967466) (xy 303.29976 -410.984653) (xy 303.299368 -410.993844)
			(xy 303.299368 -411.151324) (xy 303.299003 -411.161452) (xy 303.291241 -411.180162) (xy 303.276909 -411.194477)
			(xy 303.258189 -411.202216) (xy 303.24806 -411.202632) (xy 302.53178 -411.202632) (xy 302.521674 -411.202132)
			(xy 302.503001 -411.194394) (xy 302.488708 -411.180102) (xy 302.480969 -411.16143) (xy 302.480472 -411.151324)
			(xy 302.480472 -410.993844) (xy 302.480047 -410.984658) (xy 302.473544 -410.967474) (xy 302.467772 -410.960316)
			(xy 302.445893 -410.934663) (xy 302.407807 -410.879026) (xy 302.376658 -410.819228) (xy 302.352896 -410.75613)
			(xy 302.336863 -410.690639) (xy 302.328789 -410.6237) (xy 299.050718 -410.6237) (xy 299.042683 -410.690461)
			(xy 299.026712 -410.755842) (xy 299.003042 -410.818846) (xy 298.972012 -410.878569) (xy 298.934066 -410.934156)
			(xy 298.91228 -410.959808) (xy 298.906495 -410.966961) (xy 298.899974 -410.984146) (xy 298.89958 -410.993336)
			(xy 298.89958 -411.151324) (xy 298.899198 -411.161482) (xy 298.891391 -411.180239) (xy 298.876982 -411.194562)
			(xy 298.858179 -411.202258) (xy 298.848018 -411.202632) (xy 298.131738 -411.202632) (xy 298.12161 -411.202141)
			(xy 298.102885 -411.194421) (xy 298.088526 -411.180135) (xy 298.080711 -411.161449) (xy 298.080176 -411.151324)
			(xy 298.080176 -410.993336) (xy 298.079754 -410.98415) (xy 298.073249 -410.966965) (xy 298.067476 -410.959808)
			(xy 298.045672 -410.934169) (xy 298.007721 -410.878582) (xy 297.976686 -410.818857) (xy 297.953013 -410.75585)
			(xy 297.93704 -410.690466) (xy 297.928996 -410.623641) (xy 294.650957 -410.623641) (xy 294.650957 -410.623699)
			(xy 294.642883 -410.690637) (xy 294.626848 -410.756125) (xy 294.603085 -410.819221) (xy 294.571935 -410.879017)
			(xy 294.533848 -410.934651) (xy 294.511984 -410.960316) (xy 294.506196 -410.967467) (xy 294.499677 -410.984653)
			(xy 294.499284 -410.993844) (xy 294.499284 -411.151324) (xy 294.498834 -411.161436) (xy 294.491086 -411.180118)
			(xy 294.476778 -411.194413) (xy 294.458089 -411.202144) (xy 294.447976 -411.202632) (xy 293.731696 -411.202632)
			(xy 293.721591 -411.202119) (xy 293.702919 -411.194386) (xy 293.688625 -411.180098) (xy 293.680885 -411.161429)
			(xy 293.680388 -411.151324) (xy 293.680388 -410.993844) (xy 293.679959 -410.984659) (xy 293.673459 -410.967474)
			(xy 293.667688 -410.960316) (xy 293.645809 -410.934664) (xy 293.607721 -410.879027) (xy 293.576572 -410.819229)
			(xy 293.552809 -410.75613) (xy 293.536775 -410.69064) (xy 293.528701 -410.6237) (xy 290.250631 -410.6237)
			(xy 290.242595 -410.69046) (xy 290.226625 -410.755841) (xy 290.202956 -410.818845) (xy 290.171926 -410.878568)
			(xy 290.133982 -410.934155) (xy 290.112196 -410.959808) (xy 290.106413 -410.966963) (xy 290.09989 -410.984146)
			(xy 290.099496 -410.993336) (xy 290.099496 -411.151324) (xy 290.099098 -411.16148) (xy 290.091294 -411.180234)
			(xy 290.07689 -411.194557) (xy 290.058092 -411.202255) (xy 290.047934 -411.202632) (xy 289.331654 -411.202632)
			(xy 289.321521 -411.20221) (xy 289.302793 -411.194462) (xy 289.288438 -411.180156) (xy 289.280625 -411.161455)
			(xy 289.280092 -411.151324) (xy 289.280092 -410.993336) (xy 289.279666 -410.98415) (xy 289.273164 -410.966966)
			(xy 289.267392 -410.959808) (xy 289.245587 -410.934169) (xy 289.207635 -410.878582) (xy 289.1766 -410.818857)
			(xy 289.152925 -410.755851) (xy 289.136952 -410.690467) (xy 289.128908 -410.623642) (xy 237.026196 -410.623642)
			(xy 237.026196 -412.022036) (xy 237.025817 -412.032111) (xy 237.018067 -412.05071) (xy 237.01121 -412.058104)
			(xy 235.742988 -413.326326) (xy 235.735589 -413.333168) (xy 235.716989 -413.340886) (xy 235.70692 -413.341312)
			(xy 208.85277 -413.341312) (xy 208.842696 -413.340925) (xy 208.824097 -413.33318) (xy 208.816702 -413.326326)
			(xy 207.328262 -411.83814) (xy 207.321442 -411.830725) (xy 207.313712 -411.812137) (xy 207.313276 -411.802072)
			(xy 207.313276 -389.778748) (xy 207.312741 -389.766404) (xy 207.303453 -389.743532) (xy 207.295242 -389.734298)
			(xy 207.294734 -389.73379) (xy 204.725778 -387.165088) (xy 204.718937 -387.157689) (xy 204.711218 -387.139089)
			(xy 204.710792 -387.12902) (xy 204.710792 -374.725946) (xy 204.710253 -374.713602) (xy 204.700967 -374.690731)
			(xy 204.692758 -374.681496) (xy 204.69225 -374.680988) (xy 204.627226 -374.615964) (xy 204.620381 -374.608567)
			(xy 204.612664 -374.589966) (xy 204.61224 -374.579896) (xy 204.61224 -371.090444) (xy 204.611612 -371.07799)
			(xy 204.602074 -371.054978) (xy 204.593698 -371.04574) (xy 204.485494 -370.93779) (xy 204.478656 -370.930388)
			(xy 204.470935 -370.91179) (xy 204.470508 -370.901722) (xy 173.519592 -370.901722) (xy 173.519592 -371.386862)
			(xy 173.520022 -371.396047) (xy 173.526522 -371.413231) (xy 173.532292 -371.42039) (xy 173.554093 -371.446031)
			(xy 173.592039 -371.50162) (xy 173.62307 -371.561345) (xy 173.646506 -371.623725) (xy 174.74915 -371.623725)
			(xy 174.749154 -371.556417) (xy 174.757201 -371.489592) (xy 174.773178 -371.424208) (xy 174.796855 -371.361202)
			(xy 174.827893 -371.301477) (xy 174.865846 -371.24589) (xy 174.887636 -371.220238) (xy 174.893446 -371.213102)
			(xy 174.899952 -371.195904) (xy 174.900336 -371.18671) (xy 174.900336 -371.028722) (xy 174.900782 -371.018552)
			(xy 174.908559 -370.999758) (xy 174.922938 -370.985373) (xy 174.941728 -370.977587) (xy 174.951898 -370.97716)
			(xy 175.668178 -370.97716) (xy 175.678351 -370.977583) (xy 175.697149 -370.985364) (xy 175.711536 -370.999751)
			(xy 175.719317 -371.018549) (xy 175.71974 -371.028722) (xy 175.71974 -371.18671) (xy 175.720159 -371.195896)
			(xy 175.726668 -371.21308) (xy 175.73244 -371.220238) (xy 175.754191 -371.245921) (xy 175.792142 -371.301502)
			(xy 175.823178 -371.361221) (xy 175.846854 -371.424222) (xy 175.86283 -371.489601) (xy 175.870878 -371.55642)
			(xy 175.870881 -371.623723) (xy 175.862841 -371.690543) (xy 175.846871 -371.755923) (xy 175.823202 -371.818926)
			(xy 175.792172 -371.878649) (xy 175.754226 -371.934234) (xy 175.73244 -371.959886) (xy 175.726617 -371.967012)
			(xy 175.72012 -371.984218) (xy 175.71974 -371.993414) (xy 175.71974 -372.486682) (xy 175.720172 -372.495867)
			(xy 175.726672 -372.51305) (xy 175.73244 -372.52021) (xy 175.754262 -372.545834) (xy 175.792211 -372.601424)
			(xy 175.823244 -372.661151) (xy 175.846916 -372.72416) (xy 175.862887 -372.789545) (xy 175.870929 -372.856371)
			(xy 175.870926 -372.92368) (xy 175.862878 -372.990505) (xy 175.846901 -373.055889) (xy 175.823223 -373.118895)
			(xy 175.792185 -373.17862) (xy 175.754231 -373.234206) (xy 175.73244 -373.259858) (xy 175.726629 -373.266993)
			(xy 175.720125 -373.284191) (xy 175.71974 -373.293386) (xy 175.71974 -373.451374) (xy 175.719314 -373.461547)
			(xy 175.711534 -373.480345) (xy 175.697148 -373.494731) (xy 175.678351 -373.502513) (xy 175.668178 -373.502936)
			(xy 174.951898 -373.502936) (xy 174.941723 -373.502537) (xy 174.922923 -373.494747) (xy 174.908538 -373.480353)
			(xy 174.900757 -373.461549) (xy 174.900336 -373.451374) (xy 174.900336 -373.293386) (xy 174.899925 -373.284199)
			(xy 174.893411 -373.267015) (xy 174.887636 -373.259858) (xy 174.865882 -373.234178) (xy 174.827932 -373.178596)
			(xy 174.796898 -373.118876) (xy 174.773223 -373.055875) (xy 174.757248 -372.990496) (xy 174.749201 -372.923677)
			(xy 174.749198 -372.856374) (xy 174.757239 -372.789554) (xy 174.773208 -372.724174) (xy 174.796877 -372.661171)
			(xy 174.827906 -372.601448) (xy 174.865851 -372.545862) (xy 174.887636 -372.52021) (xy 174.893458 -372.513083)
			(xy 174.899957 -372.495878) (xy 174.900336 -372.486682) (xy 174.900336 -371.993414) (xy 174.899911 -371.984229)
			(xy 174.893407 -371.967044) (xy 174.887636 -371.959886) (xy 174.865811 -371.934265) (xy 174.827863 -371.878674)
			(xy 174.796832 -371.818946) (xy 174.773161 -371.755937) (xy 174.757191 -371.690551) (xy 174.74915 -371.623725)
			(xy 173.646506 -371.623725) (xy 173.646741 -371.624351) (xy 173.662712 -371.689734) (xy 173.670754 -371.756558)
			(xy 173.670753 -371.823863) (xy 173.662708 -371.890686) (xy 173.646734 -371.956069) (xy 173.623061 -372.019074)
			(xy 173.592028 -372.078798) (xy 173.55408 -372.134385) (xy 173.532292 -372.160038) (xy 173.526496 -372.167183)
			(xy 173.519981 -372.184374) (xy 173.519592 -372.193566) (xy 173.519592 -372.351554) (xy 173.519099 -372.361719)
			(xy 173.511335 -372.380507) (xy 173.496971 -372.394892) (xy 173.478194 -372.402684) (xy 173.46803 -372.403116)
			(xy 172.75175 -372.403116) (xy 172.741576 -372.402694) (xy 172.722773 -372.394917) (xy 172.708385 -372.38053)
			(xy 172.700607 -372.361728) (xy 172.700188 -372.351554) (xy 172.700188 -372.193566) (xy 172.699797 -372.184377)
			(xy 172.69327 -372.167192) (xy 172.687488 -372.160038) (xy 172.665713 -372.134375) (xy 172.62776 -372.078791)
			(xy 172.596724 -372.01907) (xy 172.573048 -371.956067) (xy 172.557072 -371.890685) (xy 172.549026 -371.823863)
			(xy 172.549025 -371.756558) (xy 172.557069 -371.689736) (xy 172.573042 -371.624354) (xy 172.596715 -371.561349)
			(xy 172.627749 -371.501627) (xy 172.6657 -371.446041) (xy 172.687488 -371.42039) (xy 172.69327 -371.413234)
			(xy 172.699794 -371.396052) (xy 172.700188 -371.386862) (xy 172.700188 -370.89334) (xy 172.699761 -370.884154)
			(xy 172.69326 -370.86697) (xy 172.687488 -370.859812) (xy 172.665687 -370.83417) (xy 172.627735 -370.778583)
			(xy 172.5967 -370.718859) (xy 172.573026 -370.655853) (xy 172.557052 -370.590469) (xy 172.549008 -370.523644)
			(xy 169.270946 -370.523644) (xy 169.262904 -370.590464) (xy 169.246933 -370.655845) (xy 169.223264 -370.718849)
			(xy 169.192234 -370.778572) (xy 169.15429 -370.834159) (xy 169.132504 -370.859812) (xy 169.12672 -370.866966)
			(xy 169.120198 -370.88415) (xy 169.119804 -370.89334) (xy 169.119804 -371.386862) (xy 169.120231 -371.396047)
			(xy 169.126733 -371.413232) (xy 169.132504 -371.42039) (xy 169.154304 -371.446031) (xy 169.19225 -371.50162)
			(xy 169.22328 -371.561346) (xy 169.246737 -371.623785) (xy 170.348831 -371.623785) (xy 170.348834 -371.556358)
			(xy 170.356914 -371.489416) (xy 170.372955 -371.423924) (xy 170.396726 -371.360825) (xy 170.427884 -371.301029)
			(xy 170.46598 -371.245394) (xy 170.487848 -371.21973) (xy 170.493663 -371.212598) (xy 170.500165 -371.195397)
			(xy 170.500548 -371.186202) (xy 170.500548 -371.028722) (xy 170.501045 -371.018596) (xy 170.508767 -370.999873)
			(xy 170.52305 -370.985516) (xy 170.541732 -370.977698) (xy 170.551856 -370.97716) (xy 171.268136 -370.97716)
			(xy 171.278287 -370.977591) (xy 171.297033 -370.985391) (xy 171.311354 -370.999784) (xy 171.319059 -371.018568)
			(xy 171.319444 -371.028722) (xy 171.319444 -371.186202) (xy 171.319866 -371.195388) (xy 171.326373 -371.212571)
			(xy 171.332144 -371.21973) (xy 171.353973 -371.245425) (xy 171.392066 -371.301054) (xy 171.423222 -371.360846)
			(xy 171.44699 -371.423939) (xy 171.46303 -371.489425) (xy 171.47111 -371.556361) (xy 171.471113 -371.623782)
			(xy 171.46304 -371.690719) (xy 171.447007 -371.756207) (xy 171.423245 -371.819302) (xy 171.392096 -371.879097)
			(xy 171.354008 -371.93473) (xy 171.332144 -371.960394) (xy 171.326361 -371.967548) (xy 171.31984 -371.984732)
			(xy 171.319444 -371.993922) (xy 171.319444 -372.486174) (xy 171.319879 -372.495358) (xy 171.326377 -372.512542)
			(xy 171.332144 -372.519702) (xy 171.354043 -372.545339) (xy 171.392135 -372.600976) (xy 171.423287 -372.660776)
			(xy 171.447052 -372.723876) (xy 171.463087 -372.789369) (xy 171.471161 -372.856312) (xy 171.471158 -372.923739)
			(xy 171.463077 -372.990681) (xy 171.447037 -373.056172) (xy 171.423266 -373.119271) (xy 171.392108 -373.179068)
			(xy 171.354012 -373.234702) (xy 171.332144 -373.260366) (xy 171.32633 -373.267499) (xy 171.319827 -373.284699)
			(xy 171.319444 -373.293894) (xy 171.319444 -373.451374) (xy 171.318952 -373.461501) (xy 171.31123 -373.480225)
			(xy 171.296945 -373.494583) (xy 171.27826 -373.5024) (xy 171.268136 -373.502936) (xy 170.551856 -373.502936)
			(xy 170.541704 -373.502515) (xy 170.522957 -373.494712) (xy 170.508637 -373.480316) (xy 170.500932 -373.461529)
			(xy 170.500548 -373.451374) (xy 170.500548 -373.293894) (xy 170.50013 -373.284708) (xy 170.493621 -373.267524)
			(xy 170.487848 -373.260366) (xy 170.466016 -373.234674) (xy 170.427923 -373.179044) (xy 170.396768 -373.119252)
			(xy 170.373 -373.056159) (xy 170.356961 -372.990673) (xy 170.348881 -372.923736) (xy 170.348878 -372.856315)
			(xy 170.356951 -372.789378) (xy 170.372985 -372.72389) (xy 170.396747 -372.660794) (xy 170.427897 -372.600999)
			(xy 170.465984 -372.545366) (xy 170.487848 -372.519702) (xy 170.493632 -372.512548) (xy 170.500153 -372.495364)
			(xy 170.500548 -372.486174) (xy 170.500548 -371.993922) (xy 170.500117 -371.984737) (xy 170.493617 -371.967553)
			(xy 170.487848 -371.960394) (xy 170.465945 -371.93476) (xy 170.427854 -371.879122) (xy 170.396703 -371.819322)
			(xy 170.372938 -371.756221) (xy 170.356904 -371.690728) (xy 170.348831 -371.623785) (xy 169.246737 -371.623785)
			(xy 169.24695 -371.624352) (xy 169.262921 -371.689735) (xy 169.270963 -371.756558) (xy 169.270962 -371.823863)
			(xy 169.262917 -371.890686) (xy 169.246944 -371.956068) (xy 169.223271 -372.019073) (xy 169.192239 -372.078798)
			(xy 169.154291 -372.134385) (xy 169.132504 -372.160038) (xy 169.126709 -372.167185) (xy 169.120193 -372.184374)
			(xy 169.119804 -372.193566) (xy 169.119804 -372.351554) (xy 169.1193 -372.361717) (xy 169.111537 -372.380503)
			(xy 169.097177 -372.394888) (xy 169.078405 -372.402682) (xy 169.068242 -372.403116) (xy 168.351962 -372.403116)
			(xy 168.341782 -372.402766) (xy 168.322978 -372.39496) (xy 168.308593 -372.380552) (xy 168.300817 -372.361734)
			(xy 168.3004 -372.351554) (xy 168.3004 -372.193566) (xy 168.300006 -372.184377) (xy 168.293481 -372.167193)
			(xy 168.2877 -372.160038) (xy 168.265927 -372.134374) (xy 168.227981 -372.078788) (xy 168.196949 -372.019066)
			(xy 168.173277 -371.956063) (xy 168.157304 -371.890683) (xy 168.14926 -371.823862) (xy 168.149258 -371.756559)
			(xy 168.1573 -371.689738) (xy 168.173271 -371.624357) (xy 168.19694 -371.561353) (xy 168.22797 -371.50163)
			(xy 168.265914 -371.446043) (xy 168.2877 -371.42039) (xy 168.293483 -371.413235) (xy 168.300006 -371.396052)
			(xy 168.3004 -371.386862) (xy 168.3004 -370.89334) (xy 168.299971 -370.884155) (xy 168.29347 -370.86697)
			(xy 168.2877 -370.859812) (xy 168.265902 -370.834169) (xy 168.227956 -370.77858) (xy 168.196925 -370.718855)
			(xy 168.173255 -370.65585) (xy 168.157284 -370.590467) (xy 168.149241 -370.523644) (xy 164.871178 -370.523644)
			(xy 164.871178 -370.523702) (xy 164.863103 -370.59064) (xy 164.847069 -370.656128) (xy 164.823307 -370.719224)
			(xy 164.792158 -370.77902) (xy 164.754071 -370.834655) (xy 164.732208 -370.86032) (xy 164.726421 -370.867472)
			(xy 164.7199 -370.884657) (xy 164.719508 -370.893848) (xy 164.719508 -371.386354) (xy 164.719938 -371.395539)
			(xy 164.726438 -371.412724) (xy 164.732208 -371.419882) (xy 164.754085 -371.445536) (xy 164.792173 -371.501172)
			(xy 164.823323 -371.56097) (xy 164.846957 -371.623726) (xy 165.949062 -371.623726) (xy 165.949066 -371.556417)
			(xy 165.957114 -371.489592) (xy 165.973091 -371.424207) (xy 165.996769 -371.361201) (xy 166.027807 -371.301477)
			(xy 166.065761 -371.24589) (xy 166.087552 -371.220238) (xy 166.093364 -371.213104) (xy 166.099868 -371.195905)
			(xy 166.100252 -371.18671) (xy 166.100252 -371.028722) (xy 166.100682 -371.01855) (xy 166.108463 -370.999753)
			(xy 166.122847 -370.985367) (xy 166.141642 -370.977584) (xy 166.151814 -370.97716) (xy 166.868094 -370.97716)
			(xy 166.878268 -370.977569) (xy 166.897067 -370.985356) (xy 166.911453 -370.999747) (xy 166.919234 -371.018548)
			(xy 166.919656 -371.028722) (xy 166.919656 -371.18671) (xy 166.920071 -371.195896) (xy 166.926582 -371.21308)
			(xy 166.932356 -371.220238) (xy 166.954106 -371.245921) (xy 166.992057 -371.301503) (xy 167.023092 -371.361222)
			(xy 167.046767 -371.424223) (xy 167.062743 -371.489601) (xy 167.07079 -371.55642) (xy 167.070793 -371.623722)
			(xy 167.062753 -371.690543) (xy 167.046784 -371.755923) (xy 167.023115 -371.818926) (xy 166.992086 -371.878648)
			(xy 166.954141 -371.934234) (xy 166.932356 -371.959886) (xy 166.926535 -371.967014) (xy 166.920036 -371.984218)
			(xy 166.919656 -371.993414) (xy 166.919656 -372.486682) (xy 166.920085 -372.495867) (xy 166.926586 -372.513051)
			(xy 166.932356 -372.52021) (xy 166.954177 -372.545834) (xy 166.992126 -372.601425) (xy 167.023158 -372.661152)
			(xy 167.046829 -372.72416) (xy 167.0628 -372.789546) (xy 167.070841 -372.856372) (xy 167.070838 -372.923679)
			(xy 167.06279 -372.990504) (xy 167.046814 -373.055889) (xy 167.023137 -373.118895) (xy 166.992099 -373.178619)
			(xy 166.954146 -373.234206) (xy 166.932356 -373.259858) (xy 166.926547 -373.266994) (xy 166.920041 -373.284192)
			(xy 166.919656 -373.293386) (xy 166.919656 -373.451374) (xy 166.919215 -373.461545) (xy 166.911437 -373.48034)
			(xy 166.897057 -373.494726) (xy 166.878264 -373.502511) (xy 166.868094 -373.502936) (xy 166.151814 -373.502936)
			(xy 166.14164 -373.502524) (xy 166.122841 -373.494739) (xy 166.108454 -373.480349) (xy 166.100673 -373.461548)
			(xy 166.100252 -373.451374) (xy 166.100252 -373.293386) (xy 166.099837 -373.2842) (xy 166.093325 -373.267016)
			(xy 166.087552 -373.259858) (xy 166.065797 -373.234178) (xy 166.027847 -373.178596) (xy 165.996811 -373.118877)
			(xy 165.973136 -373.055876) (xy 165.95716 -372.990497) (xy 165.949113 -372.923677) (xy 165.94911 -372.856374)
			(xy 165.957151 -372.789554) (xy 165.973121 -372.724173) (xy 165.99679 -372.66117) (xy 166.02782 -372.601448)
			(xy 166.065766 -372.545862) (xy 166.087552 -372.52021) (xy 166.093376 -372.513084) (xy 166.099873 -372.495879)
			(xy 166.100252 -372.486682) (xy 166.100252 -371.993414) (xy 166.099824 -371.984229) (xy 166.093321 -371.967045)
			(xy 166.087552 -371.959886) (xy 166.065726 -371.934265) (xy 166.027778 -371.878674) (xy 165.996745 -371.818947)
			(xy 165.973074 -371.755938) (xy 165.957104 -371.690552) (xy 165.949062 -371.623726) (xy 164.846957 -371.623726)
			(xy 164.847086 -371.624068) (xy 164.86312 -371.689559) (xy 164.871195 -371.756498) (xy 164.871194 -371.823923)
			(xy 164.863116 -371.890862) (xy 164.84708 -371.956352) (xy 164.823314 -372.019449) (xy 164.792162 -372.079246)
			(xy 164.754073 -372.134881) (xy 164.732208 -372.160546) (xy 164.72641 -372.16769) (xy 164.719896 -372.184881)
			(xy 164.719508 -372.194074) (xy 164.719508 -372.351554) (xy 164.718937 -372.361672) (xy 164.711233 -372.380383)
			(xy 164.696973 -372.394739) (xy 164.678314 -372.402568) (xy 164.6682 -372.403116) (xy 163.95192 -372.403116)
			(xy 163.941769 -372.402662) (xy 163.92302 -372.394876) (xy 163.908697 -372.38049) (xy 163.900993 -372.361707)
			(xy 163.900612 -372.351554) (xy 163.900612 -372.194074) (xy 163.900212 -372.184886) (xy 163.893691 -372.167702)
			(xy 163.887912 -372.160546) (xy 163.866061 -372.13487) (xy 163.827971 -372.079237) (xy 163.796819 -372.019442)
			(xy 163.773054 -371.956347) (xy 163.757017 -371.890859) (xy 163.74894 -371.823922) (xy 163.748939 -371.756499)
			(xy 163.757013 -371.689562) (xy 163.773048 -371.624073) (xy 163.796811 -371.560977) (xy 163.827961 -371.501181)
			(xy 163.866048 -371.445547) (xy 163.887912 -371.419882) (xy 163.8937 -371.412731) (xy 163.900219 -371.395545)
			(xy 163.900612 -371.386354) (xy 163.900612 -370.893848) (xy 163.900176 -370.884664) (xy 163.89368 -370.867479)
			(xy 163.887912 -370.86032) (xy 163.866036 -370.834665) (xy 163.827947 -370.779029) (xy 163.796796 -370.719232)
			(xy 163.773032 -370.656133) (xy 163.756997 -370.590643) (xy 163.748922 -370.523703) (xy 160.470875 -370.523703)
			(xy 160.462839 -370.590466) (xy 160.446866 -370.655848) (xy 160.423192 -370.718852) (xy 160.392158 -370.778575)
			(xy 160.354208 -370.83416) (xy 160.33242 -370.859812) (xy 160.326638 -370.866968) (xy 160.320114 -370.88415)
			(xy 160.31972 -370.89334) (xy 160.31972 -371.386862) (xy 160.320144 -371.396048) (xy 160.326647 -371.413233)
			(xy 160.33242 -371.42039) (xy 160.354223 -371.44603) (xy 160.392174 -371.501618) (xy 160.423209 -371.561342)
			(xy 160.44667 -371.623784) (xy 161.548767 -371.623784) (xy 161.548771 -371.556358) (xy 161.55685 -371.489418)
			(xy 161.572888 -371.423928) (xy 161.596655 -371.360829) (xy 161.627808 -371.301032) (xy 161.665899 -371.245396)
			(xy 161.687764 -371.21973) (xy 161.693581 -371.212599) (xy 161.700082 -371.195397) (xy 161.700464 -371.186202)
			(xy 161.700464 -371.028722) (xy 161.700945 -371.018594) (xy 161.70867 -370.999868) (xy 161.722959 -370.985511)
			(xy 161.741646 -370.977695) (xy 161.751772 -370.97716) (xy 162.468052 -370.97716) (xy 162.478166 -370.977654)
			(xy 162.496861 -370.985379) (xy 162.511176 -370.999671) (xy 162.51893 -371.018354) (xy 162.51936 -371.028468)
			(xy 162.51936 -371.186202) (xy 162.519778 -371.195388) (xy 162.526287 -371.212572) (xy 162.53206 -371.21973)
			(xy 162.553888 -371.245425) (xy 162.591981 -371.301055) (xy 162.623135 -371.360846) (xy 162.646903 -371.423939)
			(xy 162.662942 -371.489425) (xy 162.671022 -371.556361) (xy 162.671025 -371.623782) (xy 162.662953 -371.690719)
			(xy 162.64692 -371.756206) (xy 162.623158 -371.819302) (xy 162.59201 -371.879096) (xy 162.553923 -371.934729)
			(xy 162.53206 -371.960394) (xy 162.526278 -371.96755) (xy 162.519756 -371.984732) (xy 162.51936 -371.993922)
			(xy 162.51936 -372.486174) (xy 162.519791 -372.495359) (xy 162.526291 -372.512543) (xy 162.53206 -372.519702)
			(xy 162.553959 -372.545339) (xy 162.592049 -372.600977) (xy 162.623201 -372.660776) (xy 162.646965 -372.723877)
			(xy 162.662999 -372.78937) (xy 162.671073 -372.856312) (xy 162.67107 -372.923739) (xy 162.66299 -372.99068)
			(xy 162.646949 -373.056172) (xy 162.62318 -373.11927) (xy 162.592023 -373.179067) (xy 162.553927 -373.234701)
			(xy 162.53206 -373.260366) (xy 162.526248 -373.2675) (xy 162.519743 -373.284699) (xy 162.51936 -373.293894)
			(xy 162.51936 -373.451374) (xy 162.518852 -373.461499) (xy 162.511133 -373.48022) (xy 162.496853 -373.494577)
			(xy 162.478174 -373.502397) (xy 162.468052 -373.502936) (xy 161.751772 -373.502936) (xy 161.741666 -373.502439)
			(xy 161.722994 -373.494699) (xy 161.708701 -373.480406) (xy 161.700961 -373.461734) (xy 161.700464 -373.451628)
			(xy 161.700464 -373.293894) (xy 161.700042 -373.284708) (xy 161.693535 -373.267525) (xy 161.687764 -373.260366)
			(xy 161.665935 -373.234673) (xy 161.627847 -373.179041) (xy 161.596697 -373.119249) (xy 161.572933 -373.056155)
			(xy 161.556896 -372.99067) (xy 161.548818 -372.923736) (xy 161.548815 -372.856315) (xy 161.556887 -372.78938)
			(xy 161.572918 -372.723893) (xy 161.596676 -372.660798) (xy 161.627821 -372.601003) (xy 161.665903 -372.545368)
			(xy 161.687764 -372.519702) (xy 161.69355 -372.51255) (xy 161.700069 -372.495364) (xy 161.700464 -372.486174)
			(xy 161.700464 -371.993922) (xy 161.700029 -371.984738) (xy 161.693531 -371.967554) (xy 161.687764 -371.960394)
			(xy 161.665864 -371.934759) (xy 161.627779 -371.879119) (xy 161.596632 -371.819319) (xy 161.572871 -371.756218)
			(xy 161.55684 -371.690725) (xy 161.548767 -371.623784) (xy 160.44667 -371.623784) (xy 160.446882 -371.624348)
			(xy 160.462856 -371.689733) (xy 160.470899 -371.756557) (xy 160.470898 -371.823864) (xy 160.462852 -371.890688)
			(xy 160.446876 -371.956072) (xy 160.4232 -372.019077) (xy 160.392163 -372.078801) (xy 160.35421 -372.134386)
			(xy 160.33242 -372.160038) (xy 160.326627 -372.167186) (xy 160.32011 -372.184374) (xy 160.31972 -372.193566)
			(xy 160.31972 -372.351554) (xy 160.319297 -372.361728) (xy 160.31152 -372.38053) (xy 160.297133 -372.394918)
			(xy 160.278332 -372.402697) (xy 160.268158 -372.403116) (xy 159.551878 -372.403116) (xy 159.541699 -372.402753)
			(xy 159.522895 -372.394952) (xy 159.50851 -372.380547) (xy 159.500734 -372.361733) (xy 159.500316 -372.351554)
			(xy 159.500316 -372.193566) (xy 159.499919 -372.184378) (xy 159.493396 -372.167193) (xy 159.487616 -372.160038)
			(xy 159.465843 -372.134374) (xy 159.427895 -372.078789) (xy 159.396862 -372.019067) (xy 159.37319 -371.956064)
			(xy 159.357216 -371.890683) (xy 159.349172 -371.823862) (xy 159.34917 -371.756559) (xy 159.357213 -371.689738)
			(xy 159.373184 -371.624356) (xy 159.396854 -371.561353) (xy 159.427884 -371.501629) (xy 159.46583 -371.446042)
			(xy 159.487616 -371.42039) (xy 159.493401 -371.413237) (xy 159.499922 -371.396052) (xy 159.500316 -371.386862)
			(xy 159.500316 -370.89334) (xy 159.499883 -370.884155) (xy 159.493385 -370.866971) (xy 159.487616 -370.859812)
			(xy 159.465817 -370.834169) (xy 159.42787 -370.778581) (xy 159.396839 -370.718856) (xy 159.373168 -370.65585)
			(xy 159.357196 -370.590467) (xy 159.349153 -370.523644) (xy 129.670828 -370.523644) (xy 129.662785 -370.590464)
			(xy 129.646814 -370.655846) (xy 129.623143 -370.71885) (xy 129.592113 -370.778573) (xy 129.554166 -370.83416)
			(xy 129.53238 -370.859812) (xy 129.526594 -370.866964) (xy 129.520073 -370.884149) (xy 129.51968 -370.89334)
			(xy 129.51968 -371.386862) (xy 129.520113 -371.396047) (xy 129.526611 -371.413231) (xy 129.53238 -371.42039)
			(xy 129.554181 -371.446031) (xy 129.592128 -371.50162) (xy 129.62316 -371.561345) (xy 129.646596 -371.623725)
			(xy 130.749241 -371.623725) (xy 130.749245 -371.556418) (xy 130.757292 -371.489593) (xy 130.773269 -371.424208)
			(xy 130.796945 -371.361202) (xy 130.827982 -371.301478) (xy 130.865934 -371.24589) (xy 130.887724 -371.220238)
			(xy 130.893532 -371.213101) (xy 130.900039 -371.195904) (xy 130.900424 -371.18671) (xy 130.900424 -371.028722)
			(xy 130.900882 -371.018554) (xy 130.908657 -370.999762) (xy 130.923032 -370.985377) (xy 130.941818 -370.977589)
			(xy 130.951986 -370.97716) (xy 131.668266 -370.97716) (xy 131.678438 -370.977592) (xy 131.697236 -370.98537)
			(xy 131.711623 -370.999754) (xy 131.719405 -371.01855) (xy 131.719828 -371.028722) (xy 131.719828 -371.18671)
			(xy 131.720227 -371.195898) (xy 131.726748 -371.213083) (xy 131.732528 -371.220238) (xy 131.754279 -371.24592)
			(xy 131.792231 -371.301502) (xy 131.823268 -371.361221) (xy 131.846945 -371.424221) (xy 131.862921 -371.4896)
			(xy 131.870969 -371.55642) (xy 131.870972 -371.623723) (xy 131.862931 -371.690543) (xy 131.846961 -371.755924)
			(xy 131.823291 -371.818927) (xy 131.792261 -371.878649) (xy 131.754314 -371.934234) (xy 131.732528 -371.959886)
			(xy 131.726704 -371.967011) (xy 131.720208 -371.984217) (xy 131.719828 -371.993414) (xy 131.719828 -372.486682)
			(xy 131.72024 -372.495869) (xy 131.726752 -372.513054) (xy 131.732528 -372.52021) (xy 131.75435 -372.545834)
			(xy 131.7923 -372.601424) (xy 131.823334 -372.661151) (xy 131.847006 -372.724159) (xy 131.862978 -372.789545)
			(xy 131.87102 -372.856371) (xy 131.871017 -372.92368) (xy 131.862969 -372.990505) (xy 131.846991 -373.05589)
			(xy 131.823313 -373.118896) (xy 131.792274 -373.17862) (xy 131.754319 -373.234206) (xy 131.732528 -373.259858)
			(xy 131.726716 -373.266992) (xy 131.720212 -373.284191) (xy 131.719828 -373.293386) (xy 131.719828 -373.451374)
			(xy 131.719414 -373.461548) (xy 131.711631 -373.480349) (xy 131.697242 -373.494736) (xy 131.67844 -373.502515)
			(xy 131.668266 -373.502936) (xy 130.951986 -373.502936) (xy 130.94181 -373.502547) (xy 130.92301 -373.494752)
			(xy 130.908625 -373.480356) (xy 130.900845 -373.46155) (xy 130.900424 -373.451374) (xy 130.900424 -373.293386)
			(xy 130.900015 -373.284199) (xy 130.8935 -373.267015) (xy 130.887724 -373.259858) (xy 130.86597 -373.234178)
			(xy 130.828022 -373.178595) (xy 130.796988 -373.118875) (xy 130.773314 -373.055874) (xy 130.757339 -372.990496)
			(xy 130.749292 -372.923677) (xy 130.749289 -372.856375) (xy 130.75733 -372.789555) (xy 130.773299 -372.724174)
			(xy 130.796967 -372.661171) (xy 130.827995 -372.601449) (xy 130.865939 -372.545863) (xy 130.887724 -372.52021)
			(xy 130.893544 -372.513082) (xy 130.900044 -372.495878) (xy 130.900424 -372.486682) (xy 130.900424 -371.993414)
			(xy 130.900002 -371.984228) (xy 130.893496 -371.967044) (xy 130.887724 -371.959886) (xy 130.865899 -371.934264)
			(xy 130.827953 -371.878673) (xy 130.796922 -371.818945) (xy 130.773252 -371.755937) (xy 130.757282 -371.690551)
			(xy 130.749241 -371.623725) (xy 129.646596 -371.623725) (xy 129.646831 -371.624351) (xy 129.662802 -371.689734)
			(xy 129.670845 -371.756558) (xy 129.670844 -371.823863) (xy 129.662799 -371.890687) (xy 129.646825 -371.956069)
			(xy 129.623151 -372.019074) (xy 129.592117 -372.078799) (xy 129.554168 -372.134386) (xy 129.53238 -372.160038)
			(xy 129.526582 -372.167182) (xy 129.520069 -372.184374) (xy 129.51968 -372.193566) (xy 129.51968 -372.351554)
			(xy 129.519199 -372.36172) (xy 129.511432 -372.380511) (xy 129.497064 -372.394896) (xy 129.478284 -372.402686)
			(xy 129.468118 -372.403116) (xy 128.751838 -372.403116) (xy 128.741663 -372.402704) (xy 128.722861 -372.394923)
			(xy 128.708473 -372.380533) (xy 128.700695 -372.361729) (xy 128.700276 -372.351554) (xy 128.700276 -372.193566)
			(xy 128.699887 -372.184376) (xy 128.693359 -372.167192) (xy 128.687576 -372.160038) (xy 128.665801 -372.134375)
			(xy 128.627849 -372.078791) (xy 128.596813 -372.019069) (xy 128.573138 -371.956066) (xy 128.557163 -371.890685)
			(xy 128.549117 -371.823863) (xy 128.549116 -371.756558) (xy 128.557159 -371.689736) (xy 128.573132 -371.624354)
			(xy 128.596805 -371.56135) (xy 128.627838 -371.501627) (xy 128.665788 -371.446042) (xy 128.687576 -371.42039)
			(xy 128.693357 -371.413233) (xy 128.699882 -371.396052) (xy 128.700276 -371.386862) (xy 128.700276 -370.89334)
			(xy 128.699852 -370.884154) (xy 128.693349 -370.866969) (xy 128.687576 -370.859812) (xy 128.665775 -370.83417)
			(xy 128.627825 -370.778583) (xy 128.59679 -370.718858) (xy 128.573116 -370.655852) (xy 128.557143 -370.590469)
			(xy 128.549099 -370.523644) (xy 125.271037 -370.523644) (xy 125.262994 -370.590464) (xy 125.247024 -370.655845)
			(xy 125.223354 -370.718849) (xy 125.192323 -370.778573) (xy 125.154378 -370.834159) (xy 125.132592 -370.859812)
			(xy 125.126807 -370.866965) (xy 125.120286 -370.88415) (xy 125.119892 -370.89334) (xy 125.119892 -371.386862)
			(xy 125.120322 -371.396047) (xy 125.126822 -371.413231) (xy 125.132592 -371.42039) (xy 125.154393 -371.446031)
			(xy 125.192339 -371.50162) (xy 125.22337 -371.561345) (xy 125.246828 -371.623785) (xy 126.348921 -371.623785)
			(xy 126.348925 -371.556358) (xy 126.357005 -371.489416) (xy 126.373046 -371.423925) (xy 126.396816 -371.360826)
			(xy 126.427973 -371.301029) (xy 126.466069 -371.245395) (xy 126.487936 -371.21973) (xy 126.493749 -371.212597)
			(xy 126.500253 -371.195397) (xy 126.500636 -371.186202) (xy 126.500636 -371.028722) (xy 126.501144 -371.018597)
			(xy 126.508864 -370.999877) (xy 126.523144 -370.98552) (xy 126.541822 -370.9777) (xy 126.551944 -370.97716)
			(xy 127.268224 -370.97716) (xy 127.278375 -370.977601) (xy 127.29712 -370.985397) (xy 127.311441 -370.999787)
			(xy 127.319147 -371.018569) (xy 127.319532 -371.028722) (xy 127.319532 -371.186202) (xy 127.319956 -371.195387)
			(xy 127.326462 -371.212571) (xy 127.332232 -371.21973) (xy 127.354058 -371.245427) (xy 127.392145 -371.301057)
			(xy 127.423296 -371.36085) (xy 127.447061 -371.423942) (xy 127.463098 -371.489427) (xy 127.471176 -371.556361)
			(xy 127.47118 -371.623781) (xy 127.463108 -371.690717) (xy 127.447078 -371.756203) (xy 127.423319 -371.819298)
			(xy 127.392175 -371.879094) (xy 127.354093 -371.934728) (xy 127.332232 -371.960394) (xy 127.326447 -371.967547)
			(xy 127.319927 -371.984732) (xy 127.319532 -371.993922) (xy 127.319532 -372.486174) (xy 127.31997 -372.495358)
			(xy 127.326466 -372.512542) (xy 127.332232 -372.519702) (xy 127.354128 -372.54534) (xy 127.392214 -372.600979)
			(xy 127.423361 -372.66078) (xy 127.447122 -372.72388) (xy 127.463154 -372.789372) (xy 127.471227 -372.856313)
			(xy 127.471224 -372.923738) (xy 127.463145 -372.990678) (xy 127.447107 -373.056169) (xy 127.42334 -373.119267)
			(xy 127.392188 -373.179064) (xy 127.354097 -373.2347) (xy 127.332232 -373.260366) (xy 127.326417 -373.267498)
			(xy 127.319915 -373.284699) (xy 127.319532 -373.293894) (xy 127.319532 -373.451374) (xy 127.319051 -373.461503)
			(xy 127.311327 -373.480228) (xy 127.297038 -373.494587) (xy 127.27835 -373.502402) (xy 127.268224 -373.502936)
			(xy 126.551944 -373.502936) (xy 126.541797 -373.502443) (xy 126.523053 -373.494669) (xy 126.508729 -373.480294)
			(xy 126.501021 -373.461522) (xy 126.500636 -373.451374) (xy 126.500636 -373.293894) (xy 126.500221 -373.284708)
			(xy 126.49371 -373.267524) (xy 126.487936 -373.260366) (xy 126.466104 -373.234674) (xy 126.428012 -373.179044)
			(xy 126.396858 -373.119252) (xy 126.37309 -373.056158) (xy 126.357051 -372.990672) (xy 126.348972 -372.923736)
			(xy 126.348969 -372.856315) (xy 126.357042 -372.789378) (xy 126.373075 -372.72389) (xy 126.396837 -372.660795)
			(xy 126.427986 -372.601) (xy 126.466073 -372.545367) (xy 126.487936 -372.519702) (xy 126.493719 -372.512547)
			(xy 126.500241 -372.495364) (xy 126.500636 -372.486174) (xy 126.500636 -371.993922) (xy 126.500207 -371.984737)
			(xy 126.493706 -371.967553) (xy 126.487936 -371.960394) (xy 126.466033 -371.93476) (xy 126.427943 -371.879122)
			(xy 126.396792 -371.819322) (xy 126.373029 -371.756221) (xy 126.356995 -371.690727) (xy 126.348921 -371.623785)
			(xy 125.246828 -371.623785) (xy 125.247041 -371.624351) (xy 125.263012 -371.689734) (xy 125.271054 -371.756558)
			(xy 125.271053 -371.823863) (xy 125.263008 -371.890686) (xy 125.247034 -371.956069) (xy 125.223361 -372.019074)
			(xy 125.192328 -372.078798) (xy 125.15438 -372.134385) (xy 125.132592 -372.160038) (xy 125.126796 -372.167183)
			(xy 125.120281 -372.184374) (xy 125.119892 -372.193566) (xy 125.119892 -372.351554) (xy 125.119399 -372.361719)
			(xy 125.111635 -372.380507) (xy 125.097271 -372.394892) (xy 125.078494 -372.402684) (xy 125.06833 -372.403116)
			(xy 124.35205 -372.403116) (xy 124.341876 -372.402694) (xy 124.323073 -372.394917) (xy 124.308685 -372.38053)
			(xy 124.300907 -372.361728) (xy 124.300488 -372.351554) (xy 124.300488 -372.193566) (xy 124.300097 -372.184377)
			(xy 124.29357 -372.167192) (xy 124.287788 -372.160038) (xy 124.266013 -372.134375) (xy 124.22806 -372.078791)
			(xy 124.197024 -372.01907) (xy 124.173348 -371.956067) (xy 124.157372 -371.890685) (xy 124.149326 -371.823863)
			(xy 124.149325 -371.756558) (xy 124.157369 -371.689736) (xy 124.173342 -371.624354) (xy 124.197015 -371.561349)
			(xy 124.228049 -371.501627) (xy 124.266 -371.446041) (xy 124.287788 -371.42039) (xy 124.29357 -371.413234)
			(xy 124.300094 -371.396052) (xy 124.300488 -371.386862) (xy 124.300488 -370.89334) (xy 124.300061 -370.884154)
			(xy 124.29356 -370.86697) (xy 124.287788 -370.859812) (xy 124.265987 -370.83417) (xy 124.228035 -370.778583)
			(xy 124.197 -370.718859) (xy 124.173326 -370.655853) (xy 124.157352 -370.590469) (xy 124.149308 -370.523644)
			(xy 120.871269 -370.523644) (xy 120.871269 -370.523702) (xy 120.863194 -370.59064) (xy 120.847159 -370.656128)
			(xy 120.823396 -370.719225) (xy 120.792247 -370.779021) (xy 120.754159 -370.834655) (xy 120.732296 -370.86032)
			(xy 120.726508 -370.867471) (xy 120.719988 -370.884657) (xy 120.719596 -370.893848) (xy 120.719596 -371.386354)
			(xy 120.720029 -371.395539) (xy 120.726527 -371.412723) (xy 120.732296 -371.419882) (xy 120.754174 -371.445536)
			(xy 120.792262 -371.501172) (xy 120.823413 -371.56097) (xy 120.847047 -371.623725) (xy 121.949153 -371.623725)
			(xy 121.949157 -371.556417) (xy 121.957205 -371.489592) (xy 121.973182 -371.424208) (xy 121.996859 -371.361202)
			(xy 122.027896 -371.301477) (xy 122.06585 -371.24589) (xy 122.08764 -371.220238) (xy 122.09345 -371.213103)
			(xy 122.099956 -371.195904) (xy 122.10034 -371.18671) (xy 122.10034 -371.028722) (xy 122.100782 -371.018552)
			(xy 122.10856 -370.999757) (xy 122.12294 -370.985371) (xy 122.141732 -370.977586) (xy 122.151902 -370.97716)
			(xy 122.868182 -370.97716) (xy 122.878355 -370.977579) (xy 122.897154 -370.985362) (xy 122.91154 -370.99975)
			(xy 122.919322 -371.018549) (xy 122.919744 -371.028722) (xy 122.919744 -371.18671) (xy 122.920162 -371.195896)
			(xy 122.926672 -371.21308) (xy 122.932444 -371.220238) (xy 122.954195 -371.245921) (xy 122.992146 -371.301502)
			(xy 123.023182 -371.361222) (xy 123.046857 -371.424222) (xy 123.062833 -371.489601) (xy 123.070881 -371.55642)
			(xy 123.070884 -371.623723) (xy 123.062844 -371.690543) (xy 123.046874 -371.755923) (xy 123.023205 -371.818926)
			(xy 122.992175 -371.878648) (xy 122.95423 -371.934234) (xy 122.932444 -371.959886) (xy 122.926622 -371.967013)
			(xy 122.920124 -371.984218) (xy 122.919744 -371.993414) (xy 122.919744 -372.486682) (xy 122.920175 -372.495867)
			(xy 122.926676 -372.513051) (xy 122.932444 -372.52021) (xy 122.954266 -372.545834) (xy 122.992215 -372.601424)
			(xy 123.023248 -372.661152) (xy 123.046919 -372.72416) (xy 123.06289 -372.789546) (xy 123.070932 -372.856372)
			(xy 123.070929 -372.92368) (xy 123.062881 -372.990505) (xy 123.046904 -373.055889) (xy 123.023227 -373.118895)
			(xy 122.992188 -373.17862) (xy 122.954234 -373.234206) (xy 122.932444 -373.259858) (xy 122.926633 -373.266993)
			(xy 122.920129 -373.284192) (xy 122.919744 -373.293386) (xy 122.919744 -373.451374) (xy 122.919314 -373.461546)
			(xy 122.911534 -373.480344) (xy 122.89715 -373.49473) (xy 122.878354 -373.502513) (xy 122.868182 -373.502936)
			(xy 122.151902 -373.502936) (xy 122.141727 -373.502534) (xy 122.122928 -373.494745) (xy 122.108542 -373.480352)
			(xy 122.100761 -373.461549) (xy 122.10034 -373.451374) (xy 122.10034 -373.293386) (xy 122.099928 -373.284199)
			(xy 122.093415 -373.267015) (xy 122.08764 -373.259858) (xy 122.065886 -373.234178) (xy 122.027936 -373.178596)
			(xy 121.996901 -373.118876) (xy 121.973226 -373.055875) (xy 121.957251 -372.990496) (xy 121.949204 -372.923677)
			(xy 121.949201 -372.856374) (xy 121.957242 -372.789554) (xy 121.973211 -372.724174) (xy 121.99688 -372.661171)
			(xy 122.02791 -372.601448) (xy 122.065855 -372.545862) (xy 122.08764 -372.52021) (xy 122.093462 -372.513083)
			(xy 122.099961 -372.495878) (xy 122.10034 -372.486682) (xy 122.10034 -371.993414) (xy 122.099914 -371.984229)
			(xy 122.093411 -371.967045) (xy 122.08764 -371.959886) (xy 122.065815 -371.934265) (xy 122.027867 -371.878674)
			(xy 121.996835 -371.818946) (xy 121.973165 -371.755937) (xy 121.957194 -371.690551) (xy 121.949153 -371.623725)
			(xy 120.847047 -371.623725) (xy 120.847176 -371.624068) (xy 120.863211 -371.689558) (xy 120.871286 -371.756498)
			(xy 120.871284 -371.823923) (xy 120.863207 -371.890862) (xy 120.84717 -371.956352) (xy 120.823404 -372.01945)
			(xy 120.792252 -372.079246) (xy 120.754161 -372.134881) (xy 120.732296 -372.160546) (xy 120.726497 -372.167689)
			(xy 120.719984 -372.184881) (xy 120.719596 -372.194074) (xy 120.719596 -372.351554) (xy 120.719037 -372.361673)
			(xy 120.711331 -372.380387) (xy 120.697067 -372.394743) (xy 120.678404 -372.40257) (xy 120.668288 -372.403116)
			(xy 119.952008 -372.403116) (xy 119.941856 -372.402672) (xy 119.923107 -372.394882) (xy 119.908784 -372.380493)
			(xy 119.901081 -372.361707) (xy 119.9007 -372.351554) (xy 119.9007 -372.194074) (xy 119.900303 -372.184885)
			(xy 119.89378 -372.167701) (xy 119.888 -372.160546) (xy 119.86615 -372.134869) (xy 119.828061 -372.079237)
			(xy 119.796909 -372.019442) (xy 119.773144 -371.956346) (xy 119.757108 -371.890859) (xy 119.749031 -371.823922)
			(xy 119.74903 -371.756499) (xy 119.757104 -371.689562) (xy 119.773138 -371.624074) (xy 119.796901 -371.560977)
			(xy 119.82805 -371.501182) (xy 119.866137 -371.445547) (xy 119.888 -371.419882) (xy 119.893787 -371.41273)
			(xy 119.900307 -371.395545) (xy 119.9007 -371.386354) (xy 119.9007 -370.893848) (xy 119.900267 -370.884663)
			(xy 119.893769 -370.867479) (xy 119.888 -370.86032) (xy 119.866124 -370.834664) (xy 119.828036 -370.779029)
			(xy 119.796886 -370.719231) (xy 119.773122 -370.656133) (xy 119.757088 -370.590643) (xy 119.749013 -370.523703)
			(xy 116.470966 -370.523703) (xy 116.462929 -370.590466) (xy 116.446956 -370.655848) (xy 116.423282 -370.718853)
			(xy 116.392247 -370.778575) (xy 116.354297 -370.834161) (xy 116.332508 -370.859812) (xy 116.326725 -370.866967)
			(xy 116.320202 -370.88415) (xy 116.319808 -370.89334) (xy 116.319808 -371.386862) (xy 116.320235 -371.396047)
			(xy 116.326737 -371.413232) (xy 116.332508 -371.42039) (xy 116.354311 -371.44603) (xy 116.392263 -371.501617)
			(xy 116.423299 -371.561342) (xy 116.446761 -371.623785) (xy 117.548834 -371.623785) (xy 117.548837 -371.556358)
			(xy 117.556917 -371.489416) (xy 117.572959 -371.423924) (xy 117.596729 -371.360825) (xy 117.627887 -371.301028)
			(xy 117.665984 -371.245394) (xy 117.687852 -371.21973) (xy 117.693667 -371.212598) (xy 117.700169 -371.195397)
			(xy 117.700552 -371.186202) (xy 117.700552 -371.028722) (xy 117.701045 -371.018595) (xy 117.708768 -370.999872)
			(xy 117.723052 -370.985515) (xy 117.741736 -370.977697) (xy 117.75186 -370.97716) (xy 118.46814 -370.97716)
			(xy 118.478292 -370.977588) (xy 118.497037 -370.985389) (xy 118.511358 -370.999783) (xy 118.519063 -371.018568)
			(xy 118.519448 -371.028722) (xy 118.519448 -371.186202) (xy 118.519869 -371.195388) (xy 118.526376 -371.212572)
			(xy 118.532148 -371.21973) (xy 118.553976 -371.245425) (xy 118.59207 -371.301054) (xy 118.623225 -371.360846)
			(xy 118.646994 -371.423939) (xy 118.663033 -371.489425) (xy 118.671113 -371.556361) (xy 118.671116 -371.623782)
			(xy 118.663044 -371.690719) (xy 118.647011 -371.756207) (xy 118.623248 -371.819302) (xy 118.592099 -371.879097)
			(xy 118.554012 -371.93473) (xy 118.532148 -371.960394) (xy 118.526365 -371.967549) (xy 118.519844 -371.984732)
			(xy 118.519448 -371.993922) (xy 118.519448 -372.486174) (xy 118.519882 -372.495358) (xy 118.52638 -372.512542)
			(xy 118.532148 -372.519702) (xy 118.554047 -372.545339) (xy 118.592138 -372.600976) (xy 118.62329 -372.660776)
			(xy 118.647055 -372.723877) (xy 118.66309 -372.78937) (xy 118.671164 -372.856312) (xy 118.671161 -372.923739)
			(xy 118.663081 -372.990681) (xy 118.64704 -373.056172) (xy 118.62327 -373.119271) (xy 118.592112 -373.179068)
			(xy 118.554016 -373.234702) (xy 118.532148 -373.260366) (xy 118.526334 -373.267499) (xy 118.519831 -373.284699)
			(xy 118.519448 -373.293894) (xy 118.519448 -373.451374) (xy 118.518952 -373.461501) (xy 118.51123 -373.480223)
			(xy 118.496947 -373.494581) (xy 118.478264 -373.502399) (xy 118.46814 -373.502936) (xy 117.75186 -373.502936)
			(xy 117.741708 -373.502512) (xy 117.722961 -373.49471) (xy 117.708641 -373.480315) (xy 117.700936 -373.461528)
			(xy 117.700552 -373.451374) (xy 117.700552 -373.293894) (xy 117.700133 -373.284708) (xy 117.693624 -373.267524)
			(xy 117.687852 -373.260366) (xy 117.66602 -373.234674) (xy 117.627926 -373.179045) (xy 117.596771 -373.119253)
			(xy 117.573003 -373.056159) (xy 117.556964 -372.990673) (xy 117.548884 -372.923737) (xy 117.548881 -372.856315)
			(xy 117.556954 -372.789378) (xy 117.572988 -372.72389) (xy 117.596751 -372.660794) (xy 117.6279 -372.600999)
			(xy 117.665988 -372.545366) (xy 117.687852 -372.519702) (xy 117.693637 -372.512549) (xy 117.700157 -372.495364)
			(xy 117.700552 -372.486174) (xy 117.700552 -371.993922) (xy 117.70012 -371.984737) (xy 117.69362 -371.967553)
			(xy 117.687852 -371.960394) (xy 117.665949 -371.93476) (xy 117.627858 -371.879123) (xy 117.596706 -371.819323)
			(xy 117.572942 -371.756221) (xy 117.556907 -371.690728) (xy 117.548834 -371.623785) (xy 116.446761 -371.623785)
			(xy 116.446973 -371.624348) (xy 116.462946 -371.689732) (xy 116.47099 -371.756557) (xy 116.470989 -371.823864)
			(xy 116.462943 -371.890689) (xy 116.446967 -371.956072) (xy 116.42329 -372.019077) (xy 116.392252 -372.078801)
			(xy 116.354298 -372.134387) (xy 116.332508 -372.160038) (xy 116.326714 -372.167185) (xy 116.320197 -372.184374)
			(xy 116.319808 -372.193566) (xy 116.319808 -372.351554) (xy 116.31923 -372.361703) (xy 116.311479 -372.380462)
			(xy 116.29714 -372.394828) (xy 116.278394 -372.402612) (xy 116.268246 -372.403116) (xy 115.551966 -372.403116)
			(xy 115.541786 -372.402763) (xy 115.522982 -372.394958) (xy 115.508597 -372.380551) (xy 115.500821 -372.361734)
			(xy 115.500404 -372.351554) (xy 115.500404 -372.193566) (xy 115.500009 -372.184377) (xy 115.493485 -372.167193)
			(xy 115.487704 -372.160038) (xy 115.465931 -372.134374) (xy 115.427984 -372.078788) (xy 115.396952 -372.019066)
			(xy 115.37328 -371.956063) (xy 115.357307 -371.890683) (xy 115.349263 -371.823862) (xy 115.349261 -371.756559)
			(xy 115.357303 -371.689738) (xy 115.373274 -371.624357) (xy 115.396944 -371.561353) (xy 115.427973 -371.50163)
			(xy 115.465918 -371.446043) (xy 115.487704 -371.42039) (xy 115.493488 -371.413236) (xy 115.50001 -371.396052)
			(xy 115.500404 -371.386862) (xy 115.500404 -370.89334) (xy 115.499974 -370.884155) (xy 115.493474 -370.86697)
			(xy 115.487704 -370.859812) (xy 115.465906 -370.834169) (xy 115.427959 -370.77858) (xy 115.396929 -370.718855)
			(xy 115.373258 -370.65585) (xy 115.357287 -370.590467) (xy 115.349244 -370.523644) (xy 85.670941 -370.523644)
			(xy 85.670941 -370.523703) (xy 85.662866 -370.590641) (xy 85.646831 -370.65613) (xy 85.623066 -370.719226)
			(xy 85.591915 -370.779022) (xy 85.553825 -370.834655) (xy 85.53196 -370.86032) (xy 85.526167 -370.867468)
			(xy 85.519651 -370.884656) (xy 85.51926 -370.893848) (xy 85.51926 -371.386354) (xy 85.519701 -371.395538)
			(xy 85.526194 -371.412722) (xy 85.53196 -371.419882) (xy 85.553839 -371.445535) (xy 85.59193 -371.501171)
			(xy 85.623082 -371.560968) (xy 85.646742 -371.623785) (xy 86.748803 -371.623785) (xy 86.748807 -371.556358)
			(xy 86.756887 -371.489417) (xy 86.772927 -371.423926) (xy 86.796696 -371.360827) (xy 86.827851 -371.30103)
			(xy 86.865945 -371.245395) (xy 86.887812 -371.21973) (xy 86.893622 -371.212594) (xy 86.900128 -371.195397)
			(xy 86.900512 -371.186202) (xy 86.900512 -371.028722) (xy 86.901044 -371.0186) (xy 86.908759 -370.999885)
			(xy 86.923031 -370.985529) (xy 86.941701 -370.977704) (xy 86.95182 -370.97716) (xy 87.6681 -370.97716)
			(xy 87.678204 -370.977684) (xy 87.696874 -370.985414) (xy 87.711168 -370.999699) (xy 87.718909 -371.018365)
			(xy 87.719408 -371.028468) (xy 87.719408 -371.186202) (xy 87.719815 -371.195389) (xy 87.726331 -371.212574)
			(xy 87.732108 -371.21973) (xy 87.753934 -371.245426) (xy 87.792024 -371.301056) (xy 87.823176 -371.360848)
			(xy 87.846942 -371.423941) (xy 87.862979 -371.489426) (xy 87.871058 -371.556361) (xy 87.871062 -371.623782)
			(xy 87.86299 -371.690717) (xy 87.846958 -371.756204) (xy 87.823199 -371.819299) (xy 87.792053 -371.879095)
			(xy 87.753969 -371.934729) (xy 87.732108 -371.960394) (xy 87.726332 -371.967554) (xy 87.719805 -371.984733)
			(xy 87.719408 -371.993922) (xy 87.719408 -372.486174) (xy 87.719829 -372.49536) (xy 87.726335 -372.512545)
			(xy 87.732108 -372.519702) (xy 87.754005 -372.54534) (xy 87.792092 -372.600978) (xy 87.823241 -372.660779)
			(xy 87.847003 -372.723879) (xy 87.863036 -372.789371) (xy 87.871109 -372.856312) (xy 87.871106 -372.923739)
			(xy 87.863027 -372.990679) (xy 87.846988 -373.05617) (xy 87.82322 -373.119268) (xy 87.792066 -373.179065)
			(xy 87.753974 -373.234701) (xy 87.732108 -373.260366) (xy 87.726302 -373.267504) (xy 87.719793 -373.2847)
			(xy 87.719408 -373.293894) (xy 87.719408 -373.451374) (xy 87.718854 -373.461493) (xy 87.711143 -373.480205)
			(xy 87.696878 -373.49456) (xy 87.678216 -373.502389) (xy 87.6681 -373.502936) (xy 86.95182 -373.502936)
			(xy 86.941717 -373.502399) (xy 86.923046 -373.494675) (xy 86.908752 -373.480394) (xy 86.90101 -373.461731)
			(xy 86.900512 -373.451628) (xy 86.900512 -373.293894) (xy 86.900102 -373.284707) (xy 86.893588 -373.267523)
			(xy 86.887812 -373.260366) (xy 86.865981 -373.234673) (xy 86.82789 -373.179043) (xy 86.796738 -373.119251)
			(xy 86.772971 -373.056157) (xy 86.756933 -372.990672) (xy 86.748854 -372.923736) (xy 86.748851 -372.856315)
			(xy 86.756924 -372.789379) (xy 86.772956 -372.723891) (xy 86.796717 -372.660796) (xy 86.827864 -372.601001)
			(xy 86.86595 -372.545367) (xy 86.887812 -372.519702) (xy 86.893592 -372.512545) (xy 86.900116 -372.495363)
			(xy 86.900512 -372.486174) (xy 86.900512 -371.993922) (xy 86.900088 -371.984736) (xy 86.893584 -371.967552)
			(xy 86.887812 -371.960394) (xy 86.86591 -371.93476) (xy 86.827822 -371.879121) (xy 86.796672 -371.819321)
			(xy 86.77291 -371.75622) (xy 86.756876 -371.690727) (xy 86.748803 -371.623785) (xy 85.646742 -371.623785)
			(xy 85.646848 -371.624067) (xy 85.662883 -371.689557) (xy 85.670959 -371.756498) (xy 85.670957 -371.823923)
			(xy 85.662879 -371.890863) (xy 85.646841 -371.956354) (xy 85.623074 -372.019451) (xy 85.591919 -372.079248)
			(xy 85.553826 -372.134881) (xy 85.53196 -372.160546) (xy 85.526156 -372.167686) (xy 85.519647 -372.184881)
			(xy 85.51926 -372.194074) (xy 85.51926 -372.351554) (xy 85.518736 -372.361678) (xy 85.511023 -372.380398)
			(xy 85.496748 -372.394756) (xy 85.478073 -372.402576) (xy 85.467952 -372.403116) (xy 84.751672 -372.403116)
			(xy 84.741563 -372.402638) (xy 84.722888 -372.394894) (xy 84.708594 -372.380596) (xy 84.700858 -372.361917)
			(xy 84.700364 -372.351808) (xy 84.700364 -372.194074) (xy 84.699952 -372.184887) (xy 84.693438 -372.167704)
			(xy 84.687664 -372.160546) (xy 84.665815 -372.134869) (xy 84.627728 -372.079235) (xy 84.596579 -372.01944)
			(xy 84.572816 -371.956345) (xy 84.55678 -371.890858) (xy 84.548704 -371.823921) (xy 84.548703 -371.7565)
			(xy 84.556776 -371.689563) (xy 84.572809 -371.624075) (xy 84.59657 -371.560979) (xy 84.627717 -371.501183)
			(xy 84.665802 -371.445548) (xy 84.687664 -371.419882) (xy 84.693459 -371.412736) (xy 84.699973 -371.395546)
			(xy 84.700364 -371.386354) (xy 84.700364 -370.893848) (xy 84.699917 -370.884665) (xy 84.693427 -370.867481)
			(xy 84.687664 -370.86032) (xy 84.66579 -370.834664) (xy 84.627704 -370.779027) (xy 84.596555 -370.719229)
			(xy 84.572793 -370.656131) (xy 84.55676 -370.590642) (xy 84.548686 -370.523703) (xy 81.27115 -370.523703)
			(xy 81.263075 -370.590641) (xy 81.24704 -370.656129) (xy 81.223276 -370.719226) (xy 81.192125 -370.779021)
			(xy 81.154036 -370.834655) (xy 81.132172 -370.86032) (xy 81.126381 -370.867469) (xy 81.119864 -370.884657)
			(xy 81.119472 -370.893848) (xy 81.119472 -371.386354) (xy 81.119911 -371.395538) (xy 81.126405 -371.412722)
			(xy 81.132172 -371.419882) (xy 81.154051 -371.445535) (xy 81.192141 -371.501171) (xy 81.223293 -371.560969)
			(xy 81.246928 -371.623725) (xy 82.349035 -371.623725) (xy 82.349038 -371.556418) (xy 82.357086 -371.489593)
			(xy 82.373062 -371.424209) (xy 82.396738 -371.361203) (xy 82.427775 -371.301478) (xy 82.465727 -371.24589)
			(xy 82.487516 -371.220238) (xy 82.493323 -371.2131) (xy 82.499831 -371.195904) (xy 82.500216 -371.18671)
			(xy 82.500216 -371.028722) (xy 82.500751 -371.018568) (xy 82.508514 -370.999804) (xy 82.522867 -370.985439)
			(xy 82.541625 -370.977659) (xy 82.551778 -370.97716) (xy 83.268058 -370.97716) (xy 83.27823 -370.977599)
			(xy 83.297028 -370.985374) (xy 83.311415 -370.999756) (xy 83.319197 -371.018551) (xy 83.31962 -371.028722)
			(xy 83.31962 -371.18671) (xy 83.320021 -371.195898) (xy 83.326541 -371.213083) (xy 83.33232 -371.220238)
			(xy 83.354072 -371.24592) (xy 83.392024 -371.301501) (xy 83.423061 -371.361221) (xy 83.446738 -371.424221)
			(xy 83.462715 -371.4896) (xy 83.470763 -371.55642) (xy 83.470766 -371.623723) (xy 83.462725 -371.690544)
			(xy 83.446755 -371.755924) (xy 83.423085 -371.818927) (xy 83.392054 -371.878649) (xy 83.354107 -371.934234)
			(xy 83.33232 -371.959886) (xy 83.326507 -371.96702) (xy 83.320001 -371.984219) (xy 83.31962 -371.993414)
			(xy 83.31962 -372.486682) (xy 83.320034 -372.495869) (xy 83.326545 -372.513054) (xy 83.33232 -372.52021)
			(xy 83.354142 -372.545834) (xy 83.392093 -372.601424) (xy 83.423127 -372.661151) (xy 83.446799 -372.724159)
			(xy 83.462771 -372.789545) (xy 83.470813 -372.856371) (xy 83.47081 -372.92368) (xy 83.462762 -372.990505)
			(xy 83.446784 -373.05589) (xy 83.423106 -373.118896) (xy 83.392066 -373.17862) (xy 83.354111 -373.234206)
			(xy 83.33232 -373.259858) (xy 83.326519 -373.267) (xy 83.320006 -373.284193) (xy 83.31962 -373.293386)
			(xy 83.31962 -373.451374) (xy 83.319214 -373.461549) (xy 83.311429 -373.480351) (xy 83.297038 -373.494738)
			(xy 83.278233 -373.502517) (xy 83.268058 -373.502936) (xy 82.551778 -373.502936) (xy 82.541602 -373.502553)
			(xy 82.522802 -373.494756) (xy 82.508417 -373.480358) (xy 82.500637 -373.461551) (xy 82.500216 -373.451374)
			(xy 82.500216 -373.293386) (xy 82.499809 -373.284199) (xy 82.493293 -373.267014) (xy 82.487516 -373.259858)
			(xy 82.465763 -373.234178) (xy 82.427814 -373.178595) (xy 82.396781 -373.118875) (xy 82.373107 -373.055874)
			(xy 82.357133 -372.990496) (xy 82.349086 -372.923677) (xy 82.349083 -372.856375) (xy 82.357123 -372.789555)
			(xy 82.373092 -372.724175) (xy 82.39676 -372.661172) (xy 82.427788 -372.601449) (xy 82.465731 -372.545863)
			(xy 82.487516 -372.52021) (xy 82.493335 -372.513081) (xy 82.499836 -372.495878) (xy 82.500216 -372.486682)
			(xy 82.500216 -371.993414) (xy 82.499795 -371.984228) (xy 82.493288 -371.967044) (xy 82.487516 -371.959886)
			(xy 82.465692 -371.934264) (xy 82.427745 -371.878673) (xy 82.396715 -371.818945) (xy 82.373045 -371.755936)
			(xy 82.357076 -371.690551) (xy 82.349035 -371.623725) (xy 81.246928 -371.623725) (xy 81.247057 -371.624067)
			(xy 81.263092 -371.689558) (xy 81.271168 -371.756498) (xy 81.271166 -371.823923) (xy 81.263089 -371.890863)
			(xy 81.247051 -371.956353) (xy 81.223284 -372.019451) (xy 81.19213 -372.079247) (xy 81.154038 -372.134881)
			(xy 81.132172 -372.160546) (xy 81.12637 -372.167687) (xy 81.119859 -372.184881) (xy 81.119472 -372.194074)
			(xy 81.119472 -372.351554) (xy 81.118936 -372.361676) (xy 81.111226 -372.380394) (xy 81.096954 -372.394752)
			(xy 81.078283 -372.402574) (xy 81.068164 -372.403116) (xy 80.351884 -372.403116) (xy 80.341776 -372.402628)
			(xy 80.323101 -372.394888) (xy 80.308807 -372.380592) (xy 80.30107 -372.361916) (xy 80.300576 -372.351808)
			(xy 80.300576 -372.194074) (xy 80.300184 -372.184885) (xy 80.293658 -372.1677) (xy 80.287876 -372.160546)
			(xy 80.266027 -372.134869) (xy 80.227939 -372.079236) (xy 80.196789 -372.019441) (xy 80.173025 -371.956346)
			(xy 80.156989 -371.890858) (xy 80.148913 -371.823922) (xy 80.148912 -371.756499) (xy 80.156986 -371.689563)
			(xy 80.173019 -371.624075) (xy 80.196781 -371.560978) (xy 80.227928 -371.501182) (xy 80.266014 -371.445548)
			(xy 80.287876 -371.419882) (xy 80.29366 -371.412728) (xy 80.300183 -371.395544) (xy 80.300576 -371.386354)
			(xy 80.300576 -370.893848) (xy 80.300148 -370.884663) (xy 80.293647 -370.867478) (xy 80.287876 -370.86032)
			(xy 80.266001 -370.834664) (xy 80.227914 -370.779028) (xy 80.196765 -370.71923) (xy 80.173003 -370.656132)
			(xy 80.156969 -370.590642) (xy 80.148895 -370.523703) (xy 76.870824 -370.523703) (xy 76.862788 -370.590464)
			(xy 76.846817 -370.655845) (xy 76.823147 -370.718849) (xy 76.792116 -370.778573) (xy 76.75417 -370.83416)
			(xy 76.732384 -370.859812) (xy 76.726598 -370.866965) (xy 76.720078 -370.88415) (xy 76.719684 -370.89334)
			(xy 76.719684 -371.386862) (xy 76.720116 -371.396047) (xy 76.726615 -371.413231) (xy 76.732384 -371.42039)
			(xy 76.754185 -371.446031) (xy 76.792132 -371.50162) (xy 76.823163 -371.561345) (xy 76.846621 -371.623785)
			(xy 77.948715 -371.623785) (xy 77.948719 -371.556358) (xy 77.956799 -371.489417) (xy 77.972839 -371.423925)
			(xy 77.996609 -371.360826) (xy 78.027766 -371.301029) (xy 78.065861 -371.245395) (xy 78.087728 -371.21973)
			(xy 78.09354 -371.212596) (xy 78.100045 -371.195397) (xy 78.100428 -371.186202) (xy 78.100428 -371.028722)
			(xy 78.100944 -371.018598) (xy 78.108662 -370.99988) (xy 78.12294 -370.985523) (xy 78.141615 -370.977701)
			(xy 78.151736 -370.97716) (xy 78.868016 -370.97716) (xy 78.878121 -370.977671) (xy 78.896792 -370.985407)
			(xy 78.911084 -370.999695) (xy 78.918826 -371.018363) (xy 78.919324 -371.028468) (xy 78.919324 -371.186202)
			(xy 78.919728 -371.19539) (xy 78.926245 -371.212575) (xy 78.932024 -371.21973) (xy 78.95385 -371.245426)
			(xy 78.991938 -371.301057) (xy 79.023089 -371.360849) (xy 79.046854 -371.423942) (xy 79.062892 -371.489427)
			(xy 79.07097 -371.556361) (xy 79.070974 -371.623782) (xy 79.062902 -371.690717) (xy 79.046871 -371.756203)
			(xy 79.023112 -371.819299) (xy 78.991967 -371.879094) (xy 78.953885 -371.934728) (xy 78.932024 -371.960394)
			(xy 78.92625 -371.967556) (xy 78.919721 -371.984733) (xy 78.919324 -371.993922) (xy 78.919324 -372.486174)
			(xy 78.919741 -372.495361) (xy 78.926249 -372.512545) (xy 78.932024 -372.519702) (xy 78.953921 -372.54534)
			(xy 78.992007 -372.600979) (xy 79.023155 -372.660779) (xy 79.046916 -372.72388) (xy 79.062948 -372.789372)
			(xy 79.071021 -372.856313) (xy 79.071018 -372.923738) (xy 79.062939 -372.990679) (xy 79.046901 -373.056169)
			(xy 79.023134 -373.119267) (xy 78.99198 -373.179065) (xy 78.953889 -373.2347) (xy 78.932024 -373.260366)
			(xy 78.92622 -373.267506) (xy 78.919709 -373.2847) (xy 78.919324 -373.293894) (xy 78.919324 -373.451374)
			(xy 78.918851 -373.461504) (xy 78.911125 -373.480231) (xy 78.896834 -373.49459) (xy 78.878143 -373.502403)
			(xy 78.868016 -373.502936) (xy 78.151736 -373.502936) (xy 78.14162 -373.502455) (xy 78.122924 -373.494726)
			(xy 78.10861 -373.480429) (xy 78.100857 -373.461743) (xy 78.100428 -373.451628) (xy 78.100428 -373.293894)
			(xy 78.100015 -373.284707) (xy 78.093503 -373.267523) (xy 78.087728 -373.260366) (xy 78.065896 -373.234674)
			(xy 78.027805 -373.179044) (xy 77.996651 -373.119251) (xy 77.972884 -373.056158) (xy 77.956845 -372.990672)
			(xy 77.948766 -372.923736) (xy 77.948763 -372.856315) (xy 77.956836 -372.789378) (xy 77.972869 -372.723891)
			(xy 77.99663 -372.660795) (xy 78.027779 -372.601) (xy 78.065865 -372.545367) (xy 78.087728 -372.519702)
			(xy 78.09351 -372.512547) (xy 78.100033 -372.495364) (xy 78.100428 -372.486174) (xy 78.100428 -371.993922)
			(xy 78.100001 -371.984737) (xy 78.093498 -371.967553) (xy 78.087728 -371.960394) (xy 78.065826 -371.93476)
			(xy 78.027736 -371.879122) (xy 77.996586 -371.819321) (xy 77.972822 -371.75622) (xy 77.956789 -371.690727)
			(xy 77.948715 -371.623785) (xy 76.846621 -371.623785) (xy 76.846834 -371.624351) (xy 76.862805 -371.689734)
			(xy 76.870848 -371.756558) (xy 76.870847 -371.823863) (xy 76.862802 -371.890687) (xy 76.846828 -371.956069)
			(xy 76.823155 -372.019074) (xy 76.792121 -372.078798) (xy 76.754172 -372.134386) (xy 76.732384 -372.160038)
			(xy 76.726587 -372.167183) (xy 76.720073 -372.184374) (xy 76.719684 -372.193566) (xy 76.719684 -372.351554)
			(xy 76.719199 -372.36172) (xy 76.711433 -372.380509) (xy 76.697067 -372.394895) (xy 76.678287 -372.402686)
			(xy 76.668122 -372.403116) (xy 75.951842 -372.403116) (xy 75.941667 -372.402701) (xy 75.922865 -372.394921)
			(xy 75.908477 -372.380532) (xy 75.900699 -372.361729) (xy 75.90028 -372.351554) (xy 75.90028 -372.193566)
			(xy 75.899891 -372.184377) (xy 75.893363 -372.167192) (xy 75.88758 -372.160038) (xy 75.865805 -372.134375)
			(xy 75.827853 -372.078791) (xy 75.796817 -372.019069) (xy 75.773141 -371.956066) (xy 75.757166 -371.890685)
			(xy 75.74912 -371.823863) (xy 75.749119 -371.756558) (xy 75.757162 -371.689736) (xy 75.773135 -371.624354)
			(xy 75.796808 -371.56135) (xy 75.827842 -371.501627) (xy 75.865792 -371.446042) (xy 75.88758 -371.42039)
			(xy 75.893361 -371.413234) (xy 75.899886 -371.396052) (xy 75.90028 -371.386862) (xy 75.90028 -370.89334)
			(xy 75.899855 -370.884154) (xy 75.893352 -370.866969) (xy 75.88758 -370.859812) (xy 75.865779 -370.83417)
			(xy 75.827828 -370.778583) (xy 75.796793 -370.718859) (xy 75.773119 -370.655853) (xy 75.757146 -370.590469)
			(xy 75.749102 -370.523644) (xy 72.471063 -370.523644) (xy 72.471063 -370.523702) (xy 72.462988 -370.59064)
			(xy 72.446953 -370.656129) (xy 72.42319 -370.719225) (xy 72.39204 -370.779021) (xy 72.353952 -370.834655)
			(xy 72.332088 -370.86032) (xy 72.326299 -370.867471) (xy 72.31978 -370.884657) (xy 72.319388 -370.893848)
			(xy 72.319388 -371.386354) (xy 72.319823 -371.395539) (xy 72.32632 -371.412723) (xy 72.332088 -371.419882)
			(xy 72.353966 -371.445536) (xy 72.392055 -371.501172) (xy 72.423206 -371.560969) (xy 72.446841 -371.623725)
			(xy 73.548947 -371.623725) (xy 73.548951 -371.556417) (xy 73.556998 -371.489592) (xy 73.572975 -371.424208)
			(xy 73.596652 -371.361202) (xy 73.627689 -371.301477) (xy 73.665642 -371.24589) (xy 73.687432 -371.220238)
			(xy 73.693242 -371.213102) (xy 73.699748 -371.195904) (xy 73.700132 -371.18671) (xy 73.700132 -371.028722)
			(xy 73.700582 -371.018553) (xy 73.708359 -370.99976) (xy 73.722736 -370.985374) (xy 73.741525 -370.977587)
			(xy 73.751694 -370.97716) (xy 74.467974 -370.97716) (xy 74.478147 -370.977586) (xy 74.496945 -370.985366)
			(xy 74.511331 -370.999752) (xy 74.519113 -371.018549) (xy 74.519536 -371.028722) (xy 74.519536 -371.18671)
			(xy 74.519956 -371.195896) (xy 74.526464 -371.21308) (xy 74.532236 -371.220238) (xy 74.553987 -371.245921)
			(xy 74.591939 -371.301502) (xy 74.622975 -371.361221) (xy 74.646651 -371.424222) (xy 74.662627 -371.489601)
			(xy 74.670675 -371.55642) (xy 74.670678 -371.623723) (xy 74.662638 -371.690543) (xy 74.646668 -371.755924)
			(xy 74.622998 -371.818926) (xy 74.591968 -371.878649) (xy 74.554022 -371.934234) (xy 74.532236 -371.959886)
			(xy 74.526413 -371.967012) (xy 74.519916 -371.984217) (xy 74.519536 -371.993414) (xy 74.519536 -372.486682)
			(xy 74.519969 -372.495866) (xy 74.526468 -372.51305) (xy 74.532236 -372.52021) (xy 74.554058 -372.545834)
			(xy 74.592008 -372.601424) (xy 74.623041 -372.661151) (xy 74.646713 -372.724159) (xy 74.662684 -372.789545)
			(xy 74.670726 -372.856371) (xy 74.670723 -372.92368) (xy 74.662675 -372.990505) (xy 74.646698 -373.055889)
			(xy 74.62302 -373.118896) (xy 74.591981 -373.17862) (xy 74.554027 -373.234206) (xy 74.532236 -373.259858)
			(xy 74.526425 -373.266992) (xy 74.519921 -373.284191) (xy 74.519536 -373.293386) (xy 74.519536 -373.451374)
			(xy 74.519114 -373.461547) (xy 74.511333 -373.480346) (xy 74.496946 -373.494733) (xy 74.478147 -373.502514)
			(xy 74.467974 -373.502936) (xy 73.751694 -373.502936) (xy 73.741519 -373.50254) (xy 73.722719 -373.494749)
			(xy 73.708333 -373.480354) (xy 73.700553 -373.461549) (xy 73.700132 -373.451374) (xy 73.700132 -373.293386)
			(xy 73.699722 -373.284199) (xy 73.693207 -373.267015) (xy 73.687432 -373.259858) (xy 73.665678 -373.234178)
			(xy 73.627729 -373.178595) (xy 73.596694 -373.118876) (xy 73.57302 -373.055875) (xy 73.557045 -372.990496)
			(xy 73.548998 -372.923677) (xy 73.548995 -372.856374) (xy 73.557036 -372.789554) (xy 73.573005 -372.724174)
			(xy 73.596674 -372.661171) (xy 73.627702 -372.601448) (xy 73.665647 -372.545862) (xy 73.687432 -372.52021)
			(xy 73.693253 -372.513083) (xy 73.699753 -372.495878) (xy 73.700132 -372.486682) (xy 73.700132 -371.993414)
			(xy 73.699708 -371.984228) (xy 73.693203 -371.967044) (xy 73.687432 -371.959886) (xy 73.665607 -371.934265)
			(xy 73.62766 -371.878674) (xy 73.596629 -371.818946) (xy 73.572958 -371.755937) (xy 73.556988 -371.690551)
			(xy 73.548947 -371.623725) (xy 72.446841 -371.623725) (xy 72.44697 -371.624068) (xy 72.463005 -371.689558)
			(xy 72.47108 -371.756498) (xy 72.471078 -371.823923) (xy 72.463001 -371.890862) (xy 72.446964 -371.956352)
			(xy 72.423197 -372.01945) (xy 72.392044 -372.079246) (xy 72.353953 -372.134881) (xy 72.332088 -372.160546)
			(xy 72.326288 -372.167689) (xy 72.319776 -372.184881) (xy 72.319388 -372.194074) (xy 72.319388 -372.351554)
			(xy 72.318836 -372.361674) (xy 72.311129 -372.380389) (xy 72.296863 -372.394746) (xy 72.278197 -372.402572)
			(xy 72.26808 -372.403116) (xy 71.5518 -372.403116) (xy 71.541648 -372.402679) (xy 71.522899 -372.394886)
			(xy 71.508576 -372.380494) (xy 71.500873 -372.361708) (xy 71.500492 -372.351554) (xy 71.500492 -372.194074)
			(xy 71.500096 -372.184885) (xy 71.493573 -372.167701) (xy 71.487792 -372.160546) (xy 71.465942 -372.134869)
			(xy 71.427853 -372.079236) (xy 71.396703 -372.019442) (xy 71.372938 -371.956346) (xy 71.356902 -371.890859)
			(xy 71.348825 -371.823922) (xy 71.348824 -371.756499) (xy 71.356898 -371.689562) (xy 71.372932 -371.624074)
			(xy 71.396694 -371.560978) (xy 71.427843 -371.501182) (xy 71.465929 -371.445547) (xy 71.487792 -371.419882)
			(xy 71.493578 -371.412729) (xy 71.500099 -371.395545) (xy 71.500492 -371.386354) (xy 71.500492 -370.893848)
			(xy 71.500061 -370.884663) (xy 71.493562 -370.867478) (xy 71.487792 -370.86032) (xy 71.465917 -370.834664)
			(xy 71.427829 -370.779028) (xy 71.396679 -370.719231) (xy 71.372916 -370.656133) (xy 71.356881 -370.590642)
			(xy 71.348807 -370.523703) (xy 58.103008 -370.523703) (xy 58.103008 -371.310662) (xy 58.102522 -371.337931)
			(xy 58.09476 -371.391915) (xy 58.079395 -371.444245) (xy 58.056738 -371.493855) (xy 58.027252 -371.539736)
			(xy 57.991537 -371.580953) (xy 57.95032 -371.616668) (xy 57.904439 -371.646154) (xy 57.854829 -371.668811)
			(xy 57.802499 -371.684176) (xy 57.748515 -371.691938) (xy 57.693977 -371.691938) (xy 57.639993 -371.684176)
			(xy 57.587663 -371.668811) (xy 57.538053 -371.646154) (xy 57.492172 -371.616668) (xy 57.450955 -371.580953)
			(xy 57.41524 -371.539736) (xy 57.385754 -371.493855) (xy 57.363097 -371.444245) (xy 57.347732 -371.391915)
			(xy 57.33997 -371.337931) (xy 57.339484 -371.310662) (xy 54.729888 -371.310662) (xy 54.729402 -371.337931)
			(xy 54.72164 -371.391915) (xy 54.706275 -371.444245) (xy 54.683618 -371.493855) (xy 54.654132 -371.539736)
			(xy 54.618417 -371.580953) (xy 54.5772 -371.616668) (xy 54.531319 -371.646154) (xy 54.481709 -371.668811)
			(xy 54.429379 -371.684176) (xy 54.375395 -371.691938) (xy 54.320857 -371.691938) (xy 54.266873 -371.684176)
			(xy 54.214543 -371.668811) (xy 54.164933 -371.646154) (xy 54.119052 -371.616668) (xy 54.077835 -371.580953)
			(xy 54.04212 -371.539736) (xy 54.012634 -371.493855) (xy 53.989977 -371.444245) (xy 53.974612 -371.391915)
			(xy 53.96685 -371.337931) (xy 53.966364 -371.310662) (xy 48.196948 -371.310662) (xy 48.223223 -371.361224)
			(xy 48.246896 -371.424224) (xy 48.262871 -371.489602) (xy 48.270918 -371.556421) (xy 48.270921 -371.623722)
			(xy 48.262881 -371.690542) (xy 48.246913 -371.755921) (xy 48.223246 -371.818924) (xy 48.192219 -371.878647)
			(xy 48.154277 -371.934234) (xy 48.132492 -371.959886) (xy 48.126675 -371.967017) (xy 48.120173 -371.984218)
			(xy 48.119792 -371.993414) (xy 48.119792 -372.486682) (xy 48.120213 -372.495868) (xy 48.126719 -372.513052)
			(xy 48.132492 -372.52021) (xy 48.154312 -372.545835) (xy 48.192258 -372.601426) (xy 48.223288 -372.661154)
			(xy 48.246958 -372.724162) (xy 48.262927 -372.789547) (xy 48.270968 -372.856372) (xy 48.270965 -372.923679)
			(xy 48.262918 -372.990504) (xy 48.246942 -373.055887) (xy 48.223267 -373.118893) (xy 48.192232 -373.178618)
			(xy 48.154281 -373.234205) (xy 48.132492 -373.259858) (xy 48.126687 -373.266997) (xy 48.120178 -373.284192)
			(xy 48.119792 -373.293386) (xy 48.119792 -373.451374) (xy 48.119246 -373.461526) (xy 48.111486 -373.480289)
			(xy 48.097136 -373.494655) (xy 48.078382 -373.502435) (xy 48.06823 -373.502936) (xy 47.35195 -373.502936)
			(xy 47.341778 -373.502495) (xy 47.32298 -373.494721) (xy 47.308592 -373.48034) (xy 47.30081 -373.461545)
			(xy 47.300388 -373.451374) (xy 47.300388 -373.293386) (xy 47.299987 -373.284198) (xy 47.293467 -373.267013)
			(xy 47.287688 -373.259858) (xy 47.265932 -373.234179) (xy 47.227979 -373.178598) (xy 47.196942 -373.118878)
			(xy 47.173265 -373.055877) (xy 47.157288 -372.990498) (xy 47.14924 -372.923677) (xy 47.149237 -372.856374)
			(xy 47.157279 -372.789553) (xy 47.17325 -372.724172) (xy 47.196921 -372.661169) (xy 47.227953 -372.601446)
			(xy 47.265901 -372.545861) (xy 47.287688 -372.52021) (xy 47.293504 -372.513078) (xy 47.300007 -372.495878)
			(xy 47.300388 -372.486682) (xy 47.300388 -371.993414) (xy 47.299974 -371.984227) (xy 47.293463 -371.967043)
			(xy 47.287688 -371.959886) (xy 47.265861 -371.934265) (xy 47.227911 -371.878675) (xy 47.196876 -371.818948)
			(xy 47.173204 -371.755939) (xy 47.157232 -371.690553) (xy 47.14919 -371.623726) (xy 46.046568 -371.623726)
			(xy 46.046802 -371.624349) (xy 46.062775 -371.689733) (xy 46.070818 -371.756557) (xy 46.070817 -371.823864)
			(xy 46.062771 -371.890688) (xy 46.046796 -371.956071) (xy 46.023121 -372.019076) (xy 45.992085 -372.0788)
			(xy 45.954133 -372.134386) (xy 45.932344 -372.160038) (xy 45.926542 -372.167179) (xy 45.920032 -372.184373)
			(xy 45.919644 -372.193566) (xy 45.919644 -372.351554) (xy 45.919198 -372.361725) (xy 45.911425 -372.380522)
			(xy 45.897046 -372.394909) (xy 45.878253 -372.402693) (xy 45.868082 -372.403116) (xy 45.151802 -372.403116)
			(xy 45.141625 -372.402733) (xy 45.122821 -372.394941) (xy 45.108435 -372.380542) (xy 45.100658 -372.361732)
			(xy 45.10024 -372.351554) (xy 45.10024 -372.193566) (xy 45.099837 -372.184378) (xy 45.093317 -372.167194)
			(xy 45.08754 -372.160038) (xy 45.065766 -372.134374) (xy 45.027817 -372.07879) (xy 44.996783 -372.019068)
			(xy 44.973109 -371.956065) (xy 44.957135 -371.890684) (xy 44.94909 -371.823862) (xy 44.949089 -371.756559)
			(xy 44.957132 -371.689737) (xy 44.973103 -371.624356) (xy 44.996774 -371.561352) (xy 45.027806 -371.501628)
			(xy 45.065753 -371.446042) (xy 45.08754 -371.42039) (xy 45.093328 -371.413239) (xy 45.099847 -371.396053)
			(xy 45.10024 -371.386862) (xy 45.10024 -370.89334) (xy 45.099801 -370.884156) (xy 45.093306 -370.866972)
			(xy 45.08754 -370.859812) (xy 45.06574 -370.83417) (xy 45.027792 -370.778582) (xy 44.996759 -370.718857)
			(xy 44.973087 -370.655851) (xy 44.957115 -370.590468) (xy 44.949071 -370.523644) (xy 41.671032 -370.523644)
			(xy 41.671032 -370.523703) (xy 41.662957 -370.590641) (xy 41.646921 -370.65613) (xy 41.623156 -370.719227)
			(xy 41.592004 -370.779022) (xy 41.553913 -370.834656) (xy 41.532048 -370.86032) (xy 41.526254 -370.867467)
			(xy 41.519739 -370.884656) (xy 41.519348 -370.893848) (xy 41.519348 -371.386354) (xy 41.519792 -371.395537)
			(xy 41.526284 -371.412721) (xy 41.532048 -371.419882) (xy 41.553928 -371.445535) (xy 41.592019 -371.50117)
			(xy 41.623172 -371.560967) (xy 41.646832 -371.623785) (xy 42.748894 -371.623785) (xy 42.748898 -371.556358)
			(xy 42.756977 -371.489417) (xy 42.773017 -371.423926) (xy 42.796785 -371.360828) (xy 42.827941 -371.30103)
			(xy 42.866034 -371.245395) (xy 42.8879 -371.21973) (xy 42.893709 -371.212593) (xy 42.900216 -371.195396)
			(xy 42.9006 -371.186202) (xy 42.9006 -371.028722) (xy 42.901143 -371.018602) (xy 42.908856 -370.999888)
			(xy 42.923125 -370.985533) (xy 42.941791 -370.977706) (xy 42.951908 -370.97716) (xy 43.668188 -370.97716)
			(xy 43.678336 -370.977631) (xy 43.697081 -370.985415) (xy 43.711403 -370.999796) (xy 43.71911 -371.018572)
			(xy 43.719496 -371.028722) (xy 43.719496 -371.186202) (xy 43.719906 -371.195389) (xy 43.72642 -371.212573)
			(xy 43.732196 -371.21973) (xy 43.754023 -371.245426) (xy 43.792113 -371.301056) (xy 43.823265 -371.360848)
			(xy 43.847032 -371.423941) (xy 43.86307 -371.489426) (xy 43.871149 -371.556361) (xy 43.871153 -371.623782)
			(xy 43.86308 -371.690718) (xy 43.847049 -371.756205) (xy 43.823289 -371.8193) (xy 43.792142 -371.879095)
			(xy 43.754058 -371.934729) (xy 43.732196 -371.960394) (xy 43.726419 -371.967553) (xy 43.719893 -371.984733)
			(xy 43.719496 -371.993922) (xy 43.719496 -372.486174) (xy 43.71992 -372.49536) (xy 43.726424 -372.512544)
			(xy 43.732196 -372.519702) (xy 43.754094 -372.54534) (xy 43.792181 -372.600978) (xy 43.823331 -372.660778)
			(xy 43.847093 -372.723878) (xy 43.863127 -372.789371) (xy 43.8712 -372.856312) (xy 43.871197 -372.923739)
			(xy 43.863117 -372.990679) (xy 43.847078 -373.05617) (xy 43.82331 -373.119269) (xy 43.792155 -373.179066)
			(xy 43.754062 -373.234701) (xy 43.732196 -373.260366) (xy 43.726388 -373.267503) (xy 43.71988 -373.2847)
			(xy 43.719496 -373.293894) (xy 43.719496 -373.451374) (xy 43.718953 -373.461495) (xy 43.711241 -373.480208)
			(xy 43.696972 -373.494564) (xy 43.678306 -373.502391) (xy 43.668188 -373.502936) (xy 42.951908 -373.502936)
			(xy 42.941759 -373.502473) (xy 42.923014 -373.494686) (xy 42.908691 -373.480303) (xy 42.900985 -373.461525)
			(xy 42.9006 -373.451374) (xy 42.9006 -373.293894) (xy 42.900193 -373.284707) (xy 42.893677 -373.267522)
			(xy 42.8879 -373.260366) (xy 42.866069 -373.234673) (xy 42.82798 -373.179043) (xy 42.796828 -373.11925)
			(xy 42.773061 -373.056157) (xy 42.757024 -372.990671) (xy 42.748945 -372.923736) (xy 42.748942 -372.856315)
			(xy 42.757014 -372.789379) (xy 42.773046 -372.723892) (xy 42.796807 -372.660796) (xy 42.827953 -372.601001)
			(xy 42.866038 -372.545367) (xy 42.8879 -372.519702) (xy 42.893678 -372.512544) (xy 42.900204 -372.495363)
			(xy 42.9006 -372.486174) (xy 42.9006 -371.993922) (xy 42.900179 -371.984736) (xy 42.893673 -371.967551)
			(xy 42.8879 -371.960394) (xy 42.865999 -371.93476) (xy 42.827911 -371.879121) (xy 42.796762 -371.81932)
			(xy 42.773 -371.756219) (xy 42.756967 -371.690726) (xy 42.748894 -371.623785) (xy 41.646832 -371.623785)
			(xy 41.646938 -371.624066) (xy 41.662974 -371.689557) (xy 41.67105 -371.756498) (xy 41.671048 -371.823923)
			(xy 41.66297 -371.890864) (xy 41.646932 -371.956354) (xy 41.623164 -372.019452) (xy 41.592008 -372.079248)
			(xy 41.553915 -372.134882) (xy 41.532048 -372.160546) (xy 41.526243 -372.167685) (xy 41.519735 -372.18488)
			(xy 41.519348 -372.194074) (xy 41.519348 -372.351554) (xy 41.518835 -372.361679) (xy 41.51112 -372.380402)
			(xy 41.496842 -372.39476) (xy 41.478162 -372.402579) (xy 41.46804 -372.403116) (xy 40.75176 -372.403116)
			(xy 40.741605 -372.402711) (xy 40.722855 -372.394906) (xy 40.708534 -372.380504) (xy 40.700833 -372.361711)
			(xy 40.700452 -372.351554) (xy 40.700452 -372.194074) (xy 40.700043 -372.184887) (xy 40.693527 -372.167703)
			(xy 40.687752 -372.160546) (xy 40.6659 -372.13487) (xy 40.627807 -372.079238) (xy 40.596653 -372.019444)
			(xy 40.572886 -371.956349) (xy 40.556848 -371.89086) (xy 40.54877 -371.823922) (xy 40.548769 -371.756499)
			(xy 40.556844 -371.68956) (xy 40.57288 -371.624072) (xy 40.596645 -371.560975) (xy 40.627797 -371.50118)
			(xy 40.665887 -371.445546) (xy 40.687752 -371.419882) (xy 40.693545 -371.412735) (xy 40.70006 -371.395546)
			(xy 40.700452 -371.386354) (xy 40.700452 -370.893848) (xy 40.700007 -370.884665) (xy 40.693516 -370.867481)
			(xy 40.687752 -370.86032) (xy 40.665874 -370.834665) (xy 40.627783 -370.779031) (xy 40.59663 -370.719233)
			(xy 40.572864 -370.656135) (xy 40.556828 -370.590644) (xy 40.548752 -370.523704) (xy 37.271241 -370.523704)
			(xy 37.263166 -370.590641) (xy 37.247131 -370.65613) (xy 37.223366 -370.719226) (xy 37.192215 -370.779022)
			(xy 37.154125 -370.834655) (xy 37.13226 -370.86032) (xy 37.126467 -370.867468) (xy 37.119951 -370.884656)
			(xy 37.11956 -370.893848) (xy 37.11956 -371.386354) (xy 37.120001 -371.395538) (xy 37.126494 -371.412722)
			(xy 37.13226 -371.419882) (xy 37.154139 -371.445535) (xy 37.19223 -371.501171) (xy 37.223382 -371.560968)
			(xy 37.247019 -371.623725) (xy 38.349126 -371.623725) (xy 38.349129 -371.556418) (xy 38.357177 -371.489593)
			(xy 38.373153 -371.424209) (xy 38.396828 -371.361203) (xy 38.427864 -371.301478) (xy 38.465815 -371.245891)
			(xy 38.487604 -371.220238) (xy 38.49341 -371.213099) (xy 38.499919 -371.195904) (xy 38.500304 -371.18671)
			(xy 38.500304 -371.028722) (xy 38.50085 -371.01857) (xy 38.508611 -370.999808) (xy 38.522961 -370.985443)
			(xy 38.541714 -370.977661) (xy 38.551866 -370.97716) (xy 39.268146 -370.97716) (xy 39.278309 -370.977596)
			(xy 39.297084 -370.98539) (xy 39.311448 -370.999773) (xy 39.319217 -371.018558) (xy 39.319708 -371.028722)
			(xy 39.319708 -371.18671) (xy 39.320112 -371.195898) (xy 39.32663 -371.213082) (xy 39.332408 -371.220238)
			(xy 39.35416 -371.24592) (xy 39.392113 -371.301501) (xy 39.423151 -371.36122) (xy 39.446829 -371.424221)
			(xy 39.462806 -371.4896) (xy 39.470854 -371.55642) (xy 39.470857 -371.623723) (xy 39.462816 -371.690544)
			(xy 39.446845 -371.755925) (xy 39.423175 -371.818928) (xy 39.392143 -371.87865) (xy 39.354195 -371.934235)
			(xy 39.332408 -371.959886) (xy 39.326593 -371.967018) (xy 39.320089 -371.984219) (xy 39.319708 -371.993414)
			(xy 39.319708 -372.486682) (xy 39.320125 -372.495868) (xy 39.326634 -372.513053) (xy 39.332408 -372.52021)
			(xy 39.354231 -372.545834) (xy 39.392182 -372.601423) (xy 39.423217 -372.66115) (xy 39.44689 -372.724158)
			(xy 39.462862 -372.789545) (xy 39.470904 -372.856371) (xy 39.470901 -372.92368) (xy 39.462853 -372.990506)
			(xy 39.446875 -373.05589) (xy 39.423196 -373.118897) (xy 39.392156 -373.178621) (xy 39.354199 -373.234207)
			(xy 39.332408 -373.259858) (xy 39.326605 -373.266999) (xy 39.320094 -373.284193) (xy 39.319708 -373.293386)
			(xy 39.319708 -373.451374) (xy 39.319147 -373.461525) (xy 39.311389 -373.480284) (xy 39.297045 -373.494649)
			(xy 39.278296 -373.502432) (xy 39.268146 -373.502936) (xy 38.551866 -373.502936) (xy 38.541703 -373.502494)
			(xy 38.522928 -373.494703) (xy 38.508563 -373.480322) (xy 38.500794 -373.461538) (xy 38.500304 -373.451374)
			(xy 38.500304 -373.293386) (xy 38.4999 -373.284198) (xy 38.493382 -373.267014) (xy 38.487604 -373.259858)
			(xy 38.465851 -373.234178) (xy 38.427903 -373.178595) (xy 38.39687 -373.118875) (xy 38.373197 -373.055874)
			(xy 38.357223 -372.990495) (xy 38.349177 -372.923676) (xy 38.349174 -372.856375) (xy 38.357214 -372.789555)
			(xy 38.373182 -372.724175) (xy 38.396849 -372.661172) (xy 38.427877 -372.601449) (xy 38.465819 -372.545863)
			(xy 38.487604 -372.52021) (xy 38.493422 -372.51308) (xy 38.499924 -372.495878) (xy 38.500304 -372.486682)
			(xy 38.500304 -371.993414) (xy 38.499886 -371.984228) (xy 38.493378 -371.967043) (xy 38.487604 -371.959886)
			(xy 38.46578 -371.934264) (xy 38.427835 -371.878672) (xy 38.396805 -371.818944) (xy 38.373136 -371.755936)
			(xy 38.357167 -371.69055) (xy 38.349126 -371.623725) (xy 37.247019 -371.623725) (xy 37.247148 -371.624067)
			(xy 37.263183 -371.689557) (xy 37.271259 -371.756498) (xy 37.271257 -371.823923) (xy 37.263179 -371.890863)
			(xy 37.247141 -371.956354) (xy 37.223374 -372.019451) (xy 37.192219 -372.079248) (xy 37.154126 -372.134881)
			(xy 37.13226 -372.160546) (xy 37.126456 -372.167686) (xy 37.119947 -372.184881) (xy 37.11956 -372.194074)
			(xy 37.11956 -372.351554) (xy 37.119036 -372.361678) (xy 37.111323 -372.380398) (xy 37.097048 -372.394756)
			(xy 37.078373 -372.402576) (xy 37.068252 -372.403116) (xy 36.351972 -372.403116) (xy 36.341818 -372.402702)
			(xy 36.323068 -372.3949) (xy 36.308746 -372.380501) (xy 36.301045 -372.36171) (xy 36.300664 -372.351554)
			(xy 36.300664 -372.194074) (xy 36.300252 -372.184887) (xy 36.293738 -372.167704) (xy 36.287964 -372.160546)
			(xy 36.266115 -372.134869) (xy 36.228028 -372.079235) (xy 36.196879 -372.01944) (xy 36.173116 -371.956345)
			(xy 36.15708 -371.890858) (xy 36.149004 -371.823921) (xy 36.149003 -371.7565) (xy 36.157076 -371.689563)
			(xy 36.173109 -371.624075) (xy 36.19687 -371.560979) (xy 36.228017 -371.501183) (xy 36.266102 -371.445548)
			(xy 36.287964 -371.419882) (xy 36.293759 -371.412736) (xy 36.300273 -371.395546) (xy 36.300664 -371.386354)
			(xy 36.300664 -370.893848) (xy 36.300217 -370.884665) (xy 36.293727 -370.867481) (xy 36.287964 -370.86032)
			(xy 36.26609 -370.834664) (xy 36.228004 -370.779027) (xy 36.196855 -370.719229) (xy 36.173093 -370.656131)
			(xy 36.15706 -370.590642) (xy 36.148986 -370.523703) (xy 32.870915 -370.523703) (xy 32.862879 -370.590465)
			(xy 32.846908 -370.655846) (xy 32.823237 -370.71885) (xy 32.792205 -370.778573) (xy 32.754259 -370.83416)
			(xy 32.732472 -370.859812) (xy 32.726684 -370.866963) (xy 32.720165 -370.884149) (xy 32.719772 -370.89334)
			(xy 32.719772 -371.386862) (xy 32.720207 -371.396046) (xy 32.726704 -371.413231) (xy 32.732472 -371.42039)
			(xy 32.754273 -371.446031) (xy 32.792221 -371.501619) (xy 32.823253 -371.561344) (xy 32.846713 -371.623785)
			(xy 33.948806 -371.623785) (xy 33.94881 -371.556358) (xy 33.95689 -371.489417) (xy 33.97293 -371.423925)
			(xy 33.996699 -371.360827) (xy 34.027855 -371.30103) (xy 34.065949 -371.245395) (xy 34.087816 -371.21973)
			(xy 34.093627 -371.212595) (xy 34.100132 -371.195397) (xy 34.100516 -371.186202) (xy 34.100516 -371.028722)
			(xy 34.101044 -371.0186) (xy 34.10876 -370.999883) (xy 34.123033 -370.985527) (xy 34.141705 -370.977703)
			(xy 34.151824 -370.97716) (xy 34.868104 -370.97716) (xy 34.878253 -370.977618) (xy 34.896998 -370.985407)
			(xy 34.91132 -370.999792) (xy 34.919027 -371.018571) (xy 34.919412 -371.028722) (xy 34.919412 -371.186202)
			(xy 34.919819 -371.19539) (xy 34.926334 -371.212574) (xy 34.932112 -371.21973) (xy 34.953938 -371.245426)
			(xy 34.992027 -371.301057) (xy 35.023179 -371.360849) (xy 35.046945 -371.423941) (xy 35.062982 -371.489427)
			(xy 35.071061 -371.556361) (xy 35.071065 -371.623782) (xy 35.062993 -371.690717) (xy 35.046962 -371.756204)
			(xy 35.023202 -371.819299) (xy 34.992057 -371.879094) (xy 34.953973 -371.934729) (xy 34.932112 -371.960394)
			(xy 34.926337 -371.967555) (xy 34.919809 -371.984733) (xy 34.919412 -371.993922) (xy 34.919412 -372.486174)
			(xy 34.919832 -372.49536) (xy 34.926338 -372.512545) (xy 34.932112 -372.519702) (xy 34.954009 -372.54534)
			(xy 34.992096 -372.600979) (xy 35.023244 -372.660779) (xy 35.047006 -372.723879) (xy 35.063039 -372.789371)
			(xy 35.071112 -372.856312) (xy 35.071109 -372.923739) (xy 35.06303 -372.990679) (xy 35.046991 -373.05617)
			(xy 35.023224 -373.119268) (xy 34.99207 -373.179065) (xy 34.953978 -373.234701) (xy 34.932112 -373.260366)
			(xy 34.926306 -373.267505) (xy 34.919797 -373.2847) (xy 34.919412 -373.293894) (xy 34.919412 -373.451374)
			(xy 34.918854 -373.461493) (xy 34.911144 -373.480203) (xy 34.89688 -373.494559) (xy 34.878219 -373.502388)
			(xy 34.868104 -373.502936) (xy 34.151824 -373.502936) (xy 34.141676 -373.50246) (xy 34.122931 -373.494679)
			(xy 34.108608 -373.480299) (xy 34.100901 -373.461524) (xy 34.100516 -373.451374) (xy 34.100516 -373.293894)
			(xy 34.100105 -373.284707) (xy 34.093592 -373.267523) (xy 34.087816 -373.260366) (xy 34.065985 -373.234673)
			(xy 34.027894 -373.179043) (xy 33.996741 -373.119251) (xy 33.972974 -373.056158) (xy 33.956936 -372.990672)
			(xy 33.948857 -372.923736) (xy 33.948854 -372.856315) (xy 33.956927 -372.789379) (xy 33.972959 -372.723891)
			(xy 33.99672 -372.660796) (xy 34.027868 -372.601001) (xy 34.065953 -372.545367) (xy 34.087816 -372.519702)
			(xy 34.093596 -372.512545) (xy 34.10012 -372.495364) (xy 34.100516 -372.486174) (xy 34.100516 -371.993922)
			(xy 34.100092 -371.984736) (xy 34.093587 -371.967552) (xy 34.087816 -371.960394) (xy 34.065914 -371.93476)
			(xy 34.027826 -371.879121) (xy 33.996676 -371.819321) (xy 33.972913 -371.75622) (xy 33.956879 -371.690727)
			(xy 33.948806 -371.623785) (xy 32.846713 -371.623785) (xy 32.846925 -371.62435) (xy 32.862896 -371.689734)
			(xy 32.870939 -371.756558) (xy 32.870938 -371.823864) (xy 32.862892 -371.890687) (xy 32.846918 -371.95607)
			(xy 32.823244 -372.019075) (xy 32.79221 -372.078799) (xy 32.75426 -372.134386) (xy 32.732472 -372.160038)
			(xy 32.726673 -372.167181) (xy 32.72016 -372.184373) (xy 32.719772 -372.193566) (xy 32.719772 -372.351554)
			(xy 32.719299 -372.361721) (xy 32.711531 -372.380513) (xy 32.69716 -372.394899) (xy 32.678377 -372.402688)
			(xy 32.66821 -372.403116) (xy 31.95193 -372.403116) (xy 31.941755 -372.40271) (xy 31.922952 -372.394927)
			(xy 31.908564 -372.380535) (xy 31.900787 -372.361729) (xy 31.900368 -372.351554) (xy 31.900368 -372.193566)
			(xy 31.899959 -372.184379) (xy 31.893443 -372.167195) (xy 31.887668 -372.160038) (xy 31.865893 -372.134375)
			(xy 31.827942 -372.078791) (xy 31.796907 -372.019069) (xy 31.773232 -371.956066) (xy 31.757257 -371.890685)
			(xy 31.749211 -371.823863) (xy 31.74921 -371.756558) (xy 31.757253 -371.689736) (xy 31.773226 -371.624354)
			(xy 31.796898 -371.56135) (xy 31.827931 -371.501627) (xy 31.86588 -371.446042) (xy 31.887668 -371.42039)
			(xy 31.89346 -371.413242) (xy 31.899975 -371.396053) (xy 31.900368 -371.386862) (xy 31.900368 -370.89334)
			(xy 31.899923 -370.884157) (xy 31.893432 -370.866973) (xy 31.887668 -370.859812) (xy 31.865868 -370.83417)
			(xy 31.827917 -370.778583) (xy 31.796883 -370.718858) (xy 31.77321 -370.655852) (xy 31.757237 -370.590468)
			(xy 31.749193 -370.523644) (xy 28.471153 -370.523644) (xy 28.471153 -370.523703) (xy 28.463078 -370.59064)
			(xy 28.447043 -370.656129) (xy 28.42328 -370.719226) (xy 28.392129 -370.779021) (xy 28.35404 -370.834655)
			(xy 28.332176 -370.86032) (xy 28.326386 -370.867469) (xy 28.319868 -370.884657) (xy 28.319476 -370.893848)
			(xy 28.319476 -371.386354) (xy 28.319914 -371.395538) (xy 28.326409 -371.412722) (xy 28.332176 -371.419882)
			(xy 28.354055 -371.445535) (xy 28.392144 -371.501171) (xy 28.423296 -371.560969) (xy 28.446931 -371.623725)
			(xy 29.549038 -371.623725) (xy 29.549042 -371.556418) (xy 29.557089 -371.489593) (xy 29.573066 -371.424209)
			(xy 29.596742 -371.361203) (xy 29.627778 -371.301478) (xy 29.665731 -371.24589) (xy 29.68752 -371.220238)
			(xy 29.693328 -371.213101) (xy 29.699835 -371.195904) (xy 29.70022 -371.18671) (xy 29.70022 -371.028722)
			(xy 29.700682 -371.018554) (xy 29.708456 -370.999763) (xy 29.72283 -370.985378) (xy 29.741614 -370.97759)
			(xy 29.751782 -370.97716) (xy 30.468062 -370.97716) (xy 30.478234 -370.977596) (xy 30.497032 -370.985372)
			(xy 30.511419 -370.999755) (xy 30.519201 -371.01855) (xy 30.519624 -371.028722) (xy 30.519624 -371.18671)
			(xy 30.520024 -371.195898) (xy 30.526544 -371.213083) (xy 30.532324 -371.220238) (xy 30.554075 -371.24592)
			(xy 30.592028 -371.301502) (xy 30.623065 -371.361221) (xy 30.646741 -371.424221) (xy 30.662718 -371.4896)
			(xy 30.670766 -371.55642) (xy 30.670769 -371.623723) (xy 30.662728 -371.690543) (xy 30.646758 -371.755924)
			(xy 30.623088 -371.818927) (xy 30.592057 -371.878649) (xy 30.554111 -371.934234) (xy 30.532324 -371.959886)
			(xy 30.526511 -371.96702) (xy 30.520005 -371.984219) (xy 30.519624 -371.993414) (xy 30.519624 -372.486682)
			(xy 30.520037 -372.495869) (xy 30.526548 -372.513054) (xy 30.532324 -372.52021) (xy 30.554146 -372.545834)
			(xy 30.592096 -372.601424) (xy 30.62313 -372.661151) (xy 30.646803 -372.724159) (xy 30.662774 -372.789545)
			(xy 30.670816 -372.856371) (xy 30.670813 -372.92368) (xy 30.662765 -372.990505) (xy 30.646788 -373.05589)
			(xy 30.623109 -373.118896) (xy 30.59207 -373.17862) (xy 30.554115 -373.234206) (xy 30.532324 -373.259858)
			(xy 30.526523 -373.267) (xy 30.52001 -373.284193) (xy 30.519624 -373.293386) (xy 30.519624 -373.451374)
			(xy 30.519214 -373.461549) (xy 30.51143 -373.48035) (xy 30.49704 -373.494737) (xy 30.478237 -373.502516)
			(xy 30.468062 -373.502936) (xy 29.751782 -373.502936) (xy 29.741606 -373.50255) (xy 29.722806 -373.494754)
			(xy 29.708421 -373.480357) (xy 29.700641 -373.46155) (xy 29.70022 -373.451374) (xy 29.70022 -373.293386)
			(xy 29.699812 -373.284199) (xy 29.693297 -373.267015) (xy 29.68752 -373.259858) (xy 29.665767 -373.234178)
			(xy 29.627818 -373.178595) (xy 29.596784 -373.118875) (xy 29.57311 -373.055874) (xy 29.557136 -372.990496)
			(xy 29.549089 -372.923677) (xy 29.549086 -372.856375) (xy 29.557127 -372.789555) (xy 29.573095 -372.724175)
			(xy 29.596763 -372.661172) (xy 29.627792 -372.601449) (xy 29.665735 -372.545863) (xy 29.68752 -372.52021)
			(xy 29.69334 -372.513081) (xy 29.69984 -372.495878) (xy 29.70022 -372.486682) (xy 29.70022 -371.993414)
			(xy 29.699798 -371.984228) (xy 29.693292 -371.967044) (xy 29.68752 -371.959886) (xy 29.665695 -371.934264)
			(xy 29.627749 -371.878673) (xy 29.596718 -371.818945) (xy 29.573049 -371.755937) (xy 29.557079 -371.690551)
			(xy 29.549038 -371.623725) (xy 28.446931 -371.623725) (xy 28.44706 -371.624067) (xy 28.463096 -371.689558)
			(xy 28.471171 -371.756498) (xy 28.471169 -371.823923) (xy 28.463092 -371.890863) (xy 28.447054 -371.956353)
			(xy 28.423287 -372.01945) (xy 28.392134 -372.079247) (xy 28.354042 -372.134881) (xy 28.332176 -372.160546)
			(xy 28.326375 -372.167688) (xy 28.319864 -372.184881) (xy 28.319476 -372.194074) (xy 28.319476 -372.351554)
			(xy 28.318936 -372.361676) (xy 28.311226 -372.380393) (xy 28.296956 -372.39475) (xy 28.278287 -372.402574)
			(xy 28.268168 -372.403116) (xy 27.551888 -372.403116) (xy 27.541781 -372.402625) (xy 27.523105 -372.394886)
			(xy 27.508811 -372.380591) (xy 27.501074 -372.361916) (xy 27.50058 -372.351808) (xy 27.50058 -372.194074)
			(xy 27.500187 -372.184885) (xy 27.493662 -372.167701) (xy 27.48788 -372.160546) (xy 27.46603 -372.134869)
			(xy 27.427943 -372.079236) (xy 27.396792 -372.019441) (xy 27.373028 -371.956346) (xy 27.356993 -371.890858)
			(xy 27.348916 -371.823922) (xy 27.348915 -371.756499) (xy 27.356989 -371.689562) (xy 27.373022 -371.624074)
			(xy 27.396784 -371.560978) (xy 27.427932 -371.501182) (xy 27.466018 -371.445548) (xy 27.48788 -371.419882)
			(xy 27.493664 -371.412728) (xy 27.500187 -371.395544) (xy 27.50058 -371.386354) (xy 27.50058 -370.893848)
			(xy 27.500151 -370.884663) (xy 27.493651 -370.867478) (xy 27.48788 -370.86032) (xy 27.466005 -370.834664)
			(xy 27.427918 -370.779028) (xy 27.396769 -370.71923) (xy 27.373006 -370.656132) (xy 27.356972 -370.590642)
			(xy 27.348898 -370.523703) (xy 0.508 -370.523703) (xy 0.508 -372.100847) (xy 8.642336 -372.100847)
			(xy 8.642336 -372.040913) (xy 8.650159 -371.981491) (xy 8.665671 -371.923598) (xy 8.688607 -371.868226)
			(xy 8.718575 -371.81632) (xy 8.755061 -371.768771) (xy 8.797441 -371.726391) (xy 8.84499 -371.689905)
			(xy 8.896896 -371.659937) (xy 8.952268 -371.637001) (xy 9.010161 -371.621489) (xy 9.069583 -371.613666)
			(xy 9.09955 -371.613176) (xy 9.96315 -371.613176) (xy 9.993118 -371.613658) (xy 10.052541 -371.621481)
			(xy 10.110435 -371.636994) (xy 10.165808 -371.65993) (xy 10.217714 -371.689898) (xy 10.265264 -371.726385)
			(xy 10.307645 -371.768766) (xy 10.344132 -371.816316) (xy 10.3741 -371.868222) (xy 10.397036 -371.923595)
			(xy 10.412549 -371.981489) (xy 10.420372 -372.040912) (xy 10.420372 -372.100848) (xy 10.412549 -372.160271)
			(xy 10.397036 -372.218165) (xy 10.3741 -372.273538) (xy 10.344132 -372.325444) (xy 10.307645 -372.372994)
			(xy 10.265264 -372.415375) (xy 10.217714 -372.451862) (xy 10.165808 -372.48183) (xy 10.110435 -372.504766)
			(xy 10.052541 -372.520279) (xy 9.993118 -372.528102) (xy 9.96315 -372.528592) (xy 9.09955 -372.528592)
			(xy 9.069583 -372.528094) (xy 9.010161 -372.520271) (xy 8.952268 -372.504759) (xy 8.896896 -372.481823)
			(xy 8.84499 -372.451855) (xy 8.797441 -372.415369) (xy 8.755061 -372.372989) (xy 8.718575 -372.32544)
			(xy 8.688607 -372.273534) (xy 8.665671 -372.218162) (xy 8.650159 -372.160269) (xy 8.642336 -372.100847)
			(xy 0.508 -372.100847) (xy 0.508 -374.423871) (xy 27.348897 -374.423871) (xy 27.348897 -374.356446)
			(xy 27.356974 -374.289508) (xy 27.37301 -374.224019) (xy 27.396774 -374.160922) (xy 27.427926 -374.101125)
			(xy 27.466016 -374.045491) (xy 27.48788 -374.019826) (xy 27.493688 -374.012689) (xy 27.500197 -373.995492)
			(xy 27.50058 -373.986298) (xy 27.50058 -373.828818) (xy 27.501042 -373.818688) (xy 27.508772 -373.799959)
			(xy 27.523066 -373.785601) (xy 27.54176 -373.777788) (xy 27.551888 -373.777256) (xy 28.268168 -373.777256)
			(xy 28.278269 -373.77781) (xy 28.296938 -373.785529) (xy 28.311233 -373.799804) (xy 28.318977 -373.818463)
			(xy 28.319476 -373.828564) (xy 28.319476 -373.986298) (xy 28.319892 -373.995484) (xy 28.326402 -374.012669)
			(xy 28.332176 -374.019826) (xy 28.354038 -374.045493) (xy 28.392127 -374.101127) (xy 28.423278 -374.160923)
			(xy 28.447043 -374.22402) (xy 28.463078 -374.289509) (xy 28.471154 -374.356447) (xy 28.471155 -374.423823)
			(xy 31.749171 -374.423823) (xy 31.749175 -374.356514) (xy 31.757224 -374.289688) (xy 31.773202 -374.224303)
			(xy 31.796881 -374.161297) (xy 31.827921 -374.101572) (xy 31.865877 -374.045986) (xy 31.887668 -374.020334)
			(xy 31.893483 -374.013202) (xy 31.899985 -373.996001) (xy 31.900368 -373.986806) (xy 31.900368 -373.828818)
			(xy 31.900779 -373.818644) (xy 31.908564 -373.799844) (xy 31.922954 -373.785457) (xy 31.941756 -373.777677)
			(xy 31.95193 -373.777256) (xy 32.66821 -373.777256) (xy 32.678384 -373.777656) (xy 32.697183 -373.785448)
			(xy 32.711568 -373.799841) (xy 32.719349 -373.818643) (xy 32.719772 -373.828818) (xy 32.719772 -373.986806)
			(xy 32.720185 -373.995993) (xy 32.726697 -374.013177) (xy 32.732472 -374.020334) (xy 32.754218 -374.04602)
			(xy 32.792167 -374.101602) (xy 32.823202 -374.161321) (xy 32.846876 -374.224321) (xy 32.862852 -374.289699)
			(xy 32.870899 -374.356518) (xy 32.870903 -374.423819) (xy 32.870895 -374.423882) (xy 36.148964 -374.423882)
			(xy 36.148968 -374.356455) (xy 36.157048 -374.289515) (xy 36.173087 -374.224024) (xy 36.196854 -374.160925)
			(xy 36.228007 -374.101128) (xy 36.266099 -374.045492) (xy 36.287964 -374.019826) (xy 36.293782 -374.012697)
			(xy 36.300282 -373.995494) (xy 36.300664 -373.986298) (xy 36.300664 -373.828818) (xy 36.301142 -373.818689)
			(xy 36.308868 -373.799964) (xy 36.323158 -373.785606) (xy 36.341846 -373.777791) (xy 36.351972 -373.777256)
			(xy 37.068252 -373.777256) (xy 37.078398 -373.77776) (xy 37.09714 -373.785532) (xy 37.111464 -373.799903)
			(xy 37.119173 -373.818671) (xy 37.11956 -373.828818) (xy 37.11956 -373.986298) (xy 37.11998 -373.995484)
			(xy 37.126488 -374.012668) (xy 37.13226 -374.019826) (xy 37.154084 -374.045525) (xy 37.192177 -374.101153)
			(xy 37.223331 -374.160945) (xy 37.2471 -374.224037) (xy 37.263139 -374.289523) (xy 37.271219 -374.356458)
			(xy 37.271223 -374.423879) (xy 37.271223 -374.423882) (xy 40.548731 -374.423882) (xy 40.548735 -374.356454)
			(xy 40.556815 -374.289512) (xy 40.572857 -374.22402) (xy 40.596628 -374.160921) (xy 40.627787 -374.101124)
			(xy 40.665884 -374.04549) (xy 40.687752 -374.019826) (xy 40.693569 -374.012695) (xy 40.70007 -373.995494)
			(xy 40.700452 -373.986298) (xy 40.700452 -373.828818) (xy 40.700942 -373.818691) (xy 40.708666 -373.799968)
			(xy 40.722951 -373.785611) (xy 40.741636 -373.777793) (xy 40.75176 -373.777256) (xy 41.46804 -373.777256)
			(xy 41.478191 -373.777688) (xy 41.496936 -373.785489) (xy 41.511256 -373.799881) (xy 41.518963 -373.818665)
			(xy 41.519348 -373.828818) (xy 41.519348 -373.986298) (xy 41.519771 -373.995484) (xy 41.526277 -374.012667)
			(xy 41.532048 -374.019826) (xy 41.553873 -374.045524) (xy 41.591966 -374.101153) (xy 41.623121 -374.160944)
			(xy 41.64689 -374.224037) (xy 41.66293 -374.289522) (xy 41.67101 -374.356458) (xy 41.671014 -374.423823)
			(xy 44.94905 -374.423823) (xy 44.949054 -374.356514) (xy 44.957102 -374.289689) (xy 44.97308 -374.224304)
			(xy 44.996757 -374.161298) (xy 45.027796 -374.101573) (xy 45.06575 -374.045986) (xy 45.08754 -374.020334)
			(xy 45.093352 -374.0132) (xy 45.099857 -373.996001) (xy 45.10024 -373.986806) (xy 45.10024 -373.828818)
			(xy 45.100678 -373.818647) (xy 45.108458 -373.799853) (xy 45.122839 -373.785467) (xy 45.141631 -373.777682)
			(xy 45.151802 -373.777256) (xy 45.868082 -373.777256) (xy 45.878255 -373.777679) (xy 45.897053 -373.785461)
			(xy 45.911439 -373.799847) (xy 45.919221 -373.818645) (xy 45.919644 -373.828818) (xy 45.919644 -373.986806)
			(xy 45.920064 -373.995992) (xy 45.926572 -374.013176) (xy 45.932344 -374.020334) (xy 45.954091 -374.04602)
			(xy 45.992042 -374.101601) (xy 46.023078 -374.16132) (xy 46.046754 -374.22432) (xy 46.06273 -374.289698)
			(xy 46.070778 -374.356517) (xy 46.070782 -374.423819) (xy 46.070774 -374.423882) (xy 71.348786 -374.423882)
			(xy 71.348789 -374.356455) (xy 71.356869 -374.289514) (xy 71.372909 -374.224023) (xy 71.396677 -374.160924)
			(xy 71.427833 -374.101127) (xy 71.465926 -374.045491) (xy 71.487792 -374.019826) (xy 71.493602 -374.01269)
			(xy 71.500109 -373.995492) (xy 71.500492 -373.986298) (xy 71.500492 -373.828818) (xy 71.50104 -373.818698)
			(xy 71.508753 -373.799987) (xy 71.52302 -373.785631) (xy 71.541684 -373.777803) (xy 71.5518 -373.777256)
			(xy 72.26808 -373.777256) (xy 72.278227 -373.777737) (xy 72.296971 -373.785518) (xy 72.311293 -373.799896)
			(xy 72.319002 -373.818669) (xy 72.319388 -373.828818) (xy 72.319388 -373.986298) (xy 72.319802 -373.995485)
			(xy 72.326313 -374.012669) (xy 72.332088 -374.019826) (xy 72.353911 -374.045525) (xy 72.392002 -374.101154)
			(xy 72.423155 -374.160946) (xy 72.446922 -374.224038) (xy 72.462961 -374.289523) (xy 72.47104 -374.356458)
			(xy 72.471044 -374.423823) (xy 75.749081 -374.423823) (xy 75.749084 -374.356514) (xy 75.757133 -374.289688)
			(xy 75.773112 -374.224303) (xy 75.796791 -374.161296) (xy 75.827832 -374.101572) (xy 75.865788 -374.045985)
			(xy 75.88758 -374.020334) (xy 75.893385 -374.013194) (xy 75.899895 -373.996) (xy 75.90028 -373.986806)
			(xy 75.90028 -373.828818) (xy 75.900679 -373.818642) (xy 75.908466 -373.79984) (xy 75.92286 -373.785453)
			(xy 75.941666 -373.777675) (xy 75.951842 -373.777256) (xy 76.668122 -373.777256) (xy 76.678283 -373.777716)
			(xy 76.697057 -373.785501) (xy 76.711422 -373.799877) (xy 76.719192 -373.818656) (xy 76.719684 -373.828818)
			(xy 76.719684 -373.986806) (xy 76.720095 -373.995993) (xy 76.726608 -374.013177) (xy 76.732384 -374.020334)
			(xy 76.754129 -374.046021) (xy 76.792078 -374.101603) (xy 76.823112 -374.161322) (xy 76.846786 -374.224322)
			(xy 76.862761 -374.289699) (xy 76.870808 -374.356518) (xy 76.870812 -374.423819) (xy 76.870804 -374.423882)
			(xy 80.148873 -374.423882) (xy 80.148877 -374.356455) (xy 80.156957 -374.289515) (xy 80.172996 -374.224023)
			(xy 80.196764 -374.160925) (xy 80.227918 -374.101127) (xy 80.26601 -374.045492) (xy 80.287876 -374.019826)
			(xy 80.293684 -374.012689) (xy 80.300193 -373.995492) (xy 80.300576 -373.986298) (xy 80.300576 -373.828818)
			(xy 80.301042 -373.818688) (xy 80.308771 -373.79996) (xy 80.323064 -373.785602) (xy 80.341756 -373.777789)
			(xy 80.351884 -373.777256) (xy 81.068164 -373.777256) (xy 81.078265 -373.777814) (xy 81.096934 -373.785531)
			(xy 81.111228 -373.799806) (xy 81.118972 -373.818464) (xy 81.119472 -373.828564) (xy 81.119472 -373.986298)
			(xy 81.119889 -373.995484) (xy 81.126399 -374.012668) (xy 81.132172 -374.019826) (xy 81.153996 -374.045525)
			(xy 81.192087 -374.101154) (xy 81.223242 -374.160945) (xy 81.247009 -374.224038) (xy 81.263049 -374.289523)
			(xy 81.271128 -374.356458) (xy 81.271132 -374.423879) (xy 81.271132 -374.423882) (xy 84.548664 -374.423882)
			(xy 84.548668 -374.356455) (xy 84.556748 -374.289515) (xy 84.572787 -374.224024) (xy 84.596554 -374.160925)
			(xy 84.627707 -374.101128) (xy 84.665799 -374.045492) (xy 84.687664 -374.019826) (xy 84.693482 -374.012697)
			(xy 84.699982 -373.995494) (xy 84.700364 -373.986298) (xy 84.700364 -373.828818) (xy 84.700842 -373.818689)
			(xy 84.708568 -373.799964) (xy 84.722858 -373.785606) (xy 84.741546 -373.777791) (xy 84.751672 -373.777256)
			(xy 85.467952 -373.777256) (xy 85.478066 -373.777754) (xy 85.49676 -373.785478) (xy 85.511074 -373.799769)
			(xy 85.518829 -373.818451) (xy 85.51926 -373.828564) (xy 85.51926 -373.986298) (xy 85.51968 -373.995484)
			(xy 85.526188 -374.012668) (xy 85.53196 -374.019826) (xy 85.553784 -374.045525) (xy 85.591877 -374.101153)
			(xy 85.623031 -374.160945) (xy 85.6468 -374.224037) (xy 85.662839 -374.289523) (xy 85.670919 -374.356458)
			(xy 85.670923 -374.423822) (xy 115.349223 -374.423822) (xy 115.349227 -374.356515) (xy 115.357275 -374.28969)
			(xy 115.373251 -374.224306) (xy 115.396927 -374.1613) (xy 115.427963 -374.101574) (xy 115.465915 -374.045987)
			(xy 115.487704 -374.020334) (xy 115.493512 -374.013197) (xy 115.50002 -373.996) (xy 115.500404 -373.986806)
			(xy 115.500404 -373.828818) (xy 115.500947 -373.818666) (xy 115.508709 -373.799903) (xy 115.52306 -373.785539)
			(xy 115.541814 -373.777757) (xy 115.551966 -373.777256) (xy 116.268246 -373.777256) (xy 116.278409 -373.777696)
			(xy 116.297183 -373.785489) (xy 116.311547 -373.799871) (xy 116.319316 -373.818654) (xy 116.319808 -373.828818)
			(xy 116.319808 -373.986806) (xy 116.320214 -373.995994) (xy 116.32673 -374.013178) (xy 116.332508 -374.020334)
			(xy 116.354256 -374.046019) (xy 116.39221 -374.1016) (xy 116.423248 -374.161318) (xy 116.446925 -374.224319)
			(xy 116.462903 -374.289697) (xy 116.470951 -374.356517) (xy 116.470955 -374.42382) (xy 116.470948 -374.423882)
			(xy 119.748992 -374.423882) (xy 119.748995 -374.356455) (xy 119.757075 -374.289514) (xy 119.773115 -374.224022)
			(xy 119.796884 -374.160924) (xy 119.82804 -374.101126) (xy 119.866134 -374.045491) (xy 119.888 -374.019826)
			(xy 119.89381 -374.012691) (xy 119.900317 -373.995493) (xy 119.9007 -373.986298) (xy 119.9007 -373.828818)
			(xy 119.90124 -373.818697) (xy 119.908955 -373.799984) (xy 119.923224 -373.785629) (xy 119.94189 -373.777802)
			(xy 119.952008 -373.777256) (xy 120.668288 -373.777256) (xy 120.678436 -373.777731) (xy 120.69718 -373.785514)
			(xy 120.711502 -373.799894) (xy 120.71921 -373.818669) (xy 120.719596 -373.828818) (xy 120.719596 -373.986298)
			(xy 120.720008 -373.995485) (xy 120.726521 -374.012669) (xy 120.732296 -374.019826) (xy 120.754119 -374.045525)
			(xy 120.792209 -374.101155) (xy 120.823362 -374.160946) (xy 120.847129 -374.224039) (xy 120.863167 -374.289524)
			(xy 120.871246 -374.356458) (xy 120.87125 -374.423823) (xy 124.149287 -374.423823) (xy 124.149291 -374.356514)
			(xy 124.15734 -374.289688) (xy 124.173319 -374.224302) (xy 124.196998 -374.161296) (xy 124.228039 -374.101572)
			(xy 124.265996 -374.045986) (xy 124.287788 -374.020334) (xy 124.293594 -374.013195) (xy 124.300103 -373.996)
			(xy 124.300488 -373.986806) (xy 124.300488 -373.828818) (xy 124.30088 -373.818641) (xy 124.308668 -373.799837)
			(xy 124.323064 -373.78545) (xy 124.341873 -373.777673) (xy 124.35205 -373.777256) (xy 125.06833 -373.777256)
			(xy 125.078492 -373.777709) (xy 125.097265 -373.785497) (xy 125.11163 -373.799875) (xy 125.1194 -373.818656)
			(xy 125.119892 -373.828818) (xy 125.119892 -373.986806) (xy 125.120301 -373.995993) (xy 125.126816 -374.013177)
			(xy 125.132592 -374.020334) (xy 125.154338 -374.04602) (xy 125.192286 -374.101603) (xy 125.223319 -374.161322)
			(xy 125.246993 -374.224322) (xy 125.262968 -374.2897) (xy 125.271015 -374.356518) (xy 125.271019 -374.423819)
			(xy 125.271019 -374.423823) (xy 128.549078 -374.423823) (xy 128.549081 -374.356514) (xy 128.55713 -374.289688)
			(xy 128.573109 -374.224303) (xy 128.596788 -374.161296) (xy 128.627828 -374.101572) (xy 128.665784 -374.045985)
			(xy 128.687576 -374.020334) (xy 128.69338 -374.013194) (xy 128.699891 -373.996) (xy 128.700276 -373.986806)
			(xy 128.700276 -373.828818) (xy 128.700679 -373.818643) (xy 128.708465 -373.799841) (xy 128.722858 -373.785454)
			(xy 128.741663 -373.777675) (xy 128.751838 -373.777256) (xy 129.468118 -373.777256) (xy 129.478279 -373.777719)
			(xy 129.497052 -373.785503) (xy 129.511418 -373.799878) (xy 129.519188 -373.818656) (xy 129.51968 -373.828818)
			(xy 129.51968 -373.986806) (xy 129.520092 -373.995993) (xy 129.526605 -374.013177) (xy 129.53238 -374.020334)
			(xy 129.554126 -374.046021) (xy 129.592074 -374.101603) (xy 129.623108 -374.161322) (xy 129.646783 -374.224321)
			(xy 129.662758 -374.289699) (xy 129.670805 -374.356518) (xy 129.670809 -374.423819) (xy 129.670809 -374.423822)
			(xy 159.349132 -374.423822) (xy 159.349136 -374.356514) (xy 159.357184 -374.289689) (xy 159.373161 -374.224305)
			(xy 159.396837 -374.161299) (xy 159.427874 -374.101574) (xy 159.465826 -374.045986) (xy 159.487616 -374.020334)
			(xy 159.493425 -374.013198) (xy 159.499932 -373.996) (xy 159.500316 -373.986806) (xy 159.500316 -373.828818)
			(xy 159.500847 -373.818664) (xy 159.508612 -373.799899) (xy 159.522966 -373.785534) (xy 159.541724 -373.777755)
			(xy 159.551878 -373.777256) (xy 160.268158 -373.777256) (xy 160.278329 -373.777699) (xy 160.297126 -373.785473)
			(xy 160.311513 -373.799854) (xy 160.319297 -373.818647) (xy 160.31972 -373.828818) (xy 160.31972 -373.986806)
			(xy 160.320123 -373.995994) (xy 160.326641 -374.013179) (xy 160.33242 -374.020334) (xy 160.354168 -374.04602)
			(xy 160.39212 -374.1016) (xy 160.423158 -374.161319) (xy 160.446835 -374.224319) (xy 160.462812 -374.289698)
			(xy 160.47086 -374.356517) (xy 160.470864 -374.42382) (xy 160.470857 -374.423882) (xy 163.748901 -374.423882)
			(xy 163.748904 -374.356455) (xy 163.756985 -374.289514) (xy 163.773025 -374.224022) (xy 163.796794 -374.160923)
			(xy 163.827951 -374.101126) (xy 163.866045 -374.045491) (xy 163.887912 -374.019826) (xy 163.893724 -374.012692)
			(xy 163.900229 -373.995493) (xy 163.900612 -373.986298) (xy 163.900612 -373.828818) (xy 163.90114 -373.818696)
			(xy 163.908857 -373.79998) (xy 163.92313 -373.785624) (xy 163.941801 -373.7778) (xy 163.95192 -373.777256)
			(xy 164.6682 -373.777256) (xy 164.678349 -373.777721) (xy 164.697092 -373.785508) (xy 164.711414 -373.799891)
			(xy 164.719122 -373.818668) (xy 164.719508 -373.828818) (xy 164.719508 -373.986298) (xy 164.719917 -373.995485)
			(xy 164.726431 -374.01267) (xy 164.732208 -374.019826) (xy 164.75403 -374.045525) (xy 164.79212 -374.101155)
			(xy 164.823272 -374.160947) (xy 164.847038 -374.224039) (xy 164.863076 -374.289524) (xy 164.871155 -374.356458)
			(xy 164.871159 -374.423822) (xy 168.14922 -374.423822) (xy 168.149224 -374.356515) (xy 168.157272 -374.28969)
			(xy 168.173248 -374.224306) (xy 168.196924 -374.1613) (xy 168.22796 -374.101575) (xy 168.265911 -374.045987)
			(xy 168.2877 -374.020334) (xy 168.293507 -374.013196) (xy 168.300015 -373.996) (xy 168.3004 -373.986806)
			(xy 168.3004 -373.828818) (xy 168.300947 -373.818666) (xy 168.308709 -373.799905) (xy 168.323058 -373.78554)
			(xy 168.341811 -373.777758) (xy 168.351962 -373.777256) (xy 169.068242 -373.777256) (xy 169.078405 -373.777699)
			(xy 169.097178 -373.785491) (xy 169.111543 -373.799872) (xy 169.119312 -373.818655) (xy 169.119804 -373.828818)
			(xy 169.119804 -373.986806) (xy 169.120211 -373.995994) (xy 169.126727 -374.013178) (xy 169.132504 -374.020334)
			(xy 169.154249 -374.046021) (xy 169.192196 -374.101603) (xy 169.223229 -374.161322) (xy 169.246902 -374.224322)
			(xy 169.262877 -374.2897) (xy 169.270924 -374.356518) (xy 169.270928 -374.423819) (xy 169.270928 -374.423823)
			(xy 172.548987 -374.423823) (xy 172.548991 -374.356514) (xy 172.55704 -374.289688) (xy 172.573019 -374.224302)
			(xy 172.596698 -374.161296) (xy 172.627739 -374.101572) (xy 172.665696 -374.045986) (xy 172.687488 -374.020334)
			(xy 172.693294 -374.013195) (xy 172.699803 -373.996) (xy 172.700188 -373.986806) (xy 172.700188 -373.828818)
			(xy 172.70058 -373.818641) (xy 172.708368 -373.799837) (xy 172.722764 -373.78545) (xy 172.741573 -373.777673)
			(xy 172.75175 -373.777256) (xy 173.46803 -373.777256) (xy 173.478192 -373.777709) (xy 173.496965 -373.785497)
			(xy 173.51133 -373.799875) (xy 173.5191 -373.818656) (xy 173.519592 -373.828818) (xy 173.519592 -373.986806)
			(xy 173.520001 -373.995993) (xy 173.526516 -374.013177) (xy 173.532292 -374.020334) (xy 173.554038 -374.04602)
			(xy 173.591986 -374.101603) (xy 173.623019 -374.161322) (xy 173.646693 -374.224322) (xy 173.662668 -374.2897)
			(xy 173.670715 -374.356518) (xy 173.670719 -374.423819) (xy 173.662679 -374.490638) (xy 173.646712 -374.556018)
			(xy 173.623045 -374.61902) (xy 173.592018 -374.678743) (xy 173.554076 -374.73433) (xy 173.532292 -374.759982)
			(xy 173.526477 -374.767114) (xy 173.519974 -374.784315) (xy 173.519592 -374.79351) (xy 173.519592 -375.286778)
			(xy 173.520015 -375.295964) (xy 173.52652 -375.313148) (xy 173.532292 -375.320306) (xy 173.554108 -375.345934)
			(xy 173.592054 -375.401525) (xy 173.623084 -375.461252) (xy 173.646754 -375.52426) (xy 173.662724 -375.589644)
			(xy 173.670765 -375.656469) (xy 173.670763 -375.723776) (xy 173.662716 -375.7906) (xy 173.646741 -375.855984)
			(xy 173.623066 -375.918989) (xy 173.592031 -375.978714) (xy 173.554081 -376.034301) (xy 173.532292 -376.059954)
			(xy 173.526489 -376.067095) (xy 173.519978 -376.084289) (xy 173.519592 -376.093482) (xy 173.519592 -376.25147)
			(xy 173.519043 -376.261622) (xy 173.511284 -376.280385) (xy 173.496935 -376.29475) (xy 173.478182 -376.302531)
			(xy 173.46803 -376.303032) (xy 172.75175 -376.303032) (xy 172.741578 -376.302595) (xy 172.722779 -376.29482)
			(xy 172.708391 -376.280438) (xy 172.700609 -376.261642) (xy 172.700188 -376.25147) (xy 172.700188 -376.093482)
			(xy 172.699789 -376.084294) (xy 172.693268 -376.067109) (xy 172.687488 -376.059954) (xy 172.665728 -376.034278)
			(xy 172.627775 -375.978696) (xy 172.596738 -375.918976) (xy 172.573061 -375.855975) (xy 172.557085 -375.790595)
			(xy 172.549038 -375.723774) (xy 172.549035 -375.656471) (xy 172.557077 -375.589649) (xy 172.573048 -375.524268)
			(xy 172.59672 -375.461265) (xy 172.627752 -375.401542) (xy 172.665701 -375.345957) (xy 172.687488 -375.320306)
			(xy 172.693263 -375.313145) (xy 172.699791 -375.295967) (xy 172.700188 -375.286778) (xy 172.700188 -374.79351)
			(xy 172.699776 -374.784323) (xy 172.693264 -374.767138) (xy 172.687488 -374.759982) (xy 172.665658 -374.734364)
			(xy 172.627707 -374.678774) (xy 172.596673 -374.619046) (xy 172.573 -374.556037) (xy 172.557029 -374.49065)
			(xy 172.548987 -374.423823) (xy 169.270928 -374.423823) (xy 169.262888 -374.490638) (xy 169.246921 -374.556017)
			(xy 169.223255 -374.61902) (xy 169.192229 -374.678743) (xy 169.154288 -374.734329) (xy 169.132504 -374.759982)
			(xy 169.126691 -374.767115) (xy 169.120186 -374.784315) (xy 169.119804 -374.79351) (xy 169.119804 -375.286778)
			(xy 169.120224 -375.295964) (xy 169.126731 -375.313149) (xy 169.132504 -375.320306) (xy 169.15432 -375.345935)
			(xy 169.192265 -375.401525) (xy 169.223295 -375.461253) (xy 169.246964 -375.52426) (xy 169.262933 -375.589645)
			(xy 169.270974 -375.656469) (xy 169.270972 -375.723776) (xy 169.262925 -375.7906) (xy 169.24695 -375.855983)
			(xy 169.223276 -375.918989) (xy 169.192242 -375.978713) (xy 169.154292 -376.034301) (xy 169.132504 -376.059954)
			(xy 169.126702 -376.067096) (xy 169.120191 -376.084289) (xy 169.119804 -376.093482) (xy 169.119804 -376.25147)
			(xy 169.119243 -376.261621) (xy 169.111487 -376.280381) (xy 169.097142 -376.294746) (xy 169.078392 -376.302529)
			(xy 169.068242 -376.303032) (xy 168.351962 -376.303032) (xy 168.341798 -376.302597) (xy 168.323022 -376.294804)
			(xy 168.308657 -376.280421) (xy 168.30089 -376.261635) (xy 168.3004 -376.25147) (xy 168.3004 -376.093482)
			(xy 168.299998 -376.084294) (xy 168.293479 -376.06711) (xy 168.2877 -376.059954) (xy 168.265943 -376.034277)
			(xy 168.227996 -375.978693) (xy 168.196963 -375.918973) (xy 168.173291 -375.855972) (xy 168.157317 -375.790593)
			(xy 168.149271 -375.723774) (xy 168.149268 -375.656472) (xy 168.157309 -375.589652) (xy 168.173277 -375.524272)
			(xy 168.196945 -375.461269) (xy 168.227973 -375.401546) (xy 168.265915 -375.345959) (xy 168.2877 -375.320306)
			(xy 168.293477 -375.313147) (xy 168.300003 -375.295967) (xy 168.3004 -375.286778) (xy 168.3004 -374.79351)
			(xy 168.299985 -374.784323) (xy 168.293475 -374.767139) (xy 168.2877 -374.759982) (xy 168.265872 -374.734363)
			(xy 168.227927 -374.678771) (xy 168.196898 -374.619043) (xy 168.173229 -374.556034) (xy 168.15726 -374.490648)
			(xy 168.14922 -374.423822) (xy 164.871159 -374.423822) (xy 164.871159 -374.423879) (xy 164.863088 -374.490814)
			(xy 164.847057 -374.5563) (xy 164.823298 -374.619396) (xy 164.792152 -374.679191) (xy 164.754069 -374.734825)
			(xy 164.732208 -374.76049) (xy 164.726392 -374.767621) (xy 164.719889 -374.784822) (xy 164.719508 -374.794018)
			(xy 164.719508 -375.28627) (xy 164.719931 -375.295456) (xy 164.726435 -375.31264) (xy 164.732208 -375.319798)
			(xy 164.754101 -375.345439) (xy 164.792188 -375.401077) (xy 164.823337 -375.460877) (xy 164.8471 -375.523977)
			(xy 164.863133 -375.589469) (xy 164.871206 -375.65641) (xy 164.871203 -375.723835) (xy 164.863125 -375.790776)
			(xy 164.847086 -375.856266) (xy 164.823319 -375.919364) (xy 164.792165 -375.979161) (xy 164.754073 -376.034797)
			(xy 164.732208 -376.060462) (xy 164.726404 -376.067602) (xy 164.719893 -376.084796) (xy 164.719508 -376.09399)
			(xy 164.719508 -376.25147) (xy 164.71895 -376.261589) (xy 164.711241 -376.2803) (xy 164.696977 -376.294656)
			(xy 164.678316 -376.302485) (xy 164.6682 -376.303032) (xy 163.95192 -376.303032) (xy 163.941771 -376.302563)
			(xy 163.923025 -376.29478) (xy 163.908702 -376.280398) (xy 163.900996 -376.26162) (xy 163.900612 -376.25147)
			(xy 163.900612 -376.09399) (xy 163.900204 -376.084803) (xy 163.893689 -376.067618) (xy 163.887912 -376.060462)
			(xy 163.866077 -376.034773) (xy 163.827987 -375.979142) (xy 163.796834 -375.919349) (xy 163.773068 -375.856255)
			(xy 163.75703 -375.790769) (xy 163.748951 -375.723833) (xy 163.748949 -375.656412) (xy 163.757022 -375.589475)
			(xy 163.773054 -375.523988) (xy 163.796816 -375.460892) (xy 163.827963 -375.401097) (xy 163.866049 -375.345463)
			(xy 163.887912 -375.319798) (xy 163.893693 -375.312642) (xy 163.900217 -375.29546) (xy 163.900612 -375.28627)
			(xy 163.900612 -374.794018) (xy 163.90019 -374.784832) (xy 163.893684 -374.767648) (xy 163.887912 -374.76049)
			(xy 163.866006 -374.734859) (xy 163.827918 -374.67922) (xy 163.796769 -374.619419) (xy 163.773006 -374.556318)
			(xy 163.756973 -374.490824) (xy 163.748901 -374.423882) (xy 160.470857 -374.423882) (xy 160.462823 -374.49064)
			(xy 160.446853 -374.556021) (xy 160.423184 -374.619023) (xy 160.392153 -374.678745) (xy 160.354206 -374.73433)
			(xy 160.33242 -374.759982) (xy 160.326608 -374.767117) (xy 160.320102 -374.784315) (xy 160.31972 -374.79351)
			(xy 160.31972 -375.286778) (xy 160.320136 -375.295965) (xy 160.326645 -375.313149) (xy 160.33242 -375.320306)
			(xy 160.354238 -375.345933) (xy 160.392189 -375.401522) (xy 160.423223 -375.461249) (xy 160.446896 -375.524257)
			(xy 160.462868 -375.589643) (xy 160.470911 -375.656468) (xy 160.470908 -375.723777) (xy 160.46286 -375.790602)
			(xy 160.446883 -375.855986) (xy 160.423205 -375.918992) (xy 160.392166 -375.978716) (xy 160.354211 -376.034302)
			(xy 160.33242 -376.059954) (xy 160.32662 -376.067097) (xy 160.320107 -376.084289) (xy 160.31972 -376.093482)
			(xy 160.31972 -376.25147) (xy 160.31931 -376.261645) (xy 160.311528 -376.280447) (xy 160.297137 -376.294834)
			(xy 160.278333 -376.302613) (xy 160.268158 -376.303032) (xy 159.551878 -376.303032) (xy 159.541701 -376.302653)
			(xy 159.5229 -376.294855) (xy 159.508515 -376.280456) (xy 159.500737 -376.261647) (xy 159.500316 -376.25147)
			(xy 159.500316 -376.093482) (xy 159.499911 -376.084294) (xy 159.493393 -376.06711) (xy 159.487616 -376.059954)
			(xy 159.465858 -376.034277) (xy 159.42791 -375.978694) (xy 159.396877 -375.918973) (xy 159.373203 -375.855972)
			(xy 159.357229 -375.790593) (xy 159.349183 -375.723774) (xy 159.34918 -375.656471) (xy 159.357221 -375.589651)
			(xy 159.37319 -375.524271) (xy 159.396858 -375.461268) (xy 159.427887 -375.401545) (xy 159.465831 -375.345958)
			(xy 159.487616 -375.320306) (xy 159.493394 -375.313148) (xy 159.499919 -375.295967) (xy 159.500316 -375.286778)
			(xy 159.500316 -374.79351) (xy 159.499897 -374.784324) (xy 159.493389 -374.76714) (xy 159.487616 -374.759982)
			(xy 159.465788 -374.734364) (xy 159.427842 -374.678772) (xy 159.396811 -374.619043) (xy 159.373142 -374.556034)
			(xy 159.357173 -374.490648) (xy 159.349132 -374.423822) (xy 129.670809 -374.423822) (xy 129.662769 -374.490638)
			(xy 129.646801 -374.556018) (xy 129.623134 -374.619021) (xy 129.592107 -374.678743) (xy 129.554164 -374.734329)
			(xy 129.53238 -374.759982) (xy 129.526564 -374.767113) (xy 129.520062 -374.784315) (xy 129.51968 -374.79351)
			(xy 129.51968 -375.286778) (xy 129.520105 -375.295963) (xy 129.526609 -375.313148) (xy 129.53238 -375.320306)
			(xy 129.554197 -375.345934) (xy 129.592143 -375.401524) (xy 129.623174 -375.461252) (xy 129.646845 -375.524259)
			(xy 129.662815 -375.589644) (xy 129.670856 -375.656469) (xy 129.670854 -375.723776) (xy 129.662807 -375.7906)
			(xy 129.646831 -375.855984) (xy 129.623156 -375.91899) (xy 129.59212 -375.978714) (xy 129.554169 -376.034302)
			(xy 129.53238 -376.059954) (xy 129.526576 -376.067094) (xy 129.520066 -376.084288) (xy 129.51968 -376.093482)
			(xy 129.51968 -376.25147) (xy 129.519212 -376.261637) (xy 129.51144 -376.280428) (xy 129.497068 -376.294813)
			(xy 129.478285 -376.302602) (xy 129.468118 -376.303032) (xy 128.751838 -376.303032) (xy 128.741665 -376.302604)
			(xy 128.722866 -376.294826) (xy 128.708478 -376.280441) (xy 128.700697 -376.261643) (xy 128.700276 -376.25147)
			(xy 128.700276 -376.093482) (xy 128.69988 -376.084293) (xy 128.693357 -376.067109) (xy 128.687576 -376.059954)
			(xy 128.665817 -376.034278) (xy 128.627865 -375.978696) (xy 128.596828 -375.918976) (xy 128.573152 -375.855974)
			(xy 128.557176 -375.790595) (xy 128.549129 -375.723774) (xy 128.549126 -375.656471) (xy 128.557168 -375.58965)
			(xy 128.573138 -375.524269) (xy 128.59681 -375.461265) (xy 128.627841 -375.401543) (xy 128.665789 -375.345958)
			(xy 128.687576 -375.320306) (xy 128.69335 -375.313144) (xy 128.699879 -375.295967) (xy 128.700276 -375.286778)
			(xy 128.700276 -374.79351) (xy 128.699866 -374.784323) (xy 128.693353 -374.767138) (xy 128.687576 -374.759982)
			(xy 128.665746 -374.734365) (xy 128.627796 -374.678774) (xy 128.596762 -374.619046) (xy 128.57309 -374.556037)
			(xy 128.557119 -374.49065) (xy 128.549078 -374.423823) (xy 125.271019 -374.423823) (xy 125.262979 -374.490638)
			(xy 125.247012 -374.556018) (xy 125.223345 -374.61902) (xy 125.192318 -374.678743) (xy 125.154376 -374.73433)
			(xy 125.132592 -374.759982) (xy 125.126777 -374.767114) (xy 125.120274 -374.784315) (xy 125.119892 -374.79351)
			(xy 125.119892 -375.286778) (xy 125.120315 -375.295964) (xy 125.12682 -375.313148) (xy 125.132592 -375.320306)
			(xy 125.154408 -375.345934) (xy 125.192354 -375.401525) (xy 125.223384 -375.461252) (xy 125.247054 -375.52426)
			(xy 125.263024 -375.589644) (xy 125.271065 -375.656469) (xy 125.271063 -375.723776) (xy 125.263016 -375.7906)
			(xy 125.247041 -375.855984) (xy 125.223366 -375.918989) (xy 125.192331 -375.978714) (xy 125.154381 -376.034301)
			(xy 125.132592 -376.059954) (xy 125.126789 -376.067095) (xy 125.120278 -376.084289) (xy 125.119892 -376.093482)
			(xy 125.119892 -376.25147) (xy 125.119343 -376.261622) (xy 125.111584 -376.280385) (xy 125.097235 -376.29475)
			(xy 125.078482 -376.302531) (xy 125.06833 -376.303032) (xy 124.35205 -376.303032) (xy 124.341878 -376.302595)
			(xy 124.323079 -376.29482) (xy 124.308691 -376.280438) (xy 124.300909 -376.261642) (xy 124.300488 -376.25147)
			(xy 124.300488 -376.093482) (xy 124.300089 -376.084294) (xy 124.293568 -376.067109) (xy 124.287788 -376.059954)
			(xy 124.266028 -376.034278) (xy 124.228075 -375.978696) (xy 124.197038 -375.918976) (xy 124.173361 -375.855975)
			(xy 124.157385 -375.790595) (xy 124.149338 -375.723774) (xy 124.149335 -375.656471) (xy 124.157377 -375.589649)
			(xy 124.173348 -375.524268) (xy 124.19702 -375.461265) (xy 124.228052 -375.401542) (xy 124.266001 -375.345957)
			(xy 124.287788 -375.320306) (xy 124.293563 -375.313145) (xy 124.300091 -375.295967) (xy 124.300488 -375.286778)
			(xy 124.300488 -374.79351) (xy 124.300076 -374.784323) (xy 124.293564 -374.767138) (xy 124.287788 -374.759982)
			(xy 124.265958 -374.734364) (xy 124.228007 -374.678774) (xy 124.196973 -374.619046) (xy 124.1733 -374.556037)
			(xy 124.157329 -374.49065) (xy 124.149287 -374.423823) (xy 120.87125 -374.423823) (xy 120.87125 -374.423879)
			(xy 120.863178 -374.490814) (xy 120.847147 -374.556301) (xy 120.823388 -374.619396) (xy 120.792242 -374.679191)
			(xy 120.754158 -374.734825) (xy 120.732296 -374.76049) (xy 120.726478 -374.76762) (xy 120.719976 -374.784822)
			(xy 120.719596 -374.794018) (xy 120.719596 -375.28627) (xy 120.720022 -375.295456) (xy 120.726525 -375.31264)
			(xy 120.732296 -375.319798) (xy 120.75419 -375.345439) (xy 120.792278 -375.401077) (xy 120.823427 -375.460876)
			(xy 120.84719 -375.523976) (xy 120.863223 -375.589468) (xy 120.871297 -375.656409) (xy 120.871294 -375.723836)
			(xy 120.863215 -375.790776) (xy 120.847177 -375.856267) (xy 120.823409 -375.919365) (xy 120.792254 -375.979162)
			(xy 120.754162 -376.034797) (xy 120.732296 -376.060462) (xy 120.72649 -376.067601) (xy 120.719981 -376.084796)
			(xy 120.719596 -376.09399) (xy 120.719596 -376.25147) (xy 120.71905 -376.26159) (xy 120.711339 -376.280304)
			(xy 120.697071 -376.29466) (xy 120.678405 -376.302487) (xy 120.668288 -376.303032) (xy 119.952008 -376.303032)
			(xy 119.941858 -376.302572) (xy 119.923112 -376.294786) (xy 119.90879 -376.280401) (xy 119.901084 -376.261621)
			(xy 119.9007 -376.25147) (xy 119.9007 -376.09399) (xy 119.900294 -376.084802) (xy 119.893777 -376.067618)
			(xy 119.888 -376.060462) (xy 119.866166 -376.034772) (xy 119.828076 -375.979141) (xy 119.796924 -375.919349)
			(xy 119.773158 -375.856255) (xy 119.75712 -375.790769) (xy 119.749042 -375.723833) (xy 119.749039 -375.656412)
			(xy 119.757112 -375.589476) (xy 119.773145 -375.523988) (xy 119.796905 -375.460893) (xy 119.828053 -375.401097)
			(xy 119.866138 -375.345463) (xy 119.888 -375.319798) (xy 119.89378 -375.312641) (xy 119.900305 -375.29546)
			(xy 119.9007 -375.28627) (xy 119.9007 -374.794018) (xy 119.900281 -374.784832) (xy 119.893773 -374.767647)
			(xy 119.888 -374.76049) (xy 119.866095 -374.734859) (xy 119.828007 -374.679219) (xy 119.796858 -374.619418)
			(xy 119.773097 -374.556317) (xy 119.757064 -374.490824) (xy 119.748992 -374.423882) (xy 116.470948 -374.423882)
			(xy 116.462914 -374.49064) (xy 116.446944 -374.556021) (xy 116.423273 -374.619024) (xy 116.392242 -374.678746)
			(xy 116.354295 -374.734331) (xy 116.332508 -374.759982) (xy 116.326695 -374.767116) (xy 116.32019 -374.784315)
			(xy 116.319808 -374.79351) (xy 116.319808 -375.286778) (xy 116.320227 -375.295964) (xy 116.326734 -375.313149)
			(xy 116.332508 -375.320306) (xy 116.354327 -375.345933) (xy 116.392278 -375.401522) (xy 116.423313 -375.461249)
			(xy 116.446986 -375.524256) (xy 116.462959 -375.589642) (xy 116.471001 -375.656468) (xy 116.470999 -375.723777)
			(xy 116.462951 -375.790602) (xy 116.446973 -375.855987) (xy 116.423295 -375.918993) (xy 116.392255 -375.978717)
			(xy 116.354299 -376.034303) (xy 116.332508 -376.059954) (xy 116.326707 -376.067096) (xy 116.320195 -376.084289)
			(xy 116.319808 -376.093482) (xy 116.319808 -376.25147) (xy 116.319243 -376.26162) (xy 116.311487 -376.28038)
			(xy 116.297144 -376.294745) (xy 116.278395 -376.302528) (xy 116.268246 -376.303032) (xy 115.551966 -376.303032)
			(xy 115.541802 -376.302594) (xy 115.523027 -376.294803) (xy 115.508662 -376.28042) (xy 115.500894 -376.261634)
			(xy 115.500404 -376.25147) (xy 115.500404 -376.093482) (xy 115.500002 -376.084294) (xy 115.493483 -376.06711)
			(xy 115.487704 -376.059954) (xy 115.465947 -376.034277) (xy 115.427999 -375.978693) (xy 115.396967 -375.918973)
			(xy 115.373294 -375.855972) (xy 115.35732 -375.790593) (xy 115.349274 -375.723774) (xy 115.349271 -375.656472)
			(xy 115.357312 -375.589652) (xy 115.37328 -375.524271) (xy 115.396948 -375.461268) (xy 115.427976 -375.401545)
			(xy 115.465919 -375.345959) (xy 115.487704 -375.320306) (xy 115.493481 -375.313147) (xy 115.500007 -375.295967)
			(xy 115.500404 -375.286778) (xy 115.500404 -374.79351) (xy 115.499988 -374.784323) (xy 115.493478 -374.767139)
			(xy 115.487704 -374.759982) (xy 115.465876 -374.734363) (xy 115.427931 -374.678771) (xy 115.396901 -374.619043)
			(xy 115.373232 -374.556034) (xy 115.357263 -374.490648) (xy 115.349223 -374.423822) (xy 85.670923 -374.423822)
			(xy 85.670923 -374.423879) (xy 85.662851 -374.490815) (xy 85.646818 -374.556302) (xy 85.623057 -374.619398)
			(xy 85.591909 -374.679192) (xy 85.553823 -374.734826) (xy 85.53196 -374.76049) (xy 85.526138 -374.767617)
			(xy 85.519639 -374.784822) (xy 85.51926 -374.794018) (xy 85.51926 -375.28627) (xy 85.519694 -375.295454)
			(xy 85.526192 -375.312639) (xy 85.53196 -375.319798) (xy 85.553855 -375.345438) (xy 85.591945 -375.401075)
			(xy 85.623097 -375.460875) (xy 85.646861 -375.523975) (xy 85.662896 -375.589467) (xy 85.67097 -375.656409)
			(xy 85.670967 -375.723836) (xy 85.662888 -375.790777) (xy 85.646848 -375.856268) (xy 85.623079 -375.919367)
			(xy 85.591922 -375.979163) (xy 85.553827 -376.034797) (xy 85.53196 -376.060462) (xy 85.52615 -376.067597)
			(xy 85.519644 -376.084796) (xy 85.51926 -376.09399) (xy 85.51926 -376.25147) (xy 85.518749 -376.261595)
			(xy 85.511031 -376.280315) (xy 85.496752 -376.294673) (xy 85.478074 -376.302493) (xy 85.467952 -376.303032)
			(xy 84.751672 -376.303032) (xy 84.741565 -376.302539) (xy 84.722893 -376.294798) (xy 84.7086 -376.280504)
			(xy 84.700861 -376.261831) (xy 84.700364 -376.251724) (xy 84.700364 -376.09399) (xy 84.699944 -376.084804)
			(xy 84.693436 -376.06762) (xy 84.687664 -376.060462) (xy 84.665831 -376.034772) (xy 84.627744 -375.97914)
			(xy 84.596594 -375.919347) (xy 84.572829 -375.856253) (xy 84.556793 -375.790768) (xy 84.548715 -375.723833)
			(xy 84.548712 -375.656412) (xy 84.556785 -375.589477) (xy 84.572816 -375.52399) (xy 84.596575 -375.460894)
			(xy 84.62772 -375.401099) (xy 84.665803 -375.345464) (xy 84.687664 -375.319798) (xy 84.693452 -375.312647)
			(xy 84.69997 -375.295461) (xy 84.700364 -375.28627) (xy 84.700364 -374.794018) (xy 84.699931 -374.784834)
			(xy 84.693432 -374.76765) (xy 84.687664 -374.76049) (xy 84.66576 -374.734858) (xy 84.627675 -374.679218)
			(xy 84.596528 -374.619417) (xy 84.572768 -374.556316) (xy 84.556736 -374.490823) (xy 84.548664 -374.423882)
			(xy 81.271132 -374.423882) (xy 81.26306 -374.490815) (xy 81.247028 -374.556302) (xy 81.223267 -374.619397)
			(xy 81.19212 -374.679192) (xy 81.154034 -374.734825) (xy 81.132172 -374.76049) (xy 81.126351 -374.767618)
			(xy 81.119852 -374.784822) (xy 81.119472 -374.794018) (xy 81.119472 -375.28627) (xy 81.119903 -375.295455)
			(xy 81.126403 -375.312639) (xy 81.132172 -375.319798) (xy 81.154066 -375.345438) (xy 81.192156 -375.401076)
			(xy 81.223307 -375.460875) (xy 81.247071 -375.523975) (xy 81.263105 -375.589468) (xy 81.271179 -375.656409)
			(xy 81.271176 -375.723836) (xy 81.263097 -375.790777) (xy 81.247057 -375.856268) (xy 81.223289 -375.919366)
			(xy 81.192133 -375.979163) (xy 81.154039 -376.034797) (xy 81.132172 -376.060462) (xy 81.126363 -376.067598)
			(xy 81.119856 -376.084796) (xy 81.119472 -376.09399) (xy 81.119472 -376.25147) (xy 81.118949 -376.261593)
			(xy 81.111234 -376.280312) (xy 81.096958 -376.294669) (xy 81.078284 -376.302491) (xy 81.068164 -376.303032)
			(xy 80.351884 -376.303032) (xy 80.341778 -376.302529) (xy 80.323106 -376.294792) (xy 80.308813 -376.280501)
			(xy 80.301073 -376.26183) (xy 80.300576 -376.251724) (xy 80.300576 -376.09399) (xy 80.300176 -376.084802)
			(xy 80.293656 -376.067617) (xy 80.287876 -376.060462) (xy 80.266042 -376.034772) (xy 80.227954 -375.97914)
			(xy 80.196804 -375.919347) (xy 80.173039 -375.856254) (xy 80.157002 -375.790768) (xy 80.148924 -375.723833)
			(xy 80.148921 -375.656412) (xy 80.156994 -375.589476) (xy 80.173025 -375.523989) (xy 80.196785 -375.460894)
			(xy 80.227931 -375.401098) (xy 80.266015 -375.345464) (xy 80.287876 -375.319798) (xy 80.293653 -375.312639)
			(xy 80.30018 -375.295459) (xy 80.300576 -375.28627) (xy 80.300576 -374.794018) (xy 80.300163 -374.784831)
			(xy 80.293652 -374.767646) (xy 80.287876 -374.76049) (xy 80.265972 -374.734858) (xy 80.227886 -374.679218)
			(xy 80.196738 -374.619417) (xy 80.172977 -374.556316) (xy 80.156946 -374.490823) (xy 80.148873 -374.423882)
			(xy 76.870804 -374.423882) (xy 76.862772 -374.490638) (xy 76.846805 -374.556018) (xy 76.823138 -374.619021)
			(xy 76.79211 -374.678743) (xy 76.754168 -374.734329) (xy 76.732384 -374.759982) (xy 76.726568 -374.767114)
			(xy 76.720066 -374.784315) (xy 76.719684 -374.79351) (xy 76.719684 -375.286778) (xy 76.720108 -375.295964)
			(xy 76.726613 -375.313148) (xy 76.732384 -375.320306) (xy 76.754201 -375.345934) (xy 76.792147 -375.401525)
			(xy 76.823178 -375.461252) (xy 76.846848 -375.524259) (xy 76.862818 -375.589644) (xy 76.870859 -375.656469)
			(xy 76.870857 -375.723776) (xy 76.86281 -375.7906) (xy 76.846834 -375.855984) (xy 76.823159 -375.91899)
			(xy 76.792124 -375.978714) (xy 76.754173 -376.034302) (xy 76.732384 -376.059954) (xy 76.72658 -376.067094)
			(xy 76.72007 -376.084289) (xy 76.719684 -376.093482) (xy 76.719684 -376.25147) (xy 76.719212 -376.261637)
			(xy 76.711441 -376.280427) (xy 76.69707 -376.294812) (xy 76.678288 -376.302602) (xy 76.668122 -376.303032)
			(xy 75.951842 -376.303032) (xy 75.941669 -376.302601) (xy 75.92287 -376.294824) (xy 75.908482 -376.28044)
			(xy 75.900701 -376.261643) (xy 75.90028 -376.25147) (xy 75.90028 -376.093482) (xy 75.899883 -376.084293)
			(xy 75.893361 -376.067109) (xy 75.88758 -376.059954) (xy 75.865821 -376.034278) (xy 75.827868 -375.978696)
			(xy 75.796831 -375.918976) (xy 75.773155 -375.855975) (xy 75.757179 -375.790595) (xy 75.749132 -375.723774)
			(xy 75.749129 -375.656471) (xy 75.757171 -375.58965) (xy 75.773142 -375.524269) (xy 75.796813 -375.461265)
			(xy 75.827845 -375.401543) (xy 75.865793 -375.345958) (xy 75.88758 -375.320306) (xy 75.893354 -375.313145)
			(xy 75.899883 -375.295967) (xy 75.90028 -375.286778) (xy 75.90028 -374.79351) (xy 75.89987 -374.784323)
			(xy 75.893357 -374.767138) (xy 75.88758 -374.759982) (xy 75.865749 -374.734365) (xy 75.827799 -374.678774)
			(xy 75.796765 -374.619046) (xy 75.773093 -374.556037) (xy 75.757122 -374.49065) (xy 75.749081 -374.423823)
			(xy 72.471044 -374.423823) (xy 72.471044 -374.423879) (xy 72.462972 -374.490814) (xy 72.446941 -374.556301)
			(xy 72.423181 -374.619396) (xy 72.392034 -374.679191) (xy 72.35395 -374.734825) (xy 72.332088 -374.76049)
			(xy 72.326269 -374.76762) (xy 72.319768 -374.784822) (xy 72.319388 -374.794018) (xy 72.319388 -375.28627)
			(xy 72.319815 -375.295455) (xy 72.326317 -375.31264) (xy 72.332088 -375.319798) (xy 72.353982 -375.345439)
			(xy 72.39207 -375.401076) (xy 72.423221 -375.460876) (xy 72.446984 -375.523976) (xy 72.463017 -375.589468)
			(xy 72.471091 -375.656409) (xy 72.471088 -375.723836) (xy 72.463009 -375.790776) (xy 72.44697 -375.856267)
			(xy 72.423202 -375.919365) (xy 72.392047 -375.979162) (xy 72.353954 -376.034797) (xy 72.332088 -376.060462)
			(xy 72.326281 -376.0676) (xy 72.319773 -376.084796) (xy 72.319388 -376.09399) (xy 72.319388 -376.25147)
			(xy 72.31885 -376.261591) (xy 72.311137 -376.280307) (xy 72.296867 -376.294663) (xy 72.278198 -376.302488)
			(xy 72.26808 -376.303032) (xy 71.5518 -376.303032) (xy 71.54165 -376.302579) (xy 71.522904 -376.294789)
			(xy 71.508582 -376.280403) (xy 71.500876 -376.261622) (xy 71.500492 -376.25147) (xy 71.500492 -376.09399)
			(xy 71.500088 -376.084802) (xy 71.49357 -376.067618) (xy 71.487792 -376.060462) (xy 71.465958 -376.034772)
			(xy 71.427869 -375.979141) (xy 71.396717 -375.919348) (xy 71.372952 -375.856255) (xy 71.356914 -375.790769)
			(xy 71.348836 -375.723833) (xy 71.348833 -375.656412) (xy 71.356906 -375.589476) (xy 71.372938 -375.523989)
			(xy 71.396699 -375.460893) (xy 71.427845 -375.401098) (xy 71.46593 -375.345463) (xy 71.487792 -375.319798)
			(xy 71.493571 -375.31264) (xy 71.500096 -375.295459) (xy 71.500492 -375.28627) (xy 71.500492 -374.794018)
			(xy 71.500075 -374.784832) (xy 71.493566 -374.767647) (xy 71.487792 -374.76049) (xy 71.465887 -374.734859)
			(xy 71.4278 -374.679219) (xy 71.396652 -374.619418) (xy 71.37289 -374.556317) (xy 71.356858 -374.490824)
			(xy 71.348786 -374.423882) (xy 46.070774 -374.423882) (xy 46.062742 -374.490639) (xy 46.046773 -374.55602)
			(xy 46.023104 -374.619022) (xy 45.992075 -374.678745) (xy 45.95413 -374.73433) (xy 45.932344 -374.759982)
			(xy 45.926523 -374.76711) (xy 45.920025 -374.784314) (xy 45.919644 -374.79351) (xy 45.919644 -375.286778)
			(xy 45.920077 -375.295962) (xy 45.926576 -375.313146) (xy 45.932344 -375.320306) (xy 45.954162 -375.345934)
			(xy 45.992111 -375.401523) (xy 46.023144 -375.46125) (xy 46.046816 -375.524258) (xy 46.062787 -375.589643)
			(xy 46.070829 -375.656469) (xy 46.070826 -375.723776) (xy 46.062779 -375.790601) (xy 46.046802 -375.855985)
			(xy 46.023125 -375.918991) (xy 45.992088 -375.978716) (xy 45.954134 -376.034302) (xy 45.932344 -376.059954)
			(xy 45.926535 -376.06709) (xy 45.920029 -376.084288) (xy 45.919644 -376.093482) (xy 45.919644 -376.25147)
			(xy 45.919211 -376.261642) (xy 45.911433 -376.280439) (xy 45.897049 -376.294826) (xy 45.878254 -376.302609)
			(xy 45.868082 -376.303032) (xy 45.151802 -376.303032) (xy 45.141627 -376.302634) (xy 45.122826 -376.294844)
			(xy 45.10844 -376.28045) (xy 45.100661 -376.261645) (xy 45.10024 -376.25147) (xy 45.10024 -376.093482)
			(xy 45.09983 -376.084295) (xy 45.093315 -376.067111) (xy 45.08754 -376.059954) (xy 45.065782 -376.034277)
			(xy 45.027832 -375.978695) (xy 44.996798 -375.918974) (xy 44.973123 -375.855973) (xy 44.957148 -375.790594)
			(xy 44.949101 -375.723774) (xy 44.949099 -375.656471) (xy 44.95714 -375.589651) (xy 44.97311 -375.52427)
			(xy 44.996779 -375.461267) (xy 45.027809 -375.401544) (xy 45.065754 -375.345958) (xy 45.08754 -375.320306)
			(xy 45.093322 -375.31315) (xy 45.099844 -375.295968) (xy 45.10024 -375.286778) (xy 45.10024 -374.79351)
			(xy 45.099816 -374.784324) (xy 45.093311 -374.76714) (xy 45.08754 -374.759982) (xy 45.065711 -374.734364)
			(xy 45.027763 -374.678773) (xy 44.996732 -374.619044) (xy 44.973061 -374.556035) (xy 44.957091 -374.490649)
			(xy 44.94905 -374.423823) (xy 41.671014 -374.423823) (xy 41.671014 -374.423879) (xy 41.662941 -374.490816)
			(xy 41.646909 -374.556303) (xy 41.623147 -374.619398) (xy 41.591998 -374.679193) (xy 41.553911 -374.734826)
			(xy 41.532048 -374.76049) (xy 41.526224 -374.767616) (xy 41.519727 -374.784821) (xy 41.519348 -374.794018)
			(xy 41.519348 -375.28627) (xy 41.519784 -375.295454) (xy 41.526281 -375.312638) (xy 41.532048 -375.319798)
			(xy 41.553943 -375.345438) (xy 41.592035 -375.401075) (xy 41.623187 -375.460874) (xy 41.646952 -375.523974)
			(xy 41.662987 -375.589467) (xy 41.671061 -375.656409) (xy 41.671058 -375.723836) (xy 41.662978 -375.790777)
			(xy 41.646938 -375.856269) (xy 41.623168 -375.919367) (xy 41.592011 -375.979164) (xy 41.553916 -376.034798)
			(xy 41.532048 -376.060462) (xy 41.526236 -376.067596) (xy 41.519732 -376.084795) (xy 41.519348 -376.09399)
			(xy 41.519348 -376.25147) (xy 41.518849 -376.261596) (xy 41.511129 -376.280319) (xy 41.496846 -376.294677)
			(xy 41.478164 -376.302495) (xy 41.46804 -376.303032) (xy 40.75176 -376.303032) (xy 40.741607 -376.302612)
			(xy 40.72286 -376.294809) (xy 40.708539 -376.280413) (xy 40.700835 -376.261625) (xy 40.700452 -376.25147)
			(xy 40.700452 -376.09399) (xy 40.700035 -376.084804) (xy 40.693525 -376.06762) (xy 40.687752 -376.060462)
			(xy 40.665916 -376.034773) (xy 40.627823 -375.979143) (xy 40.596668 -375.919351) (xy 40.5729 -375.856257)
			(xy 40.55686 -375.79077) (xy 40.548781 -375.723834) (xy 40.548779 -375.656411) (xy 40.556852 -375.589474)
			(xy 40.572886 -375.523986) (xy 40.596649 -375.46089) (xy 40.627799 -375.401095) (xy 40.665888 -375.345462)
			(xy 40.687752 -375.319798) (xy 40.693538 -375.312646) (xy 40.700058 -375.29546) (xy 40.700452 -375.28627)
			(xy 40.700452 -374.794018) (xy 40.700022 -374.784833) (xy 40.693521 -374.767649) (xy 40.687752 -374.76049)
			(xy 40.665845 -374.73486) (xy 40.627754 -374.679221) (xy 40.596602 -374.619421) (xy 40.572838 -374.556319)
			(xy 40.556804 -374.490825) (xy 40.548731 -374.423882) (xy 37.271223 -374.423882) (xy 37.263151 -374.490815)
			(xy 37.247118 -374.556302) (xy 37.223357 -374.619398) (xy 37.192209 -374.679192) (xy 37.154123 -374.734826)
			(xy 37.13226 -374.76049) (xy 37.126438 -374.767617) (xy 37.119939 -374.784822) (xy 37.11956 -374.794018)
			(xy 37.11956 -375.28627) (xy 37.119994 -375.295454) (xy 37.126492 -375.312639) (xy 37.13226 -375.319798)
			(xy 37.154155 -375.345438) (xy 37.192245 -375.401075) (xy 37.223397 -375.460875) (xy 37.247161 -375.523975)
			(xy 37.263196 -375.589467) (xy 37.27127 -375.656409) (xy 37.271267 -375.723836) (xy 37.263188 -375.790777)
			(xy 37.247148 -375.856268) (xy 37.223379 -375.919367) (xy 37.192222 -375.979163) (xy 37.154127 -376.034797)
			(xy 37.13226 -376.060462) (xy 37.12645 -376.067597) (xy 37.119944 -376.084796) (xy 37.11956 -376.09399)
			(xy 37.11956 -376.25147) (xy 37.119049 -376.261595) (xy 37.111331 -376.280315) (xy 37.097052 -376.294673)
			(xy 37.078374 -376.302493) (xy 37.068252 -376.303032) (xy 36.351972 -376.303032) (xy 36.34182 -376.302602)
			(xy 36.323073 -376.294803) (xy 36.308752 -376.28041) (xy 36.301047 -376.261624) (xy 36.300664 -376.25147)
			(xy 36.300664 -376.09399) (xy 36.300244 -376.084804) (xy 36.293736 -376.06762) (xy 36.287964 -376.060462)
			(xy 36.266131 -376.034772) (xy 36.228044 -375.97914) (xy 36.196894 -375.919347) (xy 36.173129 -375.856253)
			(xy 36.157093 -375.790768) (xy 36.149015 -375.723833) (xy 36.149012 -375.656412) (xy 36.157085 -375.589477)
			(xy 36.173116 -375.52399) (xy 36.196875 -375.460894) (xy 36.22802 -375.401099) (xy 36.266103 -375.345464)
			(xy 36.287964 -375.319798) (xy 36.293752 -375.312647) (xy 36.30027 -375.295461) (xy 36.300664 -375.28627)
			(xy 36.300664 -374.794018) (xy 36.300231 -374.784834) (xy 36.293732 -374.76765) (xy 36.287964 -374.76049)
			(xy 36.26606 -374.734858) (xy 36.227975 -374.679218) (xy 36.196828 -374.619417) (xy 36.173068 -374.556316)
			(xy 36.157036 -374.490823) (xy 36.148964 -374.423882) (xy 32.870895 -374.423882) (xy 32.862863 -374.490639)
			(xy 32.846895 -374.556018) (xy 32.823227 -374.619021) (xy 32.7922 -374.678743) (xy 32.754257 -374.73433)
			(xy 32.732472 -374.759982) (xy 32.726654 -374.767112) (xy 32.720153 -374.784314) (xy 32.719772 -374.79351)
			(xy 32.719772 -375.286778) (xy 32.720199 -375.295963) (xy 32.726702 -375.313147) (xy 32.732472 -375.320306)
			(xy 32.754289 -375.345934) (xy 32.792236 -375.401524) (xy 32.823268 -375.461251) (xy 32.846938 -375.524259)
			(xy 32.862909 -375.589644) (xy 32.87095 -375.656469) (xy 32.870948 -375.723776) (xy 32.862901 -375.790601)
			(xy 32.846925 -375.855984) (xy 32.823249 -375.91899) (xy 32.792213 -375.978715) (xy 32.754261 -376.034302)
			(xy 32.732472 -376.059954) (xy 32.726666 -376.067093) (xy 32.720158 -376.084288) (xy 32.719772 -376.093482)
			(xy 32.719772 -376.25147) (xy 32.719312 -376.261638) (xy 32.711538 -376.28043) (xy 32.697164 -376.294816)
			(xy 32.678378 -376.302604) (xy 32.66821 -376.303032) (xy 31.95193 -376.303032) (xy 31.941757 -376.302611)
			(xy 31.922957 -376.29483) (xy 31.90857 -376.280443) (xy 31.900789 -376.261643) (xy 31.900368 -376.25147)
			(xy 31.900368 -376.093482) (xy 31.899951 -376.084296) (xy 31.89344 -376.067112) (xy 31.887668 -376.059954)
			(xy 31.865909 -376.034278) (xy 31.827957 -375.978696) (xy 31.796921 -375.918976) (xy 31.773245 -375.855974)
			(xy 31.75727 -375.790595) (xy 31.749223 -375.723774) (xy 31.74922 -375.656471) (xy 31.757261 -375.58965)
			(xy 31.773232 -375.524269) (xy 31.796903 -375.461266) (xy 31.827934 -375.401543) (xy 31.865881 -375.345958)
			(xy 31.887668 -375.320306) (xy 31.893453 -375.313153) (xy 31.899973 -375.295968) (xy 31.900368 -375.286778)
			(xy 31.900368 -374.79351) (xy 31.899938 -374.784325) (xy 31.893436 -374.767142) (xy 31.887668 -374.759982)
			(xy 31.865838 -374.734364) (xy 31.827888 -374.678774) (xy 31.796855 -374.619046) (xy 31.773184 -374.556036)
			(xy 31.757213 -374.49065) (xy 31.749171 -374.423823) (xy 28.471155 -374.423823) (xy 28.471155 -374.42387)
			(xy 28.463079 -374.490809) (xy 28.447044 -374.556297) (xy 28.423279 -374.619394) (xy 28.392129 -374.67919)
			(xy 28.35404 -374.734825) (xy 28.332176 -374.76049) (xy 28.326356 -374.767618) (xy 28.319856 -374.784822)
			(xy 28.319476 -374.794018) (xy 28.319476 -375.28627) (xy 28.319906 -375.295455) (xy 28.326407 -375.312639)
			(xy 28.332176 -375.319798) (xy 28.35407 -375.345439) (xy 28.39216 -375.401076) (xy 28.42331 -375.460875)
			(xy 28.447074 -375.523976) (xy 28.463108 -375.589468) (xy 28.471182 -375.656409) (xy 28.471179 -375.723836)
			(xy 28.4631 -375.790777) (xy 28.447061 -375.856268) (xy 28.423292 -375.919366) (xy 28.392136 -375.979163)
			(xy 28.354043 -376.034797) (xy 28.332176 -376.060462) (xy 28.326368 -376.067599) (xy 28.319861 -376.084796)
			(xy 28.319476 -376.09399) (xy 28.319476 -376.25147) (xy 28.31895 -376.261593) (xy 28.311235 -376.28031)
			(xy 28.29696 -376.294667) (xy 28.278288 -376.30249) (xy 28.268168 -376.303032) (xy 27.551888 -376.303032)
			(xy 27.541783 -376.302525) (xy 27.52311 -376.29479) (xy 27.508817 -376.2805) (xy 27.501077 -376.261829)
			(xy 27.50058 -376.251724) (xy 27.50058 -376.09399) (xy 27.500179 -376.084802) (xy 27.493659 -376.067617)
			(xy 27.48788 -376.060462) (xy 27.466046 -376.034772) (xy 27.427958 -375.979141) (xy 27.396807 -375.919348)
			(xy 27.373042 -375.856254) (xy 27.357005 -375.790768) (xy 27.348927 -375.723833) (xy 27.348924 -375.656412)
			(xy 27.356997 -375.589476) (xy 27.373029 -375.523989) (xy 27.396789 -375.460894) (xy 27.427935 -375.401098)
			(xy 27.466019 -375.345464) (xy 27.48788 -375.319798) (xy 27.493658 -375.312639) (xy 27.500184 -375.295459)
			(xy 27.50058 -375.28627) (xy 27.50058 -374.794018) (xy 27.500166 -374.784831) (xy 27.493655 -374.767646)
			(xy 27.48788 -374.76049) (xy 27.466014 -374.734827) (xy 27.427924 -374.679192) (xy 27.396773 -374.619396)
			(xy 27.373009 -374.556299) (xy 27.356973 -374.490809) (xy 27.348897 -374.423871) (xy 0.508 -374.423871)
			(xy 0.508 -376.756551) (xy 29.549067 -376.756551) (xy 29.557111 -376.689729) (xy 29.573083 -376.624347)
			(xy 29.596754 -376.561343) (xy 29.627786 -376.501619) (xy 29.665733 -376.446032) (xy 29.68752 -376.42038)
			(xy 29.69331 -376.41323) (xy 29.699828 -376.396043) (xy 29.70022 -376.386852) (xy 29.70022 -375.893584)
			(xy 29.699813 -375.884397) (xy 29.693297 -375.867212) (xy 29.68752 -375.860056) (xy 29.665765 -375.834378)
			(xy 29.627816 -375.778794) (xy 29.596782 -375.719074) (xy 29.573109 -375.656073) (xy 29.557134 -375.590694)
			(xy 29.549088 -375.523875) (xy 29.549085 -375.456573) (xy 29.557126 -375.389753) (xy 29.573095 -375.324373)
			(xy 29.596763 -375.26137) (xy 29.627791 -375.201647) (xy 29.665735 -375.146061) (xy 29.68752 -375.120408)
			(xy 29.693298 -375.11325) (xy 29.699823 -375.096069) (xy 29.70022 -375.08688) (xy 29.70022 -374.928638)
			(xy 29.700695 -374.918471) (xy 29.708464 -374.899681) (xy 29.722834 -374.885295) (xy 29.741616 -374.877506)
			(xy 29.751782 -374.877076) (xy 30.468062 -374.877076) (xy 30.478236 -374.877496) (xy 30.497037 -374.885276)
			(xy 30.511424 -374.899663) (xy 30.519204 -374.918464) (xy 30.519624 -374.928638) (xy 30.519624 -375.08688)
			(xy 30.520038 -375.096067) (xy 30.526548 -375.113252) (xy 30.532324 -375.120408) (xy 30.554144 -375.146034)
			(xy 30.592094 -375.201623) (xy 30.623128 -375.26135) (xy 30.646801 -375.324358) (xy 30.662773 -375.389744)
			(xy 30.670815 -375.45657) (xy 30.670812 -375.523878) (xy 30.662764 -375.590704) (xy 30.646787 -375.656088)
			(xy 30.623109 -375.719094) (xy 30.59207 -375.778818) (xy 30.554115 -375.834404) (xy 30.532324 -375.860056)
			(xy 30.526524 -375.867199) (xy 30.520011 -375.884391) (xy 30.519624 -375.893584) (xy 30.519624 -376.386852)
			(xy 30.520052 -376.396037) (xy 30.526553 -376.413222) (xy 30.532324 -376.42038) (xy 30.554117 -376.446028)
			(xy 30.592068 -376.501615) (xy 30.623103 -376.561338) (xy 30.646777 -376.624343) (xy 30.662751 -376.689726)
			(xy 30.670795 -376.75655) (xy 30.670795 -376.823856) (xy 30.670788 -376.823915) (xy 33.948836 -376.823915)
			(xy 33.948836 -376.756491) (xy 33.956911 -376.689553) (xy 33.972947 -376.624064) (xy 33.996711 -376.560967)
			(xy 34.027862 -376.501171) (xy 34.065952 -376.445537) (xy 34.087816 -376.419872) (xy 34.093609 -376.412724)
			(xy 34.100125 -376.395536) (xy 34.100516 -376.386344) (xy 34.100516 -375.894092) (xy 34.100106 -375.884905)
			(xy 34.093592 -375.867721) (xy 34.087816 -375.860564) (xy 34.065983 -375.834873) (xy 34.027892 -375.779243)
			(xy 33.996739 -375.71945) (xy 33.972973 -375.656357) (xy 33.956934 -375.59087) (xy 33.948856 -375.523935)
			(xy 33.948853 -375.456513) (xy 33.956926 -375.389577) (xy 33.972958 -375.324089) (xy 33.99672 -375.260994)
			(xy 34.027867 -375.201199) (xy 34.065953 -375.145565) (xy 34.087816 -375.1199) (xy 34.093597 -375.112744)
			(xy 34.10012 -375.095562) (xy 34.100516 -375.086372) (xy 34.100516 -374.928638) (xy 34.101057 -374.918517)
			(xy 34.108768 -374.899801) (xy 34.123038 -374.885444) (xy 34.141706 -374.87762) (xy 34.151824 -374.877076)
			(xy 34.868104 -374.877076) (xy 34.878255 -374.877518) (xy 34.897003 -374.88531) (xy 34.911325 -374.8997)
			(xy 34.919029 -374.918485) (xy 34.919412 -374.928638) (xy 34.919412 -375.086372) (xy 34.919833 -375.095558)
			(xy 34.926339 -375.112743) (xy 34.932112 -375.1199) (xy 34.954007 -375.14554) (xy 34.992094 -375.201178)
			(xy 35.023243 -375.260978) (xy 35.047004 -375.324078) (xy 35.063037 -375.38957) (xy 35.07111 -375.456511)
			(xy 35.071108 -375.523937) (xy 35.063029 -375.590877) (xy 35.04699 -375.656368) (xy 35.023223 -375.719466)
			(xy 34.992069 -375.779263) (xy 34.953977 -375.834899) (xy 34.932112 -375.860564) (xy 34.926307 -375.867703)
			(xy 34.919797 -375.884898) (xy 34.919412 -375.894092) (xy 34.919412 -376.386344) (xy 34.919798 -376.395534)
			(xy 34.926328 -376.412718) (xy 34.932112 -376.419872) (xy 34.953979 -376.445534) (xy 34.992067 -376.501169)
			(xy 35.023217 -376.560966) (xy 35.046981 -376.624063) (xy 35.063015 -376.689553) (xy 35.071091 -376.756491)
			(xy 35.071091 -376.756551) (xy 38.349155 -376.756551) (xy 38.357198 -376.689729) (xy 38.37317 -376.624348)
			(xy 38.396841 -376.561343) (xy 38.427872 -376.50162) (xy 38.465818 -376.446033) (xy 38.487604 -376.42038)
			(xy 38.493392 -376.413229) (xy 38.499912 -376.396043) (xy 38.500304 -376.386852) (xy 38.500304 -375.893584)
			(xy 38.499901 -375.884396) (xy 38.493382 -375.867212) (xy 38.487604 -375.860056) (xy 38.465849 -375.834378)
			(xy 38.427901 -375.778794) (xy 38.396869 -375.719074) (xy 38.373195 -375.656073) (xy 38.357221 -375.590694)
			(xy 38.349175 -375.523875) (xy 38.349172 -375.456573) (xy 38.357213 -375.389753) (xy 38.373181 -375.324373)
			(xy 38.396849 -375.26137) (xy 38.427876 -375.201647) (xy 38.465819 -375.146061) (xy 38.487604 -375.120408)
			(xy 38.49338 -375.113248) (xy 38.499907 -375.096069) (xy 38.500304 -375.08688) (xy 38.500304 -374.928638)
			(xy 38.500794 -374.918473) (xy 38.50856 -374.899686) (xy 38.522925 -374.885301) (xy 38.541702 -374.877508)
			(xy 38.551866 -374.877076) (xy 39.268146 -374.877076) (xy 39.278311 -374.877497) (xy 39.297089 -374.885293)
			(xy 39.311454 -374.899682) (xy 39.31922 -374.918472) (xy 39.319708 -374.928638) (xy 39.319708 -375.08688)
			(xy 39.320126 -375.096066) (xy 39.326634 -375.113251) (xy 39.332408 -375.120408) (xy 39.354229 -375.146034)
			(xy 39.39218 -375.201623) (xy 39.423215 -375.261349) (xy 39.446888 -375.324357) (xy 39.462861 -375.389743)
			(xy 39.470903 -375.45657) (xy 39.4709 -375.523878) (xy 39.462852 -375.590704) (xy 39.446874 -375.656089)
			(xy 39.423195 -375.719095) (xy 39.392155 -375.778819) (xy 39.354199 -375.834405) (xy 39.332408 -375.860056)
			(xy 39.326606 -375.867197) (xy 39.320094 -375.884391) (xy 39.319708 -375.893584) (xy 39.319708 -376.386852)
			(xy 39.320139 -376.396037) (xy 39.326638 -376.413222) (xy 39.332408 -376.42038) (xy 39.354201 -376.446028)
			(xy 39.392153 -376.501614) (xy 39.423189 -376.561338) (xy 39.446864 -376.624343) (xy 39.462839 -376.689726)
			(xy 39.470883 -376.75655) (xy 39.470883 -376.823856) (xy 39.470876 -376.823915) (xy 42.748924 -376.823915)
			(xy 42.748924 -376.756491) (xy 42.756999 -376.689553) (xy 42.773034 -376.624064) (xy 42.796798 -376.560968)
			(xy 42.827948 -376.501172) (xy 42.866036 -376.445537) (xy 42.8879 -376.419872) (xy 42.893691 -376.412723)
			(xy 42.900209 -376.395535) (xy 42.9006 -376.386344) (xy 42.9006 -375.894092) (xy 42.900194 -375.884904)
			(xy 42.893677 -375.86772) (xy 42.8879 -375.860564) (xy 42.866067 -375.834873) (xy 42.827978 -375.779242)
			(xy 42.796826 -375.719449) (xy 42.77306 -375.656356) (xy 42.757022 -375.59087) (xy 42.748944 -375.523935)
			(xy 42.748941 -375.456513) (xy 42.757013 -375.389577) (xy 42.773045 -375.32409) (xy 42.796806 -375.260995)
			(xy 42.827953 -375.201199) (xy 42.866038 -375.145565) (xy 42.8879 -375.1199) (xy 42.893679 -375.112742)
			(xy 42.900204 -375.095561) (xy 42.9006 -375.086372) (xy 42.9006 -374.928638) (xy 42.901157 -374.918519)
			(xy 42.908865 -374.899806) (xy 42.923129 -374.88545) (xy 42.941792 -374.877622) (xy 42.951908 -374.877076)
			(xy 43.668188 -374.877076) (xy 43.678338 -374.877531) (xy 43.697086 -374.885318) (xy 43.711409 -374.899704)
			(xy 43.719113 -374.918486) (xy 43.719496 -374.928638) (xy 43.719496 -375.086372) (xy 43.719921 -375.095558)
			(xy 43.726424 -375.112742) (xy 43.732196 -375.1199) (xy 43.754092 -375.145539) (xy 43.79218 -375.201177)
			(xy 43.823329 -375.260977) (xy 43.847092 -375.324077) (xy 43.863125 -375.38957) (xy 43.871198 -375.456511)
			(xy 43.871196 -375.523937) (xy 43.863116 -375.590878) (xy 43.847077 -375.656369) (xy 43.823309 -375.719467)
			(xy 43.792155 -375.779264) (xy 43.754062 -375.834899) (xy 43.732196 -375.860564) (xy 43.726389 -375.867702)
			(xy 43.719881 -375.884898) (xy 43.719496 -375.894092) (xy 43.719496 -376.386344) (xy 43.719886 -376.395533)
			(xy 43.726414 -376.412717) (xy 43.732196 -376.419872) (xy 43.754064 -376.445534) (xy 43.792153 -376.501169)
			(xy 43.823304 -376.560965) (xy 43.847068 -376.624063) (xy 43.863103 -376.689552) (xy 43.871179 -376.756491)
			(xy 43.871178 -376.823856) (xy 47.149219 -376.823856) (xy 47.149219 -376.75655) (xy 47.157264 -376.689727)
			(xy 47.173238 -376.624344) (xy 47.196912 -376.56134) (xy 47.227948 -376.501617) (xy 47.265899 -376.446031)
			(xy 47.287688 -376.42038) (xy 47.293474 -376.413227) (xy 47.299995 -376.396043) (xy 47.300388 -376.386852)
			(xy 47.300388 -375.893584) (xy 47.299988 -375.884396) (xy 47.293468 -375.867211) (xy 47.287688 -375.860056)
			(xy 47.26593 -375.834379) (xy 47.227977 -375.778797) (xy 47.19694 -375.719077) (xy 47.173263 -375.656076)
			(xy 47.157287 -375.590696) (xy 47.149239 -375.523876) (xy 47.149236 -375.456572) (xy 47.157278 -375.389751)
			(xy 47.173249 -375.32437) (xy 47.19692 -375.261367) (xy 47.227952 -375.201644) (xy 47.265901 -375.146059)
			(xy 47.287688 -375.120408) (xy 47.293462 -375.113247) (xy 47.299991 -375.096069) (xy 47.300388 -375.08688)
			(xy 47.300388 -374.928892) (xy 47.300815 -374.918739) (xy 47.308611 -374.899989) (xy 47.323006 -374.885666)
			(xy 47.341795 -374.877965) (xy 47.35195 -374.877584) (xy 48.06823 -374.877584) (xy 48.078364 -374.878003)
			(xy 48.097094 -374.885749) (xy 48.111451 -374.900056) (xy 48.119261 -374.91876) (xy 48.119792 -374.928892)
			(xy 48.119792 -375.08688) (xy 48.120214 -375.096066) (xy 48.12672 -375.11325) (xy 48.132492 -375.120408)
			(xy 48.15431 -375.146035) (xy 48.192256 -375.201626) (xy 48.223286 -375.261353) (xy 48.246956 -375.324361)
			(xy 48.262926 -375.389746) (xy 48.270967 -375.456571) (xy 48.270964 -375.523878) (xy 48.262917 -375.590702)
			(xy 48.246942 -375.656085) (xy 48.223267 -375.719091) (xy 48.192231 -375.778816) (xy 48.154281 -375.834403)
			(xy 48.132492 -375.860056) (xy 48.126688 -375.867196) (xy 48.120178 -375.884391) (xy 48.119792 -375.893584)
			(xy 48.119792 -376.386852) (xy 48.120227 -376.396037) (xy 48.126724 -376.413221) (xy 48.132492 -376.42038)
			(xy 48.154283 -376.446029) (xy 48.192229 -376.501617) (xy 48.223261 -376.561341) (xy 48.246932 -376.624346)
			(xy 48.262904 -376.689728) (xy 48.270947 -376.756551) (xy 73.548976 -376.756551) (xy 73.55702 -376.689728)
			(xy 73.572992 -376.624347) (xy 73.596664 -376.561342) (xy 73.627697 -376.501619) (xy 73.665645 -376.446032)
			(xy 73.687432 -376.42038) (xy 73.693224 -376.413231) (xy 73.699741 -376.396043) (xy 73.700132 -376.386852)
			(xy 73.700132 -375.893584) (xy 73.699722 -375.884397) (xy 73.693208 -375.867213) (xy 73.687432 -375.860056)
			(xy 73.665676 -375.834378) (xy 73.627727 -375.778795) (xy 73.596693 -375.719075) (xy 73.573018 -375.656074)
			(xy 73.557043 -375.590695) (xy 73.548997 -375.523875) (xy 73.548994 -375.456573) (xy 73.557035 -375.389753)
			(xy 73.573004 -375.324372) (xy 73.596673 -375.261369) (xy 73.627702 -375.201647) (xy 73.665647 -375.14606)
			(xy 73.687432 -375.120408) (xy 73.693212 -375.113251) (xy 73.699736 -375.096069) (xy 73.700132 -375.08688)
			(xy 73.700132 -374.928638) (xy 73.700595 -374.91847) (xy 73.708366 -374.899677) (xy 73.72274 -374.885291)
			(xy 73.741526 -374.877504) (xy 73.751694 -374.877076) (xy 74.467974 -374.877076) (xy 74.478149 -374.877486)
			(xy 74.49695 -374.88527) (xy 74.511337 -374.89966) (xy 74.519116 -374.918463) (xy 74.519536 -374.928638)
			(xy 74.519536 -375.08688) (xy 74.51997 -375.096064) (xy 74.526469 -375.113248) (xy 74.532236 -375.120408)
			(xy 74.554056 -375.146034) (xy 74.592006 -375.201623) (xy 74.623039 -375.26135) (xy 74.646711 -375.324358)
			(xy 74.662683 -375.389744) (xy 74.670725 -375.45657) (xy 74.670722 -375.523878) (xy 74.662674 -375.590703)
			(xy 74.646697 -375.656088) (xy 74.623019 -375.719094) (xy 74.591981 -375.778818) (xy 74.554027 -375.834404)
			(xy 74.532236 -375.860056) (xy 74.526425 -375.867191) (xy 74.519921 -375.88439) (xy 74.519536 -375.893584)
			(xy 74.519536 -376.386852) (xy 74.519983 -376.396035) (xy 74.526473 -376.413219) (xy 74.532236 -376.42038)
			(xy 74.554028 -376.446029) (xy 74.591979 -376.501615) (xy 74.623013 -376.561339) (xy 74.646687 -376.624344)
			(xy 74.66266 -376.689727) (xy 74.670704 -376.75655) (xy 74.670704 -376.823856) (xy 74.670697 -376.823915)
			(xy 77.948745 -376.823915) (xy 77.948745 -376.756491) (xy 77.956821 -376.689553) (xy 77.972856 -376.624063)
			(xy 77.996621 -376.560967) (xy 78.027773 -376.501171) (xy 78.065863 -376.445537) (xy 78.087728 -376.419872)
			(xy 78.093523 -376.412726) (xy 78.100038 -376.395536) (xy 78.100428 -376.386344) (xy 78.100428 -375.894092)
			(xy 78.100016 -375.884905) (xy 78.093503 -375.867721) (xy 78.087728 -375.860564) (xy 78.065894 -375.834873)
			(xy 78.027803 -375.779243) (xy 77.996649 -375.719451) (xy 77.972882 -375.656357) (xy 77.956844 -375.590871)
			(xy 77.948765 -375.523935) (xy 77.948762 -375.456513) (xy 77.956835 -375.389577) (xy 77.972868 -375.324089)
			(xy 77.99663 -375.260993) (xy 78.027778 -375.201198) (xy 78.065865 -375.145565) (xy 78.087728 -375.1199)
			(xy 78.093511 -375.112745) (xy 78.100033 -375.095562) (xy 78.100428 -375.086372) (xy 78.100428 -374.928638)
			(xy 78.100958 -374.918515) (xy 78.108671 -374.899797) (xy 78.122944 -374.88544) (xy 78.141616 -374.877618)
			(xy 78.151736 -374.877076) (xy 78.868016 -374.877076) (xy 78.878123 -374.877572) (xy 78.896797 -374.88531)
			(xy 78.91109 -374.899603) (xy 78.918828 -374.918277) (xy 78.919324 -374.928384) (xy 78.919324 -375.086372)
			(xy 78.919742 -375.095558) (xy 78.92625 -375.112743) (xy 78.932024 -375.1199) (xy 78.953919 -375.14554)
			(xy 78.992005 -375.201178) (xy 79.023153 -375.260978) (xy 79.046914 -375.324079) (xy 79.062947 -375.38957)
			(xy 79.07102 -375.456511) (xy 79.071017 -375.523937) (xy 79.062938 -375.590877) (xy 79.0469 -375.656367)
			(xy 79.023133 -375.719466) (xy 78.99198 -375.779263) (xy 78.953889 -375.834898) (xy 78.932024 -375.860564)
			(xy 78.926221 -375.867704) (xy 78.919709 -375.884898) (xy 78.919324 -375.894092) (xy 78.919324 -376.386344)
			(xy 78.919708 -376.395534) (xy 78.926239 -376.412718) (xy 78.932024 -376.419872) (xy 78.953891 -376.445534)
			(xy 78.991978 -376.50117) (xy 79.023127 -376.560967) (xy 79.04689 -376.624064) (xy 79.062925 -376.689553)
			(xy 79.071 -376.756491) (xy 79.071 -376.756551) (xy 82.349064 -376.756551) (xy 82.357108 -376.689729)
			(xy 82.373079 -376.624347) (xy 82.396751 -376.561343) (xy 82.427782 -376.501619) (xy 82.465729 -376.446032)
			(xy 82.487516 -376.42038) (xy 82.493305 -376.41323) (xy 82.499824 -376.396043) (xy 82.500216 -376.386852)
			(xy 82.500216 -375.893584) (xy 82.49981 -375.884396) (xy 82.493293 -375.867212) (xy 82.487516 -375.860056)
			(xy 82.46576 -375.834378) (xy 82.427812 -375.778795) (xy 82.396779 -375.719074) (xy 82.373105 -375.656073)
			(xy 82.357131 -375.590694) (xy 82.349084 -375.523875) (xy 82.349081 -375.456573) (xy 82.357122 -375.389753)
			(xy 82.373091 -375.324373) (xy 82.396759 -375.26137) (xy 82.427787 -375.201647) (xy 82.465731 -375.14606)
			(xy 82.487516 -375.120408) (xy 82.493294 -375.113249) (xy 82.499819 -375.096069) (xy 82.500216 -375.08688)
			(xy 82.500216 -374.928638) (xy 82.500694 -374.918472) (xy 82.508463 -374.899682) (xy 82.522832 -374.885297)
			(xy 82.541612 -374.877506) (xy 82.551778 -374.877076) (xy 83.268058 -374.877076) (xy 83.278232 -374.877499)
			(xy 83.297033 -374.885277) (xy 83.31142 -374.899664) (xy 83.3192 -374.918464) (xy 83.31962 -374.928638)
			(xy 83.31962 -375.08688) (xy 83.320035 -375.096067) (xy 83.326545 -375.113251) (xy 83.33232 -375.120408)
			(xy 83.35414 -375.146034) (xy 83.392091 -375.201623) (xy 83.423125 -375.26135) (xy 83.446798 -375.324358)
			(xy 83.46277 -375.389744) (xy 83.470812 -375.45657) (xy 83.470809 -375.523878) (xy 83.462761 -375.590704)
			(xy 83.446784 -375.656088) (xy 83.423105 -375.719094) (xy 83.392066 -375.778818) (xy 83.354111 -375.834404)
			(xy 83.33232 -375.860056) (xy 83.326519 -375.867199) (xy 83.320007 -375.884391) (xy 83.31962 -375.893584)
			(xy 83.31962 -376.386852) (xy 83.320049 -376.396037) (xy 83.326549 -376.413222) (xy 83.33232 -376.42038)
			(xy 83.354113 -376.446028) (xy 83.392064 -376.501614) (xy 83.4231 -376.561338) (xy 83.446774 -376.624343)
			(xy 83.462748 -376.689726) (xy 83.470792 -376.75655) (xy 83.470792 -376.823856) (xy 83.470785 -376.823915)
			(xy 86.748833 -376.823915) (xy 86.748833 -376.756491) (xy 86.756908 -376.689553) (xy 86.772944 -376.624064)
			(xy 86.796708 -376.560967) (xy 86.827859 -376.501171) (xy 86.865948 -376.445537) (xy 86.887812 -376.419872)
			(xy 86.893604 -376.412724) (xy 86.900121 -376.395536) (xy 86.900512 -376.386344) (xy 86.900512 -375.894092)
			(xy 86.900103 -375.884905) (xy 86.893588 -375.86772) (xy 86.887812 -375.860564) (xy 86.865979 -375.834873)
			(xy 86.827889 -375.779242) (xy 86.796736 -375.71945) (xy 86.772969 -375.656356) (xy 86.756931 -375.59087)
			(xy 86.748853 -375.523935) (xy 86.74885 -375.456513) (xy 86.756923 -375.389577) (xy 86.772955 -375.32409)
			(xy 86.796716 -375.260994) (xy 86.827864 -375.201199) (xy 86.86595 -375.145565) (xy 86.887812 -375.1199)
			(xy 86.893592 -375.112743) (xy 86.900116 -375.095562) (xy 86.900512 -375.086372) (xy 86.900512 -374.928638)
			(xy 86.901057 -374.918517) (xy 86.908767 -374.899802) (xy 86.923035 -374.885446) (xy 86.941702 -374.87762)
			(xy 86.95182 -374.877076) (xy 87.6681 -374.877076) (xy 87.678206 -374.877585) (xy 87.696879 -374.885318)
			(xy 87.711173 -374.899607) (xy 87.718912 -374.918278) (xy 87.719408 -374.928384) (xy 87.719408 -375.086372)
			(xy 87.71983 -375.095558) (xy 87.726335 -375.112743) (xy 87.732108 -375.1199) (xy 87.754003 -375.145539)
			(xy 87.79209 -375.201178) (xy 87.798441 -375.213371) (xy 104.681961 -375.213371) (xy 104.681961 -375.153429)
			(xy 104.689785 -375.094001) (xy 104.7053 -375.036103) (xy 104.72824 -374.980725) (xy 104.758212 -374.928815)
			(xy 104.794703 -374.881262) (xy 104.837089 -374.838879) (xy 104.884645 -374.802391) (xy 104.936557 -374.772424)
			(xy 104.991937 -374.749489) (xy 105.049837 -374.733978) (xy 105.109265 -374.726159) (xy 105.139236 -374.725692)
			(xy 106.002836 -374.725692) (xy 106.032802 -374.726184) (xy 106.092221 -374.734011) (xy 106.15011 -374.749527)
			(xy 106.205479 -374.772465) (xy 106.25738 -374.802434) (xy 106.304926 -374.838921) (xy 106.347303 -374.881301)
			(xy 106.383786 -374.92885) (xy 106.413751 -374.980753) (xy 106.436685 -375.036124) (xy 106.452196 -375.094014)
			(xy 106.460018 -375.153434) (xy 106.460018 -375.213366) (xy 106.452196 -375.272786) (xy 106.436685 -375.330676)
			(xy 106.413751 -375.386047) (xy 106.383786 -375.43795) (xy 106.347303 -375.485499) (xy 106.304926 -375.527879)
			(xy 106.25738 -375.564366) (xy 106.205479 -375.594335) (xy 106.15011 -375.617273) (xy 106.092221 -375.632789)
			(xy 106.032802 -375.640616) (xy 106.002836 -375.641108) (xy 105.139236 -375.641108) (xy 105.109265 -375.640641)
			(xy 105.049837 -375.632822) (xy 104.991937 -375.617311) (xy 104.936557 -375.594376) (xy 104.884645 -375.564409)
			(xy 104.837089 -375.527921) (xy 104.794703 -375.485538) (xy 104.758212 -375.437985) (xy 104.72824 -375.386075)
			(xy 104.7053 -375.330697) (xy 104.689785 -375.272799) (xy 104.681961 -375.213371) (xy 87.798441 -375.213371)
			(xy 87.823239 -375.260978) (xy 87.847001 -375.324078) (xy 87.863034 -375.38957) (xy 87.871107 -375.456511)
			(xy 87.871105 -375.523937) (xy 87.863026 -375.590877) (xy 87.846987 -375.656368) (xy 87.82322 -375.719466)
			(xy 87.792066 -375.779263) (xy 87.753974 -375.834899) (xy 87.732108 -375.860564) (xy 87.726303 -375.867703)
			(xy 87.719793 -375.884898) (xy 87.719408 -375.894092) (xy 87.719408 -376.386344) (xy 87.719795 -376.395534)
			(xy 87.726324 -376.412718) (xy 87.732108 -376.419872) (xy 87.753976 -376.445534) (xy 87.792064 -376.501169)
			(xy 87.823214 -376.560966) (xy 87.846977 -376.624063) (xy 87.863012 -376.689553) (xy 87.871088 -376.756491)
			(xy 87.871087 -376.823915) (xy 117.548863 -376.823915) (xy 117.548863 -376.756491) (xy 117.556939 -376.689552)
			(xy 117.572976 -376.624062) (xy 117.596742 -376.560965) (xy 117.627895 -376.50117) (xy 117.665986 -376.445536)
			(xy 117.687852 -376.419872) (xy 117.693649 -376.412728) (xy 117.700162 -376.395536) (xy 117.700552 -376.386344)
			(xy 117.700552 -375.894092) (xy 117.700134 -375.884906) (xy 117.693625 -375.867722) (xy 117.687852 -375.860564)
			(xy 117.666018 -375.834874) (xy 117.627925 -375.779244) (xy 117.59677 -375.719452) (xy 117.573001 -375.656358)
			(xy 117.556962 -375.590871) (xy 117.548883 -375.523935) (xy 117.54888 -375.456513) (xy 117.556953 -375.389576)
			(xy 117.572987 -375.324088) (xy 117.59675 -375.260992) (xy 117.6279 -375.201197) (xy 117.665988 -375.145564)
			(xy 117.687852 -375.1199) (xy 117.693638 -375.112747) (xy 117.700157 -375.095562) (xy 117.700552 -375.086372)
			(xy 117.700552 -374.928638) (xy 117.701058 -374.918512) (xy 117.708776 -374.89979) (xy 117.723056 -374.885432)
			(xy 117.741737 -374.877613) (xy 117.75186 -374.877076) (xy 118.46814 -374.877076) (xy 118.478294 -374.877488)
			(xy 118.497042 -374.885293) (xy 118.511363 -374.899691) (xy 118.519066 -374.918482) (xy 118.519448 -374.928638)
			(xy 118.519448 -375.086372) (xy 118.519883 -375.095556) (xy 118.526381 -375.11274) (xy 118.532148 -375.1199)
			(xy 118.554045 -375.145538) (xy 118.592136 -375.201176) (xy 118.623289 -375.260975) (xy 118.647053 -375.324075)
			(xy 118.663088 -375.389568) (xy 118.671162 -375.45651) (xy 118.671159 -375.523938) (xy 118.66308 -375.590879)
			(xy 118.647039 -375.656371) (xy 118.623269 -375.719469) (xy 118.592112 -375.779266) (xy 118.554016 -375.8349)
			(xy 118.532148 -375.860564) (xy 118.526335 -375.867698) (xy 118.519832 -375.884897) (xy 118.519448 -375.894092)
			(xy 118.519448 -376.386344) (xy 118.519849 -376.395532) (xy 118.52637 -376.412715) (xy 118.532148 -376.419872)
			(xy 118.554018 -376.445533) (xy 118.59211 -376.501167) (xy 118.623263 -376.560963) (xy 118.647029 -376.624061)
			(xy 118.663066 -376.689551) (xy 118.671143 -376.75649) (xy 118.671143 -376.756551) (xy 121.949182 -376.756551)
			(xy 121.957226 -376.689728) (xy 121.973199 -376.624346) (xy 121.996871 -376.561342) (xy 122.027904 -376.501618)
			(xy 122.065852 -376.446032) (xy 122.08764 -376.42038) (xy 122.093433 -376.413232) (xy 122.099949 -376.396044)
			(xy 122.10034 -376.386852) (xy 122.10034 -375.893584) (xy 122.099929 -375.884397) (xy 122.093415 -375.867213)
			(xy 122.08764 -375.860056) (xy 122.065884 -375.834378) (xy 122.027934 -375.778795) (xy 121.996899 -375.719075)
			(xy 121.973225 -375.656074) (xy 121.95725 -375.590695) (xy 121.949203 -375.523875) (xy 121.9492 -375.456573)
			(xy 121.957241 -375.389752) (xy 121.973211 -375.324372) (xy 121.99688 -375.261369) (xy 122.027909 -375.201646)
			(xy 122.065854 -375.14606) (xy 122.08764 -375.120408) (xy 122.093421 -375.113252) (xy 122.099944 -375.09607)
			(xy 122.10034 -375.08688) (xy 122.10034 -374.928638) (xy 122.100795 -374.918469) (xy 122.108568 -374.899674)
			(xy 122.122944 -374.885288) (xy 122.141733 -374.877502) (xy 122.151902 -374.877076) (xy 122.868182 -374.877076)
			(xy 122.878357 -374.877479) (xy 122.897159 -374.885265) (xy 122.911546 -374.899658) (xy 122.919325 -374.918463)
			(xy 122.919744 -374.928638) (xy 122.919744 -375.08688) (xy 122.920176 -375.096065) (xy 122.926676 -375.113249)
			(xy 122.932444 -375.120408) (xy 122.954264 -375.146034) (xy 122.992213 -375.201624) (xy 123.023246 -375.261351)
			(xy 123.046917 -375.324359) (xy 123.062889 -375.389744) (xy 123.070931 -375.45657) (xy 123.070928 -375.523878)
			(xy 123.06288 -375.590703) (xy 123.046903 -375.656087) (xy 123.023226 -375.719093) (xy 122.992188 -375.778818)
			(xy 122.954234 -375.834404) (xy 122.932444 -375.860056) (xy 122.926634 -375.867192) (xy 122.920129 -375.88439)
			(xy 122.919744 -375.893584) (xy 122.919744 -376.386852) (xy 122.92019 -376.396035) (xy 122.92668 -376.413219)
			(xy 122.932444 -376.42038) (xy 122.954236 -376.446029) (xy 122.992186 -376.501615) (xy 123.02322 -376.561339)
			(xy 123.046893 -376.624344) (xy 123.062866 -376.689727) (xy 123.07091 -376.75655) (xy 123.07091 -376.823856)
			(xy 123.070903 -376.823915) (xy 126.348951 -376.823915) (xy 126.348951 -376.756491) (xy 126.357027 -376.689552)
			(xy 126.373063 -376.624063) (xy 126.396828 -376.560966) (xy 126.42798 -376.50117) (xy 126.466071 -376.445537)
			(xy 126.487936 -376.419872) (xy 126.493732 -376.412726) (xy 126.500246 -376.395536) (xy 126.500636 -376.386344)
			(xy 126.500636 -375.894092) (xy 126.500222 -375.884905) (xy 126.49371 -375.867721) (xy 126.487936 -375.860564)
			(xy 126.466102 -375.834873) (xy 126.42801 -375.779243) (xy 126.396856 -375.719451) (xy 126.373088 -375.656357)
			(xy 126.35705 -375.590871) (xy 126.348971 -375.523935) (xy 126.348968 -375.456513) (xy 126.357041 -375.389576)
			(xy 126.373074 -375.324089) (xy 126.396836 -375.260993) (xy 126.427985 -375.201198) (xy 126.466073 -375.145565)
			(xy 126.487936 -375.1199) (xy 126.49372 -375.112746) (xy 126.500241 -375.095562) (xy 126.500636 -375.086372)
			(xy 126.500636 -374.928638) (xy 126.501158 -374.918514) (xy 126.508872 -374.899795) (xy 126.523148 -374.885437)
			(xy 126.541823 -374.877616) (xy 126.551944 -374.877076) (xy 127.268224 -374.877076) (xy 127.278377 -374.877501)
			(xy 127.297125 -374.8853) (xy 127.311447 -374.899695) (xy 127.31915 -374.918483) (xy 127.319532 -374.928638)
			(xy 127.319532 -375.086372) (xy 127.319971 -375.095556) (xy 127.326466 -375.11274) (xy 127.332232 -375.1199)
			(xy 127.354126 -375.14554) (xy 127.392212 -375.201179) (xy 127.423359 -375.260979) (xy 127.44712 -375.324079)
			(xy 127.463153 -375.389571) (xy 127.471226 -375.456511) (xy 127.471223 -375.523937) (xy 127.463144 -375.590877)
			(xy 127.447106 -375.656367) (xy 127.42334 -375.719465) (xy 127.392187 -375.779263) (xy 127.354097 -375.834898)
			(xy 127.332232 -375.860564) (xy 127.326417 -375.867696) (xy 127.319915 -375.884897) (xy 127.319532 -375.894092)
			(xy 127.319532 -376.386344) (xy 127.319936 -376.395532) (xy 127.326456 -376.412715) (xy 127.332232 -376.419872)
			(xy 127.354099 -376.445535) (xy 127.392185 -376.50117) (xy 127.423334 -376.560967) (xy 127.447097 -376.624064)
			(xy 127.463131 -376.689553) (xy 127.471206 -376.756491) (xy 127.471206 -376.756551) (xy 130.74927 -376.756551)
			(xy 130.757314 -376.689729) (xy 130.773286 -376.624347) (xy 130.796958 -376.561343) (xy 130.827989 -376.501619)
			(xy 130.865937 -376.446032) (xy 130.887724 -376.42038) (xy 130.893514 -376.413231) (xy 130.900032 -376.396043)
			(xy 130.900424 -376.386852) (xy 130.900424 -375.893584) (xy 130.900016 -375.884397) (xy 130.8935 -375.867213)
			(xy 130.887724 -375.860056) (xy 130.865968 -375.834378) (xy 130.82802 -375.778795) (xy 130.796986 -375.719074)
			(xy 130.773312 -375.656073) (xy 130.757337 -375.590695) (xy 130.749291 -375.523875) (xy 130.749288 -375.456573)
			(xy 130.757329 -375.389753) (xy 130.773298 -375.324373) (xy 130.796966 -375.26137) (xy 130.827995 -375.201647)
			(xy 130.865939 -375.146061) (xy 130.887724 -375.120408) (xy 130.893502 -375.11325) (xy 130.900027 -375.096069)
			(xy 130.900424 -375.08688) (xy 130.900424 -374.928638) (xy 130.900895 -374.918471) (xy 130.908665 -374.899679)
			(xy 130.923036 -374.885294) (xy 130.941819 -374.877505) (xy 130.951986 -374.877076) (xy 131.668266 -374.877076)
			(xy 131.67844 -374.877493) (xy 131.697241 -374.885274) (xy 131.711629 -374.899662) (xy 131.719408 -374.918464)
			(xy 131.719828 -374.928638) (xy 131.719828 -375.08688) (xy 131.720241 -375.096067) (xy 131.726752 -375.113252)
			(xy 131.732528 -375.120408) (xy 131.754348 -375.146034) (xy 131.792298 -375.201623) (xy 131.823332 -375.26135)
			(xy 131.847005 -375.324358) (xy 131.862976 -375.389744) (xy 131.871018 -375.45657) (xy 131.871016 -375.523878)
			(xy 131.862968 -375.590704) (xy 131.84699 -375.656088) (xy 131.823313 -375.719094) (xy 131.792274 -375.778818)
			(xy 131.754319 -375.834404) (xy 131.732528 -375.860056) (xy 131.726716 -375.86719) (xy 131.720213 -375.884389)
			(xy 131.719828 -375.893584) (xy 131.719828 -376.386852) (xy 131.720255 -376.396037) (xy 131.726756 -376.413222)
			(xy 131.732528 -376.42038) (xy 131.754321 -376.446029) (xy 131.792271 -376.501615) (xy 131.823306 -376.561338)
			(xy 131.84698 -376.624344) (xy 131.862954 -376.689727) (xy 131.870991 -376.756492) (xy 161.548796 -376.756492)
			(xy 161.556871 -376.689554) (xy 161.572905 -376.624066) (xy 161.596667 -376.560969) (xy 161.627816 -376.501173)
			(xy 161.665902 -376.445538) (xy 161.687764 -376.419872) (xy 161.693563 -376.412729) (xy 161.700074 -376.395536)
			(xy 161.700464 -376.386344) (xy 161.700464 -375.894092) (xy 161.700043 -375.884906) (xy 161.693535 -375.867723)
			(xy 161.687764 -375.860564) (xy 161.665933 -375.834872) (xy 161.627845 -375.779241) (xy 161.596695 -375.719448)
			(xy 161.572931 -375.656354) (xy 161.556894 -375.590869) (xy 161.548816 -375.523934) (xy 161.548814 -375.456514)
			(xy 161.556886 -375.389578) (xy 161.572917 -375.324092) (xy 161.596676 -375.260996) (xy 161.627821 -375.201201)
			(xy 161.665903 -375.145566) (xy 161.687764 -375.1199) (xy 161.693551 -375.112748) (xy 161.70007 -375.095562)
			(xy 161.700464 -375.086372) (xy 161.700464 -374.928638) (xy 161.700959 -374.918511) (xy 161.708678 -374.899786)
			(xy 161.722963 -374.885428) (xy 161.741647 -374.877611) (xy 161.751772 -374.877076) (xy 162.468052 -374.877076)
			(xy 162.478168 -374.877555) (xy 162.496866 -374.885283) (xy 162.511181 -374.89958) (xy 162.518933 -374.918268)
			(xy 162.51936 -374.928384) (xy 162.51936 -375.086372) (xy 162.519793 -375.095557) (xy 162.526292 -375.112741)
			(xy 162.53206 -375.1199) (xy 162.553957 -375.145539) (xy 162.592047 -375.201176) (xy 162.623199 -375.260976)
			(xy 162.646963 -375.324076) (xy 162.662997 -375.389569) (xy 162.671071 -375.456511) (xy 162.671068 -375.523938)
			(xy 162.662989 -375.590879) (xy 162.646949 -375.65637) (xy 162.623179 -375.719468) (xy 162.592022 -375.779265)
			(xy 162.553927 -375.834899) (xy 162.53206 -375.860564) (xy 162.526249 -375.867699) (xy 162.519744 -375.884897)
			(xy 162.51936 -375.894092) (xy 162.51936 -376.386344) (xy 162.519758 -376.395532) (xy 162.526281 -376.412716)
			(xy 162.53206 -376.419872) (xy 162.553929 -376.445533) (xy 162.592021 -376.501167) (xy 162.623173 -376.560964)
			(xy 162.646939 -376.624061) (xy 162.662975 -376.689551) (xy 162.671052 -376.756491) (xy 162.671051 -376.823855)
			(xy 165.949092 -376.823855) (xy 165.949092 -376.756551) (xy 165.957136 -376.689728) (xy 165.973109 -376.624346)
			(xy 165.996782 -376.561342) (xy 166.027815 -376.501618) (xy 166.065764 -376.446032) (xy 166.087552 -376.42038)
			(xy 166.093346 -376.413233) (xy 166.099861 -376.396044) (xy 166.100252 -376.386852) (xy 166.100252 -375.893584)
			(xy 166.099838 -375.884397) (xy 166.093326 -375.867214) (xy 166.087552 -375.860056) (xy 166.065795 -375.834378)
			(xy 166.027845 -375.778796) (xy 165.996809 -375.719076) (xy 165.973134 -375.656075) (xy 165.957159 -375.590695)
			(xy 165.949112 -375.523875) (xy 165.949109 -375.456573) (xy 165.95715 -375.389752) (xy 165.97312 -375.324371)
			(xy 165.99679 -375.261368) (xy 166.02782 -375.201646) (xy 166.065766 -375.14606) (xy 166.087552 -375.120408)
			(xy 166.093334 -375.113253) (xy 166.099856 -375.09607) (xy 166.100252 -375.08688) (xy 166.100252 -374.928638)
			(xy 166.100695 -374.918467) (xy 166.10847 -374.899671) (xy 166.12285 -374.885284) (xy 166.141643 -374.8775)
			(xy 166.151814 -374.877076) (xy 166.868094 -374.877076) (xy 166.87827 -374.87747) (xy 166.897072 -374.88526)
			(xy 166.911458 -374.899655) (xy 166.919237 -374.918462) (xy 166.919656 -374.928638) (xy 166.919656 -375.08688)
			(xy 166.920085 -375.096065) (xy 166.926587 -375.113249) (xy 166.932356 -375.120408) (xy 166.954175 -375.146034)
			(xy 166.992124 -375.201624) (xy 167.023156 -375.261351) (xy 167.046827 -375.324359) (xy 167.062798 -375.389745)
			(xy 167.07084 -375.45657) (xy 167.070837 -375.523878) (xy 167.062789 -375.590703) (xy 167.046813 -375.656087)
			(xy 167.023136 -375.719093) (xy 166.992099 -375.778817) (xy 166.954146 -375.834404) (xy 166.932356 -375.860056)
			(xy 166.926548 -375.867193) (xy 166.920041 -375.88439) (xy 166.919656 -375.893584) (xy 166.919656 -376.386852)
			(xy 166.920099 -376.396035) (xy 166.926591 -376.41322) (xy 166.932356 -376.42038) (xy 166.954148 -376.446029)
			(xy 166.992097 -376.501616) (xy 167.02313 -376.56134) (xy 167.046803 -376.624345) (xy 167.062776 -376.689727)
			(xy 167.07082 -376.75655) (xy 167.07082 -376.823856) (xy 167.070813 -376.823915) (xy 170.34886 -376.823915)
			(xy 170.34886 -376.756491) (xy 170.356936 -376.689552) (xy 170.372972 -376.624063) (xy 170.396738 -376.560966)
			(xy 170.427891 -376.50117) (xy 170.465983 -376.445536) (xy 170.487848 -376.419872) (xy 170.493645 -376.412727)
			(xy 170.500158 -376.395536) (xy 170.500548 -376.386344) (xy 170.500548 -375.894092) (xy 170.500131 -375.884906)
			(xy 170.493621 -375.867722) (xy 170.487848 -375.860564) (xy 170.466014 -375.834874) (xy 170.427921 -375.779244)
			(xy 170.396766 -375.719452) (xy 170.372998 -375.656358) (xy 170.356959 -375.590871) (xy 170.34888 -375.523935)
			(xy 170.348877 -375.456513) (xy 170.35695 -375.389576) (xy 170.372984 -375.324088) (xy 170.396747 -375.260992)
			(xy 170.427896 -375.201197) (xy 170.465984 -375.145564) (xy 170.487848 -375.1199) (xy 170.493633 -375.112747)
			(xy 170.500153 -375.095562) (xy 170.500548 -375.086372) (xy 170.500548 -374.928638) (xy 170.501058 -374.918513)
			(xy 170.508775 -374.899791) (xy 170.523054 -374.885433) (xy 170.541734 -374.877614) (xy 170.551856 -374.877076)
			(xy 171.268136 -374.877076) (xy 171.278289 -374.877492) (xy 171.297038 -374.885295) (xy 171.311359 -374.899692)
			(xy 171.319062 -374.918482) (xy 171.319444 -374.928638) (xy 171.319444 -375.086372) (xy 171.31988 -375.095556)
			(xy 171.326377 -375.11274) (xy 171.332144 -375.1199) (xy 171.354041 -375.145538) (xy 171.392133 -375.201175)
			(xy 171.423285 -375.260975) (xy 171.44705 -375.324075) (xy 171.463085 -375.389568) (xy 171.471159 -375.45651)
			(xy 171.471156 -375.523938) (xy 171.463076 -375.590879) (xy 171.447036 -375.656371) (xy 171.423266 -375.719469)
			(xy 171.392108 -375.779266) (xy 171.354012 -375.8349) (xy 171.332144 -375.860564) (xy 171.326331 -375.867697)
			(xy 171.319828 -375.884897) (xy 171.319444 -375.894092) (xy 171.319444 -376.386344) (xy 171.319845 -376.395532)
			(xy 171.326366 -376.412716) (xy 171.332144 -376.419872) (xy 171.354014 -376.445533) (xy 171.392106 -376.501167)
			(xy 171.42326 -376.560963) (xy 171.447026 -376.624061) (xy 171.463063 -376.689551) (xy 171.47114 -376.75649)
			(xy 171.47114 -376.756551) (xy 174.749179 -376.756551) (xy 174.757223 -376.689728) (xy 174.773195 -376.624346)
			(xy 174.796868 -376.561342) (xy 174.8279 -376.501619) (xy 174.865848 -376.446032) (xy 174.887636 -376.42038)
			(xy 174.893428 -376.413232) (xy 174.899945 -376.396043) (xy 174.900336 -376.386852) (xy 174.900336 -375.893584)
			(xy 174.899926 -375.884397) (xy 174.893411 -375.867213) (xy 174.887636 -375.860056) (xy 174.86588 -375.834378)
			(xy 174.82793 -375.778795) (xy 174.796896 -375.719075) (xy 174.773222 -375.656074) (xy 174.757246 -375.590695)
			(xy 174.7492 -375.523875) (xy 174.749197 -375.456573) (xy 174.757238 -375.389752) (xy 174.773207 -375.324372)
			(xy 174.796876 -375.261369) (xy 174.827906 -375.201646) (xy 174.865851 -375.14606) (xy 174.887636 -375.120408)
			(xy 174.893416 -375.113251) (xy 174.89994 -375.096069) (xy 174.900336 -375.08688) (xy 174.900336 -374.928638)
			(xy 174.900795 -374.918469) (xy 174.908567 -374.899676) (xy 174.922942 -374.88529) (xy 174.941729 -374.877503)
			(xy 174.951898 -374.877076) (xy 175.668178 -374.877076) (xy 175.678353 -374.877483) (xy 175.697154 -374.885268)
			(xy 175.711541 -374.899659) (xy 175.71932 -374.918463) (xy 175.71974 -374.928638) (xy 175.71974 -375.08688)
			(xy 175.720173 -375.096064) (xy 175.726672 -375.113248) (xy 175.73244 -375.120408) (xy 175.75426 -375.146034)
			(xy 175.792209 -375.201624) (xy 175.823242 -375.261351) (xy 175.846914 -375.324359) (xy 175.862886 -375.389744)
			(xy 175.870928 -375.45657) (xy 175.870925 -375.523878) (xy 175.862877 -375.590703) (xy 175.8469 -375.656087)
			(xy 175.823223 -375.719093) (xy 175.792185 -375.778818) (xy 175.754231 -375.834404) (xy 175.73244 -375.860056)
			(xy 175.72663 -375.867191) (xy 175.720125 -375.88439) (xy 175.71974 -375.893584) (xy 175.71974 -376.386852)
			(xy 175.720186 -376.396035) (xy 175.726676 -376.413219) (xy 175.73244 -376.42038) (xy 175.754232 -376.446029)
			(xy 175.792182 -376.501615) (xy 175.823216 -376.561339) (xy 175.84689 -376.624344) (xy 175.862863 -376.689727)
			(xy 175.870907 -376.75655) (xy 175.870907 -376.823856) (xy 175.862862 -376.890679) (xy 175.846888 -376.956062)
			(xy 175.823214 -377.019066) (xy 175.792179 -377.07879) (xy 175.754228 -377.134376) (xy 175.73244 -377.160028)
			(xy 175.726642 -377.167172) (xy 175.72013 -377.184364) (xy 175.71974 -377.193556) (xy 175.71974 -377.35129)
			(xy 175.719328 -377.361464) (xy 175.711542 -377.380262) (xy 175.697152 -377.394648) (xy 175.678352 -377.40243)
			(xy 175.668178 -377.402852) (xy 174.951898 -377.402852) (xy 174.941725 -377.402438) (xy 174.922928 -377.39465)
			(xy 174.908543 -377.380262) (xy 174.90076 -377.361463) (xy 174.900336 -377.35129) (xy 174.900336 -377.193556)
			(xy 174.899939 -377.184368) (xy 174.893415 -377.167184) (xy 174.887636 -377.160028) (xy 174.865852 -377.134373)
			(xy 174.827903 -377.078787) (xy 174.79687 -377.019063) (xy 174.773197 -376.956059) (xy 174.757224 -376.890678)
			(xy 174.74918 -376.823855) (xy 174.749179 -376.756551) (xy 171.47114 -376.756551) (xy 171.471139 -376.823916)
			(xy 171.463062 -376.890855) (xy 171.447024 -376.956345) (xy 171.423257 -377.019442) (xy 171.392103 -377.079238)
			(xy 171.35401 -377.134872) (xy 171.332144 -377.160536) (xy 171.326343 -377.167678) (xy 171.319832 -377.184871)
			(xy 171.319444 -377.194064) (xy 171.319444 -377.35129) (xy 171.318965 -377.361418) (xy 171.311237 -377.380142)
			(xy 171.296948 -377.394499) (xy 171.278262 -377.402316) (xy 171.268136 -377.402852) (xy 170.551856 -377.402852)
			(xy 170.541706 -377.402415) (xy 170.522962 -377.394615) (xy 170.508642 -377.380224) (xy 170.500935 -377.361442)
			(xy 170.500548 -377.35129) (xy 170.500548 -377.194064) (xy 170.500144 -377.184876) (xy 170.493625 -377.167693)
			(xy 170.487848 -377.160536) (xy 170.465986 -377.134868) (xy 170.427894 -377.079235) (xy 170.396741 -377.01944)
			(xy 170.372974 -376.956343) (xy 170.356937 -376.890854) (xy 170.34886 -376.823915) (xy 167.070813 -376.823915)
			(xy 167.062775 -376.890679) (xy 167.046801 -376.956061) (xy 167.023128 -377.019066) (xy 166.992094 -377.07879)
			(xy 166.954144 -377.134376) (xy 166.932356 -377.160028) (xy 166.92656 -377.167173) (xy 166.920046 -377.184364)
			(xy 166.919656 -377.193556) (xy 166.919656 -377.35129) (xy 166.919228 -377.361462) (xy 166.911445 -377.380257)
			(xy 166.897061 -377.394643) (xy 166.878266 -377.402427) (xy 166.868094 -377.402852) (xy 166.151814 -377.402852)
			(xy 166.141642 -377.402425) (xy 166.122846 -377.394642) (xy 166.10846 -377.380258) (xy 166.100676 -377.361462)
			(xy 166.100252 -377.35129) (xy 166.100252 -377.193556) (xy 166.099851 -377.184368) (xy 166.09333 -377.167185)
			(xy 166.087552 -377.160028) (xy 166.065768 -377.134373) (xy 166.027818 -377.078787) (xy 165.996784 -377.019064)
			(xy 165.97311 -376.95606) (xy 165.957137 -376.890678) (xy 165.949092 -376.823855) (xy 162.671051 -376.823855)
			(xy 162.671051 -376.823915) (xy 162.662974 -376.890855) (xy 162.646937 -376.956344) (xy 162.623171 -377.019442)
			(xy 162.592017 -377.079238) (xy 162.553926 -377.134871) (xy 162.53206 -377.160536) (xy 162.526261 -377.167679)
			(xy 162.519749 -377.184871) (xy 162.51936 -377.194064) (xy 162.51936 -377.35129) (xy 162.518865 -377.361416)
			(xy 162.511141 -377.380137) (xy 162.496857 -377.394494) (xy 162.478175 -377.402313) (xy 162.468052 -377.402852)
			(xy 161.751772 -377.402852) (xy 161.741668 -377.402339) (xy 161.722999 -377.394602) (xy 161.708707 -377.380314)
			(xy 161.700964 -377.361648) (xy 161.700464 -377.351544) (xy 161.700464 -377.194064) (xy 161.700057 -377.184877)
			(xy 161.69354 -377.167693) (xy 161.687764 -377.160536) (xy 161.665905 -377.134867) (xy 161.627819 -377.079232)
			(xy 161.59667 -377.019436) (xy 161.572907 -376.95634) (xy 161.556872 -376.890852) (xy 161.548797 -376.823914)
			(xy 161.548796 -376.756492) (xy 131.870991 -376.756492) (xy 131.870998 -376.75655) (xy 131.870998 -376.823856)
			(xy 131.862953 -376.890679) (xy 131.846979 -376.956062) (xy 131.823304 -377.019067) (xy 131.792268 -377.07879)
			(xy 131.754317 -377.134376) (xy 131.732528 -377.160028) (xy 131.726728 -377.167171) (xy 131.720218 -377.184363)
			(xy 131.719828 -377.193556) (xy 131.719828 -377.35129) (xy 131.719427 -377.361465) (xy 131.711639 -377.380266)
			(xy 131.697246 -377.394653) (xy 131.678441 -377.402432) (xy 131.668266 -377.402852) (xy 130.951986 -377.402852)
			(xy 130.941826 -377.402378) (xy 130.923055 -377.394597) (xy 130.90869 -377.380225) (xy 130.900918 -377.36145)
			(xy 130.900424 -377.35129) (xy 130.900424 -377.193556) (xy 130.90003 -377.184367) (xy 130.893504 -377.167183)
			(xy 130.887724 -377.160028) (xy 130.865941 -377.134372) (xy 130.827993 -377.078786) (xy 130.79696 -377.019063)
			(xy 130.773288 -376.956059) (xy 130.757315 -376.890677) (xy 130.749271 -376.823855) (xy 130.74927 -376.756551)
			(xy 127.471206 -376.756551) (xy 127.471205 -376.823915) (xy 127.46313 -376.890853) (xy 127.447095 -376.956342)
			(xy 127.423332 -377.019438) (xy 127.392182 -377.079235) (xy 127.354095 -377.13487) (xy 127.332232 -377.160536)
			(xy 127.326429 -377.167677) (xy 127.31992 -377.184871) (xy 127.319532 -377.194064) (xy 127.319532 -377.35129)
			(xy 127.319064 -377.36142) (xy 127.311335 -377.380146) (xy 127.297042 -377.394503) (xy 127.278351 -377.402318)
			(xy 127.268224 -377.402852) (xy 126.551944 -377.402852) (xy 126.541799 -377.402343) (xy 126.523058 -377.394572)
			(xy 126.508735 -377.380202) (xy 126.501024 -377.361436) (xy 126.500636 -377.35129) (xy 126.500636 -377.194064)
			(xy 126.500235 -377.184876) (xy 126.493714 -377.167692) (xy 126.487936 -377.160536) (xy 126.466075 -377.134868)
			(xy 126.427984 -377.079235) (xy 126.396831 -377.019439) (xy 126.373065 -376.956343) (xy 126.357028 -376.890854)
			(xy 126.348951 -376.823915) (xy 123.070903 -376.823915) (xy 123.062865 -376.890679) (xy 123.046891 -376.956062)
			(xy 123.023217 -377.019066) (xy 122.992183 -377.07879) (xy 122.954232 -377.134376) (xy 122.932444 -377.160028)
			(xy 122.926646 -377.167172) (xy 122.920134 -377.184364) (xy 122.919744 -377.193556) (xy 122.919744 -377.35129)
			(xy 122.919328 -377.361463) (xy 122.911543 -377.380261) (xy 122.897154 -377.394647) (xy 122.878355 -377.402429)
			(xy 122.868182 -377.402852) (xy 122.151902 -377.402852) (xy 122.141729 -377.402434) (xy 122.122933 -377.394648)
			(xy 122.108547 -377.380261) (xy 122.100764 -377.361463) (xy 122.10034 -377.35129) (xy 122.10034 -377.193556)
			(xy 122.099942 -377.184368) (xy 122.093419 -377.167184) (xy 122.08764 -377.160028) (xy 122.065856 -377.134373)
			(xy 122.027907 -377.078787) (xy 121.996873 -377.019064) (xy 121.9732 -376.95606) (xy 121.957227 -376.890678)
			(xy 121.949183 -376.823855) (xy 121.949182 -376.756551) (xy 118.671143 -376.756551) (xy 118.671142 -376.823916)
			(xy 118.663065 -376.890855) (xy 118.647028 -376.956345) (xy 118.623261 -377.019442) (xy 118.592107 -377.079238)
			(xy 118.554014 -377.134872) (xy 118.532148 -377.160536) (xy 118.526347 -377.167678) (xy 118.519836 -377.184871)
			(xy 118.519448 -377.194064) (xy 118.519448 -377.35129) (xy 118.518965 -377.361418) (xy 118.511238 -377.380141)
			(xy 118.496951 -377.394498) (xy 118.478265 -377.402315) (xy 118.46814 -377.402852) (xy 117.75186 -377.402852)
			(xy 117.74171 -377.402412) (xy 117.722967 -377.394613) (xy 117.708647 -377.380223) (xy 117.700939 -377.361442)
			(xy 117.700552 -377.35129) (xy 117.700552 -377.194064) (xy 117.700147 -377.184876) (xy 117.693628 -377.167693)
			(xy 117.687852 -377.160536) (xy 117.66599 -377.134868) (xy 117.627898 -377.079235) (xy 117.596744 -377.01944)
			(xy 117.572977 -376.956343) (xy 117.55694 -376.890854) (xy 117.548863 -376.823915) (xy 87.871087 -376.823915)
			(xy 87.863011 -376.890853) (xy 87.846976 -376.956342) (xy 87.823211 -377.019439) (xy 87.792061 -377.079236)
			(xy 87.753972 -377.134871) (xy 87.732108 -377.160536) (xy 87.726315 -377.167684) (xy 87.719798 -377.184872)
			(xy 87.719408 -377.194064) (xy 87.719408 -377.35129) (xy 87.718867 -377.36141) (xy 87.711151 -377.380122)
			(xy 87.696882 -377.394477) (xy 87.678217 -377.402305) (xy 87.6681 -377.402852) (xy 86.95182 -377.402852)
			(xy 86.941719 -377.4023) (xy 86.923051 -377.394578) (xy 86.908757 -377.380303) (xy 86.901013 -377.361644)
			(xy 86.900512 -377.351544) (xy 86.900512 -377.194064) (xy 86.900117 -377.184875) (xy 86.893592 -377.167691)
			(xy 86.887812 -377.160536) (xy 86.865952 -377.134868) (xy 86.827862 -377.079234) (xy 86.79671 -377.019438)
			(xy 86.772945 -376.956342) (xy 86.756909 -376.890853) (xy 86.748833 -376.823915) (xy 83.470785 -376.823915)
			(xy 83.462747 -376.89068) (xy 83.446772 -376.956063) (xy 83.423097 -377.019067) (xy 83.392061 -377.078791)
			(xy 83.354109 -377.134376) (xy 83.33232 -377.160028) (xy 83.326531 -377.167179) (xy 83.320011 -377.184365)
			(xy 83.31962 -377.193556) (xy 83.31962 -377.35129) (xy 83.319227 -377.361466) (xy 83.311438 -377.380269)
			(xy 83.297042 -377.394655) (xy 83.278234 -377.402433) (xy 83.268058 -377.402852) (xy 82.551778 -377.402852)
			(xy 82.541618 -377.402385) (xy 82.522846 -377.394601) (xy 82.508481 -377.380227) (xy 82.500709 -377.361451)
			(xy 82.500216 -377.35129) (xy 82.500216 -377.193556) (xy 82.499823 -377.184367) (xy 82.493297 -377.167183)
			(xy 82.487516 -377.160028) (xy 82.465733 -377.134372) (xy 82.427785 -377.078786) (xy 82.396753 -377.019063)
			(xy 82.373081 -376.956059) (xy 82.357109 -376.890677) (xy 82.349065 -376.823855) (xy 82.349064 -376.756551)
			(xy 79.071 -376.756551) (xy 79.070999 -376.823915) (xy 79.062924 -376.890853) (xy 79.046888 -376.956342)
			(xy 79.023125 -377.019439) (xy 78.991975 -377.079235) (xy 78.953887 -377.13487) (xy 78.932024 -377.160536)
			(xy 78.926232 -377.167685) (xy 78.919714 -377.184872) (xy 78.919324 -377.194064) (xy 78.919324 -377.35129)
			(xy 78.918864 -377.36142) (xy 78.911133 -377.380148) (xy 78.896838 -377.394506) (xy 78.878144 -377.402319)
			(xy 78.868016 -377.402852) (xy 78.151736 -377.402852) (xy 78.141636 -377.402286) (xy 78.122969 -377.39457)
			(xy 78.108674 -377.380299) (xy 78.100929 -377.361643) (xy 78.100428 -377.351544) (xy 78.100428 -377.194064)
			(xy 78.100029 -377.184876) (xy 78.093507 -377.167692) (xy 78.087728 -377.160536) (xy 78.065867 -377.134868)
			(xy 78.027776 -377.079235) (xy 77.996624 -377.019439) (xy 77.972858 -376.956342) (xy 77.956822 -376.890853)
			(xy 77.948745 -376.823915) (xy 74.670697 -376.823915) (xy 74.662659 -376.890679) (xy 74.646685 -376.956062)
			(xy 74.623011 -377.019067) (xy 74.591976 -377.07879) (xy 74.554025 -377.134376) (xy 74.532236 -377.160028)
			(xy 74.526437 -377.167171) (xy 74.519926 -377.184364) (xy 74.519536 -377.193556) (xy 74.519536 -377.35129)
			(xy 74.519127 -377.361464) (xy 74.511341 -377.380264) (xy 74.49695 -377.39465) (xy 74.478148 -377.402431)
			(xy 74.467974 -377.402852) (xy 73.751694 -377.402852) (xy 73.741521 -377.402441) (xy 73.722724 -377.394652)
			(xy 73.708339 -377.380263) (xy 73.700556 -377.361463) (xy 73.700132 -377.35129) (xy 73.700132 -377.193556)
			(xy 73.699736 -377.184367) (xy 73.693212 -377.167184) (xy 73.687432 -377.160028) (xy 73.665648 -377.134373)
			(xy 73.6277 -377.078786) (xy 73.596667 -377.019063) (xy 73.572994 -376.956059) (xy 73.557021 -376.890677)
			(xy 73.548977 -376.823855) (xy 73.548976 -376.756551) (xy 48.270947 -376.756551) (xy 48.270947 -376.823855)
			(xy 48.262903 -376.890678) (xy 48.24693 -376.95606) (xy 48.223258 -377.019064) (xy 48.192226 -377.078788)
			(xy 48.154279 -377.134375) (xy 48.132492 -377.160028) (xy 48.1267 -377.167176) (xy 48.120183 -377.184365)
			(xy 48.119792 -377.193556) (xy 48.119792 -377.351544) (xy 48.119414 -377.361702) (xy 48.111603 -377.380457)
			(xy 48.097193 -377.394779) (xy 48.07839 -377.402476) (xy 48.06823 -377.402852) (xy 47.35195 -377.402852)
			(xy 47.341825 -377.402332) (xy 47.323104 -377.394619) (xy 47.308746 -377.380343) (xy 47.300926 -377.361666)
			(xy 47.300388 -377.351544) (xy 47.300388 -377.193556) (xy 47.300002 -377.184366) (xy 47.293472 -377.167182)
			(xy 47.287688 -377.160028) (xy 47.265903 -377.134373) (xy 47.227951 -377.078788) (xy 47.196914 -377.019066)
			(xy 47.173239 -376.956061) (xy 47.157265 -376.890679) (xy 47.149219 -376.823856) (xy 43.871178 -376.823856)
			(xy 43.871178 -376.823915) (xy 43.863102 -376.890854) (xy 43.847066 -376.956343) (xy 43.823301 -377.01944)
			(xy 43.79215 -377.079236) (xy 43.75406 -377.134871) (xy 43.732196 -377.160536) (xy 43.726401 -377.167682)
			(xy 43.719886 -377.184872) (xy 43.719496 -377.194064) (xy 43.719496 -377.35129) (xy 43.718966 -377.361412)
			(xy 43.711248 -377.380126) (xy 43.696976 -377.394481) (xy 43.678307 -377.402307) (xy 43.668188 -377.402852)
			(xy 42.951908 -377.402852) (xy 42.941761 -377.402373) (xy 42.923019 -377.39459) (xy 42.908697 -377.380211)
			(xy 42.900988 -377.361439) (xy 42.9006 -377.35129) (xy 42.9006 -377.194064) (xy 42.900207 -377.184875)
			(xy 42.893682 -377.167691) (xy 42.8879 -377.160536) (xy 42.86604 -377.134868) (xy 42.827951 -377.079233)
			(xy 42.7968 -377.019438) (xy 42.773036 -376.956341) (xy 42.757 -376.890853) (xy 42.748924 -376.823915)
			(xy 39.470876 -376.823915) (xy 39.462838 -376.89068) (xy 39.446863 -376.956063) (xy 39.423187 -377.019068)
			(xy 39.39215 -377.078791) (xy 39.354198 -377.134377) (xy 39.332408 -377.160028) (xy 39.326618 -377.167178)
			(xy 39.320099 -377.184365) (xy 39.319708 -377.193556) (xy 39.319708 -377.35129) (xy 39.31916 -377.361441)
			(xy 39.311397 -377.380202) (xy 39.297049 -377.394566) (xy 39.278297 -377.402349) (xy 39.268146 -377.402852)
			(xy 38.551866 -377.402852) (xy 38.541705 -377.402394) (xy 38.522933 -377.394607) (xy 38.508569 -377.38023)
			(xy 38.500797 -377.361452) (xy 38.500304 -377.35129) (xy 38.500304 -377.193556) (xy 38.499914 -377.184367)
			(xy 38.493386 -377.167183) (xy 38.487604 -377.160028) (xy 38.465821 -377.134372) (xy 38.427875 -377.078785)
			(xy 38.396843 -377.019062) (xy 38.373172 -376.956058) (xy 38.357199 -376.890677) (xy 38.349156 -376.823855)
			(xy 38.349155 -376.756551) (xy 35.071091 -376.756551) (xy 35.07109 -376.823915) (xy 35.063014 -376.890853)
			(xy 35.046979 -376.956342) (xy 35.023215 -377.019439) (xy 34.992064 -377.079236) (xy 34.953976 -377.134871)
			(xy 34.932112 -377.160536) (xy 34.926319 -377.167684) (xy 34.919802 -377.184872) (xy 34.919412 -377.194064)
			(xy 34.919412 -377.35129) (xy 34.918867 -377.36141) (xy 34.911152 -377.380121) (xy 34.896884 -377.394476)
			(xy 34.878221 -377.402304) (xy 34.868104 -377.402852) (xy 34.151824 -377.402852) (xy 34.141678 -377.40236)
			(xy 34.122936 -377.394582) (xy 34.108614 -377.380208) (xy 34.100904 -377.361438) (xy 34.100516 -377.35129)
			(xy 34.100516 -377.194064) (xy 34.10012 -377.184875) (xy 34.093596 -377.167691) (xy 34.087816 -377.160536)
			(xy 34.065955 -377.134868) (xy 34.027866 -377.079234) (xy 33.996714 -377.019438) (xy 33.972949 -376.956342)
			(xy 33.956912 -376.890853) (xy 33.948836 -376.823915) (xy 30.670788 -376.823915) (xy 30.66275 -376.89068)
			(xy 30.646775 -376.956062) (xy 30.6231 -377.019067) (xy 30.592065 -377.078791) (xy 30.554113 -377.134376)
			(xy 30.532324 -377.160028) (xy 30.526536 -377.167179) (xy 30.520015 -377.184365) (xy 30.519624 -377.193556)
			(xy 30.519624 -377.35129) (xy 30.519227 -377.361466) (xy 30.511438 -377.380267) (xy 30.497044 -377.394654)
			(xy 30.478238 -377.402433) (xy 30.468062 -377.402852) (xy 29.751782 -377.402852) (xy 29.741622 -377.402381)
			(xy 29.72285 -377.394599) (xy 29.708485 -377.380226) (xy 29.700713 -377.36145) (xy 29.70022 -377.35129)
			(xy 29.70022 -377.193556) (xy 29.699827 -377.184367) (xy 29.693301 -377.167183) (xy 29.68752 -377.160028)
			(xy 29.665737 -377.134372) (xy 29.627789 -377.078786) (xy 29.596757 -377.019063) (xy 29.573084 -376.956059)
			(xy 29.557112 -376.890677) (xy 29.549068 -376.823855) (xy 29.549067 -376.756551) (xy 0.508 -376.756551)
			(xy 0.508 -378.323793) (xy 27.348888 -378.323793) (xy 27.34889 -378.256368) (xy 27.356968 -378.189428)
			(xy 27.373006 -378.123938) (xy 27.396772 -378.06084) (xy 27.427925 -378.001043) (xy 27.466015 -377.945408)
			(xy 27.48788 -377.919742) (xy 27.493681 -377.9126) (xy 27.500194 -377.895407) (xy 27.50058 -377.886214)
			(xy 27.50058 -377.728734) (xy 27.501056 -377.718605) (xy 27.50878 -377.699877) (xy 27.52307 -377.685518)
			(xy 27.541761 -377.677705) (xy 27.551888 -377.677172) (xy 28.268168 -377.677172) (xy 28.278285 -377.677641)
			(xy 28.296983 -377.685374) (xy 28.311297 -377.699674) (xy 28.319048 -377.718363) (xy 28.319476 -377.72848)
			(xy 28.319476 -377.886214) (xy 28.319885 -377.895401) (xy 28.3264 -377.912585) (xy 28.332176 -377.919742)
			(xy 28.354015 -377.945428) (xy 28.392106 -378.001059) (xy 28.42326 -378.060852) (xy 28.447026 -378.123946)
			(xy 28.463064 -378.189433) (xy 28.471143 -378.256369) (xy 28.471145 -378.323734) (xy 31.749183 -378.323734)
			(xy 31.749186 -378.256427) (xy 31.757233 -378.189602) (xy 31.773209 -378.124218) (xy 31.796886 -378.061212)
			(xy 31.827924 -378.001488) (xy 31.865878 -377.945902) (xy 31.887668 -377.92025) (xy 31.893477 -377.913114)
			(xy 31.899982 -377.895916) (xy 31.900368 -377.886722) (xy 31.900368 -377.728734) (xy 31.900793 -377.718561)
			(xy 31.908572 -377.699761) (xy 31.922958 -377.685374) (xy 31.941757 -377.677593) (xy 31.95193 -377.677172)
			(xy 32.66821 -377.677172) (xy 32.678386 -377.677557) (xy 32.697188 -377.685351) (xy 32.711574 -377.699749)
			(xy 32.719352 -377.718557) (xy 32.719772 -377.728734) (xy 32.719772 -377.886722) (xy 32.720178 -377.89591)
			(xy 32.726695 -377.913094) (xy 32.732472 -377.92025) (xy 32.754234 -377.945924) (xy 32.792182 -378.001507)
			(xy 32.823216 -378.061228) (xy 32.84689 -378.12423) (xy 32.862864 -378.189609) (xy 32.87091 -378.256429)
			(xy 32.870913 -378.323732) (xy 32.870906 -378.323793) (xy 36.148976 -378.323793) (xy 36.148978 -378.256368)
			(xy 36.157056 -378.189429) (xy 36.173093 -378.123939) (xy 36.196859 -378.060841) (xy 36.22801 -378.001044)
			(xy 36.2661 -377.945408) (xy 36.287964 -377.919742) (xy 36.293775 -377.912608) (xy 36.300279 -377.895409)
			(xy 36.300664 -377.886214) (xy 36.300664 -377.728734) (xy 36.301155 -377.718607) (xy 36.308876 -377.699882)
			(xy 36.323162 -377.685523) (xy 36.341847 -377.677707) (xy 36.351972 -377.677172) (xy 37.068252 -377.677172)
			(xy 37.0784 -377.67766) (xy 37.097145 -377.685435) (xy 37.11147 -377.699811) (xy 37.119176 -377.718585)
			(xy 37.11956 -377.728734) (xy 37.11956 -377.886214) (xy 37.119972 -377.895401) (xy 37.126485 -377.912585)
			(xy 37.13226 -377.919742) (xy 37.1541 -377.945428) (xy 37.192192 -378.001058) (xy 37.223346 -378.060851)
			(xy 37.247113 -378.123946) (xy 37.263152 -378.189433) (xy 37.27123 -378.256369) (xy 37.271233 -378.323792)
			(xy 37.271233 -378.323794) (xy 40.548742 -378.323794) (xy 40.548744 -378.256367) (xy 40.556824 -378.189426)
			(xy 40.572863 -378.123935) (xy 40.596633 -378.060837) (xy 40.627789 -378.00104) (xy 40.665885 -377.945406)
			(xy 40.687752 -377.919742) (xy 40.693562 -377.912607) (xy 40.700067 -377.895408) (xy 40.700452 -377.886214)
			(xy 40.700452 -377.728734) (xy 40.700955 -377.718608) (xy 40.708674 -377.699885) (xy 40.722955 -377.685528)
			(xy 40.741637 -377.677709) (xy 40.75176 -377.677172) (xy 41.46804 -377.677172) (xy 41.478193 -377.677588)
			(xy 41.496941 -377.685392) (xy 41.511262 -377.699789) (xy 41.518965 -377.718579) (xy 41.519348 -377.728734)
			(xy 41.519348 -377.886214) (xy 41.519763 -377.8954) (xy 41.526275 -377.912584) (xy 41.532048 -377.919742)
			(xy 41.553888 -377.945427) (xy 41.591981 -378.001058) (xy 41.623136 -378.060851) (xy 41.646904 -378.123945)
			(xy 41.662943 -378.189432) (xy 41.671021 -378.256369) (xy 41.671024 -378.323792) (xy 41.671024 -378.323793)
			(xy 71.348797 -378.323793) (xy 71.348799 -378.256368) (xy 71.356877 -378.189428) (xy 71.372915 -378.123937)
			(xy 71.396682 -378.060839) (xy 71.427835 -378.001042) (xy 71.465927 -377.945407) (xy 71.487792 -377.919742)
			(xy 71.493595 -377.912601) (xy 71.500106 -377.895407) (xy 71.500492 -377.886214) (xy 71.500492 -377.728734)
			(xy 71.501053 -377.718615) (xy 71.508761 -377.699904) (xy 71.523024 -377.685548) (xy 71.541685 -377.67772)
			(xy 71.5518 -377.677172) (xy 72.26808 -377.677172) (xy 72.278229 -377.677637) (xy 72.296976 -377.685421)
			(xy 72.311299 -377.699804) (xy 72.319005 -377.718583) (xy 72.319388 -377.728734) (xy 72.319388 -377.886214)
			(xy 72.319794 -377.895402) (xy 72.326311 -377.912586) (xy 72.332088 -377.919742) (xy 72.353927 -377.945428)
			(xy 72.392017 -378.001059) (xy 72.42317 -378.060853) (xy 72.446936 -378.123947) (xy 72.462973 -378.189433)
			(xy 72.471052 -378.25637) (xy 72.471054 -378.323734) (xy 75.749092 -378.323734) (xy 75.749095 -378.256427)
			(xy 75.757142 -378.189601) (xy 75.773119 -378.124217) (xy 75.796796 -378.061212) (xy 75.827835 -378.001488)
			(xy 75.86579 -377.945902) (xy 75.88758 -377.92025) (xy 75.893378 -377.913106) (xy 75.899892 -377.895915)
			(xy 75.90028 -377.886722) (xy 75.90028 -377.728734) (xy 75.900693 -377.718559) (xy 75.908474 -377.699757)
			(xy 75.922864 -377.68537) (xy 75.941667 -377.677591) (xy 75.951842 -377.677172) (xy 76.668122 -377.677172)
			(xy 76.678299 -377.677547) (xy 76.697101 -377.685345) (xy 76.711486 -377.699746) (xy 76.719264 -377.718556)
			(xy 76.719684 -377.728734) (xy 76.719684 -377.886722) (xy 76.720087 -377.89591) (xy 76.726606 -377.913094)
			(xy 76.732384 -377.92025) (xy 76.754146 -377.945923) (xy 76.792094 -378.001507) (xy 76.823127 -378.061228)
			(xy 76.8468 -378.12423) (xy 76.862774 -378.189609) (xy 76.87082 -378.256429) (xy 76.870822 -378.323732)
			(xy 76.870815 -378.323793) (xy 80.148885 -378.323793) (xy 80.148887 -378.256368) (xy 80.156965 -378.189428)
			(xy 80.173003 -378.123938) (xy 80.196769 -378.06084) (xy 80.227921 -378.001043) (xy 80.266011 -377.945408)
			(xy 80.287876 -377.919742) (xy 80.293677 -377.9126) (xy 80.30019 -377.895407) (xy 80.300576 -377.886214)
			(xy 80.300576 -377.728734) (xy 80.301056 -377.718605) (xy 80.308779 -377.699878) (xy 80.323068 -377.685519)
			(xy 80.341758 -377.677705) (xy 80.351884 -377.677172) (xy 81.068164 -377.677172) (xy 81.078281 -377.677645)
			(xy 81.096978 -377.685376) (xy 81.111293 -377.699675) (xy 81.119044 -377.718364) (xy 81.119472 -377.72848)
			(xy 81.119472 -377.886214) (xy 81.119882 -377.895401) (xy 81.126396 -377.912585) (xy 81.132172 -377.919742)
			(xy 81.154011 -377.945428) (xy 81.192103 -378.001059) (xy 81.223256 -378.060852) (xy 81.247023 -378.123946)
			(xy 81.263061 -378.189433) (xy 81.27114 -378.256369) (xy 81.271142 -378.323792) (xy 81.271142 -378.323793)
			(xy 84.548676 -378.323793) (xy 84.548678 -378.256368) (xy 84.556756 -378.189429) (xy 84.572793 -378.123939)
			(xy 84.596559 -378.060841) (xy 84.62771 -378.001044) (xy 84.6658 -377.945408) (xy 84.687664 -377.919742)
			(xy 84.693475 -377.912608) (xy 84.699979 -377.895409) (xy 84.700364 -377.886214) (xy 84.700364 -377.728734)
			(xy 84.700855 -377.718607) (xy 84.708576 -377.699882) (xy 84.722862 -377.685523) (xy 84.741547 -377.677707)
			(xy 84.751672 -377.677172) (xy 85.467952 -377.677172) (xy 85.478068 -377.677655) (xy 85.496765 -377.685382)
			(xy 85.51108 -377.699678) (xy 85.518832 -377.718365) (xy 85.51926 -377.72848) (xy 85.51926 -377.886214)
			(xy 85.519672 -377.895401) (xy 85.526185 -377.912585) (xy 85.53196 -377.919742) (xy 85.5538 -377.945428)
			(xy 85.591892 -378.001058) (xy 85.623046 -378.060851) (xy 85.646813 -378.123946) (xy 85.662852 -378.189433)
			(xy 85.67093 -378.256369) (xy 85.670933 -378.323734) (xy 115.349234 -378.323734) (xy 115.349237 -378.256427)
			(xy 115.357283 -378.189603) (xy 115.373258 -378.12422) (xy 115.396932 -378.061215) (xy 115.427966 -378.00149)
			(xy 115.465916 -377.945903) (xy 115.487704 -377.92025) (xy 115.493505 -377.913108) (xy 115.500017 -377.895915)
			(xy 115.500404 -377.886722) (xy 115.500404 -377.728734) (xy 115.500961 -377.718583) (xy 115.508717 -377.699821)
			(xy 115.523064 -377.685456) (xy 115.541815 -377.677674) (xy 115.551966 -377.677172) (xy 116.268246 -377.677172)
			(xy 116.278411 -377.677597) (xy 116.297188 -377.685393) (xy 116.311552 -377.69978) (xy 116.319319 -377.718568)
			(xy 116.319808 -377.728734) (xy 116.319808 -377.886722) (xy 116.320206 -377.895911) (xy 116.326728 -377.913095)
			(xy 116.332508 -377.92025) (xy 116.354272 -377.945922) (xy 116.392225 -378.001505) (xy 116.423262 -378.061225)
			(xy 116.446939 -378.124227) (xy 116.462915 -378.189607) (xy 116.470962 -378.256428) (xy 116.470964 -378.323732)
			(xy 116.470957 -378.323793) (xy 119.749003 -378.323793) (xy 119.749005 -378.256368) (xy 119.757084 -378.189428)
			(xy 119.773122 -378.123937) (xy 119.796889 -378.060839) (xy 119.828043 -378.001042) (xy 119.866134 -377.945407)
			(xy 119.888 -377.919742) (xy 119.893804 -377.912602) (xy 119.900314 -377.895407) (xy 119.9007 -377.886214)
			(xy 119.9007 -377.728734) (xy 119.901253 -377.718614) (xy 119.908963 -377.699902) (xy 119.923228 -377.685546)
			(xy 119.941892 -377.677718) (xy 119.952008 -377.677172) (xy 120.668288 -377.677172) (xy 120.678438 -377.677631)
			(xy 120.697185 -377.685417) (xy 120.711507 -377.699802) (xy 120.719213 -377.718582) (xy 120.719596 -377.728734)
			(xy 120.719596 -377.886214) (xy 120.72 -377.895402) (xy 120.726518 -377.912586) (xy 120.732296 -377.919742)
			(xy 120.754135 -377.945428) (xy 120.792224 -378.00106) (xy 120.823376 -378.060853) (xy 120.847142 -378.123947)
			(xy 120.86318 -378.189434) (xy 120.871258 -378.25637) (xy 120.87126 -378.323734) (xy 124.149298 -378.323734)
			(xy 124.149301 -378.256426) (xy 124.157348 -378.189601) (xy 124.173325 -378.124217) (xy 124.197003 -378.061211)
			(xy 124.228042 -378.001487) (xy 124.265997 -377.945902) (xy 124.287788 -377.92025) (xy 124.293587 -377.913106)
			(xy 124.300101 -377.895915) (xy 124.300488 -377.886722) (xy 124.300488 -377.728734) (xy 124.300893 -377.718558)
			(xy 124.308676 -377.699755) (xy 124.323068 -377.685367) (xy 124.341874 -377.67759) (xy 124.35205 -377.677172)
			(xy 125.06833 -377.677172) (xy 125.078508 -377.67754) (xy 125.09731 -377.685341) (xy 125.111695 -377.699744)
			(xy 125.119473 -377.718556) (xy 125.119892 -377.728734) (xy 125.119892 -377.886722) (xy 125.120293 -377.89591)
			(xy 125.126813 -377.913094) (xy 125.132592 -377.92025) (xy 125.154353 -377.945924) (xy 125.192301 -378.001508)
			(xy 125.223334 -378.061229) (xy 125.247006 -378.12423) (xy 125.26298 -378.189609) (xy 125.271026 -378.256429)
			(xy 125.271028 -378.323732) (xy 125.271028 -378.323734) (xy 128.549089 -378.323734) (xy 128.549092 -378.256427)
			(xy 128.557139 -378.189602) (xy 128.573116 -378.124218) (xy 128.596793 -378.061212) (xy 128.627831 -378.001488)
			(xy 128.665786 -377.945902) (xy 128.687576 -377.92025) (xy 128.693374 -377.913105) (xy 128.699888 -377.895915)
			(xy 128.700276 -377.886722) (xy 128.700276 -377.728734) (xy 128.700693 -377.71856) (xy 128.708474 -377.699759)
			(xy 128.722862 -377.685371) (xy 128.741664 -377.677592) (xy 128.751838 -377.677172) (xy 129.468118 -377.677172)
			(xy 129.478295 -377.67755) (xy 129.497097 -377.685347) (xy 129.511482 -377.699747) (xy 129.51926 -377.718557)
			(xy 129.51968 -377.728734) (xy 129.51968 -377.886722) (xy 129.520084 -377.89591) (xy 129.526602 -377.913094)
			(xy 129.53238 -377.92025) (xy 129.554142 -377.945923) (xy 129.59209 -378.001507) (xy 129.623123 -378.061228)
			(xy 129.646797 -378.12423) (xy 129.662771 -378.189609) (xy 129.670817 -378.256429) (xy 129.670819 -378.323732)
			(xy 129.670819 -378.323734) (xy 159.349143 -378.323734) (xy 159.349146 -378.256427) (xy 159.357192 -378.189603)
			(xy 159.373167 -378.12422) (xy 159.396842 -378.061214) (xy 159.427877 -378.00149) (xy 159.465827 -377.945902)
			(xy 159.487616 -377.92025) (xy 159.493418 -377.913109) (xy 159.499929 -377.895915) (xy 159.500316 -377.886722)
			(xy 159.500316 -377.728734) (xy 159.500791 -377.718567) (xy 159.508561 -377.699778) (xy 159.522931 -377.685392)
			(xy 159.541712 -377.677602) (xy 159.551878 -377.677172) (xy 160.268158 -377.677172) (xy 160.278331 -377.677599)
			(xy 160.297131 -377.685377) (xy 160.311519 -377.699762) (xy 160.319299 -377.718561) (xy 160.31972 -377.728734)
			(xy 160.31972 -377.886722) (xy 160.320115 -377.895911) (xy 160.326639 -377.913095) (xy 160.33242 -377.92025)
			(xy 160.354183 -377.945923) (xy 160.392136 -378.001505) (xy 160.423172 -378.061226) (xy 160.446848 -378.124227)
			(xy 160.462824 -378.189608) (xy 160.470871 -378.256429) (xy 160.470874 -378.323732) (xy 160.470867 -378.323793)
			(xy 163.748912 -378.323793) (xy 163.748914 -378.256367) (xy 163.756993 -378.189427) (xy 163.773031 -378.123937)
			(xy 163.796799 -378.060839) (xy 163.827953 -378.001042) (xy 163.866046 -377.945407) (xy 163.887912 -377.919742)
			(xy 163.893717 -377.912603) (xy 163.900226 -377.895408) (xy 163.900612 -377.886214) (xy 163.900612 -377.728734)
			(xy 163.901154 -377.718613) (xy 163.908865 -377.699898) (xy 163.923134 -377.685542) (xy 163.941802 -377.677716)
			(xy 163.95192 -377.677172) (xy 164.6682 -377.677172) (xy 164.678351 -377.677621) (xy 164.697098 -377.685411)
			(xy 164.71142 -377.699799) (xy 164.719125 -377.718582) (xy 164.719508 -377.728734) (xy 164.719508 -377.886214)
			(xy 164.71991 -377.895402) (xy 164.726429 -377.912586) (xy 164.732208 -377.919742) (xy 164.754046 -377.945428)
			(xy 164.792135 -378.00106) (xy 164.823286 -378.060853) (xy 164.847052 -378.123948) (xy 164.863089 -378.189434)
			(xy 164.871167 -378.25637) (xy 164.871169 -378.323734) (xy 168.149231 -378.323734) (xy 168.149234 -378.256427)
			(xy 168.15728 -378.189604) (xy 168.173254 -378.12422) (xy 168.196928 -378.061215) (xy 168.227963 -378.00149)
			(xy 168.265912 -377.945903) (xy 168.2877 -377.92025) (xy 168.2935 -377.913107) (xy 168.300013 -377.895915)
			(xy 168.3004 -377.886722) (xy 168.3004 -377.728734) (xy 168.30096 -377.718583) (xy 168.308717 -377.699822)
			(xy 168.323062 -377.685457) (xy 168.341812 -377.677675) (xy 168.351962 -377.677172) (xy 169.068242 -377.677172)
			(xy 169.078407 -377.6776) (xy 169.097183 -377.685394) (xy 169.111548 -377.699781) (xy 169.119315 -377.718569)
			(xy 169.119804 -377.728734) (xy 169.119804 -377.886722) (xy 169.120203 -377.89591) (xy 169.126724 -377.913095)
			(xy 169.132504 -377.92025) (xy 169.154265 -377.945924) (xy 169.192212 -378.001508) (xy 169.223244 -378.061229)
			(xy 169.246916 -378.124231) (xy 169.26289 -378.18961) (xy 169.270935 -378.256429) (xy 169.270937 -378.323732)
			(xy 169.270937 -378.323734) (xy 172.548998 -378.323734) (xy 172.549001 -378.256426) (xy 172.557048 -378.189601)
			(xy 172.573025 -378.124217) (xy 172.596703 -378.061211) (xy 172.627742 -378.001487) (xy 172.665697 -377.945902)
			(xy 172.687488 -377.92025) (xy 172.693287 -377.913106) (xy 172.699801 -377.895915) (xy 172.700188 -377.886722)
			(xy 172.700188 -377.728734) (xy 172.700593 -377.718558) (xy 172.708376 -377.699755) (xy 172.722768 -377.685367)
			(xy 172.741574 -377.67759) (xy 172.75175 -377.677172) (xy 173.46803 -377.677172) (xy 173.478208 -377.67754)
			(xy 173.49701 -377.685341) (xy 173.511395 -377.699744) (xy 173.519173 -377.718556) (xy 173.519592 -377.728734)
			(xy 173.519592 -377.886722) (xy 173.519993 -377.89591) (xy 173.526513 -377.913094) (xy 173.532292 -377.92025)
			(xy 173.554053 -377.945924) (xy 173.592001 -378.001508) (xy 173.623034 -378.061229) (xy 173.646706 -378.12423)
			(xy 173.66268 -378.189609) (xy 173.670726 -378.256429) (xy 173.670728 -378.323732) (xy 173.662687 -378.390552)
			(xy 173.646718 -378.455932) (xy 173.623049 -378.518936) (xy 173.592021 -378.578659) (xy 173.554077 -378.634245)
			(xy 173.532292 -378.659898) (xy 173.526513 -378.667056) (xy 173.519988 -378.684237) (xy 173.519592 -378.693426)
			(xy 173.519592 -378.766811) (xy 193.48983 -378.766811) (xy 193.48983 -378.633249) (xy 193.497894 -378.499931)
			(xy 193.513994 -378.367343) (xy 193.538069 -378.235969) (xy 193.570032 -378.106288) (xy 193.609767 -377.978774)
			(xy 193.657129 -377.853891) (xy 193.711944 -377.732096) (xy 193.774014 -377.613833) (xy 193.84311 -377.499534)
			(xy 193.918982 -377.389614) (xy 194.001352 -377.284477) (xy 194.08992 -377.184504) (xy 194.184362 -377.090062)
			(xy 194.284335 -377.001494) (xy 194.389472 -376.919124) (xy 194.499392 -376.843252) (xy 194.613691 -376.774156)
			(xy 194.731954 -376.712086) (xy 194.853749 -376.657271) (xy 194.978632 -376.609909) (xy 195.106146 -376.570174)
			(xy 195.235827 -376.538211) (xy 195.367201 -376.514136) (xy 195.499789 -376.498036) (xy 195.633107 -376.489972)
			(xy 195.766669 -376.489972) (xy 195.899987 -376.498036) (xy 196.032575 -376.514136) (xy 196.163949 -376.538211)
			(xy 196.29363 -376.570174) (xy 196.421144 -376.609909) (xy 196.546027 -376.657271) (xy 196.667822 -376.712086)
			(xy 196.786085 -376.774156) (xy 196.900384 -376.843252) (xy 197.010304 -376.919124) (xy 197.115441 -377.001494)
			(xy 197.215414 -377.090062) (xy 197.309856 -377.184504) (xy 197.398424 -377.284477) (xy 197.480794 -377.389614)
			(xy 197.556666 -377.499534) (xy 197.625762 -377.613833) (xy 197.687832 -377.732096) (xy 197.742647 -377.853891)
			(xy 197.790009 -377.978774) (xy 197.829744 -378.106288) (xy 197.861707 -378.235969) (xy 197.885782 -378.367343)
			(xy 197.901882 -378.499931) (xy 197.909946 -378.633249) (xy 197.91045 -378.70003) (xy 197.909946 -378.766811)
			(xy 197.901882 -378.900129) (xy 197.885782 -379.032717) (xy 197.861707 -379.164091) (xy 197.829744 -379.293772)
			(xy 197.790009 -379.421286) (xy 197.742647 -379.546169) (xy 197.687832 -379.667964) (xy 197.625762 -379.786227)
			(xy 197.556666 -379.900526) (xy 197.480794 -380.010446) (xy 197.398424 -380.115583) (xy 197.309856 -380.215556)
			(xy 197.215414 -380.309998) (xy 197.115441 -380.398566) (xy 197.010304 -380.480936) (xy 196.900384 -380.556808)
			(xy 196.786085 -380.625904) (xy 196.667822 -380.687974) (xy 196.546027 -380.742789) (xy 196.421144 -380.790151)
			(xy 196.29363 -380.829886) (xy 196.163949 -380.861849) (xy 196.032575 -380.885924) (xy 195.899987 -380.902024)
			(xy 195.766669 -380.910088) (xy 195.633107 -380.910088) (xy 195.499789 -380.902024) (xy 195.367201 -380.885924)
			(xy 195.235827 -380.861849) (xy 195.106146 -380.829886) (xy 194.978632 -380.790151) (xy 194.853749 -380.742789)
			(xy 194.731954 -380.687974) (xy 194.613691 -380.625904) (xy 194.499392 -380.556808) (xy 194.389472 -380.480936)
			(xy 194.284335 -380.398566) (xy 194.184362 -380.309998) (xy 194.08992 -380.215556) (xy 194.001352 -380.115583)
			(xy 193.918982 -380.010446) (xy 193.84311 -379.900526) (xy 193.774014 -379.786227) (xy 193.711944 -379.667964)
			(xy 193.657129 -379.546169) (xy 193.609767 -379.421286) (xy 193.570032 -379.293772) (xy 193.538069 -379.164091)
			(xy 193.513994 -379.032717) (xy 193.497894 -378.900129) (xy 193.48983 -378.766811) (xy 173.519592 -378.766811)
			(xy 173.519592 -379.186694) (xy 173.520007 -379.195881) (xy 173.526518 -379.213065) (xy 173.532292 -379.220222)
			(xy 173.554124 -379.245837) (xy 173.592069 -379.30143) (xy 173.623099 -379.361159) (xy 173.646768 -379.424168)
			(xy 173.662737 -379.489554) (xy 173.670777 -379.556381) (xy 173.670772 -379.623689) (xy 173.662724 -379.690514)
			(xy 173.646747 -379.755898) (xy 173.623071 -379.818905) (xy 173.592034 -379.87863) (xy 173.554082 -379.934217)
			(xy 173.532292 -379.95987) (xy 173.526482 -379.967006) (xy 173.519976 -379.984204) (xy 173.519592 -379.993398)
			(xy 173.519592 -380.151386) (xy 173.519056 -380.161539) (xy 173.511292 -380.180302) (xy 173.496939 -380.194667)
			(xy 173.478183 -380.202447) (xy 173.46803 -380.202948) (xy 172.75175 -380.202948) (xy 172.74158 -380.202495)
			(xy 172.722784 -380.194724) (xy 172.708396 -380.180347) (xy 172.700612 -380.161556) (xy 172.700188 -380.151386)
			(xy 172.700188 -379.993398) (xy 172.699781 -379.98421) (xy 172.693266 -379.967026) (xy 172.687488 -379.95987)
			(xy 172.665744 -379.934181) (xy 172.627791 -379.878601) (xy 172.596753 -379.818883) (xy 172.573075 -379.755883)
			(xy 172.557097 -379.690505) (xy 172.549049 -379.623686) (xy 172.549045 -379.556383) (xy 172.557085 -379.489563)
			(xy 172.573055 -379.424183) (xy 172.596724 -379.36118) (xy 172.627755 -379.301458) (xy 172.665702 -379.245873)
			(xy 172.687488 -379.220222) (xy 172.693299 -379.213087) (xy 172.699805 -379.195889) (xy 172.700188 -379.186694)
			(xy 172.700188 -378.693426) (xy 172.699768 -378.68424) (xy 172.693262 -378.667055) (xy 172.687488 -378.659898)
			(xy 172.665673 -378.634268) (xy 172.627722 -378.578679) (xy 172.596687 -378.518953) (xy 172.573014 -378.455946)
			(xy 172.557041 -378.39056) (xy 172.548998 -378.323734) (xy 169.270937 -378.323734) (xy 169.262897 -378.390552)
			(xy 169.246928 -378.455932) (xy 169.22326 -378.518935) (xy 169.192232 -378.578658) (xy 169.154289 -378.634245)
			(xy 169.132504 -378.659898) (xy 169.126726 -378.667057) (xy 169.1202 -378.684237) (xy 169.119804 -378.693426)
			(xy 169.119804 -379.186694) (xy 169.120216 -379.195881) (xy 169.126728 -379.213065) (xy 169.132504 -379.220222)
			(xy 169.154336 -379.245838) (xy 169.19228 -379.30143) (xy 169.223309 -379.361159) (xy 169.246977 -379.424169)
			(xy 169.262946 -379.489555) (xy 169.270986 -379.556381) (xy 169.270982 -379.623689) (xy 169.262933 -379.690513)
			(xy 169.246957 -379.755898) (xy 169.223281 -379.818904) (xy 169.192245 -379.878629) (xy 169.154293 -379.934217)
			(xy 169.132504 -379.95987) (xy 169.126696 -379.967007) (xy 169.120188 -379.984204) (xy 169.119804 -379.993398)
			(xy 169.119804 -380.151386) (xy 169.119256 -380.161538) (xy 169.111494 -380.180299) (xy 169.097146 -380.194663)
			(xy 169.078393 -380.202445) (xy 169.068242 -380.202948) (xy 168.351962 -380.202948) (xy 168.3418 -380.202497)
			(xy 168.323027 -380.194708) (xy 168.308663 -380.180329) (xy 168.300892 -380.161548) (xy 168.3004 -380.151386)
			(xy 168.3004 -379.993398) (xy 168.299991 -379.984211) (xy 168.293476 -379.967026) (xy 168.2877 -379.95987)
			(xy 168.265959 -379.93418) (xy 168.228011 -379.878598) (xy 168.196978 -379.818879) (xy 168.173304 -379.75588)
			(xy 168.157329 -379.690503) (xy 168.149282 -379.623685) (xy 168.149278 -379.556384) (xy 168.157317 -379.489565)
			(xy 168.173284 -379.424186) (xy 168.19695 -379.361184) (xy 168.227975 -379.301461) (xy 168.265916 -379.245875)
			(xy 168.2877 -379.220222) (xy 168.293512 -379.213088) (xy 168.300018 -379.195889) (xy 168.3004 -379.186694)
			(xy 168.3004 -378.693426) (xy 168.299977 -378.68424) (xy 168.293472 -378.667056) (xy 168.2877 -378.659898)
			(xy 168.265888 -378.634266) (xy 168.227942 -378.578676) (xy 168.196912 -378.518949) (xy 168.173243 -378.455942)
			(xy 168.157273 -378.390558) (xy 168.149231 -378.323734) (xy 164.871169 -378.323734) (xy 164.871169 -378.323791)
			(xy 164.863096 -378.390728) (xy 164.847063 -378.456215) (xy 164.823302 -378.519311) (xy 164.792155 -378.579106)
			(xy 164.75407 -378.634741) (xy 164.732208 -378.660406) (xy 164.726427 -378.667563) (xy 164.719903 -378.684744)
			(xy 164.719508 -378.693934) (xy 164.719508 -379.186186) (xy 164.719923 -379.195373) (xy 164.726433 -379.212557)
			(xy 164.732208 -379.219714) (xy 164.754117 -379.245342) (xy 164.792204 -379.300982) (xy 164.823352 -379.360784)
			(xy 164.847113 -379.423885) (xy 164.863145 -379.489379) (xy 164.871217 -379.556321) (xy 164.871213 -379.623748)
			(xy 164.863133 -379.690689) (xy 164.847093 -379.756181) (xy 164.823324 -379.81928) (xy 164.792168 -379.879077)
			(xy 164.754074 -379.934713) (xy 164.732208 -379.960378) (xy 164.726397 -379.967513) (xy 164.719891 -379.984711)
			(xy 164.719508 -379.993906) (xy 164.719508 -380.151386) (xy 164.718963 -380.161506) (xy 164.711249 -380.180218)
			(xy 164.696981 -380.194573) (xy 164.678317 -380.202401) (xy 164.6682 -380.202948) (xy 163.95192 -380.202948)
			(xy 163.941773 -380.202463) (xy 163.92303 -380.194683) (xy 163.908708 -380.180306) (xy 163.900999 -380.161534)
			(xy 163.900612 -380.151386) (xy 163.900612 -379.993906) (xy 163.900196 -379.98472) (xy 163.893686 -379.967535)
			(xy 163.887912 -379.960378) (xy 163.866093 -379.934676) (xy 163.828002 -379.879047) (xy 163.796849 -379.819256)
			(xy 163.773081 -379.756164) (xy 163.757042 -379.690679) (xy 163.748963 -379.623745) (xy 163.748958 -379.556324)
			(xy 163.75703 -379.489389) (xy 163.773061 -379.423902) (xy 163.79682 -379.360807) (xy 163.827966 -379.301013)
			(xy 163.86605 -379.245379) (xy 163.887912 -379.219714) (xy 163.893729 -379.212583) (xy 163.900231 -379.195382)
			(xy 163.900612 -379.186186) (xy 163.900612 -378.693934) (xy 163.900183 -378.684749) (xy 163.893682 -378.667565)
			(xy 163.887912 -378.660406) (xy 163.866022 -378.634762) (xy 163.827933 -378.579125) (xy 163.796783 -378.519326)
			(xy 163.77302 -378.456226) (xy 163.756986 -378.390734) (xy 163.748912 -378.323793) (xy 160.470867 -378.323793)
			(xy 160.462831 -378.390554) (xy 160.44686 -378.455935) (xy 160.423188 -378.518939) (xy 160.392156 -378.578661)
			(xy 160.354207 -378.634246) (xy 160.33242 -378.659898) (xy 160.326644 -378.667058) (xy 160.320116 -378.684237)
			(xy 160.31972 -378.693426) (xy 160.31972 -379.186694) (xy 160.320129 -379.195881) (xy 160.326643 -379.213066)
			(xy 160.33242 -379.220222) (xy 160.354254 -379.245836) (xy 160.392205 -379.301427) (xy 160.423238 -379.361156)
			(xy 160.44691 -379.424165) (xy 160.462881 -379.489552) (xy 160.470922 -379.55638) (xy 160.470918 -379.623689)
			(xy 160.462869 -379.690516) (xy 160.44689 -379.755901) (xy 160.42321 -379.818908) (xy 160.392169 -379.878632)
			(xy 160.354212 -379.934219) (xy 160.33242 -379.95987) (xy 160.326614 -379.967008) (xy 160.320104 -379.984204)
			(xy 160.31972 -379.993398) (xy 160.31972 -380.151386) (xy 160.319324 -380.161562) (xy 160.311536 -380.180364)
			(xy 160.297141 -380.194751) (xy 160.278334 -380.202529) (xy 160.268158 -380.202948) (xy 159.551878 -380.202948)
			(xy 159.541717 -380.202484) (xy 159.522945 -380.1947) (xy 159.50858 -380.180325) (xy 159.500808 -380.161547)
			(xy 159.500316 -380.151386) (xy 159.500316 -379.993398) (xy 159.499903 -379.984211) (xy 159.493391 -379.967027)
			(xy 159.487616 -379.95987) (xy 159.465874 -379.93418) (xy 159.427926 -379.878599) (xy 159.396892 -379.81888)
			(xy 159.373217 -379.75588) (xy 159.357242 -379.690503) (xy 159.349195 -379.623685) (xy 159.34919 -379.556384)
			(xy 159.35723 -379.489565) (xy 159.373197 -379.424186) (xy 159.396864 -379.361183) (xy 159.42789 -379.301461)
			(xy 159.465832 -379.245875) (xy 159.487616 -379.220222) (xy 159.49343 -379.213089) (xy 159.499934 -379.195889)
			(xy 159.500316 -379.186694) (xy 159.500316 -378.693426) (xy 159.49989 -378.684241) (xy 159.493387 -378.667056)
			(xy 159.487616 -378.659898) (xy 159.465803 -378.634267) (xy 159.427857 -378.578677) (xy 159.396826 -378.51895)
			(xy 159.373156 -378.455943) (xy 159.357185 -378.390558) (xy 159.349143 -378.323734) (xy 129.670819 -378.323734)
			(xy 129.662778 -378.390552) (xy 129.646808 -378.455933) (xy 129.623139 -378.518936) (xy 129.59211 -378.578659)
			(xy 129.554166 -378.634246) (xy 129.53238 -378.659898) (xy 129.526599 -378.667054) (xy 129.520076 -378.684236)
			(xy 129.51968 -378.693426) (xy 129.51968 -379.186694) (xy 129.520098 -379.19588) (xy 129.526607 -379.213064)
			(xy 129.53238 -379.220222) (xy 129.554212 -379.245837) (xy 129.592159 -379.301429) (xy 129.623189 -379.361158)
			(xy 129.646858 -379.424168) (xy 129.662827 -379.489554) (xy 129.670868 -379.55638) (xy 129.670863 -379.623689)
			(xy 129.662815 -379.690514) (xy 129.646838 -379.755899) (xy 129.623161 -379.818905) (xy 129.592123 -379.87863)
			(xy 129.55417 -379.934218) (xy 129.53238 -379.95987) (xy 129.526569 -379.967005) (xy 129.520064 -379.984203)
			(xy 129.51968 -379.993398) (xy 129.51968 -380.151386) (xy 129.519156 -380.161541) (xy 129.511389 -380.180306)
			(xy 129.497033 -380.194671) (xy 129.478272 -380.202449) (xy 129.468118 -380.202948) (xy 128.751838 -380.202948)
			(xy 128.741667 -380.202505) (xy 128.722871 -380.19473) (xy 128.708484 -380.18035) (xy 128.7007 -380.161557)
			(xy 128.700276 -380.151386) (xy 128.700276 -379.993398) (xy 128.699872 -379.98421) (xy 128.693355 -379.967025)
			(xy 128.687576 -379.95987) (xy 128.665832 -379.934181) (xy 128.62788 -379.878601) (xy 128.596842 -379.818883)
			(xy 128.573165 -379.755883) (xy 128.557188 -379.690505) (xy 128.54914 -379.623686) (xy 128.549136 -379.556384)
			(xy 128.557176 -379.489563) (xy 128.573145 -379.424183) (xy 128.596814 -379.361181) (xy 128.627844 -379.301459)
			(xy 128.66579 -379.245874) (xy 128.687576 -379.220222) (xy 128.693385 -379.213086) (xy 128.699893 -379.195889)
			(xy 128.700276 -379.186694) (xy 128.700276 -378.693426) (xy 128.699859 -378.684239) (xy 128.693351 -378.667055)
			(xy 128.687576 -378.659898) (xy 128.665762 -378.634267) (xy 128.627811 -378.578679) (xy 128.596777 -378.518952)
			(xy 128.573104 -378.455945) (xy 128.557132 -378.39056) (xy 128.549089 -378.323734) (xy 125.271028 -378.323734)
			(xy 125.262987 -378.390552) (xy 125.247018 -378.455932) (xy 125.223349 -378.518936) (xy 125.192321 -378.578659)
			(xy 125.154377 -378.634245) (xy 125.132592 -378.659898) (xy 125.126813 -378.667056) (xy 125.120288 -378.684237)
			(xy 125.119892 -378.693426) (xy 125.119892 -379.186694) (xy 125.120307 -379.195881) (xy 125.126818 -379.213065)
			(xy 125.132592 -379.220222) (xy 125.154424 -379.245837) (xy 125.192369 -379.30143) (xy 125.223399 -379.361159)
			(xy 125.247068 -379.424168) (xy 125.263037 -379.489554) (xy 125.271077 -379.556381) (xy 125.271072 -379.623689)
			(xy 125.263024 -379.690514) (xy 125.247047 -379.755898) (xy 125.223371 -379.818905) (xy 125.192334 -379.87863)
			(xy 125.154382 -379.934217) (xy 125.132592 -379.95987) (xy 125.126782 -379.967006) (xy 125.120276 -379.984204)
			(xy 125.119892 -379.993398) (xy 125.119892 -380.151386) (xy 125.119356 -380.161539) (xy 125.111592 -380.180302)
			(xy 125.097239 -380.194667) (xy 125.078483 -380.202447) (xy 125.06833 -380.202948) (xy 124.35205 -380.202948)
			(xy 124.34188 -380.202495) (xy 124.323084 -380.194724) (xy 124.308696 -380.180347) (xy 124.300912 -380.161556)
			(xy 124.300488 -380.151386) (xy 124.300488 -379.993398) (xy 124.300081 -379.98421) (xy 124.293566 -379.967026)
			(xy 124.287788 -379.95987) (xy 124.266044 -379.934181) (xy 124.228091 -379.878601) (xy 124.197053 -379.818883)
			(xy 124.173375 -379.755883) (xy 124.157397 -379.690505) (xy 124.149349 -379.623686) (xy 124.149345 -379.556383)
			(xy 124.157385 -379.489563) (xy 124.173355 -379.424183) (xy 124.197024 -379.36118) (xy 124.228055 -379.301458)
			(xy 124.266002 -379.245873) (xy 124.287788 -379.220222) (xy 124.293599 -379.213087) (xy 124.300105 -379.195889)
			(xy 124.300488 -379.186694) (xy 124.300488 -378.693426) (xy 124.300068 -378.68424) (xy 124.293562 -378.667055)
			(xy 124.287788 -378.659898) (xy 124.265973 -378.634268) (xy 124.228022 -378.578679) (xy 124.196987 -378.518953)
			(xy 124.173314 -378.455946) (xy 124.157341 -378.39056) (xy 124.149298 -378.323734) (xy 120.87126 -378.323734)
			(xy 120.87126 -378.323791) (xy 120.863187 -378.390728) (xy 120.847154 -378.456216) (xy 120.823392 -378.519311)
			(xy 120.792244 -378.579107) (xy 120.754159 -378.634741) (xy 120.732296 -378.660406) (xy 120.726514 -378.667561)
			(xy 120.719991 -378.684744) (xy 120.719596 -378.693934) (xy 120.719596 -379.186186) (xy 120.720014 -379.195372)
			(xy 120.726522 -379.212557) (xy 120.732296 -379.219714) (xy 120.754205 -379.245342) (xy 120.792293 -379.300982)
			(xy 120.823442 -379.360783) (xy 120.847204 -379.423885) (xy 120.863236 -379.489378) (xy 120.871308 -379.556321)
			(xy 120.871304 -379.623748) (xy 120.863224 -379.69069) (xy 120.847183 -379.756181) (xy 120.823414 -379.81928)
			(xy 120.792257 -379.879078) (xy 120.754163 -379.934713) (xy 120.732296 -379.960378) (xy 120.726483 -379.967512)
			(xy 120.719978 -379.984711) (xy 120.719596 -379.993906) (xy 120.719596 -380.151386) (xy 120.719063 -380.161507)
			(xy 120.711347 -380.180221) (xy 120.697075 -380.194577) (xy 120.678406 -380.202403) (xy 120.668288 -380.202948)
			(xy 119.952008 -380.202948) (xy 119.94186 -380.202473) (xy 119.923117 -380.194689) (xy 119.908795 -380.180309)
			(xy 119.901087 -380.161535) (xy 119.9007 -380.151386) (xy 119.9007 -379.993906) (xy 119.900287 -379.984719)
			(xy 119.893775 -379.967535) (xy 119.888 -379.960378) (xy 119.866181 -379.934675) (xy 119.828091 -379.879046)
			(xy 119.796938 -379.819255) (xy 119.773172 -379.756163) (xy 119.757133 -379.690679) (xy 119.749053 -379.623745)
			(xy 119.749049 -379.556325) (xy 119.757121 -379.489389) (xy 119.773151 -379.423903) (xy 119.79691 -379.360808)
			(xy 119.828056 -379.301013) (xy 119.866139 -379.245379) (xy 119.888 -379.219714) (xy 119.893816 -379.212582)
			(xy 119.900319 -379.195381) (xy 119.9007 -379.186186) (xy 119.9007 -378.693934) (xy 119.900273 -378.684749)
			(xy 119.893771 -378.667564) (xy 119.888 -378.660406) (xy 119.86611 -378.634762) (xy 119.828023 -378.579124)
			(xy 119.796873 -378.519325) (xy 119.77311 -378.456226) (xy 119.757077 -378.390734) (xy 119.749003 -378.323793)
			(xy 116.470957 -378.323793) (xy 116.462922 -378.390554) (xy 116.44695 -378.455936) (xy 116.423278 -378.518939)
			(xy 116.392245 -378.578662) (xy 116.354296 -378.634247) (xy 116.332508 -378.659898) (xy 116.326731 -378.667057)
			(xy 116.320204 -378.684237) (xy 116.319808 -378.693426) (xy 116.319808 -379.186694) (xy 116.320219 -379.195881)
			(xy 116.326732 -379.213066) (xy 116.332508 -379.220222) (xy 116.354343 -379.245836) (xy 116.392293 -379.301427)
			(xy 116.423328 -379.361155) (xy 116.447 -379.424165) (xy 116.462971 -379.489552) (xy 116.471013 -379.55638)
			(xy 116.471009 -379.623689) (xy 116.462959 -379.690516) (xy 116.44698 -379.755901) (xy 116.423299 -379.818908)
			(xy 116.392258 -379.878633) (xy 116.3543 -379.934219) (xy 116.332508 -379.95987) (xy 116.3267 -379.967007)
			(xy 116.320192 -379.984204) (xy 116.319808 -379.993398) (xy 116.319808 -380.151386) (xy 116.319256 -380.161537)
			(xy 116.311495 -380.180297) (xy 116.297148 -380.194661) (xy 116.278397 -380.202445) (xy 116.268246 -380.202948)
			(xy 115.551966 -380.202948) (xy 115.541804 -380.202494) (xy 115.523032 -380.194706) (xy 115.508667 -380.180328)
			(xy 115.500896 -380.161548) (xy 115.500404 -380.151386) (xy 115.500404 -379.993398) (xy 115.499994 -379.984211)
			(xy 115.49348 -379.967027) (xy 115.487704 -379.95987) (xy 115.465963 -379.93418) (xy 115.428015 -379.878598)
			(xy 115.396981 -379.81888) (xy 115.373307 -379.75588) (xy 115.357332 -379.690503) (xy 115.349285 -379.623685)
			(xy 115.349281 -379.556384) (xy 115.35732 -379.489565) (xy 115.373287 -379.424186) (xy 115.396953 -379.361184)
			(xy 115.427979 -379.301461) (xy 115.46592 -379.245875) (xy 115.487704 -379.220222) (xy 115.493517 -379.213088)
			(xy 115.500022 -379.195889) (xy 115.500404 -379.186694) (xy 115.500404 -378.693426) (xy 115.49998 -378.68424)
			(xy 115.493476 -378.667056) (xy 115.487704 -378.659898) (xy 115.465892 -378.634266) (xy 115.427946 -378.578676)
			(xy 115.396916 -378.518949) (xy 115.373246 -378.455942) (xy 115.357276 -378.390558) (xy 115.349234 -378.323734)
			(xy 85.670933 -378.323734) (xy 85.670933 -378.323792) (xy 85.662859 -378.390729) (xy 85.646825 -378.456217)
			(xy 85.623062 -378.519313) (xy 85.591912 -378.579108) (xy 85.553824 -378.634741) (xy 85.53196 -378.660406)
			(xy 85.526173 -378.667558) (xy 85.519654 -378.684743) (xy 85.51926 -378.693934) (xy 85.51926 -379.186186)
			(xy 85.519686 -379.195371) (xy 85.526189 -379.212555) (xy 85.53196 -379.219714) (xy 85.553871 -379.245341)
			(xy 85.591961 -379.30098) (xy 85.623111 -379.360781) (xy 85.646875 -379.423883) (xy 85.662908 -379.489377)
			(xy 85.670981 -379.55632) (xy 85.670977 -379.623749) (xy 85.662896 -379.690691) (xy 85.646854 -379.756183)
			(xy 85.623083 -379.819282) (xy 85.591925 -379.879079) (xy 85.553828 -379.934713) (xy 85.53196 -379.960378)
			(xy 85.526143 -379.967508) (xy 85.519641 -379.98471) (xy 85.51926 -379.993906) (xy 85.51926 -380.151386)
			(xy 85.518762 -380.161512) (xy 85.511039 -380.180233) (xy 85.496756 -380.194589) (xy 85.478075 -380.202409)
			(xy 85.467952 -380.202948) (xy 84.751672 -380.202948) (xy 84.741567 -380.202439) (xy 84.722898 -380.194701)
			(xy 84.708606 -380.180412) (xy 84.700863 -380.161744) (xy 84.700364 -380.15164) (xy 84.700364 -379.993906)
			(xy 84.699937 -379.984721) (xy 84.693433 -379.967537) (xy 84.687664 -379.960378) (xy 84.665846 -379.934675)
			(xy 84.627759 -379.879045) (xy 84.596608 -379.819254) (xy 84.572843 -379.756162) (xy 84.556805 -379.690678)
			(xy 84.548726 -379.623744) (xy 84.548722 -379.556325) (xy 84.556793 -379.48939) (xy 84.572822 -379.423904)
			(xy 84.59658 -379.36081) (xy 84.627723 -379.301014) (xy 84.665804 -379.24538) (xy 84.687664 -379.219714)
			(xy 84.693487 -379.212588) (xy 84.699984 -379.195383) (xy 84.700364 -379.186186) (xy 84.700364 -378.693934)
			(xy 84.699923 -378.68475) (xy 84.693429 -378.667566) (xy 84.687664 -378.660406) (xy 84.665776 -378.634761)
			(xy 84.62769 -378.579123) (xy 84.596543 -378.519324) (xy 84.572781 -378.456224) (xy 84.556749 -378.390733)
			(xy 84.548676 -378.323793) (xy 81.271142 -378.323793) (xy 81.263068 -378.390729) (xy 81.247035 -378.456217)
			(xy 81.223272 -378.519312) (xy 81.192123 -378.579108) (xy 81.154035 -378.634741) (xy 81.132172 -378.660406)
			(xy 81.126387 -378.667559) (xy 81.119866 -378.684744) (xy 81.119472 -378.693934) (xy 81.119472 -379.186186)
			(xy 81.119895 -379.195372) (xy 81.126401 -379.212556) (xy 81.132172 -379.219714) (xy 81.154082 -379.245341)
			(xy 81.192171 -379.300981) (xy 81.223322 -379.360782) (xy 81.247084 -379.423884) (xy 81.263118 -379.489378)
			(xy 81.27119 -379.556321) (xy 81.271186 -379.623748) (xy 81.263105 -379.69069) (xy 81.247064 -379.756182)
			(xy 81.223293 -379.819281) (xy 81.192136 -379.879079) (xy 81.15404 -379.934713) (xy 81.132172 -379.960378)
			(xy 81.126356 -379.967509) (xy 81.119854 -379.984711) (xy 81.119472 -379.993906) (xy 81.119472 -380.151386)
			(xy 81.118962 -380.16151) (xy 81.111241 -380.180229) (xy 81.096962 -380.194585) (xy 81.078286 -380.202407)
			(xy 81.068164 -380.202948) (xy 80.351884 -380.202948) (xy 80.34178 -380.202429) (xy 80.323111 -380.194695)
			(xy 80.308818 -380.180409) (xy 80.301076 -380.161744) (xy 80.300576 -380.15164) (xy 80.300576 -379.993906)
			(xy 80.300168 -379.984718) (xy 80.293654 -379.967534) (xy 80.287876 -379.960378) (xy 80.266058 -379.934675)
			(xy 80.22797 -379.879045) (xy 80.196818 -379.819254) (xy 80.173052 -379.756162) (xy 80.157015 -379.690678)
			(xy 80.148935 -379.623744) (xy 80.148931 -379.556325) (xy 80.157002 -379.48939) (xy 80.173032 -379.423904)
			(xy 80.19679 -379.360809) (xy 80.227934 -379.301014) (xy 80.266016 -379.24538) (xy 80.287876 -379.219714)
			(xy 80.293689 -379.21258) (xy 80.300195 -379.195381) (xy 80.300576 -379.186186) (xy 80.300576 -378.693934)
			(xy 80.300155 -378.684748) (xy 80.29365 -378.667563) (xy 80.287876 -378.660406) (xy 80.265987 -378.634761)
			(xy 80.227901 -378.579123) (xy 80.196753 -378.519324) (xy 80.172991 -378.456225) (xy 80.156958 -378.390733)
			(xy 80.148885 -378.323793) (xy 76.870815 -378.323793) (xy 76.862781 -378.390552) (xy 76.846812 -378.455933)
			(xy 76.823143 -378.518936) (xy 76.792114 -378.578659) (xy 76.75417 -378.634246) (xy 76.732384 -378.659898)
			(xy 76.726604 -378.667055) (xy 76.72008 -378.684236) (xy 76.719684 -378.693426) (xy 76.719684 -379.186694)
			(xy 76.720101 -379.19588) (xy 76.72661 -379.213065) (xy 76.732384 -379.220222) (xy 76.754216 -379.245837)
			(xy 76.792162 -379.30143) (xy 76.823192 -379.361158) (xy 76.846861 -379.424168) (xy 76.86283 -379.489554)
			(xy 76.870871 -379.55638) (xy 76.870866 -379.623689) (xy 76.862818 -379.690514) (xy 76.846841 -379.755899)
			(xy 76.823164 -379.818905) (xy 76.792127 -379.87863) (xy 76.754174 -379.934218) (xy 76.732384 -379.95987)
			(xy 76.726573 -379.967005) (xy 76.720068 -379.984203) (xy 76.719684 -379.993398) (xy 76.719684 -380.151386)
			(xy 76.719156 -380.16154) (xy 76.71139 -380.180305) (xy 76.697035 -380.19467) (xy 76.678276 -380.202449)
			(xy 76.668122 -380.202948) (xy 75.951842 -380.202948) (xy 75.941671 -380.202501) (xy 75.922875 -380.194728)
			(xy 75.908488 -380.180349) (xy 75.900704 -380.161556) (xy 75.90028 -380.151386) (xy 75.90028 -379.993398)
			(xy 75.899875 -379.98421) (xy 75.893358 -379.967026) (xy 75.88758 -379.95987) (xy 75.865836 -379.934181)
			(xy 75.827883 -379.878601) (xy 75.796846 -379.818883) (xy 75.773169 -379.755883) (xy 75.757191 -379.690505)
			(xy 75.749143 -379.623686) (xy 75.749139 -379.556383) (xy 75.757179 -379.489563) (xy 75.773148 -379.424183)
			(xy 75.796818 -379.36118) (xy 75.827848 -379.301458) (xy 75.865794 -379.245874) (xy 75.88758 -379.220222)
			(xy 75.89339 -379.213086) (xy 75.899897 -379.195889) (xy 75.90028 -379.186694) (xy 75.90028 -378.693426)
			(xy 75.899862 -378.68424) (xy 75.893354 -378.667055) (xy 75.88758 -378.659898) (xy 75.865766 -378.634267)
			(xy 75.827815 -378.578679) (xy 75.79678 -378.518953) (xy 75.773107 -378.455945) (xy 75.757135 -378.39056)
			(xy 75.749092 -378.323734) (xy 72.471054 -378.323734) (xy 72.471054 -378.323791) (xy 72.46298 -378.390728)
			(xy 72.446947 -378.456216) (xy 72.423186 -378.519312) (xy 72.392037 -378.579107) (xy 72.353951 -378.634741)
			(xy 72.332088 -378.660406) (xy 72.326305 -378.667561) (xy 72.319783 -378.684744) (xy 72.319388 -378.693934)
			(xy 72.319388 -379.186186) (xy 72.319808 -379.195372) (xy 72.326315 -379.212556) (xy 72.332088 -379.219714)
			(xy 72.353998 -379.245342) (xy 72.392086 -379.300981) (xy 72.423235 -379.360783) (xy 72.446997 -379.423884)
			(xy 72.46303 -379.489378) (xy 72.471102 -379.556321) (xy 72.471098 -379.623748) (xy 72.463017 -379.69069)
			(xy 72.446977 -379.756182) (xy 72.423207 -379.819281) (xy 72.39205 -379.879078) (xy 72.353955 -379.934713)
			(xy 72.332088 -379.960378) (xy 72.326274 -379.967511) (xy 72.31977 -379.984711) (xy 72.319388 -379.993906)
			(xy 72.319388 -380.151386) (xy 72.318863 -380.161508) (xy 72.311145 -380.180224) (xy 72.296871 -380.19458)
			(xy 72.278199 -380.202404) (xy 72.26808 -380.202948) (xy 71.5518 -380.202948) (xy 71.541652 -380.202479)
			(xy 71.522909 -380.194693) (xy 71.508587 -380.180311) (xy 71.500879 -380.161536) (xy 71.500492 -380.151386)
			(xy 71.500492 -379.993906) (xy 71.500081 -379.984719) (xy 71.493568 -379.967534) (xy 71.487792 -379.960378)
			(xy 71.465974 -379.934675) (xy 71.427884 -379.879046) (xy 71.396732 -379.819255) (xy 71.372965 -379.756163)
			(xy 71.356927 -379.690678) (xy 71.348847 -379.623744) (xy 71.348843 -379.556325) (xy 71.356914 -379.48939)
			(xy 71.372945 -379.423903) (xy 71.396703 -379.360808) (xy 71.427848 -379.301013) (xy 71.465931 -379.245379)
			(xy 71.487792 -379.219714) (xy 71.493607 -379.212582) (xy 71.500111 -379.195381) (xy 71.500492 -379.186186)
			(xy 71.500492 -378.693934) (xy 71.500067 -378.684748) (xy 71.493564 -378.667564) (xy 71.487792 -378.660406)
			(xy 71.465903 -378.634762) (xy 71.427815 -378.579124) (xy 71.396666 -378.519325) (xy 71.372904 -378.456225)
			(xy 71.35687 -378.390734) (xy 71.348797 -378.323793) (xy 41.671024 -378.323793) (xy 41.66295 -378.390729)
			(xy 41.646915 -378.456218) (xy 41.623152 -378.519314) (xy 41.592001 -378.579109) (xy 41.553912 -378.634742)
			(xy 41.532048 -378.660406) (xy 41.52626 -378.667557) (xy 41.519742 -378.684743) (xy 41.519348 -378.693934)
			(xy 41.519348 -379.186186) (xy 41.519776 -379.195371) (xy 41.526279 -379.212555) (xy 41.532048 -379.219714)
			(xy 41.553959 -379.245341) (xy 41.59205 -379.30098) (xy 41.623201 -379.360781) (xy 41.646965 -379.423883)
			(xy 41.662999 -379.489377) (xy 41.671072 -379.55632) (xy 41.671068 -379.623749) (xy 41.662987 -379.690691)
			(xy 41.646945 -379.756183) (xy 41.623173 -379.819282) (xy 41.592014 -379.879079) (xy 41.553917 -379.934714)
			(xy 41.532048 -379.960378) (xy 41.526229 -379.967507) (xy 41.519729 -379.98471) (xy 41.519348 -379.993906)
			(xy 41.519348 -380.151386) (xy 41.518862 -380.161513) (xy 41.511136 -380.180236) (xy 41.49685 -380.194594)
			(xy 41.478165 -380.202411) (xy 41.46804 -380.202948) (xy 40.75176 -380.202948) (xy 40.741609 -380.202512)
			(xy 40.722865 -380.194712) (xy 40.708545 -380.180321) (xy 40.700838 -380.161539) (xy 40.700452 -380.151386)
			(xy 40.700452 -379.993906) (xy 40.700027 -379.984721) (xy 40.693523 -379.967537) (xy 40.687752 -379.960378)
			(xy 40.665931 -379.934676) (xy 40.627838 -379.879048) (xy 40.596682 -379.819258) (xy 40.572913 -379.756165)
			(xy 40.556873 -379.69068) (xy 40.548793 -379.623745) (xy 40.548788 -379.556324) (xy 40.556861 -379.489388)
			(xy 40.572893 -379.423901) (xy 40.596654 -379.360806) (xy 40.627802 -379.301011) (xy 40.665889 -379.245378)
			(xy 40.687752 -379.219714) (xy 40.693574 -379.212587) (xy 40.700072 -379.195382) (xy 40.700452 -379.186186)
			(xy 40.700452 -378.693934) (xy 40.700014 -378.68475) (xy 40.693519 -378.667566) (xy 40.687752 -378.660406)
			(xy 40.665861 -378.634763) (xy 40.627769 -378.579126) (xy 40.596617 -378.519328) (xy 40.572852 -378.456228)
			(xy 40.556817 -378.390735) (xy 40.548742 -378.323794) (xy 37.271233 -378.323794) (xy 37.263159 -378.390729)
			(xy 37.247125 -378.456217) (xy 37.223362 -378.519313) (xy 37.192212 -378.579108) (xy 37.154124 -378.634741)
			(xy 37.13226 -378.660406) (xy 37.126473 -378.667558) (xy 37.119954 -378.684743) (xy 37.11956 -378.693934)
			(xy 37.11956 -379.186186) (xy 37.119986 -379.195371) (xy 37.126489 -379.212555) (xy 37.13226 -379.219714)
			(xy 37.154171 -379.245341) (xy 37.192261 -379.30098) (xy 37.223411 -379.360781) (xy 37.247175 -379.423883)
			(xy 37.263208 -379.489377) (xy 37.271281 -379.55632) (xy 37.271277 -379.623749) (xy 37.263196 -379.690691)
			(xy 37.247154 -379.756183) (xy 37.223383 -379.819282) (xy 37.192225 -379.879079) (xy 37.154128 -379.934713)
			(xy 37.13226 -379.960378) (xy 37.126443 -379.967508) (xy 37.119941 -379.98471) (xy 37.11956 -379.993906)
			(xy 37.11956 -380.151386) (xy 37.119062 -380.161512) (xy 37.111339 -380.180233) (xy 37.097056 -380.194589)
			(xy 37.078375 -380.202409) (xy 37.068252 -380.202948) (xy 36.351972 -380.202948) (xy 36.341822 -380.202502)
			(xy 36.323078 -380.194707) (xy 36.308758 -380.180318) (xy 36.30105 -380.161538) (xy 36.300664 -380.151386)
			(xy 36.300664 -379.993906) (xy 36.300237 -379.984721) (xy 36.293733 -379.967537) (xy 36.287964 -379.960378)
			(xy 36.266146 -379.934675) (xy 36.228059 -379.879045) (xy 36.196908 -379.819254) (xy 36.173143 -379.756162)
			(xy 36.157105 -379.690678) (xy 36.149026 -379.623744) (xy 36.149022 -379.556325) (xy 36.157093 -379.48939)
			(xy 36.173122 -379.423904) (xy 36.19688 -379.36081) (xy 36.228023 -379.301014) (xy 36.266104 -379.24538)
			(xy 36.287964 -379.219714) (xy 36.293787 -379.212588) (xy 36.300284 -379.195383) (xy 36.300664 -379.186186)
			(xy 36.300664 -378.693934) (xy 36.300223 -378.68475) (xy 36.293729 -378.667566) (xy 36.287964 -378.660406)
			(xy 36.266076 -378.634761) (xy 36.22799 -378.579123) (xy 36.196843 -378.519324) (xy 36.173081 -378.456224)
			(xy 36.157049 -378.390733) (xy 36.148976 -378.323793) (xy 32.870906 -378.323793) (xy 32.862871 -378.390552)
			(xy 32.846902 -378.455933) (xy 32.823232 -378.518936) (xy 32.792203 -378.578659) (xy 32.754258 -378.634246)
			(xy 32.732472 -378.659898) (xy 32.72669 -378.667053) (xy 32.720167 -378.684236) (xy 32.719772 -378.693426)
			(xy 32.719772 -379.186694) (xy 32.720191 -379.19588) (xy 32.726699 -379.213064) (xy 32.732472 -379.220222)
			(xy 32.754305 -379.245837) (xy 32.792251 -379.301429) (xy 32.823282 -379.361158) (xy 32.846952 -379.424167)
			(xy 32.862921 -379.489554) (xy 32.870962 -379.55638) (xy 32.870957 -379.623689) (xy 32.862909 -379.690514)
			(xy 32.846931 -379.755899) (xy 32.823254 -379.818905) (xy 32.792216 -379.87863) (xy 32.754262 -379.934218)
			(xy 32.732472 -379.95987) (xy 32.72666 -379.967004) (xy 32.720155 -379.984203) (xy 32.719772 -379.993398)
			(xy 32.719772 -380.151386) (xy 32.719325 -380.161556) (xy 32.711547 -380.180348) (xy 32.697168 -380.194733)
			(xy 32.678379 -380.20252) (xy 32.66821 -380.202948) (xy 31.95193 -380.202948) (xy 31.941759 -380.202511)
			(xy 31.922962 -380.194733) (xy 31.908576 -380.180351) (xy 31.900792 -380.161557) (xy 31.900368 -380.151386)
			(xy 31.900368 -379.993398) (xy 31.899944 -379.984213) (xy 31.893438 -379.967029) (xy 31.887668 -379.95987)
			(xy 31.865925 -379.934181) (xy 31.827973 -379.878601) (xy 31.796936 -379.818882) (xy 31.773259 -379.755883)
			(xy 31.757282 -379.690505) (xy 31.749234 -379.623686) (xy 31.74923 -379.556384) (xy 31.75727 -379.489564)
			(xy 31.773239 -379.424184) (xy 31.796908 -379.361181) (xy 31.827937 -379.301459) (xy 31.865882 -379.245874)
			(xy 31.887668 -379.220222) (xy 31.893488 -379.213094) (xy 31.899987 -379.19589) (xy 31.900368 -379.186694)
			(xy 31.900368 -378.693426) (xy 31.89993 -378.684242) (xy 31.893434 -378.667058) (xy 31.887668 -378.659898)
			(xy 31.865854 -378.634267) (xy 31.827904 -378.578678) (xy 31.79687 -378.518952) (xy 31.773198 -378.455945)
			(xy 31.757226 -378.39056) (xy 31.749183 -378.323734) (xy 28.471145 -378.323734) (xy 28.471145 -378.323792)
			(xy 28.463071 -378.390728) (xy 28.447038 -378.456216) (xy 28.423275 -378.519312) (xy 28.392126 -378.579108)
			(xy 28.354039 -378.634741) (xy 28.332176 -378.660406) (xy 28.326392 -378.66756) (xy 28.31987 -378.684744)
			(xy 28.319476 -378.693934) (xy 28.319476 -379.186186) (xy 28.319898 -379.195372) (xy 28.326404 -379.212556)
			(xy 28.332176 -379.219714) (xy 28.354036 -379.245382) (xy 28.392125 -379.301016) (xy 28.423276 -379.360812)
			(xy 28.447 -379.423801) (xy 29.549058 -379.423801) (xy 29.549059 -379.356496) (xy 29.557103 -379.289673)
			(xy 29.573076 -379.224291) (xy 29.596749 -379.161286) (xy 29.627783 -379.101562) (xy 29.665732 -379.045976)
			(xy 29.68752 -379.020324) (xy 29.693334 -379.013191) (xy 29.699837 -378.995991) (xy 29.70022 -378.986796)
			(xy 29.70022 -378.828554) (xy 29.700695 -378.818396) (xy 29.708482 -378.799629) (xy 29.722852 -378.785266)
			(xy 29.741623 -378.77749) (xy 29.751782 -378.776992) (xy 30.468062 -378.776992) (xy 30.478212 -378.777564)
			(xy 30.496971 -378.785317) (xy 30.511336 -378.799658) (xy 30.51912 -378.818405) (xy 30.519624 -378.828554)
			(xy 30.519624 -378.986796) (xy 30.520031 -378.995984) (xy 30.526546 -379.013168) (xy 30.532324 -379.020324)
			(xy 30.55411 -379.045978) (xy 30.592059 -379.101564) (xy 30.623093 -379.161287) (xy 30.646766 -379.224291)
			(xy 30.662739 -379.289673) (xy 30.670784 -379.356496) (xy 30.670784 -379.423801) (xy 30.66274 -379.490624)
			(xy 30.646767 -379.556006) (xy 30.623094 -379.61901) (xy 30.592061 -379.678734) (xy 30.554112 -379.73432)
			(xy 30.532324 -379.759972) (xy 30.526517 -379.76711) (xy 30.520008 -379.784306) (xy 30.519624 -379.7935)
			(xy 30.519624 -380.286768) (xy 30.520044 -380.295954) (xy 30.52655 -380.313139) (xy 30.532324 -380.320296)
			(xy 30.554132 -380.345932) (xy 30.592083 -380.40152) (xy 30.623117 -380.461245) (xy 30.646791 -380.524252)
			(xy 30.662763 -380.589636) (xy 30.6708 -380.656404) (xy 33.948845 -380.656404) (xy 33.95692 -380.589467)
			(xy 33.972953 -380.523978) (xy 33.996716 -380.460882) (xy 34.027865 -380.401087) (xy 34.065953 -380.345453)
			(xy 34.087816 -380.319788) (xy 34.093602 -380.312635) (xy 34.100122 -380.29545) (xy 34.100516 -380.28626)
			(xy 34.100516 -379.794008) (xy 34.100098 -379.784822) (xy 34.093589 -379.767638) (xy 34.087816 -379.76048)
			(xy 34.065999 -379.734776) (xy 34.027907 -379.679148) (xy 33.996754 -379.619357) (xy 33.972986 -379.556265)
			(xy 33.956947 -379.49078) (xy 33.948867 -379.423846) (xy 33.948863 -379.356426) (xy 33.956934 -379.289491)
			(xy 33.972965 -379.224004) (xy 33.996724 -379.160909) (xy 34.02787 -379.101114) (xy 34.065954 -379.045481)
			(xy 34.087816 -379.019816) (xy 34.093633 -379.012685) (xy 34.100135 -378.995484) (xy 34.100516 -378.986288)
			(xy 34.100516 -378.828554) (xy 34.100988 -378.818427) (xy 34.108727 -378.79971) (xy 34.123017 -378.785356)
			(xy 34.1417 -378.777534) (xy 34.151824 -378.776992) (xy 34.868104 -378.776992) (xy 34.878257 -378.777418)
			(xy 34.897008 -378.785214) (xy 34.911331 -378.799609) (xy 34.919032 -378.818399) (xy 34.919412 -378.828554)
			(xy 34.919412 -378.986288) (xy 34.919825 -378.995475) (xy 34.926336 -379.012659) (xy 34.932112 -379.019816)
			(xy 34.954023 -379.045443) (xy 34.992109 -379.101083) (xy 35.023257 -379.160885) (xy 35.047018 -379.223986)
			(xy 35.06305 -379.28948) (xy 35.071122 -379.356422) (xy 35.071117 -379.42385) (xy 35.063037 -379.490791)
			(xy 35.046997 -379.556283) (xy 35.023228 -379.619381) (xy 34.992072 -379.679179) (xy 34.953978 -379.734815)
			(xy 34.932112 -379.76048) (xy 34.9263 -379.767615) (xy 34.919794 -379.784813) (xy 34.919412 -379.794008)
			(xy 34.919412 -380.28626) (xy 34.919839 -380.295446) (xy 34.92634 -380.31263) (xy 34.932112 -380.319788)
			(xy 34.953995 -380.345437) (xy 34.992083 -380.401074) (xy 35.023232 -380.460873) (xy 35.046994 -380.523972)
			(xy 35.063028 -380.589463) (xy 35.071102 -380.656403) (xy 35.071102 -380.656464) (xy 38.349165 -380.656464)
			(xy 38.357207 -380.589643) (xy 38.373176 -380.524262) (xy 38.396845 -380.461259) (xy 38.427874 -380.401536)
			(xy 38.465819 -380.345949) (xy 38.487604 -380.320296) (xy 38.493385 -380.31314) (xy 38.499909 -380.295958)
			(xy 38.500304 -380.286768) (xy 38.500304 -379.7935) (xy 38.499893 -379.784313) (xy 38.49338 -379.767129)
			(xy 38.487604 -379.759972) (xy 38.465865 -379.73428) (xy 38.427917 -379.678699) (xy 38.396884 -379.61898)
			(xy 38.37321 -379.555981) (xy 38.357234 -379.490604) (xy 38.349187 -379.423786) (xy 38.349183 -379.356486)
			(xy 38.357221 -379.289667) (xy 38.373188 -379.224288) (xy 38.396854 -379.161286) (xy 38.42788 -379.101563)
			(xy 38.465821 -379.045977) (xy 38.487604 -379.020324) (xy 38.493416 -379.01319) (xy 38.499921 -378.995991)
			(xy 38.500304 -378.986796) (xy 38.500304 -378.828554) (xy 38.500795 -378.818397) (xy 38.508578 -378.799634)
			(xy 38.522944 -378.785271) (xy 38.541709 -378.777493) (xy 38.551866 -378.776992) (xy 39.268146 -378.776992)
			(xy 39.278301 -378.777495) (xy 39.297062 -378.785276) (xy 39.311424 -378.799638) (xy 39.319205 -378.818399)
			(xy 39.319708 -378.828554) (xy 39.319708 -378.986796) (xy 39.320118 -378.995983) (xy 39.326632 -379.013168)
			(xy 39.332408 -379.020324) (xy 39.354244 -379.045937) (xy 39.392195 -379.101528) (xy 39.423229 -379.161256)
			(xy 39.446902 -379.224266) (xy 39.462873 -379.289653) (xy 39.470914 -379.356481) (xy 39.47091 -379.423791)
			(xy 39.46286 -379.490618) (xy 39.44688 -379.556003) (xy 39.4232 -379.61901) (xy 39.392158 -379.678735)
			(xy 39.3542 -379.734321) (xy 39.332408 -379.759972) (xy 39.326599 -379.767109) (xy 39.320092 -379.784306)
			(xy 39.319708 -379.7935) (xy 39.319708 -380.286768) (xy 39.320132 -380.295954) (xy 39.326636 -380.313138)
			(xy 39.332408 -380.320296) (xy 39.354217 -380.345931) (xy 39.392169 -380.401519) (xy 39.423204 -380.461244)
			(xy 39.446878 -380.524251) (xy 39.462851 -380.589636) (xy 39.470887 -380.656404) (xy 42.748933 -380.656404)
			(xy 42.757007 -380.589467) (xy 42.773041 -380.523979) (xy 42.796803 -380.460883) (xy 42.827951 -380.401087)
			(xy 42.866037 -380.345453) (xy 42.8879 -380.319788) (xy 42.893684 -380.312634) (xy 42.900206 -380.29545)
			(xy 42.9006 -380.28626) (xy 42.9006 -379.794008) (xy 42.900186 -379.784821) (xy 42.893675 -379.767637)
			(xy 42.8879 -379.76048) (xy 42.866083 -379.734776) (xy 42.827993 -379.679147) (xy 42.79684 -379.619356)
			(xy 42.773073 -379.556264) (xy 42.757035 -379.49078) (xy 42.748955 -379.423846) (xy 42.748951 -379.356426)
			(xy 42.757022 -379.289491) (xy 42.773052 -379.224005) (xy 42.796811 -379.16091) (xy 42.827956 -379.101115)
			(xy 42.866039 -379.045481) (xy 42.8879 -379.019816) (xy 42.893715 -379.012684) (xy 42.900219 -378.995483)
			(xy 42.9006 -378.986288) (xy 42.9006 -378.828554) (xy 42.901088 -378.818429) (xy 42.908823 -378.799715)
			(xy 42.923108 -378.785361) (xy 42.941786 -378.777537) (xy 42.951908 -378.776992) (xy 43.668188 -378.776992)
			(xy 43.67834 -378.777431) (xy 43.697091 -378.785221) (xy 43.711414 -378.799613) (xy 43.719116 -378.8184)
			(xy 43.719496 -378.828554) (xy 43.719496 -378.986288) (xy 43.719913 -378.995474) (xy 43.726422 -379.012659)
			(xy 43.732196 -379.019816) (xy 43.754107 -379.045442) (xy 43.792195 -379.101082) (xy 43.823344 -379.160884)
			(xy 43.847105 -379.223986) (xy 43.863138 -379.28948) (xy 43.87121 -379.356422) (xy 43.871205 -379.42385)
			(xy 43.863125 -379.490791) (xy 43.847084 -379.556283) (xy 43.823314 -379.619382) (xy 43.792158 -379.67918)
			(xy 43.754063 -379.734815) (xy 43.732196 -379.76048) (xy 43.726382 -379.767613) (xy 43.719878 -379.784813)
			(xy 43.719496 -379.794008) (xy 43.719496 -380.28626) (xy 43.719926 -380.295445) (xy 43.726426 -380.31263)
			(xy 43.732196 -380.319788) (xy 43.75408 -380.345437) (xy 43.792168 -380.401074) (xy 43.823318 -380.460872)
			(xy 43.847081 -380.523971) (xy 43.863116 -380.589462) (xy 43.87119 -380.656402) (xy 43.87119 -380.656463)
			(xy 73.548987 -380.656463) (xy 73.557029 -380.589642) (xy 73.572999 -380.524261) (xy 73.596669 -380.461258)
			(xy 73.6277 -380.401535) (xy 73.665646 -380.345948) (xy 73.687432 -380.320296) (xy 73.693217 -380.313143)
			(xy 73.699738 -380.295958) (xy 73.700132 -380.286768) (xy 73.700132 -379.7935) (xy 73.699715 -379.784314)
			(xy 73.693205 -379.76713) (xy 73.687432 -379.759972) (xy 73.665692 -379.734281) (xy 73.627742 -379.6787)
			(xy 73.596707 -379.618982) (xy 73.573032 -379.555982) (xy 73.557056 -379.490605) (xy 73.549008 -379.423787)
			(xy 73.549004 -379.356486) (xy 73.557043 -379.289666) (xy 73.573011 -379.224287) (xy 73.596678 -379.161285)
			(xy 73.627705 -379.101562) (xy 73.665648 -379.045976) (xy 73.687432 -379.020324) (xy 73.693247 -379.013192)
			(xy 73.69975 -378.995991) (xy 73.700132 -378.986796) (xy 73.700132 -378.828554) (xy 73.700596 -378.818394)
			(xy 73.708384 -378.799625) (xy 73.722759 -378.785262) (xy 73.741534 -378.777488) (xy 73.751694 -378.776992)
			(xy 74.467974 -378.776992) (xy 74.478125 -378.777553) (xy 74.496884 -378.785311) (xy 74.511249 -378.799655)
			(xy 74.519032 -378.818404) (xy 74.519536 -378.828554) (xy 74.519536 -378.986796) (xy 74.519962 -378.995981)
			(xy 74.526466 -379.013165) (xy 74.532236 -379.020324) (xy 74.554072 -379.045937) (xy 74.592021 -379.101528)
			(xy 74.623053 -379.161257) (xy 74.646725 -379.224267) (xy 74.662695 -379.289654) (xy 74.670736 -379.356481)
			(xy 74.670731 -379.423791) (xy 74.662682 -379.490617) (xy 74.646703 -379.556002) (xy 74.623024 -379.619009)
			(xy 74.591984 -379.678734) (xy 74.554028 -379.73432) (xy 74.532236 -379.759972) (xy 74.526419 -379.767102)
			(xy 74.519918 -379.784304) (xy 74.519536 -379.7935) (xy 74.519536 -380.286768) (xy 74.519976 -380.295952)
			(xy 74.52647 -380.313136) (xy 74.532236 -380.320296) (xy 74.554044 -380.345932) (xy 74.591994 -380.40152)
			(xy 74.623028 -380.461246) (xy 74.6467 -380.524252) (xy 74.662673 -380.589637) (xy 74.670709 -380.656404)
			(xy 77.948754 -380.656404) (xy 77.956829 -380.589466) (xy 77.972863 -380.523978) (xy 77.996626 -380.460882)
			(xy 78.027776 -380.401086) (xy 78.065864 -380.345453) (xy 78.087728 -380.319788) (xy 78.093516 -380.312637)
			(xy 78.100035 -380.295451) (xy 78.100428 -380.28626) (xy 78.100428 -379.794008) (xy 78.100008 -379.784822)
			(xy 78.093501 -379.767638) (xy 78.087728 -379.76048) (xy 78.06591 -379.734776) (xy 78.027818 -379.679148)
			(xy 77.996664 -379.619357) (xy 77.972896 -379.556265) (xy 77.956856 -379.490781) (xy 77.948776 -379.423846)
			(xy 77.948772 -379.356426) (xy 77.956843 -379.28949) (xy 77.972874 -379.224004) (xy 77.996634 -379.160909)
			(xy 78.027781 -379.101114) (xy 78.065866 -379.045481) (xy 78.087728 -379.019816) (xy 78.093546 -379.012686)
			(xy 78.100047 -378.995484) (xy 78.100428 -378.986288) (xy 78.100428 -378.828554) (xy 78.100889 -378.818426)
			(xy 78.108629 -378.799706) (xy 78.122923 -378.785352) (xy 78.14161 -378.777532) (xy 78.151736 -378.776992)
			(xy 78.868016 -378.776992) (xy 78.878125 -378.777472) (xy 78.896802 -378.785213) (xy 78.911096 -378.799512)
			(xy 78.918831 -378.818191) (xy 78.919324 -378.8283) (xy 78.919324 -378.986288) (xy 78.919734 -378.995475)
			(xy 78.926247 -379.01266) (xy 78.932024 -379.019816) (xy 78.953934 -379.045443) (xy 78.99202 -379.101083)
			(xy 79.023167 -379.160885) (xy 79.046928 -379.223987) (xy 79.062959 -379.28948) (xy 79.071031 -379.356423)
			(xy 79.071026 -379.42385) (xy 79.062946 -379.490791) (xy 79.046906 -379.556282) (xy 79.023138 -379.619381)
			(xy 78.991983 -379.679179) (xy 78.95389 -379.734814) (xy 78.932024 -379.76048) (xy 78.926214 -379.767616)
			(xy 78.919706 -379.784813) (xy 78.919324 -379.794008) (xy 78.919324 -380.28626) (xy 78.919748 -380.295446)
			(xy 78.926251 -380.312631) (xy 78.932024 -380.319788) (xy 78.953907 -380.345437) (xy 78.991993 -380.401075)
			(xy 79.023142 -380.460873) (xy 79.046904 -380.523972) (xy 79.062937 -380.589463) (xy 79.071011 -380.656403)
			(xy 79.071011 -380.656464) (xy 82.349074 -380.656464) (xy 82.357116 -380.589643) (xy 82.373086 -380.524262)
			(xy 82.396755 -380.461258) (xy 82.427785 -380.401535) (xy 82.46573 -380.345948) (xy 82.487516 -380.320296)
			(xy 82.493299 -380.313141) (xy 82.499821 -380.295958) (xy 82.500216 -380.286768) (xy 82.500216 -379.7935)
			(xy 82.499803 -379.784313) (xy 82.493291 -379.767129) (xy 82.487516 -379.759972) (xy 82.465776 -379.734281)
			(xy 82.427828 -379.678699) (xy 82.396794 -379.618981) (xy 82.373119 -379.555982) (xy 82.357144 -379.490604)
			(xy 82.349096 -379.423786) (xy 82.349092 -379.356486) (xy 82.357131 -379.289667) (xy 82.373098 -379.224288)
			(xy 82.396764 -379.161285) (xy 82.427791 -379.101563) (xy 82.465732 -379.045977) (xy 82.487516 -379.020324)
			(xy 82.493329 -379.013191) (xy 82.499833 -378.995991) (xy 82.500216 -378.986796) (xy 82.500216 -378.828554)
			(xy 82.500695 -378.818396) (xy 82.508481 -378.79963) (xy 82.52285 -378.785267) (xy 82.54162 -378.777491)
			(xy 82.551778 -378.776992) (xy 83.268058 -378.776992) (xy 83.278207 -378.777567) (xy 83.296967 -378.785319)
			(xy 83.311332 -378.799659) (xy 83.319116 -378.818405) (xy 83.31962 -378.828554) (xy 83.31962 -378.986796)
			(xy 83.320028 -378.995984) (xy 83.326543 -379.013168) (xy 83.33232 -379.020324) (xy 83.354156 -379.045937)
			(xy 83.392107 -379.101528) (xy 83.42314 -379.161256) (xy 83.446812 -379.224266) (xy 83.462783 -379.289654)
			(xy 83.470824 -379.356481) (xy 83.470819 -379.423791) (xy 83.46277 -379.490618) (xy 83.446791 -379.556003)
			(xy 83.423111 -379.61901) (xy 83.392069 -379.678734) (xy 83.354112 -379.734321) (xy 83.33232 -379.759972)
			(xy 83.326513 -379.76711) (xy 83.320004 -379.784306) (xy 83.31962 -379.7935) (xy 83.31962 -380.286768)
			(xy 83.320041 -380.295954) (xy 83.326547 -380.313139) (xy 83.33232 -380.320296) (xy 83.354129 -380.345931)
			(xy 83.392079 -380.401519) (xy 83.423114 -380.461245) (xy 83.446788 -380.524252) (xy 83.46276 -380.589636)
			(xy 83.470797 -380.656404) (xy 86.748842 -380.656404) (xy 86.756916 -380.589467) (xy 86.77295 -380.523979)
			(xy 86.796713 -380.460883) (xy 86.827862 -380.401087) (xy 86.865949 -380.345453) (xy 86.887812 -380.319788)
			(xy 86.893598 -380.312635) (xy 86.900118 -380.29545) (xy 86.900512 -380.28626) (xy 86.900512 -379.794008)
			(xy 86.900095 -379.784822) (xy 86.893586 -379.767637) (xy 86.887812 -379.76048) (xy 86.865995 -379.734776)
			(xy 86.827904 -379.679147) (xy 86.79675 -379.619357) (xy 86.772983 -379.556265) (xy 86.756944 -379.49078)
			(xy 86.748864 -379.423846) (xy 86.74886 -379.356426) (xy 86.756931 -379.289491) (xy 86.772962 -379.224004)
			(xy 86.796721 -379.160909) (xy 86.827867 -379.101115) (xy 86.86595 -379.045481) (xy 86.887812 -379.019816)
			(xy 86.893628 -379.012685) (xy 86.900131 -378.995483) (xy 86.900512 -378.986288) (xy 86.900512 -378.828554)
			(xy 86.900988 -378.818428) (xy 86.908726 -378.799711) (xy 86.923015 -378.785357) (xy 86.941696 -378.777535)
			(xy 86.95182 -378.776992) (xy 87.6681 -378.776992) (xy 87.678208 -378.777485) (xy 87.696884 -378.785221)
			(xy 87.711179 -378.799516) (xy 87.718915 -378.818192) (xy 87.719408 -378.8283) (xy 87.719408 -378.986288)
			(xy 87.719822 -378.995475) (xy 87.726333 -379.012659) (xy 87.732108 -379.019816) (xy 87.754019 -379.045442)
			(xy 87.792106 -379.101083) (xy 87.823254 -379.160884) (xy 87.847015 -379.223986) (xy 87.863047 -379.28948)
			(xy 87.871119 -379.356422) (xy 87.871114 -379.42385) (xy 87.863034 -379.490791) (xy 87.846994 -379.556283)
			(xy 87.823224 -379.619382) (xy 87.792068 -379.679179) (xy 87.753975 -379.734815) (xy 87.732108 -379.76048)
			(xy 87.726296 -379.767614) (xy 87.71979 -379.784813) (xy 87.719408 -379.794008) (xy 87.719408 -380.28626)
			(xy 87.719836 -380.295445) (xy 87.726337 -380.31263) (xy 87.732108 -380.319788) (xy 87.753991 -380.345437)
			(xy 87.792079 -380.401074) (xy 87.823228 -380.460873) (xy 87.846991 -380.523972) (xy 87.863025 -380.589463)
			(xy 87.871099 -380.656402) (xy 87.871097 -380.723828) (xy 87.863019 -380.790767) (xy 87.846982 -380.856257)
			(xy 87.838954 -380.877572) (xy 105.0036 -380.877572) (xy 105.0036 -380.013972) (xy 105.00409 -379.983988)
			(xy 105.011918 -379.924532) (xy 105.027439 -379.866607) (xy 105.050388 -379.811203) (xy 105.080372 -379.759269)
			(xy 105.116878 -379.711693) (xy 105.159283 -379.669288) (xy 105.206859 -379.632782) (xy 105.258793 -379.602798)
			(xy 105.314197 -379.579849) (xy 105.372122 -379.564328) (xy 105.431578 -379.5565) (xy 105.491546 -379.5565)
			(xy 105.551002 -379.564328) (xy 105.608927 -379.579849) (xy 105.664331 -379.602798) (xy 105.716265 -379.632782)
			(xy 105.763841 -379.669288) (xy 105.806246 -379.711693) (xy 105.842752 -379.759269) (xy 105.872736 -379.811203)
			(xy 105.895685 -379.866607) (xy 105.911206 -379.924532) (xy 105.919034 -379.983988) (xy 105.919524 -380.013972)
			(xy 105.919524 -380.656403) (xy 117.548873 -380.656403) (xy 117.556947 -380.589466) (xy 117.572982 -380.523977)
			(xy 117.596746 -380.460881) (xy 117.627898 -380.401085) (xy 117.665987 -380.345452) (xy 117.687852 -380.319788)
			(xy 117.693643 -380.312639) (xy 117.700159 -380.295451) (xy 117.700552 -380.28626) (xy 117.700552 -379.794008)
			(xy 117.700126 -379.784823) (xy 117.693622 -379.767639) (xy 117.687852 -379.76048) (xy 117.666033 -379.734777)
			(xy 117.62794 -379.679149) (xy 117.596784 -379.619358) (xy 117.573015 -379.556266) (xy 117.556975 -379.490781)
			(xy 117.548894 -379.423846) (xy 117.54889 -379.356426) (xy 117.556962 -379.28949) (xy 117.572994 -379.224003)
			(xy 117.596755 -379.160908) (xy 117.627903 -379.101113) (xy 117.665989 -379.04548) (xy 117.687852 -379.019816)
			(xy 117.693673 -379.012688) (xy 117.700172 -378.995484) (xy 117.700552 -378.986288) (xy 117.700552 -378.828554)
			(xy 117.700989 -378.818423) (xy 117.708734 -378.799698) (xy 117.723036 -378.785343) (xy 117.741731 -378.777528)
			(xy 117.75186 -378.776992) (xy 118.46814 -378.776992) (xy 118.478296 -378.777389) (xy 118.497047 -378.785196)
			(xy 118.511369 -378.7996) (xy 118.519069 -378.818396) (xy 118.519448 -378.828554) (xy 118.519448 -378.986288)
			(xy 118.519875 -378.995473) (xy 118.526378 -379.012657) (xy 118.532148 -379.019816) (xy 118.554061 -379.045441)
			(xy 118.592152 -379.10108) (xy 118.623303 -379.160882) (xy 118.647067 -379.223984) (xy 118.663101 -379.289478)
			(xy 118.671174 -379.356422) (xy 118.671169 -379.42385) (xy 118.663088 -379.490793) (xy 118.647046 -379.556285)
			(xy 118.623274 -379.619384) (xy 118.592115 -379.679181) (xy 118.554017 -379.734816) (xy 118.532148 -379.76048)
			(xy 118.526329 -379.767609) (xy 118.519829 -379.784812) (xy 118.519448 -379.794008) (xy 118.519448 -380.28626)
			(xy 118.519889 -380.295444) (xy 118.526382 -380.312628) (xy 118.532148 -380.319788) (xy 118.554033 -380.345436)
			(xy 118.592125 -380.401072) (xy 118.623278 -380.46087) (xy 118.647043 -380.523969) (xy 118.663079 -380.589461)
			(xy 118.671154 -380.656402) (xy 118.671154 -380.656463) (xy 121.949193 -380.656463) (xy 121.957235 -380.589642)
			(xy 121.973206 -380.524261) (xy 121.996876 -380.461257) (xy 122.027907 -380.401534) (xy 122.065854 -380.345948)
			(xy 122.08764 -380.320296) (xy 122.093426 -380.313143) (xy 122.099946 -380.295958) (xy 122.10034 -380.286768)
			(xy 122.10034 -379.7935) (xy 122.099921 -379.784314) (xy 122.093413 -379.76713) (xy 122.08764 -379.759972)
			(xy 122.0659 -379.734281) (xy 122.027949 -379.6787) (xy 121.996914 -379.618982) (xy 121.973238 -379.555982)
			(xy 121.957262 -379.490605) (xy 121.949214 -379.423787) (xy 121.94921 -379.356485) (xy 121.957249 -379.289666)
			(xy 121.973217 -379.224287) (xy 121.996884 -379.161284) (xy 122.027912 -379.101562) (xy 122.065855 -379.045976)
			(xy 122.08764 -379.020324) (xy 122.093456 -379.013193) (xy 122.099958 -378.995991) (xy 122.10034 -378.986796)
			(xy 122.10034 -378.828554) (xy 122.100796 -378.818393) (xy 122.108586 -378.799623) (xy 122.122963 -378.785259)
			(xy 122.141741 -378.777486) (xy 122.151902 -378.776992) (xy 122.868182 -378.776992) (xy 122.878333 -378.777547)
			(xy 122.897093 -378.785307) (xy 122.911457 -378.799653) (xy 122.919241 -378.818404) (xy 122.919744 -378.828554)
			(xy 122.919744 -378.986796) (xy 122.920169 -378.995981) (xy 122.926674 -379.013165) (xy 122.932444 -379.020324)
			(xy 122.95428 -379.045937) (xy 122.992228 -379.101529) (xy 123.02326 -379.161257) (xy 123.046931 -379.224267)
			(xy 123.062901 -379.289654) (xy 123.070942 -379.356482) (xy 123.070937 -379.423791) (xy 123.062888 -379.490617)
			(xy 123.04691 -379.556002) (xy 123.023231 -379.619009) (xy 122.992191 -379.678733) (xy 122.954235 -379.73432)
			(xy 122.932444 -379.759972) (xy 122.926627 -379.767103) (xy 122.920126 -379.784305) (xy 122.919744 -379.7935)
			(xy 122.919744 -380.286768) (xy 122.920182 -380.295952) (xy 122.926678 -380.313136) (xy 122.932444 -380.320296)
			(xy 122.954252 -380.345932) (xy 122.992201 -380.40152) (xy 123.023235 -380.461246) (xy 123.046907 -380.524252)
			(xy 123.062879 -380.589637) (xy 123.070915 -380.656404) (xy 126.34896 -380.656404) (xy 126.357035 -380.589466)
			(xy 126.373069 -380.523978) (xy 126.396833 -380.460881) (xy 126.427983 -380.401086) (xy 126.466072 -380.345453)
			(xy 126.487936 -380.319788) (xy 126.493725 -380.312637) (xy 126.500243 -380.295451) (xy 126.500636 -380.28626)
			(xy 126.500636 -379.794008) (xy 126.500214 -379.784822) (xy 126.493708 -379.767638) (xy 126.487936 -379.76048)
			(xy 126.466118 -379.734776) (xy 126.428025 -379.679148) (xy 126.396871 -379.619358) (xy 126.373102 -379.556266)
			(xy 126.357062 -379.490781) (xy 126.348982 -379.423846) (xy 126.348978 -379.356426) (xy 126.357049 -379.28949)
			(xy 126.373081 -379.224003) (xy 126.396841 -379.160908) (xy 126.427988 -379.101114) (xy 126.466074 -379.045481)
			(xy 126.487936 -379.019816) (xy 126.493755 -379.012687) (xy 126.500256 -378.995484) (xy 126.500636 -378.986288)
			(xy 126.500636 -378.828554) (xy 126.501089 -378.818425) (xy 126.508831 -378.799703) (xy 126.523127 -378.785349)
			(xy 126.541817 -378.777531) (xy 126.551944 -378.776992) (xy 127.268224 -378.776992) (xy 127.278379 -378.777402)
			(xy 127.29713 -378.785204) (xy 127.311452 -378.799604) (xy 127.319153 -378.818397) (xy 127.319532 -378.828554)
			(xy 127.319532 -378.986288) (xy 127.319963 -378.995473) (xy 127.326464 -379.012656) (xy 127.332232 -379.019816)
			(xy 127.354142 -379.045443) (xy 127.392227 -379.101084) (xy 127.423374 -379.160885) (xy 127.447134 -379.223987)
			(xy 127.463165 -379.289481) (xy 127.471237 -379.356423) (xy 127.471232 -379.423849) (xy 127.463152 -379.49079)
			(xy 127.447113 -379.556282) (xy 127.423345 -379.61938) (xy 127.39219 -379.679178) (xy 127.354098 -379.734814)
			(xy 127.332232 -379.76048) (xy 127.326411 -379.767607) (xy 127.319913 -379.784812) (xy 127.319532 -379.794008)
			(xy 127.319532 -380.28626) (xy 127.319977 -380.295443) (xy 127.326468 -380.312627) (xy 127.332232 -380.319788)
			(xy 127.354114 -380.345438) (xy 127.392201 -380.401075) (xy 127.423349 -380.460874) (xy 127.44711 -380.523973)
			(xy 127.463143 -380.589463) (xy 127.471217 -380.656403) (xy 127.471217 -380.656463) (xy 130.74928 -380.656463)
			(xy 130.757322 -380.589642) (xy 130.773292 -380.524262) (xy 130.796962 -380.461258) (xy 130.827992 -380.401535)
			(xy 130.865938 -380.345948) (xy 130.887724 -380.320296) (xy 130.893508 -380.313142) (xy 130.900029 -380.295958)
			(xy 130.900424 -380.286768) (xy 130.900424 -379.7935) (xy 130.900009 -379.784313) (xy 130.893498 -379.767129)
			(xy 130.887724 -379.759972) (xy 130.865984 -379.734281) (xy 130.828035 -379.678699) (xy 130.797 -379.618981)
			(xy 130.773326 -379.555982) (xy 130.75735 -379.490605) (xy 130.749302 -379.423787) (xy 130.749298 -379.356486)
			(xy 130.757337 -379.289667) (xy 130.773304 -379.224287) (xy 130.796971 -379.161285) (xy 130.827998 -379.101563)
			(xy 130.86594 -379.045977) (xy 130.887724 -379.020324) (xy 130.893538 -379.013191) (xy 130.900042 -378.995991)
			(xy 130.900424 -378.986796) (xy 130.900424 -378.828554) (xy 130.900895 -378.818395) (xy 130.908682 -378.799628)
			(xy 130.923054 -378.785264) (xy 130.941827 -378.777489) (xy 130.951986 -378.776992) (xy 131.668266 -378.776992)
			(xy 131.678416 -378.77756) (xy 131.697175 -378.785315) (xy 131.71154 -378.799657) (xy 131.719324 -378.818405)
			(xy 131.719828 -378.828554) (xy 131.719828 -378.986796) (xy 131.720234 -378.995984) (xy 131.72675 -379.013168)
			(xy 131.732528 -379.020324) (xy 131.754364 -379.045937) (xy 131.792314 -379.101528) (xy 131.823347 -379.161257)
			(xy 131.847018 -379.224267) (xy 131.862989 -379.289654) (xy 131.87103 -379.356481) (xy 131.871025 -379.423791)
			(xy 131.862976 -379.490617) (xy 131.846997 -379.556003) (xy 131.823317 -379.619009) (xy 131.792277 -379.678734)
			(xy 131.75432 -379.73432) (xy 131.732528 -379.759972) (xy 131.72671 -379.767101) (xy 131.72021 -379.784304)
			(xy 131.719828 -379.7935) (xy 131.719828 -380.286768) (xy 131.720247 -380.295954) (xy 131.726754 -380.313139)
			(xy 131.732528 -380.320296) (xy 131.754336 -380.345932) (xy 131.792287 -380.40152) (xy 131.823321 -380.461245)
			(xy 131.846994 -380.524252) (xy 131.862967 -380.589636) (xy 131.871003 -380.656404) (xy 161.548806 -380.656404)
			(xy 161.55688 -380.589468) (xy 161.572912 -380.523981) (xy 161.596672 -380.460885) (xy 161.627819 -380.401089)
			(xy 161.665902 -380.345454) (xy 161.687764 -380.319788) (xy 161.693556 -380.31264) (xy 161.700072 -380.295451)
			(xy 161.700464 -380.28626) (xy 161.700464 -379.794008) (xy 161.700036 -379.784823) (xy 161.693533 -379.767639)
			(xy 161.687764 -379.76048) (xy 161.665948 -379.734775) (xy 161.627861 -379.679146) (xy 161.59671 -379.619354)
			(xy 161.572945 -379.556263) (xy 161.556907 -379.490779) (xy 161.548828 -379.423846) (xy 161.548823 -379.356426)
			(xy 161.556894 -379.289492) (xy 161.572923 -379.224006) (xy 161.59668 -379.160911) (xy 161.627824 -379.101116)
			(xy 161.665904 -379.045482) (xy 161.687764 -379.019816) (xy 161.693587 -379.01269) (xy 161.700084 -378.995484)
			(xy 161.700464 -378.986288) (xy 161.700464 -378.828554) (xy 161.70089 -378.818421) (xy 161.708637 -378.799695)
			(xy 161.722942 -378.785339) (xy 161.741641 -378.777526) (xy 161.751772 -378.776992) (xy 162.468052 -378.776992)
			(xy 162.47817 -378.777455) (xy 162.496871 -378.785186) (xy 162.511187 -378.799488) (xy 162.518935 -378.818182)
			(xy 162.51936 -378.8283) (xy 162.51936 -378.986288) (xy 162.519785 -378.995473) (xy 162.526289 -379.012658)
			(xy 162.53206 -379.019816) (xy 162.553973 -379.045442) (xy 162.592062 -379.101081) (xy 162.623213 -379.160882)
			(xy 162.646977 -379.223984) (xy 162.66301 -379.289479) (xy 162.671083 -379.356422) (xy 162.671078 -379.42385)
			(xy 162.662997 -379.490792) (xy 162.646955 -379.556285) (xy 162.623184 -379.619384) (xy 162.592025 -379.679181)
			(xy 162.553928 -379.734815) (xy 162.53206 -379.76048) (xy 162.526242 -379.76761) (xy 162.519741 -379.784812)
			(xy 162.51936 -379.794008) (xy 162.51936 -380.28626) (xy 162.519799 -380.295444) (xy 162.526294 -380.312628)
			(xy 162.53206 -380.319788) (xy 162.553945 -380.345436) (xy 162.592036 -380.401072) (xy 162.623188 -380.460871)
			(xy 162.646953 -380.52397) (xy 162.662988 -380.589461) (xy 162.671063 -380.656402) (xy 162.671063 -380.656463)
			(xy 165.949102 -380.656463) (xy 165.957144 -380.589642) (xy 165.973115 -380.524261) (xy 165.996786 -380.461257)
			(xy 166.027818 -380.401534) (xy 166.065765 -380.345948) (xy 166.087552 -380.320296) (xy 166.093339 -380.313144)
			(xy 166.099858 -380.295959) (xy 166.100252 -380.286768) (xy 166.100252 -379.7935) (xy 166.09983 -379.784314)
			(xy 166.093323 -379.76713) (xy 166.087552 -379.759972) (xy 166.065811 -379.734281) (xy 166.02786 -379.678701)
			(xy 165.996824 -379.618982) (xy 165.973148 -379.555983) (xy 165.957171 -379.490605) (xy 165.949123 -379.423787)
			(xy 165.949119 -379.356485) (xy 165.957158 -379.289666) (xy 165.973127 -379.224286) (xy 165.996795 -379.161284)
			(xy 166.027823 -379.101562) (xy 166.065767 -379.045976) (xy 166.087552 -379.020324) (xy 166.09337 -379.013194)
			(xy 166.09987 -378.995992) (xy 166.100252 -378.986796) (xy 166.100252 -378.828554) (xy 166.100696 -378.818392)
			(xy 166.108488 -378.799619) (xy 166.122869 -378.785255) (xy 166.141651 -378.777484) (xy 166.151814 -378.776992)
			(xy 166.868094 -378.776992) (xy 166.878246 -378.777537) (xy 166.897006 -378.785301) (xy 166.91137 -378.79965)
			(xy 166.919153 -378.818403) (xy 166.919656 -378.828554) (xy 166.919656 -378.986796) (xy 166.920078 -378.995982)
			(xy 166.926584 -379.013166) (xy 166.932356 -379.020324) (xy 166.954191 -379.045937) (xy 166.992139 -379.101529)
			(xy 167.02317 -379.161258) (xy 167.046841 -379.224268) (xy 167.06281 -379.289655) (xy 167.070851 -379.356482)
			(xy 167.070847 -379.423791) (xy 167.062798 -379.490617) (xy 167.046819 -379.556001) (xy 167.023141 -379.619008)
			(xy 166.992102 -379.678733) (xy 166.954147 -379.73432) (xy 166.932356 -379.759972) (xy 166.926541 -379.767104)
			(xy 166.920038 -379.784305) (xy 166.919656 -379.7935) (xy 166.919656 -380.286768) (xy 166.920091 -380.295952)
			(xy 166.926588 -380.313137) (xy 166.932356 -380.320296) (xy 166.954164 -380.345932) (xy 166.992112 -380.40152)
			(xy 167.023145 -380.461246) (xy 167.046817 -380.524253) (xy 167.062789 -380.589637) (xy 167.070824 -380.656403)
			(xy 170.34887 -380.656403) (xy 170.356944 -380.589466) (xy 170.372979 -380.523977) (xy 170.396743 -380.460881)
			(xy 170.427894 -380.401086) (xy 170.465984 -380.345452) (xy 170.487848 -380.319788) (xy 170.493638 -380.312638)
			(xy 170.500155 -380.295451) (xy 170.500548 -380.28626) (xy 170.500548 -379.794008) (xy 170.500123 -379.784823)
			(xy 170.493619 -379.767639) (xy 170.487848 -379.76048) (xy 170.46603 -379.734777) (xy 170.427936 -379.679149)
			(xy 170.396781 -379.619358) (xy 170.373012 -379.556266) (xy 170.356971 -379.490781) (xy 170.348891 -379.423846)
			(xy 170.348887 -379.356426) (xy 170.356959 -379.28949) (xy 170.37299 -379.224003) (xy 170.396751 -379.160908)
			(xy 170.427899 -379.101113) (xy 170.465985 -379.04548) (xy 170.487848 -379.019816) (xy 170.493669 -379.012688)
			(xy 170.500168 -378.995484) (xy 170.500548 -378.986288) (xy 170.500548 -378.828554) (xy 170.500989 -378.818423)
			(xy 170.508734 -378.7997) (xy 170.523034 -378.785345) (xy 170.541727 -378.777529) (xy 170.551856 -378.776992)
			(xy 171.268136 -378.776992) (xy 171.278291 -378.777392) (xy 171.297043 -378.785198) (xy 171.311365 -378.799601)
			(xy 171.319065 -378.818396) (xy 171.319444 -378.828554) (xy 171.319444 -378.986288) (xy 171.319872 -378.995473)
			(xy 171.326375 -379.012657) (xy 171.332144 -379.019816) (xy 171.354057 -379.045441) (xy 171.392148 -379.10108)
			(xy 171.4233 -379.160881) (xy 171.447064 -379.223984) (xy 171.463098 -379.289478) (xy 171.47117 -379.356422)
			(xy 171.471166 -379.42385) (xy 171.463085 -379.490793) (xy 171.447042 -379.556285) (xy 171.42327 -379.619384)
			(xy 171.392111 -379.679182) (xy 171.354013 -379.734816) (xy 171.332144 -379.76048) (xy 171.326324 -379.767608)
			(xy 171.319825 -379.784812) (xy 171.319444 -379.794008) (xy 171.319444 -380.28626) (xy 171.319886 -380.295444)
			(xy 171.326379 -380.312628) (xy 171.332144 -380.319788) (xy 171.35403 -380.345436) (xy 171.392121 -380.401072)
			(xy 171.423274 -380.46087) (xy 171.44704 -380.523969) (xy 171.463076 -380.589461) (xy 171.471151 -380.656402)
			(xy 171.471151 -380.656463) (xy 174.74919 -380.656463) (xy 174.757232 -380.589642) (xy 174.773202 -380.524261)
			(xy 174.796873 -380.461258) (xy 174.827904 -380.401535) (xy 174.86585 -380.345948) (xy 174.887636 -380.320296)
			(xy 174.893421 -380.313143) (xy 174.899942 -380.295958) (xy 174.900336 -380.286768) (xy 174.900336 -379.7935)
			(xy 174.899918 -379.784314) (xy 174.893409 -379.76713) (xy 174.887636 -379.759972) (xy 174.865896 -379.734281)
			(xy 174.827946 -379.6787) (xy 174.796911 -379.618982) (xy 174.773235 -379.555982) (xy 174.757259 -379.490605)
			(xy 174.749211 -379.423787) (xy 174.749207 -379.356486) (xy 174.757246 -379.289666) (xy 174.773214 -379.224287)
			(xy 174.796881 -379.161284) (xy 174.827909 -379.101562) (xy 174.865851 -379.045976) (xy 174.887636 -379.020324)
			(xy 174.893452 -379.013193) (xy 174.899954 -378.995991) (xy 174.900336 -378.986796) (xy 174.900336 -378.828554)
			(xy 174.900796 -378.818394) (xy 174.908585 -378.799624) (xy 174.922961 -378.78526) (xy 174.941737 -378.777487)
			(xy 174.951898 -378.776992) (xy 175.668178 -378.776992) (xy 175.678329 -378.77755) (xy 175.697089 -378.785309)
			(xy 175.711453 -378.799654) (xy 175.719237 -378.818404) (xy 175.71974 -378.828554) (xy 175.71974 -378.986796)
			(xy 175.720166 -378.995981) (xy 175.72667 -379.013165) (xy 175.73244 -379.020324) (xy 175.754276 -379.045937)
			(xy 175.792225 -379.101529) (xy 175.823257 -379.161257) (xy 175.846928 -379.224267) (xy 175.862898 -379.289654)
			(xy 175.870939 -379.356481) (xy 175.870934 -379.423791) (xy 175.862885 -379.490617) (xy 175.846907 -379.556002)
			(xy 175.823227 -379.619009) (xy 175.792187 -379.678734) (xy 175.754231 -379.73432) (xy 175.73244 -379.759972)
			(xy 175.726623 -379.767102) (xy 175.720122 -379.784305) (xy 175.71974 -379.7935) (xy 175.71974 -380.286768)
			(xy 175.720179 -380.295952) (xy 175.726674 -380.313136) (xy 175.73244 -380.320296) (xy 175.754248 -380.345932)
			(xy 175.792198 -380.40152) (xy 175.823231 -380.461246) (xy 175.846904 -380.524252) (xy 175.862876 -380.589637)
			(xy 175.870919 -380.656462) (xy 175.870917 -380.723769) (xy 175.862871 -380.790593) (xy 175.846895 -380.855977)
			(xy 175.823219 -380.918982) (xy 175.792182 -380.978706) (xy 175.75423 -381.034292) (xy 175.73244 -381.059944)
			(xy 175.726635 -381.067083) (xy 175.720127 -381.084278) (xy 175.71974 -381.093472) (xy 175.71974 -381.251206)
			(xy 175.71934 -381.261381) (xy 175.711549 -381.28018) (xy 175.697156 -381.294565) (xy 175.678353 -381.302346)
			(xy 175.668178 -381.302768) (xy 174.951898 -381.302768) (xy 174.941741 -381.302268) (xy 174.922973 -381.294494)
			(xy 174.908608 -381.280131) (xy 174.900832 -381.261363) (xy 174.900336 -381.251206) (xy 174.900336 -381.093472)
			(xy 174.899931 -381.084284) (xy 174.893413 -381.067101) (xy 174.887636 -381.059944) (xy 174.865868 -381.034275)
			(xy 174.827919 -380.978691) (xy 174.796885 -380.91897) (xy 174.773211 -380.855968) (xy 174.757237 -380.790587)
			(xy 174.749191 -380.723767) (xy 174.74919 -380.656463) (xy 171.471151 -380.656463) (xy 171.471149 -380.723828)
			(xy 171.46307 -380.790769) (xy 171.447031 -380.85626) (xy 171.423262 -380.919358) (xy 171.392106 -380.979154)
			(xy 171.354011 -381.034788) (xy 171.332144 -381.060452) (xy 171.326336 -381.067589) (xy 171.31983 -381.084786)
			(xy 171.319444 -381.09398) (xy 171.319444 -381.251206) (xy 171.318978 -381.261335) (xy 171.311245 -381.280059)
			(xy 171.296952 -381.294416) (xy 171.278263 -381.302232) (xy 171.268136 -381.302768) (xy 170.551856 -381.302768)
			(xy 170.541695 -381.302414) (xy 170.522936 -381.294598) (xy 170.508613 -381.28018) (xy 170.50092 -381.26137)
			(xy 170.500548 -381.251206) (xy 170.500548 -381.09398) (xy 170.500137 -381.084793) (xy 170.493623 -381.067609)
			(xy 170.487848 -381.060452) (xy 170.466002 -381.034771) (xy 170.42791 -380.97914) (xy 170.396755 -380.919347)
			(xy 170.372988 -380.856252) (xy 170.35695 -380.790764) (xy 170.348871 -380.723827) (xy 170.34887 -380.656403)
			(xy 167.070824 -380.656403) (xy 167.070831 -380.656462) (xy 167.070829 -380.723768) (xy 167.062783 -380.790592)
			(xy 167.046808 -380.855976) (xy 167.023133 -380.918981) (xy 166.992097 -380.978705) (xy 166.954145 -381.034292)
			(xy 166.932356 -381.059944) (xy 166.926553 -381.067084) (xy 166.920043 -381.084279) (xy 166.919656 -381.093472)
			(xy 166.919656 -381.251206) (xy 166.919171 -381.261365) (xy 166.911394 -381.280135) (xy 166.897025 -381.2945)
			(xy 166.878253 -381.302274) (xy 166.868094 -381.302768) (xy 166.151814 -381.302768) (xy 166.141644 -381.302325)
			(xy 166.122851 -381.294546) (xy 166.108466 -381.280166) (xy 166.100679 -381.261376) (xy 166.100252 -381.251206)
			(xy 166.100252 -381.093472) (xy 166.099844 -381.084285) (xy 166.093327 -381.067101) (xy 166.087552 -381.059944)
			(xy 166.065784 -381.034276) (xy 166.027833 -380.978692) (xy 165.996799 -380.918971) (xy 165.973124 -380.855968)
			(xy 165.957149 -380.790588) (xy 165.949103 -380.723767) (xy 165.949102 -380.656463) (xy 162.671063 -380.656463)
			(xy 162.671061 -380.723828) (xy 162.662983 -380.790768) (xy 162.646944 -380.856259) (xy 162.623176 -380.919357)
			(xy 162.59202 -380.979153) (xy 162.553927 -381.034787) (xy 162.53206 -381.060452) (xy 162.526254 -381.06759)
			(xy 162.519746 -381.084786) (xy 162.51936 -381.09398) (xy 162.51936 -381.251206) (xy 162.518878 -381.261333)
			(xy 162.511148 -381.280054) (xy 162.496861 -381.29441) (xy 162.478177 -381.302229) (xy 162.468052 -381.302768)
			(xy 161.751772 -381.302768) (xy 161.741644 -381.302406) (xy 161.722933 -381.294643) (xy 161.708619 -381.28031)
			(xy 161.70088 -381.261589) (xy 161.700464 -381.25146) (xy 161.700464 -381.09398) (xy 161.700049 -381.084794)
			(xy 161.693537 -381.06761) (xy 161.687764 -381.060452) (xy 161.665921 -381.03477) (xy 161.627834 -380.979137)
			(xy 161.596684 -380.919343) (xy 161.572921 -380.856248) (xy 161.556885 -380.790762) (xy 161.548808 -380.723826)
			(xy 161.548806 -380.656404) (xy 131.871003 -380.656404) (xy 131.87101 -380.656461) (xy 131.871008 -380.723769)
			(xy 131.862961 -380.790593) (xy 131.846985 -380.855977) (xy 131.823309 -380.918982) (xy 131.792271 -380.978706)
			(xy 131.754318 -381.034292) (xy 131.732528 -381.059944) (xy 131.726722 -381.067082) (xy 131.720215 -381.084278)
			(xy 131.719828 -381.093472) (xy 131.719828 -381.251206) (xy 131.71944 -381.261382) (xy 131.711647 -381.280184)
			(xy 131.69725 -381.294569) (xy 131.678443 -381.302348) (xy 131.668266 -381.302768) (xy 130.951986 -381.302768)
			(xy 130.941828 -381.302278) (xy 130.92306 -381.2945) (xy 130.908695 -381.280133) (xy 130.90092 -381.261364)
			(xy 130.900424 -381.251206) (xy 130.900424 -381.093472) (xy 130.900022 -381.084284) (xy 130.893502 -381.0671)
			(xy 130.887724 -381.059944) (xy 130.865956 -381.034276) (xy 130.828008 -380.978691) (xy 130.796975 -380.91897)
			(xy 130.773301 -380.855967) (xy 130.757327 -380.790587) (xy 130.749282 -380.723767) (xy 130.74928 -380.656463)
			(xy 127.471217 -380.656463) (xy 127.471215 -380.723827) (xy 127.463138 -380.790766) (xy 127.447101 -380.856256)
			(xy 127.423336 -380.919354) (xy 127.392185 -380.979151) (xy 127.354096 -381.034786) (xy 127.332232 -381.060452)
			(xy 127.326423 -381.067588) (xy 127.319918 -381.084786) (xy 127.319532 -381.09398) (xy 127.319532 -381.251206)
			(xy 127.319077 -381.261337) (xy 127.311342 -381.280063) (xy 127.297046 -381.29442) (xy 127.278352 -381.302234)
			(xy 127.268224 -381.302768) (xy 126.551944 -381.302768) (xy 126.541789 -381.302342) (xy 126.523031 -381.294555)
			(xy 126.508705 -381.280159) (xy 126.50101 -381.261363) (xy 126.500636 -381.251206) (xy 126.500636 -381.09398)
			(xy 126.500227 -381.084793) (xy 126.493712 -381.067609) (xy 126.487936 -381.060452) (xy 126.46609 -381.034771)
			(xy 126.427999 -380.97914) (xy 126.396845 -380.919346) (xy 126.373078 -380.856251) (xy 126.35704 -380.790764)
			(xy 126.348962 -380.723826) (xy 126.34896 -380.656404) (xy 123.070915 -380.656404) (xy 123.070922 -380.656462)
			(xy 123.07092 -380.723769) (xy 123.062874 -380.790593) (xy 123.046898 -380.855976) (xy 123.023223 -380.918982)
			(xy 122.992186 -380.978706) (xy 122.954234 -381.034292) (xy 122.932444 -381.059944) (xy 122.926639 -381.067083)
			(xy 122.920131 -381.084279) (xy 122.919744 -381.093472) (xy 122.919744 -381.251206) (xy 122.919341 -381.26138)
			(xy 122.91155 -381.280178) (xy 122.897158 -381.294564) (xy 122.878356 -381.302345) (xy 122.868182 -381.302768)
			(xy 122.151902 -381.302768) (xy 122.141745 -381.302265) (xy 122.122977 -381.294492) (xy 122.108612 -381.28013)
			(xy 122.100836 -381.261363) (xy 122.10034 -381.251206) (xy 122.10034 -381.093472) (xy 122.099934 -381.084285)
			(xy 122.093417 -381.067101) (xy 122.08764 -381.059944) (xy 122.065872 -381.034276) (xy 122.027923 -380.978691)
			(xy 121.996888 -380.91897) (xy 121.973215 -380.855968) (xy 121.95724 -380.790588) (xy 121.949194 -380.723767)
			(xy 121.949193 -380.656463) (xy 118.671154 -380.656463) (xy 118.671152 -380.723828) (xy 118.663073 -380.790769)
			(xy 118.647034 -380.85626) (xy 118.623265 -380.919357) (xy 118.592109 -380.979154) (xy 118.554015 -381.034788)
			(xy 118.532148 -381.060452) (xy 118.52634 -381.067589) (xy 118.519834 -381.084786) (xy 118.519448 -381.09398)
			(xy 118.519448 -381.251206) (xy 118.518978 -381.261335) (xy 118.511246 -381.280058) (xy 118.496954 -381.294415)
			(xy 118.478266 -381.302231) (xy 118.46814 -381.302768) (xy 117.75186 -381.302768) (xy 117.741699 -381.30241)
			(xy 117.72294 -381.294596) (xy 117.708617 -381.280179) (xy 117.700924 -381.261369) (xy 117.700552 -381.251206)
			(xy 117.700552 -381.09398) (xy 117.70014 -381.084793) (xy 117.693626 -381.06761) (xy 117.687852 -381.060452)
			(xy 117.666006 -381.034771) (xy 117.627913 -380.97914) (xy 117.596759 -380.919347) (xy 117.572991 -380.856252)
			(xy 117.556953 -380.790764) (xy 117.548874 -380.723827) (xy 117.548873 -380.656403) (xy 105.919524 -380.656403)
			(xy 105.919524 -380.877572) (xy 105.919034 -380.907556) (xy 105.911206 -380.967012) (xy 105.895685 -381.024937)
			(xy 105.872736 -381.080341) (xy 105.842752 -381.132275) (xy 105.806246 -381.179851) (xy 105.763841 -381.222256)
			(xy 105.716265 -381.258762) (xy 105.664331 -381.288746) (xy 105.608927 -381.311695) (xy 105.551002 -381.327216)
			(xy 105.491546 -381.335044) (xy 105.431578 -381.335044) (xy 105.372122 -381.327216) (xy 105.314197 -381.311695)
			(xy 105.258793 -381.288746) (xy 105.206859 -381.258762) (xy 105.159283 -381.222256) (xy 105.116878 -381.179851)
			(xy 105.080372 -381.132275) (xy 105.050388 -381.080341) (xy 105.027439 -381.024937) (xy 105.011918 -380.967012)
			(xy 105.00409 -380.907556) (xy 105.0036 -380.877572) (xy 87.838954 -380.877572) (xy 87.823216 -380.919355)
			(xy 87.792063 -380.979152) (xy 87.753973 -381.034787) (xy 87.732108 -381.060452) (xy 87.726308 -381.067595)
			(xy 87.719795 -381.084787) (xy 87.719408 -381.09398) (xy 87.719408 -381.251206) (xy 87.71888 -381.261327)
			(xy 87.711159 -381.280039) (xy 87.696886 -381.294394) (xy 87.678218 -381.302221) (xy 87.6681 -381.302768)
			(xy 86.95182 -381.302768) (xy 86.941695 -381.302367) (xy 86.922985 -381.294619) (xy 86.908669 -381.280298)
			(xy 86.900929 -381.261585) (xy 86.900512 -381.25146) (xy 86.900512 -381.09398) (xy 86.900109 -381.084792)
			(xy 86.89359 -381.067608) (xy 86.887812 -381.060452) (xy 86.865967 -381.034771) (xy 86.827877 -380.979139)
			(xy 86.796725 -380.919345) (xy 86.772959 -380.85625) (xy 86.756922 -380.790763) (xy 86.748844 -380.723826)
			(xy 86.748842 -380.656404) (xy 83.470797 -380.656404) (xy 83.470804 -380.656461) (xy 83.470802 -380.723769)
			(xy 83.462755 -380.790593) (xy 83.446779 -380.855977) (xy 83.423102 -380.918983) (xy 83.392064 -380.978706)
			(xy 83.35411 -381.034292) (xy 83.33232 -381.059944) (xy 83.326525 -381.06709) (xy 83.320009 -381.08428)
			(xy 83.31962 -381.093472) (xy 83.31962 -381.251206) (xy 83.31924 -381.261383) (xy 83.311445 -381.280186)
			(xy 83.297046 -381.294572) (xy 83.278236 -381.302349) (xy 83.268058 -381.302768) (xy 82.551778 -381.302768)
			(xy 82.54162 -381.302285) (xy 82.522851 -381.294504) (xy 82.508487 -381.280136) (xy 82.500712 -381.261365)
			(xy 82.500216 -381.251206) (xy 82.500216 -381.093472) (xy 82.499816 -381.084284) (xy 82.493295 -381.0671)
			(xy 82.487516 -381.059944) (xy 82.465749 -381.034275) (xy 82.427801 -380.978691) (xy 82.396768 -380.918969)
			(xy 82.373095 -380.855967) (xy 82.357121 -380.790587) (xy 82.349076 -380.723767) (xy 82.349074 -380.656464)
			(xy 79.071011 -380.656464) (xy 79.071009 -380.723827) (xy 79.062932 -380.790767) (xy 79.046895 -380.856256)
			(xy 79.02313 -380.919354) (xy 78.991978 -380.979151) (xy 78.953888 -381.034786) (xy 78.932024 -381.060452)
			(xy 78.926226 -381.067596) (xy 78.919711 -381.084787) (xy 78.919324 -381.09398) (xy 78.919324 -381.251206)
			(xy 78.918877 -381.261337) (xy 78.911141 -381.280066) (xy 78.896842 -381.294423) (xy 78.878145 -381.302235)
			(xy 78.868016 -381.302768) (xy 78.151736 -381.302768) (xy 78.141612 -381.302354) (xy 78.122903 -381.294611)
			(xy 78.108586 -381.280294) (xy 78.100846 -381.261584) (xy 78.100428 -381.25146) (xy 78.100428 -381.09398)
			(xy 78.100021 -381.084793) (xy 78.093505 -381.067609) (xy 78.087728 -381.060452) (xy 78.065883 -381.034771)
			(xy 78.027792 -380.979139) (xy 77.996638 -380.919346) (xy 77.972872 -380.856251) (xy 77.956834 -380.790763)
			(xy 77.948756 -380.723826) (xy 77.948754 -380.656404) (xy 74.670709 -380.656404) (xy 74.670716 -380.656462)
			(xy 74.670714 -380.723769) (xy 74.662667 -380.790593) (xy 74.646691 -380.855977) (xy 74.623015 -380.918982)
			(xy 74.591978 -380.978706) (xy 74.554026 -381.034292) (xy 74.532236 -381.059944) (xy 74.52643 -381.067082)
			(xy 74.519923 -381.084278) (xy 74.519536 -381.093472) (xy 74.519536 -381.251206) (xy 74.51914 -381.261381)
			(xy 74.511349 -381.280181) (xy 74.496954 -381.294567) (xy 74.478149 -381.302347) (xy 74.467974 -381.302768)
			(xy 73.751694 -381.302768) (xy 73.741537 -381.302272) (xy 73.722769 -381.294496) (xy 73.708404 -381.280131)
			(xy 73.700628 -381.261363) (xy 73.700132 -381.251206) (xy 73.700132 -381.093472) (xy 73.699728 -381.084284)
			(xy 73.693209 -381.0671) (xy 73.687432 -381.059944) (xy 73.665664 -381.034275) (xy 73.627715 -380.978691)
			(xy 73.596682 -380.91897) (xy 73.573008 -380.855967) (xy 73.557034 -380.790587) (xy 73.548988 -380.723767)
			(xy 73.548987 -380.656463) (xy 43.87119 -380.656463) (xy 43.871188 -380.723828) (xy 43.86311 -380.790767)
			(xy 43.847073 -380.856258) (xy 43.823306 -380.919355) (xy 43.792153 -380.979152) (xy 43.754061 -381.034787)
			(xy 43.732196 -381.060452) (xy 43.726394 -381.067594) (xy 43.719883 -381.084787) (xy 43.719496 -381.09398)
			(xy 43.719496 -381.251206) (xy 43.718979 -381.261329) (xy 43.711256 -381.280043) (xy 43.69698 -381.294398)
			(xy 43.678308 -381.302223) (xy 43.668188 -381.302768) (xy 42.951908 -381.302768) (xy 42.94175 -381.302371)
			(xy 42.922992 -381.294572) (xy 42.908667 -381.280167) (xy 42.900973 -381.261366) (xy 42.9006 -381.251206)
			(xy 42.9006 -381.09398) (xy 42.9002 -381.084792) (xy 42.893679 -381.067607) (xy 42.8879 -381.060452)
			(xy 42.866056 -381.034771) (xy 42.827966 -380.979138) (xy 42.796815 -380.919344) (xy 42.773049 -380.85625)
			(xy 42.757013 -380.790763) (xy 42.748935 -380.723826) (xy 42.748933 -380.656404) (xy 39.470887 -380.656404)
			(xy 39.470894 -380.656461) (xy 39.470893 -380.723769) (xy 39.462846 -380.790594) (xy 39.446869 -380.855978)
			(xy 39.423192 -380.918983) (xy 39.392153 -380.978707) (xy 39.354199 -381.034293) (xy 39.332408 -381.059944)
			(xy 39.326611 -381.067089) (xy 39.320096 -381.08428) (xy 39.319708 -381.093472) (xy 39.319708 -381.251206)
			(xy 39.319173 -381.261358) (xy 39.311405 -381.280119) (xy 39.297052 -381.294482) (xy 39.278298 -381.302265)
			(xy 39.268146 -381.302768) (xy 38.551866 -381.302768) (xy 38.541707 -381.302295) (xy 38.522938 -381.29451)
			(xy 38.508574 -381.280138) (xy 38.5008 -381.261365) (xy 38.500304 -381.251206) (xy 38.500304 -381.093472)
			(xy 38.499907 -381.084283) (xy 38.493384 -381.067099) (xy 38.487604 -381.059944) (xy 38.465837 -381.034275)
			(xy 38.42789 -380.97869) (xy 38.396858 -380.918969) (xy 38.373185 -380.855966) (xy 38.357212 -380.790587)
			(xy 38.349167 -380.723766) (xy 38.349165 -380.656464) (xy 35.071102 -380.656464) (xy 35.0711 -380.723828)
			(xy 35.063023 -380.790767) (xy 35.046985 -380.856257) (xy 35.023219 -380.919355) (xy 34.992067 -380.979151)
			(xy 34.953977 -381.034787) (xy 34.932112 -381.060452) (xy 34.926312 -381.067595) (xy 34.919799 -381.084787)
			(xy 34.919412 -381.09398) (xy 34.919412 -381.251206) (xy 34.91888 -381.261327) (xy 34.91116 -381.280038)
			(xy 34.896888 -381.294392) (xy 34.878222 -381.30222) (xy 34.868104 -381.302768) (xy 34.151824 -381.302768)
			(xy 34.141667 -381.302358) (xy 34.122909 -381.294565) (xy 34.108584 -381.280164) (xy 34.100889 -381.261365)
			(xy 34.100516 -381.251206) (xy 34.100516 -381.09398) (xy 34.100112 -381.084792) (xy 34.093594 -381.067608)
			(xy 34.087816 -381.060452) (xy 34.065971 -381.034771) (xy 34.027881 -380.979139) (xy 33.996728 -380.919345)
			(xy 33.972962 -380.85625) (xy 33.956925 -380.790763) (xy 33.948847 -380.723826) (xy 33.948845 -380.656404)
			(xy 30.6708 -380.656404) (xy 30.670807 -380.656461) (xy 30.670805 -380.723769) (xy 30.662758 -380.790593)
			(xy 30.646782 -380.855977) (xy 30.623105 -380.918982) (xy 30.592068 -380.978706) (xy 30.554114 -381.034292)
			(xy 30.532324 -381.059944) (xy 30.526529 -381.067091) (xy 30.520013 -381.08428) (xy 30.519624 -381.093472)
			(xy 30.519624 -381.251206) (xy 30.51924 -381.261383) (xy 30.511446 -381.280185) (xy 30.497048 -381.294571)
			(xy 30.478239 -381.302349) (xy 30.468062 -381.302768) (xy 29.751782 -381.302768) (xy 29.741624 -381.302282)
			(xy 29.722855 -381.294502) (xy 29.708491 -381.280135) (xy 29.700716 -381.261364) (xy 29.70022 -381.251206)
			(xy 29.70022 -381.093472) (xy 29.699819 -381.084284) (xy 29.693298 -381.0671) (xy 29.68752 -381.059944)
			(xy 29.665752 -381.034276) (xy 29.627804 -380.978691) (xy 29.596771 -380.918969) (xy 29.573098 -380.855967)
			(xy 29.557124 -380.790587) (xy 29.549079 -380.723767) (xy 29.549077 -380.656463) (xy 29.557119 -380.589643)
			(xy 29.573089 -380.524262) (xy 29.596759 -380.461258) (xy 29.627789 -380.401535) (xy 29.665734 -380.345948)
			(xy 29.68752 -380.320296) (xy 29.693303 -380.313141) (xy 29.699825 -380.295958) (xy 29.70022 -380.286768)
			(xy 29.70022 -379.7935) (xy 29.699806 -379.784313) (xy 29.693295 -379.767129) (xy 29.68752 -379.759972)
			(xy 29.66573 -379.734322) (xy 29.627781 -379.678735) (xy 29.596748 -379.619011) (xy 29.573075 -379.556006)
			(xy 29.557102 -379.490624) (xy 29.549058 -379.423801) (xy 28.447 -379.423801) (xy 28.447041 -379.423909)
			(xy 28.463077 -379.489397) (xy 28.471153 -379.556335) (xy 28.471153 -379.623759) (xy 28.463078 -379.690697)
			(xy 28.447043 -379.756186) (xy 28.423279 -379.819282) (xy 28.392128 -379.879078) (xy 28.35404 -379.934713)
			(xy 28.332176 -379.960378) (xy 28.326361 -379.96751) (xy 28.319858 -379.984711) (xy 28.319476 -379.993906)
			(xy 28.319476 -380.151386) (xy 28.318962 -380.16151) (xy 28.311242 -380.180228) (xy 28.296964 -380.194584)
			(xy 28.278289 -380.202406) (xy 28.268168 -380.202948) (xy 27.551888 -380.202948) (xy 27.541784 -380.202426)
			(xy 27.523115 -380.194693) (xy 27.508823 -380.180408) (xy 27.50108 -380.161743) (xy 27.50058 -380.15164)
			(xy 27.50058 -379.993906) (xy 27.500171 -379.984719) (xy 27.493657 -379.967534) (xy 27.48788 -379.960378)
			(xy 27.466012 -379.934716) (xy 27.427923 -379.879081) (xy 27.396771 -379.819285) (xy 27.373007 -379.756187)
			(xy 27.356972 -379.690698) (xy 27.348896 -379.623759) (xy 27.348896 -379.556335) (xy 27.356973 -379.489396)
			(xy 27.373009 -379.423907) (xy 27.396774 -379.36081) (xy 27.427926 -379.301013) (xy 27.466015 -379.245379)
			(xy 27.48788 -379.219714) (xy 27.493693 -379.21258) (xy 27.500199 -379.195381) (xy 27.50058 -379.186186)
			(xy 27.50058 -378.693934) (xy 27.500158 -378.684748) (xy 27.493653 -378.667563) (xy 27.48788 -378.660406)
			(xy 27.465991 -378.634761) (xy 27.427905 -378.579124) (xy 27.396756 -378.519324) (xy 27.372994 -378.456225)
			(xy 27.356961 -378.390733) (xy 27.348888 -378.323793) (xy 0.508 -378.323793) (xy 0.508 -382.223705)
			(xy 27.348899 -382.223705) (xy 27.3489 -382.15628) (xy 27.356976 -382.089342) (xy 27.373012 -382.023853)
			(xy 27.396777 -381.960755) (xy 27.427928 -381.900959) (xy 27.466016 -381.845324) (xy 27.48788 -381.819658)
			(xy 27.493675 -381.812511) (xy 27.500191 -381.795322) (xy 27.50058 -381.78613) (xy 27.50058 -381.628904)
			(xy 27.501088 -381.618798) (xy 27.508821 -381.600124) (xy 27.52311 -381.58583) (xy 27.541782 -381.578091)
			(xy 27.551888 -381.577596) (xy 28.268168 -381.577596) (xy 28.278288 -381.578042) (xy 28.29699 -381.585779)
			(xy 28.311306 -381.600086) (xy 28.319053 -381.618784) (xy 28.319476 -381.628904) (xy 28.319476 -381.78613)
			(xy 28.319877 -381.795318) (xy 28.326398 -381.812502) (xy 28.332176 -381.819658) (xy 28.354031 -381.845331)
			(xy 28.392122 -381.900964) (xy 28.423274 -381.960759) (xy 28.44704 -382.023855) (xy 28.463077 -382.089343)
			(xy 28.471154 -382.156281) (xy 28.471155 -382.223646) (xy 31.749194 -382.223646) (xy 31.749195 -382.156339)
			(xy 31.757241 -382.089516) (xy 31.773216 -382.024132) (xy 31.796891 -381.961127) (xy 31.827927 -381.901404)
			(xy 31.865879 -381.845818) (xy 31.887668 -381.820166) (xy 31.89347 -381.813025) (xy 31.899979 -381.795831)
			(xy 31.900368 -381.786638) (xy 31.900368 -381.628904) (xy 31.900824 -381.618754) (xy 31.908613 -381.600008)
			(xy 31.922998 -381.585686) (xy 31.941778 -381.57798) (xy 31.95193 -381.577596) (xy 32.66821 -381.577596)
			(xy 32.678332 -381.578117) (xy 32.697045 -381.58584) (xy 32.711399 -381.600115) (xy 32.719226 -381.618785)
			(xy 32.719772 -381.628904) (xy 32.719772 -381.786638) (xy 32.72017 -381.795826) (xy 32.726693 -381.81301)
			(xy 32.732472 -381.820166) (xy 32.75425 -381.845826) (xy 32.792198 -381.901412) (xy 32.823231 -381.961134)
			(xy 32.846904 -382.024138) (xy 32.862877 -382.089519) (xy 32.870922 -382.15634) (xy 32.870923 -382.223645)
			(xy 32.870916 -382.223704) (xy 36.148987 -382.223704) (xy 36.148988 -382.156281) (xy 36.157064 -382.089342)
			(xy 36.1731 -382.023853) (xy 36.196863 -381.960756) (xy 36.228013 -381.900959) (xy 36.266101 -381.845324)
			(xy 36.287964 -381.819658) (xy 36.293769 -381.812519) (xy 36.300277 -381.795323) (xy 36.300664 -381.78613)
			(xy 36.300664 -381.628904) (xy 36.301188 -381.6188) (xy 36.308917 -381.600129) (xy 36.323202 -381.585835)
			(xy 36.341868 -381.578094) (xy 36.351972 -381.577596) (xy 37.068252 -381.577596) (xy 37.078371 -381.578055)
			(xy 37.097073 -381.585787) (xy 37.111388 -381.60009) (xy 37.119136 -381.618786) (xy 37.11956 -381.628904)
			(xy 37.11956 -381.78613) (xy 37.119965 -381.795318) (xy 37.126483 -381.812501) (xy 37.13226 -381.819658)
			(xy 37.154116 -381.845331) (xy 37.192207 -381.900963) (xy 37.223361 -381.960758) (xy 37.247127 -382.023854)
			(xy 37.263164 -382.089343) (xy 37.271242 -382.156281) (xy 37.271243 -382.223704) (xy 37.271243 -382.223705)
			(xy 40.548753 -382.223705) (xy 40.548754 -382.15628) (xy 40.556832 -382.08934) (xy 40.57287 -382.02385)
			(xy 40.596638 -381.960752) (xy 40.627792 -381.900956) (xy 40.665886 -381.845322) (xy 40.687752 -381.819658)
			(xy 40.693555 -381.812518) (xy 40.700065 -381.795323) (xy 40.700452 -381.78613) (xy 40.700452 -381.628904)
			(xy 40.700987 -381.618801) (xy 40.708715 -381.600133) (xy 40.722996 -381.585839) (xy 40.741658 -381.578096)
			(xy 40.75176 -381.577596) (xy 41.46804 -381.577596) (xy 41.478151 -381.578052) (xy 41.496829 -381.585802)
			(xy 41.511122 -381.600108) (xy 41.518856 -381.618793) (xy 41.519348 -381.628904) (xy 41.519348 -381.78613)
			(xy 41.519755 -381.795317) (xy 41.526272 -381.812501) (xy 41.532048 -381.819658) (xy 41.553904 -381.84533)
			(xy 41.591996 -381.900963) (xy 41.62315 -381.960757) (xy 41.646917 -382.023853) (xy 41.662955 -382.089342)
			(xy 41.671033 -382.156281) (xy 41.671034 -382.223645) (xy 44.949073 -382.223645) (xy 44.949074 -382.15634)
			(xy 44.957119 -382.089516) (xy 44.973093 -382.024133) (xy 44.996767 -381.961128) (xy 45.027801 -381.901405)
			(xy 45.065751 -381.845818) (xy 45.08754 -381.820166) (xy 45.093339 -381.813022) (xy 45.099851 -381.795831)
			(xy 45.10024 -381.786638) (xy 45.10024 -381.628904) (xy 45.100626 -381.618745) (xy 45.108427 -381.599985)
			(xy 45.122836 -381.58566) (xy 45.141641 -381.577968) (xy 45.151802 -381.577596) (xy 45.868082 -381.577596)
			(xy 45.878202 -381.57814) (xy 45.896915 -381.585854) (xy 45.91127 -381.600122) (xy 45.919098 -381.618787)
			(xy 45.919644 -381.628904) (xy 45.919644 -381.786638) (xy 45.920049 -381.795826) (xy 45.926568 -381.813009)
			(xy 45.932344 -381.820166) (xy 45.954122 -381.845826) (xy 45.992072 -381.901411) (xy 46.023107 -381.961133)
			(xy 46.046781 -382.024137) (xy 46.062755 -382.089518) (xy 46.070801 -382.15634) (xy 46.070801 -382.223645)
			(xy 46.070794 -382.223705) (xy 71.348808 -382.223705) (xy 71.348809 -382.15628) (xy 71.356886 -382.089342)
			(xy 71.372922 -382.023852) (xy 71.396687 -381.960755) (xy 71.427838 -381.900958) (xy 71.465928 -381.845323)
			(xy 71.487792 -381.819658) (xy 71.493588 -381.812512) (xy 71.500103 -381.795322) (xy 71.500492 -381.78613)
			(xy 71.500492 -381.628904) (xy 71.500919 -381.618783) (xy 71.508664 -381.600081) (xy 71.522977 -381.585767)
			(xy 71.541679 -381.57802) (xy 71.5518 -381.577596) (xy 72.26808 -381.577596) (xy 72.278201 -381.578032)
			(xy 72.296903 -381.585773) (xy 72.311218 -381.600083) (xy 72.318965 -381.618783) (xy 72.319388 -381.628904)
			(xy 72.319388 -381.78613) (xy 72.319786 -381.795318) (xy 72.326308 -381.812503) (xy 72.332088 -381.819658)
			(xy 72.353943 -381.845331) (xy 72.392032 -381.900964) (xy 72.423184 -381.960759) (xy 72.446949 -382.023855)
			(xy 72.462986 -382.089343) (xy 72.471063 -382.156281) (xy 72.471064 -382.223646) (xy 75.749104 -382.223646)
			(xy 75.749104 -382.156339) (xy 75.75715 -382.089515) (xy 75.773125 -382.024132) (xy 75.796801 -381.961127)
			(xy 75.827838 -381.901403) (xy 75.86579 -381.845818) (xy 75.88758 -381.820166) (xy 75.893371 -381.813017)
			(xy 75.89989 -381.795829) (xy 75.90028 -381.786638) (xy 75.90028 -381.628904) (xy 75.900725 -381.618753)
			(xy 75.908515 -381.600004) (xy 75.922904 -381.585681) (xy 75.941689 -381.577978) (xy 75.951842 -381.577596)
			(xy 76.668122 -381.577596) (xy 76.678245 -381.578107) (xy 76.696958 -381.585834) (xy 76.711312 -381.600112)
			(xy 76.719138 -381.618784) (xy 76.719684 -381.628904) (xy 76.719684 -381.786638) (xy 76.720079 -381.795827)
			(xy 76.726604 -381.813011) (xy 76.732384 -381.820166) (xy 76.754161 -381.845826) (xy 76.792109 -381.901412)
			(xy 76.823141 -381.961135) (xy 76.846814 -382.024138) (xy 76.862787 -382.089519) (xy 76.870831 -382.156341)
			(xy 76.870832 -382.223644) (xy 76.870825 -382.223704) (xy 80.148896 -382.223704) (xy 80.148897 -382.15628)
			(xy 80.156973 -382.089342) (xy 80.173009 -382.023853) (xy 80.196773 -381.960755) (xy 80.227924 -381.900959)
			(xy 80.266012 -381.845324) (xy 80.287876 -381.819658) (xy 80.29367 -381.812511) (xy 80.300187 -381.795322)
			(xy 80.300576 -381.78613) (xy 80.300576 -381.628904) (xy 80.301088 -381.618798) (xy 80.30882 -381.600125)
			(xy 80.323108 -381.585831) (xy 80.341779 -381.578092) (xy 80.351884 -381.577596) (xy 81.068164 -381.577596)
			(xy 81.078284 -381.578046) (xy 81.096986 -381.585781) (xy 81.111301 -381.600087) (xy 81.119048 -381.618785)
			(xy 81.119472 -381.628904) (xy 81.119472 -381.78613) (xy 81.119874 -381.795318) (xy 81.126394 -381.812502)
			(xy 81.132172 -381.819658) (xy 81.154027 -381.845331) (xy 81.192118 -381.900964) (xy 81.223271 -381.960759)
			(xy 81.247037 -382.023854) (xy 81.263074 -382.089343) (xy 81.271151 -382.156281) (xy 81.271152 -382.223704)
			(xy 84.548687 -382.223704) (xy 84.548688 -382.156281) (xy 84.556764 -382.089342) (xy 84.5728 -382.023853)
			(xy 84.596563 -381.960756) (xy 84.627713 -381.900959) (xy 84.665801 -381.845324) (xy 84.687664 -381.819658)
			(xy 84.693469 -381.812519) (xy 84.699977 -381.795323) (xy 84.700364 -381.78613) (xy 84.700364 -381.628904)
			(xy 84.700888 -381.6188) (xy 84.708617 -381.600129) (xy 84.722902 -381.585835) (xy 84.741568 -381.578094)
			(xy 84.751672 -381.577596) (xy 85.467952 -381.577596) (xy 85.478071 -381.578055) (xy 85.496773 -381.585787)
			(xy 85.511088 -381.60009) (xy 85.518836 -381.618786) (xy 85.51926 -381.628904) (xy 85.51926 -381.78613)
			(xy 85.519665 -381.795318) (xy 85.526183 -381.812501) (xy 85.53196 -381.819658) (xy 85.553816 -381.845331)
			(xy 85.591907 -381.900963) (xy 85.623061 -381.960758) (xy 85.646827 -382.023854) (xy 85.662864 -382.089343)
			(xy 85.670942 -382.156281) (xy 85.670943 -382.223646) (xy 88.948982 -382.223646) (xy 88.948983 -382.156339)
			(xy 88.957028 -382.089516) (xy 88.973003 -382.024133) (xy 88.996677 -381.961128) (xy 89.027712 -381.901404)
			(xy 89.065663 -381.845818) (xy 89.087452 -381.820166) (xy 89.093252 -381.813023) (xy 89.099763 -381.795831)
			(xy 89.100152 -381.786638) (xy 89.100152 -381.628904) (xy 89.100624 -381.618756) (xy 89.108409 -381.600013)
			(xy 89.12279 -381.585691) (xy 89.141564 -381.577983) (xy 89.151714 -381.577596) (xy 89.867994 -381.577596)
			(xy 89.878115 -381.57813) (xy 89.896828 -381.585848) (xy 89.911183 -381.600119) (xy 89.91901 -381.618786)
			(xy 89.919556 -381.628904) (xy 89.919556 -381.786638) (xy 89.919958 -381.795826) (xy 89.926478 -381.81301)
			(xy 89.932256 -381.820166) (xy 89.954034 -381.845826) (xy 89.991983 -381.901411) (xy 90.023017 -381.961134)
			(xy 90.046691 -382.024137) (xy 90.062665 -382.089519) (xy 90.07071 -382.15634) (xy 90.070711 -382.223645)
			(xy 115.349246 -382.223645) (xy 115.349247 -382.15634) (xy 115.357291 -382.089517) (xy 115.373264 -382.024135)
			(xy 115.396937 -381.96113) (xy 115.427969 -381.901406) (xy 115.465917 -381.845819) (xy 115.487704 -381.820166)
			(xy 115.493498 -381.813019) (xy 115.500014 -381.79583) (xy 115.500404 -381.786638) (xy 115.500404 -381.628904)
			(xy 115.500825 -381.61875) (xy 115.50862 -381.599997) (xy 115.523017 -381.585673) (xy 115.54181 -381.577974)
			(xy 115.551966 -381.577596) (xy 116.268246 -381.577596) (xy 116.27837 -381.578088) (xy 116.297084 -381.585822)
			(xy 116.311437 -381.600106) (xy 116.319262 -381.618782) (xy 116.319808 -381.628904) (xy 116.319808 -381.786638)
			(xy 116.320198 -381.795827) (xy 116.326725 -381.813012) (xy 116.332508 -381.820166) (xy 116.354288 -381.845826)
			(xy 116.39224 -381.90141) (xy 116.423277 -381.961132) (xy 116.446952 -382.024135) (xy 116.462928 -382.089517)
			(xy 116.470973 -382.15634) (xy 116.470974 -382.223645) (xy 116.470967 -382.223705) (xy 119.749014 -382.223705)
			(xy 119.749015 -382.15628) (xy 119.757092 -382.089341) (xy 119.773128 -382.023852) (xy 119.796894 -381.960754)
			(xy 119.828046 -381.900958) (xy 119.866135 -381.845323) (xy 119.888 -381.819658) (xy 119.893797 -381.812513)
			(xy 119.900311 -381.795322) (xy 119.9007 -381.78613) (xy 119.9007 -381.628904) (xy 119.901119 -381.618782)
			(xy 119.908866 -381.600078) (xy 119.923182 -381.585764) (xy 119.941886 -381.578019) (xy 119.952008 -381.577596)
			(xy 120.668288 -381.577596) (xy 120.678409 -381.578026) (xy 120.697112 -381.585769) (xy 120.711426 -381.600081)
			(xy 120.719173 -381.618783) (xy 120.719596 -381.628904) (xy 120.719596 -381.78613) (xy 120.719992 -381.795319)
			(xy 120.726516 -381.812503) (xy 120.732296 -381.819658) (xy 120.75415 -381.845331) (xy 120.79224 -381.900965)
			(xy 120.823391 -381.96076) (xy 120.847156 -382.023855) (xy 120.863192 -382.089344) (xy 120.871269 -382.156281)
			(xy 120.87127 -382.223646) (xy 124.14931 -382.223646) (xy 124.14931 -382.156339) (xy 124.157356 -382.089515)
			(xy 124.173332 -382.024132) (xy 124.197008 -381.961127) (xy 124.228045 -381.901403) (xy 124.265998 -381.845818)
			(xy 124.287788 -381.820166) (xy 124.29358 -381.813018) (xy 124.300098 -381.79583) (xy 124.300488 -381.786638)
			(xy 124.300488 -381.628904) (xy 124.300925 -381.618752) (xy 124.308717 -381.600002) (xy 124.323109 -381.585679)
			(xy 124.341896 -381.577977) (xy 124.35205 -381.577596) (xy 125.06833 -381.577596) (xy 125.078453 -381.578101)
			(xy 125.097167 -381.58583) (xy 125.11152 -381.60011) (xy 125.119346 -381.618783) (xy 125.119892 -381.628904)
			(xy 125.119892 -381.786638) (xy 125.120286 -381.795827) (xy 125.126811 -381.813011) (xy 125.132592 -381.820166)
			(xy 125.154369 -381.845827) (xy 125.192316 -381.901413) (xy 125.223348 -381.961135) (xy 125.24702 -382.024139)
			(xy 125.262993 -382.089519) (xy 125.271037 -382.156341) (xy 125.271038 -382.223644) (xy 125.271038 -382.223646)
			(xy 128.5491 -382.223646) (xy 128.549101 -382.156339) (xy 128.557147 -382.089515) (xy 128.573122 -382.024132)
			(xy 128.596798 -381.961127) (xy 128.627834 -381.901404) (xy 128.665787 -381.845818) (xy 128.687576 -381.820166)
			(xy 128.693367 -381.813016) (xy 128.699886 -381.795829) (xy 128.700276 -381.786638) (xy 128.700276 -381.628904)
			(xy 128.700724 -381.618753) (xy 128.708514 -381.600005) (xy 128.722902 -381.585683) (xy 128.741685 -381.577979)
			(xy 128.751838 -381.577596) (xy 129.468118 -381.577596) (xy 129.47824 -381.57811) (xy 129.496954 -381.585836)
			(xy 129.511308 -381.600113) (xy 129.519134 -381.618784) (xy 129.51968 -381.628904) (xy 129.51968 -381.786638)
			(xy 129.520076 -381.795827) (xy 129.5266 -381.813011) (xy 129.53238 -381.820166) (xy 129.554157 -381.845826)
			(xy 129.592105 -381.901412) (xy 129.623138 -381.961135) (xy 129.64681 -382.024138) (xy 129.662784 -382.089519)
			(xy 129.670828 -382.156341) (xy 129.670829 -382.223644) (xy 129.670829 -382.223645) (xy 159.349155 -382.223645)
			(xy 159.349156 -382.15634) (xy 159.3572 -382.089517) (xy 159.373174 -382.024134) (xy 159.396847 -381.96113)
			(xy 159.42788 -381.901406) (xy 159.465828 -381.845818) (xy 159.487616 -381.820166) (xy 159.493411 -381.81302)
			(xy 159.499926 -381.79583) (xy 159.500316 -381.786638) (xy 159.500316 -381.628904) (xy 159.50072 -381.61878)
			(xy 159.508469 -381.600073) (xy 159.52279 -381.585758) (xy 159.5415 -381.578016) (xy 159.551624 -381.577596)
			(xy 160.268158 -381.577596) (xy 160.278277 -381.57816) (xy 160.296988 -381.585866) (xy 160.311345 -381.600128)
			(xy 160.319173 -381.618789) (xy 160.31972 -381.628904) (xy 160.31972 -381.786638) (xy 160.320108 -381.795828)
			(xy 160.326637 -381.813012) (xy 160.33242 -381.820166) (xy 160.354199 -381.845826) (xy 160.392151 -381.90141)
			(xy 160.423187 -381.961132) (xy 160.446862 -382.024136) (xy 160.462837 -382.089518) (xy 160.470882 -382.15634)
			(xy 160.470883 -382.223645) (xy 160.470876 -382.223705) (xy 163.748923 -382.223705) (xy 163.748924 -382.15628)
			(xy 163.757001 -382.089341) (xy 163.773038 -382.023851) (xy 163.796804 -381.960754) (xy 163.827956 -381.900957)
			(xy 163.866047 -381.845323) (xy 163.887912 -381.819658) (xy 163.89371 -381.812514) (xy 163.900224 -381.795323)
			(xy 163.900612 -381.78613) (xy 163.900612 -381.628904) (xy 163.90102 -381.61878) (xy 163.908769 -381.600074)
			(xy 163.923088 -381.58576) (xy 163.941796 -381.578016) (xy 163.95192 -381.577596) (xy 164.6682 -381.577596)
			(xy 164.678322 -381.578016) (xy 164.697025 -381.585763) (xy 164.711339 -381.600079) (xy 164.719085 -381.618782)
			(xy 164.719508 -381.628904) (xy 164.719508 -381.78613) (xy 164.719902 -381.795319) (xy 164.726426 -381.812503)
			(xy 164.732208 -381.819658) (xy 164.754062 -381.845331) (xy 164.79215 -381.900965) (xy 164.823301 -381.96076)
			(xy 164.847065 -382.023856) (xy 164.863101 -382.089344) (xy 164.871178 -382.156281) (xy 164.871179 -382.223645)
			(xy 168.149243 -382.223645) (xy 168.149244 -382.15634) (xy 168.157288 -382.089517) (xy 168.173261 -382.024135)
			(xy 168.196933 -381.96113) (xy 168.227965 -381.901406) (xy 168.265913 -381.845819) (xy 168.2877 -381.820166)
			(xy 168.293494 -381.813019) (xy 168.30001 -381.79583) (xy 168.3004 -381.786638) (xy 168.3004 -381.628904)
			(xy 168.300825 -381.61875) (xy 168.308619 -381.599998) (xy 168.323015 -381.585674) (xy 168.341806 -381.577975)
			(xy 168.351962 -381.577596) (xy 169.068242 -381.577596) (xy 169.078366 -381.578091) (xy 169.09708 -381.585824)
			(xy 169.111433 -381.600107) (xy 169.119258 -381.618783) (xy 169.119804 -381.628904) (xy 169.119804 -381.786638)
			(xy 169.120195 -381.795827) (xy 169.126722 -381.813012) (xy 169.132504 -381.820166) (xy 169.154281 -381.845827)
			(xy 169.192227 -381.901413) (xy 169.223258 -381.961136) (xy 169.24693 -382.024139) (xy 169.262902 -382.08952)
			(xy 169.270946 -382.156341) (xy 169.270947 -382.223644) (xy 169.270947 -382.223646) (xy 172.54901 -382.223646)
			(xy 172.54901 -382.156339) (xy 172.557056 -382.089515) (xy 172.573032 -382.024132) (xy 172.596708 -381.961127)
			(xy 172.627745 -381.901403) (xy 172.665698 -381.845818) (xy 172.687488 -381.820166) (xy 172.69328 -381.813018)
			(xy 172.699798 -381.79583) (xy 172.700188 -381.786638) (xy 172.700188 -381.628904) (xy 172.700625 -381.618752)
			(xy 172.708417 -381.600002) (xy 172.722809 -381.585679) (xy 172.741596 -381.577977) (xy 172.75175 -381.577596)
			(xy 173.46803 -381.577596) (xy 173.478153 -381.578101) (xy 173.496867 -381.58583) (xy 173.51122 -381.60011)
			(xy 173.519046 -381.618783) (xy 173.519592 -381.628904) (xy 173.519592 -381.786638) (xy 173.519986 -381.795827)
			(xy 173.526511 -381.813011) (xy 173.532292 -381.820166) (xy 173.554069 -381.845827) (xy 173.592016 -381.901413)
			(xy 173.623048 -381.961135) (xy 173.64672 -382.024139) (xy 173.662693 -382.089519) (xy 173.670737 -382.156341)
			(xy 173.670738 -382.223644) (xy 173.662695 -382.290466) (xy 173.646725 -382.355847) (xy 173.623054 -382.418851)
			(xy 173.592024 -382.478574) (xy 173.554078 -382.534161) (xy 173.532292 -382.559814) (xy 173.526506 -382.566967)
			(xy 173.519985 -382.584151) (xy 173.519592 -382.593342) (xy 173.519592 -383.086864) (xy 173.520021 -383.096049)
			(xy 173.526522 -383.113234) (xy 173.532292 -383.120392) (xy 173.554094 -383.146032) (xy 173.592041 -383.201621)
			(xy 173.623072 -383.261346) (xy 173.646507 -383.323727) (xy 174.749152 -383.323727) (xy 174.749155 -383.256419)
			(xy 174.757202 -383.189594) (xy 174.773179 -383.12421) (xy 174.796856 -383.061204) (xy 174.827893 -383.001479)
			(xy 174.865846 -382.945892) (xy 174.887636 -382.92024) (xy 174.893445 -382.913104) (xy 174.899951 -382.895906)
			(xy 174.900336 -382.886712) (xy 174.900336 -382.728724) (xy 174.900742 -382.718567) (xy 174.908536 -382.699808)
			(xy 174.922939 -382.685482) (xy 174.941739 -382.677788) (xy 174.951898 -382.677416) (xy 175.668178 -382.677416)
			(xy 175.6783 -382.677944) (xy 175.697017 -382.68566) (xy 175.711373 -382.699933) (xy 175.719197 -382.718605)
			(xy 175.71974 -382.728724) (xy 175.71974 -382.886712) (xy 175.720158 -382.895898) (xy 175.726668 -382.913082)
			(xy 175.73244 -382.92024) (xy 175.754193 -382.945921) (xy 175.792144 -383.001503) (xy 175.82318 -383.061222)
			(xy 175.846856 -383.124223) (xy 175.862832 -383.189602) (xy 175.870879 -383.256422) (xy 175.870883 -383.323724)
			(xy 175.862842 -383.390545) (xy 175.846872 -383.455925) (xy 175.823202 -383.518928) (xy 175.792172 -383.578651)
			(xy 175.754226 -383.634236) (xy 175.73244 -383.659888) (xy 175.726616 -383.667014) (xy 175.720119 -383.684219)
			(xy 175.71974 -383.693416) (xy 175.71974 -384.186684) (xy 175.720171 -384.195869) (xy 175.726672 -384.213053)
			(xy 175.73244 -384.220212) (xy 175.754264 -384.245835) (xy 175.792213 -384.301425) (xy 175.823246 -384.361152)
			(xy 175.846918 -384.424161) (xy 175.862889 -384.489547) (xy 175.87093 -384.556373) (xy 175.870927 -384.623681)
			(xy 175.862879 -384.690507) (xy 175.846902 -384.755891) (xy 175.823224 -384.818897) (xy 175.792185 -384.878622)
			(xy 175.754231 -384.934208) (xy 175.73244 -384.95986) (xy 175.726628 -384.966994) (xy 175.720124 -384.984193)
			(xy 175.71974 -384.993388) (xy 175.71974 -385.151376) (xy 175.71926 -385.161524) (xy 175.71148 -385.180268)
			(xy 175.697101 -385.194591) (xy 175.678327 -385.202298) (xy 175.668178 -385.202684) (xy 174.951898 -385.202684)
			(xy 174.941774 -385.202176) (xy 174.923058 -385.194452) (xy 174.908702 -385.180172) (xy 174.900879 -385.161497)
			(xy 174.900336 -385.151376) (xy 174.900336 -384.993388) (xy 174.899924 -384.984201) (xy 174.893411 -384.967017)
			(xy 174.887636 -384.95986) (xy 174.865884 -384.934179) (xy 174.827934 -384.878596) (xy 174.7969 -384.818877)
			(xy 174.773225 -384.755876) (xy 174.75725 -384.690497) (xy 174.749203 -384.623678) (xy 174.749199 -384.556376)
			(xy 174.75724 -384.489556) (xy 174.773209 -384.424176) (xy 174.796878 -384.361173) (xy 174.827906 -384.30145)
			(xy 174.865851 -384.245864) (xy 174.887636 -384.220212) (xy 174.893457 -384.213084) (xy 174.899956 -384.19588)
			(xy 174.900336 -384.186684) (xy 174.900336 -383.693416) (xy 174.89991 -383.684231) (xy 174.893407 -383.667046)
			(xy 174.887636 -383.659888) (xy 174.865813 -383.634265) (xy 174.827865 -383.578674) (xy 174.796834 -383.518947)
			(xy 174.773163 -383.455938) (xy 174.757193 -383.390553) (xy 174.749152 -383.323727) (xy 173.646507 -383.323727)
			(xy 173.646742 -383.324352) (xy 173.662713 -383.389736) (xy 173.670756 -383.456559) (xy 173.670754 -383.523865)
			(xy 173.662709 -383.590688) (xy 173.646735 -383.656071) (xy 173.623062 -383.719076) (xy 173.592028 -383.7788)
			(xy 173.55408 -383.834387) (xy 173.532292 -383.86004) (xy 173.526495 -383.867185) (xy 173.519981 -383.884376)
			(xy 173.519592 -383.893568) (xy 173.519592 -384.051556) (xy 173.519142 -384.061708) (xy 173.51136 -384.080461)
			(xy 173.496971 -384.094786) (xy 173.478184 -384.102486) (xy 173.46803 -384.102864) (xy 172.75175 -384.102864)
			(xy 172.741627 -384.102333) (xy 172.722908 -384.094622) (xy 172.70855 -384.080349) (xy 172.700728 -384.061676)
			(xy 172.700188 -384.051556) (xy 172.700188 -383.893568) (xy 172.699796 -383.884379) (xy 172.69327 -383.867194)
			(xy 172.687488 -383.86004) (xy 172.665715 -383.834376) (xy 172.627762 -383.778792) (xy 172.596725 -383.719071)
			(xy 172.57305 -383.656068) (xy 172.557074 -383.590686) (xy 172.549028 -383.523864) (xy 172.549026 -383.45656)
			(xy 172.55707 -383.389737) (xy 172.573042 -383.324355) (xy 172.596716 -383.261351) (xy 172.62775 -383.201629)
			(xy 172.6657 -383.146043) (xy 172.687488 -383.120392) (xy 172.693269 -383.113236) (xy 172.699793 -383.096054)
			(xy 172.700188 -383.086864) (xy 172.700188 -382.593342) (xy 172.69976 -382.584157) (xy 172.693259 -382.566972)
			(xy 172.687488 -382.559814) (xy 172.665689 -382.534171) (xy 172.627737 -382.478584) (xy 172.596702 -382.41886)
			(xy 172.573027 -382.355854) (xy 172.557054 -382.29047) (xy 172.54901 -382.223646) (xy 169.270947 -382.223646)
			(xy 169.262905 -382.290465) (xy 169.246934 -382.355847) (xy 169.223264 -382.41885) (xy 169.192235 -382.478574)
			(xy 169.15429 -382.534161) (xy 169.132504 -382.559814) (xy 169.126719 -382.566968) (xy 169.120197 -382.584152)
			(xy 169.119804 -382.593342) (xy 169.119804 -383.086864) (xy 169.120231 -383.096049) (xy 169.126733 -383.113234)
			(xy 169.132504 -383.120392) (xy 169.154306 -383.146032) (xy 169.192252 -383.201621) (xy 169.223282 -383.261347)
			(xy 169.246739 -383.323787) (xy 170.348832 -383.323787) (xy 170.348835 -383.256359) (xy 170.356915 -383.189418)
			(xy 170.372956 -383.123926) (xy 170.396726 -383.060827) (xy 170.427884 -383.001031) (xy 170.46598 -382.945396)
			(xy 170.487848 -382.919732) (xy 170.493662 -382.912599) (xy 170.500165 -382.895399) (xy 170.500548 -382.886204)
			(xy 170.500548 -382.728724) (xy 170.501103 -382.718623) (xy 170.508823 -382.699955) (xy 170.523098 -382.685662)
			(xy 170.541756 -382.677917) (xy 170.551856 -382.677416) (xy 171.268136 -382.677416) (xy 171.278249 -382.677856)
			(xy 171.296931 -382.685608) (xy 171.311225 -382.699919) (xy 171.318956 -382.71861) (xy 171.319444 -382.728724)
			(xy 171.319444 -382.886204) (xy 171.319865 -382.89539) (xy 171.326372 -382.912574) (xy 171.332144 -382.919732)
			(xy 171.353975 -382.945425) (xy 171.392068 -383.001055) (xy 171.423223 -383.060846) (xy 171.446992 -383.12394)
			(xy 171.463032 -383.189426) (xy 171.471111 -383.256362) (xy 171.471115 -383.323784) (xy 171.463041 -383.390721)
			(xy 171.447008 -383.456209) (xy 171.423246 -383.519304) (xy 171.392096 -383.579099) (xy 171.354008 -383.634732)
			(xy 171.332144 -383.660396) (xy 171.32636 -383.66755) (xy 171.319839 -383.684734) (xy 171.319444 -383.693924)
			(xy 171.319444 -384.186176) (xy 171.319878 -384.19536) (xy 171.326376 -384.212544) (xy 171.332144 -384.219704)
			(xy 171.354045 -384.245339) (xy 171.392137 -384.300977) (xy 171.423289 -384.360776) (xy 171.447054 -384.423877)
			(xy 171.463088 -384.489371) (xy 171.471162 -384.556313) (xy 171.471159 -384.623741) (xy 171.463078 -384.690683)
			(xy 171.447037 -384.756174) (xy 171.423267 -384.819273) (xy 171.392109 -384.87907) (xy 171.354012 -384.934704)
			(xy 171.332144 -384.960368) (xy 171.326329 -384.9675) (xy 171.319827 -384.984701) (xy 171.319444 -384.993896)
			(xy 171.319444 -385.151376) (xy 171.318896 -385.161478) (xy 171.311175 -385.180147) (xy 171.296897 -385.194441)
			(xy 171.278237 -385.202185) (xy 171.268136 -385.202684) (xy 170.551856 -385.202684) (xy 170.541742 -385.20225)
			(xy 170.52306 -385.194495) (xy 170.508766 -385.180183) (xy 170.501036 -385.16149) (xy 170.500548 -385.151376)
			(xy 170.500548 -384.993896) (xy 170.500129 -384.98471) (xy 170.49362 -384.967526) (xy 170.487848 -384.960368)
			(xy 170.466018 -384.934674) (xy 170.427925 -384.879045) (xy 170.39677 -384.819253) (xy 170.373001 -384.75616)
			(xy 170.356962 -384.690674) (xy 170.348883 -384.623738) (xy 170.348879 -384.556316) (xy 170.356952 -384.489379)
			(xy 170.372985 -384.423892) (xy 170.396748 -384.360796) (xy 170.427897 -384.301001) (xy 170.465984 -384.245368)
			(xy 170.487848 -384.219704) (xy 170.493631 -384.21255) (xy 170.500153 -384.195366) (xy 170.500548 -384.186176)
			(xy 170.500548 -383.693924) (xy 170.500116 -383.684739) (xy 170.493616 -383.667555) (xy 170.487848 -383.660396)
			(xy 170.465947 -383.634761) (xy 170.427856 -383.579123) (xy 170.396704 -383.519323) (xy 170.37294 -383.456222)
			(xy 170.356906 -383.390729) (xy 170.348832 -383.323787) (xy 169.246739 -383.323787) (xy 169.246952 -383.324353)
			(xy 169.262922 -383.389736) (xy 169.270965 -383.456559) (xy 169.270963 -383.523865) (xy 169.262918 -383.590688)
			(xy 169.246945 -383.65607) (xy 169.223272 -383.719075) (xy 169.192239 -383.7788) (xy 169.154291 -383.834387)
			(xy 169.132504 -383.86004) (xy 169.126708 -383.867186) (xy 169.120193 -383.884376) (xy 169.119804 -383.893568)
			(xy 169.119804 -384.051556) (xy 169.119342 -384.061707) (xy 169.111562 -384.080457) (xy 169.097177 -384.094782)
			(xy 169.078394 -384.102484) (xy 169.068242 -384.102864) (xy 168.351962 -384.102864) (xy 168.341833 -384.102405)
			(xy 168.323112 -384.094665) (xy 168.308757 -384.080371) (xy 168.300939 -384.061682) (xy 168.3004 -384.051556)
			(xy 168.3004 -383.893568) (xy 168.300005 -383.884379) (xy 168.293481 -383.867195) (xy 168.2877 -383.86004)
			(xy 168.265929 -383.834374) (xy 168.227982 -383.778789) (xy 168.196951 -383.719067) (xy 168.173279 -383.656064)
			(xy 168.157306 -383.590684) (xy 168.149261 -383.523864) (xy 168.149259 -383.456561) (xy 168.157301 -383.38974)
			(xy 168.173272 -383.324359) (xy 168.196941 -383.261355) (xy 168.22797 -383.201632) (xy 168.265914 -383.146045)
			(xy 168.2877 -383.120392) (xy 168.293482 -383.113237) (xy 168.300006 -383.096054) (xy 168.3004 -383.086864)
			(xy 168.3004 -382.593342) (xy 168.29997 -382.584157) (xy 168.29347 -382.566972) (xy 168.2877 -382.559814)
			(xy 168.265904 -382.534169) (xy 168.227958 -382.478581) (xy 168.196927 -382.418856) (xy 168.173256 -382.355851)
			(xy 168.157285 -382.290468) (xy 168.149243 -382.223645) (xy 164.871179 -382.223645) (xy 164.871179 -382.223704)
			(xy 164.863104 -382.290641) (xy 164.84707 -382.35613) (xy 164.823307 -382.419226) (xy 164.792158 -382.479022)
			(xy 164.754071 -382.534657) (xy 164.732208 -382.560322) (xy 164.726421 -382.567474) (xy 164.7199 -382.584659)
			(xy 164.719508 -382.59385) (xy 164.719508 -383.086356) (xy 164.719937 -383.095541) (xy 164.726437 -383.112726)
			(xy 164.732208 -383.119884) (xy 164.754087 -383.145536) (xy 164.792175 -383.201173) (xy 164.823325 -383.260971)
			(xy 164.846959 -383.323727) (xy 165.949064 -383.323727) (xy 165.949067 -383.256419) (xy 165.957115 -383.189594)
			(xy 165.973092 -383.124209) (xy 165.996769 -383.061203) (xy 166.027808 -383.001479) (xy 166.065762 -382.945892)
			(xy 166.087552 -382.92024) (xy 166.093363 -382.913105) (xy 166.099868 -382.895907) (xy 166.100252 -382.886712)
			(xy 166.100252 -382.728724) (xy 166.10074 -382.718577) (xy 166.108519 -382.699835) (xy 166.122895 -382.685512)
			(xy 166.141666 -382.677803) (xy 166.151814 -382.677416) (xy 166.868094 -382.677416) (xy 166.878217 -382.677931)
			(xy 166.896934 -382.685652) (xy 166.911289 -382.699929) (xy 166.919113 -382.718603) (xy 166.919656 -382.728724)
			(xy 166.919656 -382.886712) (xy 166.92007 -382.895899) (xy 166.926582 -382.913082) (xy 166.932356 -382.92024)
			(xy 166.954108 -382.945921) (xy 166.992059 -383.001503) (xy 167.023094 -383.061223) (xy 167.046769 -383.124224)
			(xy 167.062744 -383.189602) (xy 167.070791 -383.256422) (xy 167.070795 -383.323724) (xy 167.062754 -383.390544)
			(xy 167.046785 -383.455925) (xy 167.023116 -383.518928) (xy 166.992086 -383.57865) (xy 166.954142 -383.634236)
			(xy 166.932356 -383.659888) (xy 166.926534 -383.667015) (xy 166.920036 -383.68422) (xy 166.919656 -383.693416)
			(xy 166.919656 -384.186684) (xy 166.920084 -384.195869) (xy 166.926586 -384.213053) (xy 166.932356 -384.220212)
			(xy 166.954179 -384.245835) (xy 166.992127 -384.301425) (xy 167.023159 -384.361153) (xy 167.04683 -384.424161)
			(xy 167.062801 -384.489547) (xy 167.070842 -384.556373) (xy 167.070839 -384.623681) (xy 167.062791 -384.690506)
			(xy 167.046814 -384.75589) (xy 167.023137 -384.818897) (xy 166.9921 -384.878621) (xy 166.954146 -384.934208)
			(xy 166.932356 -384.95986) (xy 166.926546 -384.966995) (xy 166.92004 -384.984194) (xy 166.919656 -384.993388)
			(xy 166.919656 -385.151376) (xy 166.91916 -385.161522) (xy 166.911383 -385.180263) (xy 166.89701 -385.194585)
			(xy 166.878241 -385.202296) (xy 166.868094 -385.202684) (xy 166.151814 -385.202684) (xy 166.141691 -385.202163)
			(xy 166.122975 -385.194444) (xy 166.108619 -385.180169) (xy 166.100795 -385.161496) (xy 166.100252 -385.151376)
			(xy 166.100252 -384.993388) (xy 166.099836 -384.984202) (xy 166.093325 -384.967018) (xy 166.087552 -384.95986)
			(xy 166.065799 -384.934179) (xy 166.027849 -384.878597) (xy 165.996813 -384.818877) (xy 165.973138 -384.755877)
			(xy 165.957162 -384.690498) (xy 165.949115 -384.623678) (xy 165.949111 -384.556376) (xy 165.957152 -384.489555)
			(xy 165.973122 -384.424175) (xy 165.996791 -384.361172) (xy 166.027821 -384.30145) (xy 166.065766 -384.245864)
			(xy 166.087552 -384.220212) (xy 166.093375 -384.213086) (xy 166.099872 -384.19588) (xy 166.100252 -384.186684)
			(xy 166.100252 -383.693416) (xy 166.099823 -383.684231) (xy 166.093321 -383.667047) (xy 166.087552 -383.659888)
			(xy 166.065728 -383.634265) (xy 166.02778 -383.578675) (xy 165.996747 -383.518947) (xy 165.973076 -383.455939)
			(xy 165.957105 -383.390553) (xy 165.949064 -383.323727) (xy 164.846959 -383.323727) (xy 164.847088 -383.32407)
			(xy 164.863122 -383.38956) (xy 164.871196 -383.4565) (xy 164.871195 -383.523924) (xy 164.863117 -383.590864)
			(xy 164.84708 -383.656353) (xy 164.823315 -383.719451) (xy 164.792163 -383.779248) (xy 164.754073 -383.834883)
			(xy 164.732208 -383.860548) (xy 164.726409 -383.867692) (xy 164.719896 -383.884883) (xy 164.719508 -383.894076)
			(xy 164.719508 -384.051556) (xy 164.719048 -384.061675) (xy 164.711316 -384.080376) (xy 164.697013 -384.094691)
			(xy 164.678318 -384.102439) (xy 164.6682 -384.102864) (xy 163.95192 -384.102864) (xy 163.941794 -384.102467)
			(xy 163.923084 -384.094719) (xy 163.908768 -384.080396) (xy 163.901028 -384.061682) (xy 163.900612 -384.051556)
			(xy 163.900612 -383.894076) (xy 163.900211 -383.884888) (xy 163.893691 -383.867704) (xy 163.887912 -383.860548)
			(xy 163.866063 -383.83487) (xy 163.827973 -383.779238) (xy 163.796821 -383.719443) (xy 163.773056 -383.656348)
			(xy 163.757019 -383.59086) (xy 163.748941 -383.523923) (xy 163.74894 -383.456501) (xy 163.757014 -383.389563)
			(xy 163.773049 -383.324075) (xy 163.796811 -383.260979) (xy 163.827961 -383.201183) (xy 163.866049 -383.145549)
			(xy 163.887912 -383.119884) (xy 163.893699 -383.112732) (xy 163.900219 -383.095547) (xy 163.900612 -383.086356)
			(xy 163.900612 -382.59385) (xy 163.900175 -382.584666) (xy 163.89368 -382.567481) (xy 163.887912 -382.560322)
			(xy 163.866038 -382.534665) (xy 163.827949 -382.47903) (xy 163.796798 -382.419232) (xy 163.773034 -382.356134)
			(xy 163.756998 -382.290644) (xy 163.748923 -382.223705) (xy 160.470876 -382.223705) (xy 160.46284 -382.290468)
			(xy 160.446866 -382.35585) (xy 160.423193 -382.418854) (xy 160.392159 -382.478577) (xy 160.354208 -382.534162)
			(xy 160.33242 -382.559814) (xy 160.326637 -382.566969) (xy 160.320114 -382.584152) (xy 160.31972 -382.593342)
			(xy 160.31972 -383.086864) (xy 160.320143 -383.09605) (xy 160.326647 -383.113235) (xy 160.33242 -383.120392)
			(xy 160.354225 -383.146031) (xy 160.392176 -383.201618) (xy 160.42321 -383.261343) (xy 160.446672 -383.323786)
			(xy 161.548769 -383.323786) (xy 161.548772 -383.25636) (xy 161.556851 -383.18942) (xy 161.572889 -383.123929)
			(xy 161.596656 -383.060831) (xy 161.627809 -383.001034) (xy 161.665899 -382.945398) (xy 161.687764 -382.919732)
			(xy 161.69358 -382.912601) (xy 161.700081 -382.895399) (xy 161.700464 -382.886204) (xy 161.700464 -382.728724)
			(xy 161.701004 -382.718621) (xy 161.708727 -382.69995) (xy 161.723007 -382.685656) (xy 161.74167 -382.677914)
			(xy 161.751772 -382.677416) (xy 162.468052 -382.677416) (xy 162.478173 -382.677856) (xy 162.496879 -382.685591)
			(xy 162.511195 -382.699901) (xy 162.51894 -382.718603) (xy 162.51936 -382.728724) (xy 162.51936 -382.886204)
			(xy 162.519777 -382.89539) (xy 162.526287 -382.912574) (xy 162.53206 -382.919732) (xy 162.55389 -382.945426)
			(xy 162.591982 -383.001055) (xy 162.623137 -383.060847) (xy 162.646905 -383.12394) (xy 162.662944 -383.189426)
			(xy 162.671023 -383.256362) (xy 162.671027 -383.323784) (xy 162.662954 -383.39072) (xy 162.646921 -383.456208)
			(xy 162.623159 -383.519303) (xy 162.59201 -383.579098) (xy 162.553923 -383.634731) (xy 162.53206 -383.660396)
			(xy 162.526278 -383.667551) (xy 162.519755 -383.684734) (xy 162.51936 -383.693924) (xy 162.51936 -384.186176)
			(xy 162.51979 -384.195361) (xy 162.526291 -384.212545) (xy 162.53206 -384.219704) (xy 162.553961 -384.245339)
			(xy 162.592051 -384.300977) (xy 162.623202 -384.360777) (xy 162.646966 -384.423878) (xy 162.663 -384.489371)
			(xy 162.671074 -384.556313) (xy 162.671071 -384.623741) (xy 162.662991 -384.690682) (xy 162.64695 -384.756174)
			(xy 162.62318 -384.819272) (xy 162.592023 -384.879069) (xy 162.553928 -384.934703) (xy 162.53206 -384.960368)
			(xy 162.526247 -384.967501) (xy 162.519743 -384.984701) (xy 162.51936 -384.993896) (xy 162.51936 -385.151376)
			(xy 162.518964 -385.161502) (xy 162.511216 -385.180213) (xy 162.496893 -385.194529) (xy 162.478178 -385.202268)
			(xy 162.468052 -385.202684) (xy 161.751772 -385.202684) (xy 161.741659 -385.202238) (xy 161.722978 -385.194488)
			(xy 161.708683 -385.180179) (xy 161.700952 -385.161489) (xy 161.700464 -385.151376) (xy 161.700464 -384.993896)
			(xy 161.700041 -384.98471) (xy 161.693535 -384.967527) (xy 161.687764 -384.960368) (xy 161.665937 -384.934673)
			(xy 161.627849 -384.879042) (xy 161.596699 -384.819249) (xy 161.572934 -384.756157) (xy 161.556897 -384.690671)
			(xy 161.548819 -384.623737) (xy 161.548816 -384.556317) (xy 161.556888 -384.489382) (xy 161.572918 -384.423895)
			(xy 161.596677 -384.3608) (xy 161.627821 -384.301005) (xy 161.665903 -384.24537) (xy 161.687764 -384.219704)
			(xy 161.693549 -384.212551) (xy 161.700069 -384.195366) (xy 161.700464 -384.186176) (xy 161.700464 -383.693924)
			(xy 161.700028 -383.68474) (xy 161.693531 -383.667556) (xy 161.687764 -383.660396) (xy 161.665866 -383.634759)
			(xy 161.627781 -383.57912) (xy 161.596634 -383.519319) (xy 161.572873 -383.456219) (xy 161.556841 -383.390727)
			(xy 161.548769 -383.323786) (xy 160.446672 -383.323786) (xy 160.446884 -383.32435) (xy 160.462857 -383.389734)
			(xy 160.470901 -383.456558) (xy 160.470899 -383.523866) (xy 160.462853 -383.59069) (xy 160.446877 -383.656074)
			(xy 160.423201 -383.719079) (xy 160.392163 -383.778803) (xy 160.35421 -383.834388) (xy 160.33242 -383.86004)
			(xy 160.326626 -383.867187) (xy 160.320109 -383.884376) (xy 160.31972 -383.893568) (xy 160.31972 -384.051556)
			(xy 160.319248 -384.061673) (xy 160.311518 -384.080372) (xy 160.297219 -384.094687) (xy 160.278529 -384.102437)
			(xy 160.268412 -384.102864) (xy 159.551878 -384.102864) (xy 159.54175 -384.102392) (xy 159.523029 -384.094657)
			(xy 159.508674 -384.080367) (xy 159.500855 -384.061681) (xy 159.500316 -384.051556) (xy 159.500316 -383.893568)
			(xy 159.499918 -383.88438) (xy 159.493395 -383.867196) (xy 159.487616 -383.86004) (xy 159.465845 -383.834375)
			(xy 159.427897 -383.77879) (xy 159.396864 -383.719068) (xy 159.373191 -383.656065) (xy 159.357218 -383.590684)
			(xy 159.349173 -383.523864) (xy 159.349172 -383.45656) (xy 159.357214 -383.389739) (xy 159.373184 -383.324358)
			(xy 159.396854 -383.261354) (xy 159.427884 -383.201631) (xy 159.46583 -383.146044) (xy 159.487616 -383.120392)
			(xy 159.4934 -383.113238) (xy 159.499922 -383.096054) (xy 159.500316 -383.086864) (xy 159.500316 -382.593342)
			(xy 159.499882 -382.584157) (xy 159.493384 -382.566973) (xy 159.487616 -382.559814) (xy 159.465819 -382.53417)
			(xy 159.427872 -382.478582) (xy 159.396841 -382.418857) (xy 159.373169 -382.355851) (xy 159.357198 -382.290468)
			(xy 159.349155 -382.223645) (xy 129.670829 -382.223645) (xy 129.662786 -382.290466) (xy 129.646815 -382.355847)
			(xy 129.623144 -382.418851) (xy 129.592113 -382.478575) (xy 129.554167 -382.534162) (xy 129.53238 -382.559814)
			(xy 129.526593 -382.566966) (xy 129.520073 -382.584151) (xy 129.51968 -382.593342) (xy 129.51968 -383.086864)
			(xy 129.520112 -383.096049) (xy 129.526611 -383.113233) (xy 129.53238 -383.120392) (xy 129.554183 -383.146031)
			(xy 129.59213 -383.20162) (xy 129.623162 -383.261346) (xy 129.646598 -383.323727) (xy 130.749242 -383.323727)
			(xy 130.749246 -383.256419) (xy 130.757293 -383.189594) (xy 130.77327 -383.12421) (xy 130.796946 -383.061204)
			(xy 130.827982 -383.00148) (xy 130.865935 -382.945892) (xy 130.887724 -382.92024) (xy 130.893531 -382.913103)
			(xy 130.900039 -382.895906) (xy 130.900424 -382.886712) (xy 130.900424 -382.728724) (xy 130.900842 -382.718568)
			(xy 130.908634 -382.699812) (xy 130.923032 -382.685487) (xy 130.941828 -382.67779) (xy 130.951986 -382.677416)
			(xy 131.668266 -382.677416) (xy 131.678388 -382.677954) (xy 131.697103 -382.685666) (xy 131.71146 -382.699937)
			(xy 131.719284 -382.718606) (xy 131.719828 -382.728724) (xy 131.719828 -382.886712) (xy 131.720226 -382.895901)
			(xy 131.726747 -382.913085) (xy 131.732528 -382.92024) (xy 131.754281 -382.945921) (xy 131.792233 -383.001502)
			(xy 131.82327 -383.061222) (xy 131.846946 -383.124223) (xy 131.862923 -383.189602) (xy 131.87097 -383.256422)
			(xy 131.870973 -383.323724) (xy 131.862932 -383.390545) (xy 131.846962 -383.455926) (xy 131.823292 -383.518929)
			(xy 131.792261 -383.578651) (xy 131.754314 -383.634236) (xy 131.732528 -383.659888) (xy 131.726703 -383.667013)
			(xy 131.720207 -383.684219) (xy 131.719828 -383.693416) (xy 131.719828 -384.186684) (xy 131.720239 -384.195871)
			(xy 131.726751 -384.213056) (xy 131.732528 -384.220212) (xy 131.754352 -384.245834) (xy 131.792302 -384.301424)
			(xy 131.823336 -384.361152) (xy 131.847008 -384.42416) (xy 131.86298 -384.489546) (xy 131.871021 -384.556373)
			(xy 131.871018 -384.623681) (xy 131.86297 -384.690507) (xy 131.846992 -384.755892) (xy 131.823314 -384.818898)
			(xy 131.792274 -384.878622) (xy 131.754319 -384.934208) (xy 131.732528 -384.95986) (xy 131.726715 -384.966993)
			(xy 131.720212 -384.984193) (xy 131.719828 -384.993388) (xy 131.719828 -385.151376) (xy 131.719359 -385.161525)
			(xy 131.711577 -385.180272) (xy 131.697195 -385.194595) (xy 131.678417 -385.202301) (xy 131.668266 -385.202684)
			(xy 130.951986 -385.202684) (xy 130.941861 -385.202185) (xy 130.923145 -385.194457) (xy 130.90879 -385.180175)
			(xy 130.900967 -385.161498) (xy 130.900424 -385.151376) (xy 130.900424 -384.993388) (xy 130.900014 -384.984201)
			(xy 130.8935 -384.967017) (xy 130.887724 -384.95986) (xy 130.865972 -384.934178) (xy 130.828023 -384.878596)
			(xy 130.796989 -384.818876) (xy 130.773315 -384.755876) (xy 130.75734 -384.690497) (xy 130.749294 -384.623678)
			(xy 130.74929 -384.556376) (xy 130.757331 -384.489556) (xy 130.773299 -384.424176) (xy 130.796967 -384.361173)
			(xy 130.827996 -384.301451) (xy 130.865939 -384.245865) (xy 130.887724 -384.220212) (xy 130.893543 -384.213083)
			(xy 130.900044 -384.19588) (xy 130.900424 -384.186684) (xy 130.900424 -383.693416) (xy 130.900001 -383.68423)
			(xy 130.893495 -383.667046) (xy 130.887724 -383.659888) (xy 130.865901 -383.634265) (xy 130.827955 -383.578674)
			(xy 130.796924 -383.518946) (xy 130.773254 -383.455938) (xy 130.757284 -383.390552) (xy 130.749242 -383.323727)
			(xy 129.646598 -383.323727) (xy 129.646833 -383.324352) (xy 129.662804 -383.389735) (xy 129.670846 -383.456559)
			(xy 129.670845 -383.523865) (xy 129.6628 -383.590688) (xy 129.646826 -383.656071) (xy 129.623152 -383.719076)
			(xy 129.592118 -383.778801) (xy 129.554168 -383.834388) (xy 129.53238 -383.86004) (xy 129.526582 -383.867184)
			(xy 129.520069 -383.884375) (xy 129.51968 -383.893568) (xy 129.51968 -384.051556) (xy 129.519242 -384.06171)
			(xy 129.511457 -384.080465) (xy 129.497065 -384.094791) (xy 129.478274 -384.102488) (xy 129.468118 -384.102864)
			(xy 128.751838 -384.102864) (xy 128.741714 -384.102342) (xy 128.722995 -384.094628) (xy 128.708637 -384.080352)
			(xy 128.700816 -384.061677) (xy 128.700276 -384.051556) (xy 128.700276 -383.893568) (xy 128.699886 -383.884379)
			(xy 128.693359 -383.867194) (xy 128.687576 -383.86004) (xy 128.665803 -383.834375) (xy 128.627851 -383.778792)
			(xy 128.596815 -383.71907) (xy 128.57314 -383.656067) (xy 128.557165 -383.590686) (xy 128.549119 -383.523864)
			(xy 128.549117 -383.45656) (xy 128.55716 -383.389738) (xy 128.573133 -383.324356) (xy 128.596805 -383.261352)
			(xy 128.627839 -383.201629) (xy 128.665788 -383.146044) (xy 128.687576 -383.120392) (xy 128.693356 -383.113235)
			(xy 128.699881 -383.096054) (xy 128.700276 -383.086864) (xy 128.700276 -382.593342) (xy 128.699851 -382.584156)
			(xy 128.693348 -382.566971) (xy 128.687576 -382.559814) (xy 128.665777 -382.53417) (xy 128.627826 -382.478584)
			(xy 128.596792 -382.418859) (xy 128.573118 -382.355853) (xy 128.557144 -382.29047) (xy 128.5491 -382.223646)
			(xy 125.271038 -382.223646) (xy 125.262995 -382.290466) (xy 125.247025 -382.355847) (xy 125.223354 -382.418851)
			(xy 125.192324 -382.478574) (xy 125.154378 -382.534161) (xy 125.132592 -382.559814) (xy 125.126806 -382.566967)
			(xy 125.120285 -382.584151) (xy 125.119892 -382.593342) (xy 125.119892 -383.086864) (xy 125.120321 -383.096049)
			(xy 125.126822 -383.113234) (xy 125.132592 -383.120392) (xy 125.154394 -383.146032) (xy 125.192341 -383.201621)
			(xy 125.223372 -383.261346) (xy 125.24683 -383.323787) (xy 126.348923 -383.323787) (xy 126.348926 -383.256359)
			(xy 126.357006 -383.189418) (xy 126.373047 -383.123926) (xy 126.396816 -383.060828) (xy 126.427973 -383.001031)
			(xy 126.466069 -382.945397) (xy 126.487936 -382.919732) (xy 126.493749 -382.912598) (xy 126.500253 -382.895399)
			(xy 126.500636 -382.886204) (xy 126.500636 -382.728724) (xy 126.501036 -382.718599) (xy 126.508783 -382.699889)
			(xy 126.523105 -382.685572) (xy 126.541818 -382.677832) (xy 126.551944 -382.677416) (xy 127.268224 -382.677416)
			(xy 127.278336 -382.677866) (xy 127.297018 -382.685614) (xy 127.311313 -382.699922) (xy 127.319044 -382.718611)
			(xy 127.319532 -382.728724) (xy 127.319532 -382.886204) (xy 127.319956 -382.895389) (xy 127.326462 -382.912573)
			(xy 127.332232 -382.919732) (xy 127.354059 -382.945427) (xy 127.392147 -383.001058) (xy 127.423298 -383.06085)
			(xy 127.447062 -383.123943) (xy 127.463099 -383.189428) (xy 127.471178 -383.256363) (xy 127.471181 -383.323783)
			(xy 127.463109 -383.390718) (xy 127.447078 -383.456205) (xy 127.42332 -383.5193) (xy 127.392175 -383.579096)
			(xy 127.354093 -383.63473) (xy 127.332232 -383.660396) (xy 127.326446 -383.667549) (xy 127.319927 -383.684734)
			(xy 127.319532 -383.693924) (xy 127.319532 -384.186176) (xy 127.319969 -384.19536) (xy 127.326466 -384.212544)
			(xy 127.332232 -384.219704) (xy 127.35413 -384.245341) (xy 127.392216 -384.30098) (xy 127.423363 -384.36078)
			(xy 127.447124 -384.423881) (xy 127.463156 -384.489373) (xy 127.471228 -384.556314) (xy 127.471225 -384.62374)
			(xy 127.463146 -384.69068) (xy 127.447108 -384.756171) (xy 127.423341 -384.819269) (xy 127.392188 -384.879066)
			(xy 127.354097 -384.934702) (xy 127.332232 -384.960368) (xy 127.326416 -384.967499) (xy 127.319915 -384.984701)
			(xy 127.319532 -384.993896) (xy 127.319532 -385.151376) (xy 127.318996 -385.161479) (xy 127.311272 -385.180151)
			(xy 127.296991 -385.194445) (xy 127.278327 -385.202187) (xy 127.268224 -385.202684) (xy 126.551944 -385.202684)
			(xy 126.541822 -385.202247) (xy 126.523117 -385.194511) (xy 126.5088 -385.1802) (xy 126.501056 -385.161497)
			(xy 126.500636 -385.151376) (xy 126.500636 -384.993896) (xy 126.50022 -384.98471) (xy 126.49371 -384.967526)
			(xy 126.487936 -384.960368) (xy 126.466106 -384.934674) (xy 126.428014 -384.879045) (xy 126.39686 -384.819253)
			(xy 126.373092 -384.756159) (xy 126.357053 -384.690673) (xy 126.348974 -384.623738) (xy 126.34897 -384.556316)
			(xy 126.357043 -384.48938) (xy 126.373076 -384.423892) (xy 126.396838 -384.360797) (xy 126.427986 -384.301002)
			(xy 126.466073 -384.245369) (xy 126.487936 -384.219704) (xy 126.493718 -384.212549) (xy 126.50024 -384.195366)
			(xy 126.500636 -384.186176) (xy 126.500636 -383.693924) (xy 126.500206 -383.684739) (xy 126.493705 -383.667555)
			(xy 126.487936 -383.660396) (xy 126.466035 -383.634761) (xy 126.427945 -383.579123) (xy 126.396794 -383.519323)
			(xy 126.373031 -383.456222) (xy 126.356996 -383.390729) (xy 126.348923 -383.323787) (xy 125.24683 -383.323787)
			(xy 125.247042 -383.324352) (xy 125.263013 -383.389736) (xy 125.271056 -383.456559) (xy 125.271054 -383.523865)
			(xy 125.263009 -383.590688) (xy 125.247035 -383.656071) (xy 125.223362 -383.719076) (xy 125.192328 -383.7788)
			(xy 125.15438 -383.834387) (xy 125.132592 -383.86004) (xy 125.126795 -383.867185) (xy 125.120281 -383.884376)
			(xy 125.119892 -383.893568) (xy 125.119892 -384.051556) (xy 125.119442 -384.061708) (xy 125.11166 -384.080461)
			(xy 125.097271 -384.094786) (xy 125.078484 -384.102486) (xy 125.06833 -384.102864) (xy 124.35205 -384.102864)
			(xy 124.341927 -384.102333) (xy 124.323208 -384.094622) (xy 124.30885 -384.080349) (xy 124.301028 -384.061676)
			(xy 124.300488 -384.051556) (xy 124.300488 -383.893568) (xy 124.300096 -383.884379) (xy 124.29357 -383.867194)
			(xy 124.287788 -383.86004) (xy 124.266015 -383.834376) (xy 124.228062 -383.778792) (xy 124.197025 -383.719071)
			(xy 124.17335 -383.656068) (xy 124.157374 -383.590686) (xy 124.149328 -383.523864) (xy 124.149326 -383.45656)
			(xy 124.15737 -383.389737) (xy 124.173342 -383.324355) (xy 124.197016 -383.261351) (xy 124.22805 -383.201629)
			(xy 124.266 -383.146043) (xy 124.287788 -383.120392) (xy 124.293569 -383.113236) (xy 124.300093 -383.096054)
			(xy 124.300488 -383.086864) (xy 124.300488 -382.593342) (xy 124.30006 -382.584157) (xy 124.293559 -382.566972)
			(xy 124.287788 -382.559814) (xy 124.265989 -382.534171) (xy 124.228037 -382.478584) (xy 124.197002 -382.41886)
			(xy 124.173327 -382.355854) (xy 124.157354 -382.29047) (xy 124.14931 -382.223646) (xy 120.87127 -382.223646)
			(xy 120.87127 -382.223704) (xy 120.863195 -382.290642) (xy 120.84716 -382.35613) (xy 120.823397 -382.419227)
			(xy 120.792247 -382.479023) (xy 120.75416 -382.534657) (xy 120.732296 -382.560322) (xy 120.726507 -382.567473)
			(xy 120.719988 -382.584659) (xy 120.719596 -382.59385) (xy 120.719596 -383.086356) (xy 120.720028 -383.095541)
			(xy 120.726527 -383.112725) (xy 120.732296 -383.119884) (xy 120.754176 -383.145536) (xy 120.792264 -383.201173)
			(xy 120.823415 -383.26097) (xy 120.847049 -383.323727) (xy 121.949155 -383.323727) (xy 121.949158 -383.256419)
			(xy 121.957206 -383.189594) (xy 121.973182 -383.12421) (xy 121.996859 -383.061204) (xy 122.027897 -383.001479)
			(xy 122.06585 -382.945892) (xy 122.08764 -382.92024) (xy 122.09345 -382.913104) (xy 122.099955 -382.895906)
			(xy 122.10034 -382.886712) (xy 122.10034 -382.728724) (xy 122.100742 -382.718566) (xy 122.108537 -382.699807)
			(xy 122.122941 -382.685481) (xy 122.141742 -382.677788) (xy 122.151902 -382.677416) (xy 122.868182 -382.677416)
			(xy 122.878305 -382.677941) (xy 122.897021 -382.685658) (xy 122.911377 -382.699932) (xy 122.919201 -382.718604)
			(xy 122.919744 -382.728724) (xy 122.919744 -382.886712) (xy 122.920161 -382.895898) (xy 122.926671 -382.913082)
			(xy 122.932444 -382.92024) (xy 122.954197 -382.945921) (xy 122.992148 -383.001503) (xy 123.023183 -383.061222)
			(xy 123.046859 -383.124223) (xy 123.062835 -383.189602) (xy 123.070882 -383.256422) (xy 123.070886 -383.323724)
			(xy 123.062845 -383.390545) (xy 123.046875 -383.455925) (xy 123.023206 -383.518928) (xy 122.992176 -383.57865)
			(xy 122.95423 -383.634236) (xy 122.932444 -383.659888) (xy 122.926621 -383.667014) (xy 122.920124 -383.684219)
			(xy 122.919744 -383.693416) (xy 122.919744 -384.186684) (xy 122.920174 -384.195869) (xy 122.926675 -384.213053)
			(xy 122.932444 -384.220212) (xy 122.954268 -384.245835) (xy 122.992217 -384.301425) (xy 123.023249 -384.361152)
			(xy 123.046921 -384.424161) (xy 123.062892 -384.489547) (xy 123.070933 -384.556373) (xy 123.07093 -384.623681)
			(xy 123.062882 -384.690507) (xy 123.046905 -384.755891) (xy 123.023227 -384.818897) (xy 122.992189 -384.878622)
			(xy 122.954235 -384.934208) (xy 122.932444 -384.95986) (xy 122.926633 -384.966994) (xy 122.920128 -384.984193)
			(xy 122.919744 -384.993388) (xy 122.919744 -385.151376) (xy 122.91926 -385.161523) (xy 122.91148 -385.180267)
			(xy 122.897103 -385.194589) (xy 122.878331 -385.202298) (xy 122.868182 -385.202684) (xy 122.151902 -385.202684)
			(xy 122.141778 -385.202172) (xy 122.123062 -385.19445) (xy 122.108706 -385.180171) (xy 122.100883 -385.161497)
			(xy 122.10034 -385.151376) (xy 122.10034 -384.993388) (xy 122.099927 -384.984201) (xy 122.093414 -384.967017)
			(xy 122.08764 -384.95986) (xy 122.065888 -384.934179) (xy 122.027938 -384.878596) (xy 121.996903 -384.818877)
			(xy 121.973228 -384.755876) (xy 121.957253 -384.690498) (xy 121.949206 -384.623678) (xy 121.949202 -384.556376)
			(xy 121.957243 -384.489556) (xy 121.973212 -384.424176) (xy 121.996881 -384.361173) (xy 122.02791 -384.30145)
			(xy 122.065855 -384.245864) (xy 122.08764 -384.220212) (xy 122.093461 -384.213085) (xy 122.09996 -384.19588)
			(xy 122.10034 -384.186684) (xy 122.10034 -383.693416) (xy 122.099913 -383.684231) (xy 122.09341 -383.667047)
			(xy 122.08764 -383.659888) (xy 122.065817 -383.634265) (xy 122.027869 -383.578674) (xy 121.996837 -383.518947)
			(xy 121.973166 -383.455939) (xy 121.957196 -383.390553) (xy 121.949155 -383.323727) (xy 120.847049 -383.323727)
			(xy 120.847178 -383.324069) (xy 120.863212 -383.38956) (xy 120.871287 -383.4565) (xy 120.871286 -383.523925)
			(xy 120.863208 -383.590864) (xy 120.847171 -383.656354) (xy 120.823405 -383.719452) (xy 120.792252 -383.779248)
			(xy 120.754161 -383.834883) (xy 120.732296 -383.860548) (xy 120.726496 -383.867691) (xy 120.719984 -383.884883)
			(xy 120.719596 -383.894076) (xy 120.719596 -384.051556) (xy 120.719148 -384.061676) (xy 120.711413 -384.080379)
			(xy 120.697106 -384.094695) (xy 120.678408 -384.102441) (xy 120.668288 -384.102864) (xy 119.952008 -384.102864)
			(xy 119.941882 -384.102477) (xy 119.923171 -384.094724) (xy 119.908855 -384.080399) (xy 119.901116 -384.061683)
			(xy 119.9007 -384.051556) (xy 119.9007 -383.894076) (xy 119.900302 -383.884888) (xy 119.89378 -383.867703)
			(xy 119.888 -383.860548) (xy 119.866152 -383.83487) (xy 119.828063 -383.779237) (xy 119.796911 -383.719443)
			(xy 119.773146 -383.656348) (xy 119.75711 -383.59086) (xy 119.749032 -383.523923) (xy 119.749031 -383.456501)
			(xy 119.757105 -383.389564) (xy 119.773139 -383.324075) (xy 119.796901 -383.260979) (xy 119.82805 -383.201184)
			(xy 119.866137 -383.145549) (xy 119.888 -383.119884) (xy 119.893786 -383.112731) (xy 119.900307 -383.095547)
			(xy 119.9007 -383.086356) (xy 119.9007 -382.59385) (xy 119.900266 -382.584665) (xy 119.893769 -382.567481)
			(xy 119.888 -382.560322) (xy 119.866126 -382.534665) (xy 119.828038 -382.479029) (xy 119.796888 -382.419232)
			(xy 119.773124 -382.356134) (xy 119.757089 -382.290644) (xy 119.749014 -382.223705) (xy 116.470967 -382.223705)
			(xy 116.46293 -382.290468) (xy 116.446957 -382.35585) (xy 116.423283 -382.418855) (xy 116.392248 -382.478577)
			(xy 116.354297 -382.534163) (xy 116.332508 -382.559814) (xy 116.326724 -382.566968) (xy 116.320202 -382.584152)
			(xy 116.319808 -382.593342) (xy 116.319808 -383.086864) (xy 116.320234 -383.09605) (xy 116.326736 -383.113234)
			(xy 116.332508 -383.120392) (xy 116.354313 -383.146031) (xy 116.392265 -383.201618) (xy 116.4233 -383.261343)
			(xy 116.446764 -383.323787) (xy 117.548835 -383.323787) (xy 117.548838 -383.256359) (xy 117.556918 -383.189418)
			(xy 117.572959 -383.123926) (xy 117.59673 -383.060827) (xy 117.627888 -383.00103) (xy 117.665984 -382.945396)
			(xy 117.687852 -382.919732) (xy 117.693666 -382.9126) (xy 117.700169 -382.895399) (xy 117.700552 -382.886204)
			(xy 117.700552 -382.728724) (xy 117.701103 -382.718623) (xy 117.708824 -382.699954) (xy 117.7231 -382.68566)
			(xy 117.741759 -382.677916) (xy 117.75186 -382.677416) (xy 118.46814 -382.677416) (xy 118.478253 -382.677853)
			(xy 118.496935 -382.685607) (xy 118.511229 -382.699918) (xy 118.51896 -382.71861) (xy 118.519448 -382.728724)
			(xy 118.519448 -382.886204) (xy 118.519868 -382.89539) (xy 118.526376 -382.912574) (xy 118.532148 -382.919732)
			(xy 118.553978 -382.945426) (xy 118.592072 -383.001055) (xy 118.623227 -383.060847) (xy 118.646995 -383.12394)
			(xy 118.663035 -383.189426) (xy 118.671114 -383.256362) (xy 118.671118 -383.323784) (xy 118.663045 -383.390721)
			(xy 118.647011 -383.456208) (xy 118.623249 -383.519304) (xy 118.592099 -383.579099) (xy 118.554012 -383.634732)
			(xy 118.532148 -383.660396) (xy 118.526364 -383.66755) (xy 118.519843 -383.684734) (xy 118.519448 -383.693924)
			(xy 118.519448 -384.186176) (xy 118.519881 -384.195361) (xy 118.52638 -384.212545) (xy 118.532148 -384.219704)
			(xy 118.554049 -384.245339) (xy 118.59214 -384.300977) (xy 118.623292 -384.360777) (xy 118.647057 -384.423878)
			(xy 118.663091 -384.489371) (xy 118.671165 -384.556313) (xy 118.671162 -384.623741) (xy 118.663082 -384.690682)
			(xy 118.647041 -384.756174) (xy 118.62327 -384.819273) (xy 118.592112 -384.87907) (xy 118.554016 -384.934704)
			(xy 118.532148 -384.960368) (xy 118.526334 -384.9675) (xy 118.519831 -384.984701) (xy 118.519448 -384.993896)
			(xy 118.519448 -385.151376) (xy 118.518897 -385.161477) (xy 118.511176 -385.180146) (xy 118.4969 -385.19444)
			(xy 118.478241 -385.202184) (xy 118.46814 -385.202684) (xy 117.75186 -385.202684) (xy 117.741747 -385.202247)
			(xy 117.723065 -385.194493) (xy 117.708771 -385.180182) (xy 117.70104 -385.16149) (xy 117.700552 -385.151376)
			(xy 117.700552 -384.993896) (xy 117.700132 -384.98471) (xy 117.693624 -384.967526) (xy 117.687852 -384.960368)
			(xy 117.666022 -384.934674) (xy 117.627928 -384.879045) (xy 117.596773 -384.819253) (xy 117.573005 -384.75616)
			(xy 117.556965 -384.690674) (xy 117.548886 -384.623738) (xy 117.548882 -384.556316) (xy 117.556955 -384.489379)
			(xy 117.572989 -384.423892) (xy 117.596751 -384.360796) (xy 117.627901 -384.301001) (xy 117.665988 -384.245368)
			(xy 117.687852 -384.219704) (xy 117.693636 -384.21255) (xy 117.700157 -384.195366) (xy 117.700552 -384.186176)
			(xy 117.700552 -383.693924) (xy 117.700119 -383.684739) (xy 117.69362 -383.667555) (xy 117.687852 -383.660396)
			(xy 117.665951 -383.634761) (xy 117.62786 -383.579123) (xy 117.596708 -383.519323) (xy 117.572943 -383.456222)
			(xy 117.556909 -383.390729) (xy 117.548835 -383.323787) (xy 116.446764 -383.323787) (xy 116.446975 -383.324349)
			(xy 116.462948 -383.389733) (xy 116.470992 -383.456558) (xy 116.47099 -383.523866) (xy 116.462944 -383.59069)
			(xy 116.446967 -383.656074) (xy 116.423291 -383.719079) (xy 116.392252 -383.778803) (xy 116.354298 -383.834389)
			(xy 116.332508 -383.86004) (xy 116.326713 -383.867186) (xy 116.320197 -383.884376) (xy 116.319808 -383.893568)
			(xy 116.319808 -384.051556) (xy 116.319342 -384.061706) (xy 116.311563 -384.080456) (xy 116.297179 -384.094781)
			(xy 116.278398 -384.102483) (xy 116.268246 -384.102864) (xy 115.551966 -384.102864) (xy 115.541838 -384.102401)
			(xy 115.523116 -384.094663) (xy 115.508761 -384.08037) (xy 115.500943 -384.061682) (xy 115.500404 -384.051556)
			(xy 115.500404 -383.893568) (xy 115.500009 -383.884379) (xy 115.493485 -383.867195) (xy 115.487704 -383.86004)
			(xy 115.465933 -383.834374) (xy 115.427986 -383.778789) (xy 115.396954 -383.719067) (xy 115.373282 -383.656064)
			(xy 115.357309 -383.590684) (xy 115.349264 -383.523864) (xy 115.349262 -383.45656) (xy 115.357305 -383.38974)
			(xy 115.373275 -383.324359) (xy 115.396944 -383.261355) (xy 115.427974 -383.201632) (xy 115.465918 -383.146045)
			(xy 115.487704 -383.120392) (xy 115.493487 -383.113237) (xy 115.50001 -383.096054) (xy 115.500404 -383.086864)
			(xy 115.500404 -382.593342) (xy 115.499973 -382.584157) (xy 115.493474 -382.566973) (xy 115.487704 -382.559814)
			(xy 115.465908 -382.534169) (xy 115.427961 -382.478581) (xy 115.39693 -382.418856) (xy 115.37326 -382.355851)
			(xy 115.357288 -382.290468) (xy 115.349246 -382.223645) (xy 90.070711 -382.223645) (xy 90.062667 -382.290467)
			(xy 90.046695 -382.355848) (xy 90.023023 -382.418852) (xy 89.991991 -382.478576) (xy 89.954043 -382.534162)
			(xy 89.932256 -382.559814) (xy 89.926465 -382.566963) (xy 89.919948 -382.584151) (xy 89.919556 -382.593342)
			(xy 89.919556 -383.086864) (xy 89.919994 -383.096048) (xy 89.926489 -383.113232) (xy 89.932256 -383.120392)
			(xy 89.95406 -383.146031) (xy 89.992008 -383.201619) (xy 90.023041 -383.261345) (xy 90.046478 -383.323726)
			(xy 91.149124 -383.323726) (xy 91.149128 -383.256419) (xy 91.157175 -383.189595) (xy 91.17315 -383.124211)
			(xy 91.196825 -383.061205) (xy 91.227861 -383.001481) (xy 91.265811 -382.945893) (xy 91.2876 -382.92024)
			(xy 91.293405 -382.9131) (xy 91.299914 -382.895906) (xy 91.3003 -382.886712) (xy 91.3003 -382.728724)
			(xy 91.300741 -382.718571) (xy 91.308529 -382.699819) (xy 91.32292 -382.685495) (xy 91.341708 -382.677795)
			(xy 91.351862 -382.677416) (xy 92.068142 -382.677416) (xy 92.078268 -382.677891) (xy 92.096986 -382.685629)
			(xy 92.11134 -382.699918) (xy 92.119162 -382.7186) (xy 92.119704 -382.728724) (xy 92.119704 -382.886712)
			(xy 92.120108 -382.8959) (xy 92.126626 -382.913084) (xy 92.132404 -382.92024) (xy 92.154155 -382.945922)
			(xy 92.192102 -383.001505) (xy 92.223135 -383.061225) (xy 92.246808 -383.124225) (xy 92.262782 -383.189604)
			(xy 92.270828 -383.256422) (xy 92.270831 -383.323724) (xy 92.262791 -383.390543) (xy 92.246824 -383.455923)
			(xy 92.223157 -383.518926) (xy 92.19213 -383.578648) (xy 92.154188 -383.634235) (xy 92.132404 -383.659888)
			(xy 92.126588 -383.66702) (xy 92.120085 -383.68422) (xy 92.119704 -383.693416) (xy 92.119704 -384.186684)
			(xy 92.120121 -384.19587) (xy 92.12663 -384.213055) (xy 92.132404 -384.220212) (xy 92.154226 -384.245836)
			(xy 92.192171 -384.301427) (xy 92.2232 -384.361155) (xy 92.246869 -384.424163) (xy 92.262838 -384.489548)
			(xy 92.270879 -384.556374) (xy 92.270875 -384.623681) (xy 92.262828 -384.690505) (xy 92.246853 -384.755889)
			(xy 92.223178 -384.818894) (xy 92.192143 -384.878619) (xy 92.154193 -384.934207) (xy 92.132404 -384.95986)
			(xy 92.1266 -384.967) (xy 92.12009 -384.984194) (xy 92.119704 -384.993388) (xy 92.119704 -385.151376)
			(xy 92.119259 -385.161528) (xy 92.111472 -385.180279) (xy 92.097082 -385.194603) (xy 92.078296 -385.202305)
			(xy 92.068142 -385.202684) (xy 91.351862 -385.202684) (xy 91.341736 -385.202205) (xy 91.323018 -385.194469)
			(xy 91.308664 -385.180181) (xy 91.300842 -385.1615) (xy 91.3003 -385.151376) (xy 91.3003 -384.993388)
			(xy 91.299895 -384.9842) (xy 91.293378 -384.967016) (xy 91.2876 -384.95986) (xy 91.265849 -384.934178)
			(xy 91.227901 -384.878595) (xy 91.196869 -384.818875) (xy 91.173196 -384.755875) (xy 91.157221 -384.690497)
			(xy 91.149175 -384.623678) (xy 91.149172 -384.556376) (xy 91.157212 -384.489557) (xy 91.17318 -384.424177)
			(xy 91.196847 -384.361174) (xy 91.227874 -384.301451) (xy 91.265816 -384.245865) (xy 91.2876 -384.220212)
			(xy 91.293416 -384.213081) (xy 91.299919 -384.19588) (xy 91.3003 -384.186684) (xy 91.3003 -383.693416)
			(xy 91.299882 -383.68423) (xy 91.293374 -383.667045) (xy 91.2876 -383.659888) (xy 91.265778 -383.634264)
			(xy 91.227833 -383.578673) (xy 91.196803 -383.518945) (xy 91.173134 -383.455937) (xy 91.157165 -383.390552)
			(xy 91.149124 -383.323726) (xy 90.046478 -383.323726) (xy 90.046713 -383.324351) (xy 90.062685 -383.389735)
			(xy 90.070728 -383.456559) (xy 90.070727 -383.523865) (xy 90.062681 -383.590689) (xy 90.046706 -383.656072)
			(xy 90.023031 -383.719077) (xy 89.991996 -383.778801) (xy 89.954045 -383.834388) (xy 89.932256 -383.86004)
			(xy 89.926454 -383.867181) (xy 89.919944 -383.884375) (xy 89.919556 -383.893568) (xy 89.919556 -384.051556)
			(xy 89.919043 -384.0617) (xy 89.911273 -384.080441) (xy 89.896905 -384.094764) (xy 89.87814 -384.102475)
			(xy 89.867994 -384.102864) (xy 89.151714 -384.102864) (xy 89.141589 -384.102362) (xy 89.122869 -384.09464)
			(xy 89.108512 -384.080358) (xy 89.100692 -384.061679) (xy 89.100152 -384.051556) (xy 89.100152 -383.893568)
			(xy 89.099745 -383.884381) (xy 89.093228 -383.867197) (xy 89.087452 -383.86004) (xy 89.06568 -383.834375)
			(xy 89.02773 -383.778791) (xy 88.996695 -383.719069) (xy 88.973021 -383.656066) (xy 88.957046 -383.590685)
			(xy 88.949001 -383.523864) (xy 88.948999 -383.45656) (xy 88.957042 -383.389738) (xy 88.973014 -383.324357)
			(xy 88.996685 -383.261353) (xy 89.027717 -383.20163) (xy 89.065665 -383.146044) (xy 89.087452 -383.120392)
			(xy 89.093241 -383.113242) (xy 89.099759 -383.096055) (xy 89.100152 -383.086864) (xy 89.100152 -382.593342)
			(xy 89.09971 -382.584158) (xy 89.093217 -382.566975) (xy 89.087452 -382.559814) (xy 89.065654 -382.53417)
			(xy 89.027704 -382.478583) (xy 88.996671 -382.418858) (xy 88.972998 -382.355853) (xy 88.957025 -382.290469)
			(xy 88.948982 -382.223646) (xy 85.670943 -382.223646) (xy 85.670943 -382.223704) (xy 85.662867 -382.290643)
			(xy 85.646832 -382.356132) (xy 85.623067 -382.419228) (xy 85.591915 -382.479024) (xy 85.553825 -382.534657)
			(xy 85.53196 -382.560322) (xy 85.526167 -382.567469) (xy 85.519651 -382.584658) (xy 85.51926 -382.59385)
			(xy 85.51926 -383.086356) (xy 85.5197 -383.09554) (xy 85.526194 -383.112724) (xy 85.53196 -383.119884)
			(xy 85.553841 -383.145536) (xy 85.591932 -383.201171) (xy 85.623084 -383.260969) (xy 85.646743 -383.323786)
			(xy 86.748805 -383.323786) (xy 86.748808 -383.25636) (xy 86.756888 -383.189419) (xy 86.772927 -383.123927)
			(xy 86.796696 -383.060829) (xy 86.827852 -383.001032) (xy 86.865945 -382.945397) (xy 86.887812 -382.919732)
			(xy 86.893621 -382.912596) (xy 86.900128 -382.895398) (xy 86.900512 -382.886204) (xy 86.900512 -382.728724)
			(xy 86.900936 -382.718602) (xy 86.908678 -382.699896) (xy 86.922993 -382.685581) (xy 86.941698 -382.677837)
			(xy 86.95182 -382.677416) (xy 87.6681 -382.677416) (xy 87.678224 -382.677816) (xy 87.696931 -382.685568)
			(xy 87.711246 -382.699889) (xy 87.718988 -382.718599) (xy 87.719408 -382.728724) (xy 87.719408 -382.886204)
			(xy 87.719815 -382.895392) (xy 87.726331 -382.912576) (xy 87.732108 -382.919732) (xy 87.753936 -382.945427)
			(xy 87.792026 -383.001057) (xy 87.823177 -383.060849) (xy 87.846943 -383.123942) (xy 87.862981 -383.189428)
			(xy 87.87106 -383.256363) (xy 87.871063 -383.323783) (xy 87.862991 -383.390719) (xy 87.846959 -383.456206)
			(xy 87.8232 -383.519301) (xy 87.792053 -383.579096) (xy 87.75397 -383.634731) (xy 87.732108 -383.660396)
			(xy 87.726332 -383.667556) (xy 87.719805 -383.684735) (xy 87.719408 -383.693924) (xy 87.719408 -384.186176)
			(xy 87.719828 -384.195362) (xy 87.726335 -384.212547) (xy 87.732108 -384.219704) (xy 87.754007 -384.24534)
			(xy 87.792094 -384.300979) (xy 87.823243 -384.360779) (xy 87.847005 -384.42388) (xy 87.863037 -384.489373)
			(xy 87.87111 -384.556314) (xy 87.871107 -384.62374) (xy 87.863028 -384.690681) (xy 87.846989 -384.756172)
			(xy 87.823221 -384.81927) (xy 87.792066 -384.879067) (xy 87.753974 -384.934703) (xy 87.732108 -384.960368)
			(xy 87.726301 -384.967506) (xy 87.719792 -384.984702) (xy 87.719408 -384.993896) (xy 87.719408 -385.151376)
			(xy 87.718965 -385.161496) (xy 87.711226 -385.180198) (xy 87.696918 -385.194512) (xy 87.67822 -385.20226)
			(xy 87.6681 -385.202684) (xy 86.95182 -385.202684) (xy 86.941697 -385.202267) (xy 86.922991 -385.194523)
			(xy 86.908675 -385.180206) (xy 86.900932 -385.161499) (xy 86.900512 -385.151376) (xy 86.900512 -384.993896)
			(xy 86.900101 -384.984709) (xy 86.893587 -384.967525) (xy 86.887812 -384.960368) (xy 86.865983 -384.934674)
			(xy 86.827892 -384.879044) (xy 86.796739 -384.819252) (xy 86.772973 -384.756158) (xy 86.756934 -384.690673)
			(xy 86.748855 -384.623738) (xy 86.748852 -384.556316) (xy 86.756925 -384.48938) (xy 86.772957 -384.423893)
			(xy 86.796717 -384.360798) (xy 86.827865 -384.301003) (xy 86.86595 -384.245369) (xy 86.887812 -384.219704)
			(xy 86.893591 -384.212546) (xy 86.900116 -384.195365) (xy 86.900512 -384.186176) (xy 86.900512 -383.693924)
			(xy 86.900088 -383.684738) (xy 86.893583 -383.667554) (xy 86.887812 -383.660396) (xy 86.865912 -383.63476)
			(xy 86.827824 -383.579122) (xy 86.796674 -383.519322) (xy 86.772911 -383.456221) (xy 86.756878 -383.390728)
			(xy 86.748805 -383.323786) (xy 85.646743 -383.323786) (xy 85.646849 -383.324068) (xy 85.662885 -383.389559)
			(xy 85.67096 -383.456499) (xy 85.670959 -383.523925) (xy 85.662881 -383.590865) (xy 85.646842 -383.656355)
			(xy 85.623074 -383.719453) (xy 85.59192 -383.77925) (xy 85.553826 -383.834883) (xy 85.53196 -383.860548)
			(xy 85.526156 -383.867687) (xy 85.519647 -383.884883) (xy 85.51926 -383.894076) (xy 85.51926 -384.051556)
			(xy 85.518847 -384.061681) (xy 85.511106 -384.080391) (xy 85.496787 -384.094708) (xy 85.478077 -384.102448)
			(xy 85.467952 -384.102864) (xy 84.751672 -384.102864) (xy 84.741543 -384.102506) (xy 84.722832 -384.094742)
			(xy 84.708517 -384.080407) (xy 84.70078 -384.061685) (xy 84.700364 -384.051556) (xy 84.700364 -383.894076)
			(xy 84.699951 -383.884889) (xy 84.693438 -383.867706) (xy 84.687664 -383.860548) (xy 84.665817 -383.834869)
			(xy 84.62773 -383.779236) (xy 84.596581 -383.719441) (xy 84.572817 -383.656346) (xy 84.556782 -383.590859)
			(xy 84.548705 -383.523923) (xy 84.548704 -383.456501) (xy 84.556778 -383.389565) (xy 84.57281 -383.324077)
			(xy 84.596571 -383.260981) (xy 84.627718 -383.201185) (xy 84.665802 -383.14555) (xy 84.687664 -383.119884)
			(xy 84.693458 -383.112737) (xy 84.699972 -383.095548) (xy 84.700364 -383.086356) (xy 84.700364 -382.59385)
			(xy 84.699916 -382.584667) (xy 84.693427 -382.567483) (xy 84.687664 -382.560322) (xy 84.665791 -382.534664)
			(xy 84.627705 -382.479028) (xy 84.596557 -382.41923) (xy 84.572795 -382.356132) (xy 84.556761 -382.290643)
			(xy 84.548687 -382.223704) (xy 81.271152 -382.223704) (xy 81.263076 -382.290642) (xy 81.247041 -382.356131)
			(xy 81.223277 -382.419228) (xy 81.192126 -382.479023) (xy 81.154036 -382.534657) (xy 81.132172 -382.560322)
			(xy 81.12638 -382.56747) (xy 81.119863 -382.584659) (xy 81.119472 -382.59385) (xy 81.119472 -383.086356)
			(xy 81.11991 -383.09554) (xy 81.126405 -383.112724) (xy 81.132172 -383.119884) (xy 81.154053 -383.145536)
			(xy 81.192143 -383.201172) (xy 81.223294 -383.260969) (xy 81.246931 -383.323727) (xy 82.349036 -383.323727)
			(xy 82.34904 -383.256419) (xy 82.357087 -383.189595) (xy 82.373063 -383.124211) (xy 82.396739 -383.061205)
			(xy 82.427775 -383.00148) (xy 82.465727 -382.945892) (xy 82.487516 -382.92024) (xy 82.493322 -382.913102)
			(xy 82.499831 -382.895906) (xy 82.500216 -382.886712) (xy 82.500216 -382.728724) (xy 82.500636 -382.718601)
			(xy 82.508379 -382.699895) (xy 82.522695 -382.685579) (xy 82.541401 -382.677836) (xy 82.551524 -382.677416)
			(xy 83.268058 -382.677416) (xy 83.278179 -382.67796) (xy 83.296895 -382.68567) (xy 83.311252 -382.699938)
			(xy 83.319076 -382.718606) (xy 83.31962 -382.728724) (xy 83.31962 -382.886712) (xy 83.32002 -382.8959)
			(xy 83.32654 -382.913085) (xy 83.33232 -382.92024) (xy 83.354074 -382.945921) (xy 83.392026 -383.001502)
			(xy 83.423063 -383.061221) (xy 83.44674 -383.124222) (xy 83.462717 -383.189601) (xy 83.470764 -383.256421)
			(xy 83.470767 -383.323724) (xy 83.462726 -383.390545) (xy 83.446756 -383.455926) (xy 83.423085 -383.518929)
			(xy 83.392054 -383.578651) (xy 83.354107 -383.634236) (xy 83.33232 -383.659888) (xy 83.326506 -383.667021)
			(xy 83.320001 -383.684221) (xy 83.31962 -383.693416) (xy 83.31962 -384.186684) (xy 83.320033 -384.195871)
			(xy 83.326544 -384.213056) (xy 83.33232 -384.220212) (xy 83.354144 -384.245835) (xy 83.392095 -384.301424)
			(xy 83.423129 -384.361152) (xy 83.446801 -384.42416) (xy 83.462773 -384.489546) (xy 83.470815 -384.556373)
			(xy 83.470812 -384.623681) (xy 83.462763 -384.690507) (xy 83.446785 -384.755892) (xy 83.423107 -384.818898)
			(xy 83.392067 -384.878622) (xy 83.354111 -384.934208) (xy 83.33232 -384.95986) (xy 83.326518 -384.967001)
			(xy 83.320006 -384.984195) (xy 83.31962 -384.993388) (xy 83.31962 -385.151376) (xy 83.319165 -385.161494)
			(xy 83.311428 -385.180194) (xy 83.297124 -385.194508) (xy 83.27843 -385.202258) (xy 83.268312 -385.202684)
			(xy 82.551778 -385.202684) (xy 82.541653 -385.202192) (xy 82.522936 -385.194462) (xy 82.508581 -385.180178)
			(xy 82.500758 -385.161499) (xy 82.500216 -385.151376) (xy 82.500216 -384.993388) (xy 82.499808 -384.984201)
			(xy 82.493293 -384.967016) (xy 82.487516 -384.95986) (xy 82.465765 -384.934178) (xy 82.427816 -384.878595)
			(xy 82.396783 -384.818876) (xy 82.373109 -384.755875) (xy 82.357134 -384.690497) (xy 82.349088 -384.623678)
			(xy 82.349084 -384.556376) (xy 82.357125 -384.489556) (xy 82.373093 -384.424177) (xy 82.396761 -384.361174)
			(xy 82.427788 -384.301451) (xy 82.465731 -384.245865) (xy 82.487516 -384.220212) (xy 82.493334 -384.213082)
			(xy 82.499835 -384.19588) (xy 82.500216 -384.186684) (xy 82.500216 -383.693416) (xy 82.499794 -383.68423)
			(xy 82.493288 -383.667046) (xy 82.487516 -383.659888) (xy 82.465694 -383.634265) (xy 82.427747 -383.578674)
			(xy 82.396717 -383.518946) (xy 82.373047 -383.455938) (xy 82.357077 -383.390552) (xy 82.349036 -383.323727)
			(xy 81.246931 -383.323727) (xy 81.247059 -383.324068) (xy 81.263094 -383.389559) (xy 81.271169 -383.456499)
			(xy 81.271168 -383.523925) (xy 81.26309 -383.590865) (xy 81.247052 -383.656355) (xy 81.223285 -383.719453)
			(xy 81.19213 -383.779249) (xy 81.154038 -383.834883) (xy 81.132172 -383.860548) (xy 81.126369 -383.867688)
			(xy 81.119859 -383.884883) (xy 81.119472 -383.894076) (xy 81.119472 -384.051556) (xy 81.119047 -384.061679)
			(xy 81.111308 -384.080387) (xy 81.096994 -384.094704) (xy 81.078287 -384.102446) (xy 81.068164 -384.102864)
			(xy 80.351884 -384.102864) (xy 80.341756 -384.102496) (xy 80.323045 -384.094736) (xy 80.30873 -384.080405)
			(xy 80.300992 -384.061685) (xy 80.300576 -384.051556) (xy 80.300576 -383.894076) (xy 80.300183 -383.884887)
			(xy 80.293658 -383.867703) (xy 80.287876 -383.860548) (xy 80.266029 -383.834869) (xy 80.227941 -383.779236)
			(xy 80.196791 -383.719442) (xy 80.173027 -383.656347) (xy 80.156991 -383.590859) (xy 80.148914 -383.523923)
			(xy 80.148913 -383.456501) (xy 80.156987 -383.389564) (xy 80.17302 -383.324076) (xy 80.196781 -383.26098)
			(xy 80.227929 -383.201184) (xy 80.266014 -383.14555) (xy 80.287876 -383.119884) (xy 80.293659 -383.112729)
			(xy 80.300183 -383.095546) (xy 80.300576 -383.086356) (xy 80.300576 -382.59385) (xy 80.300147 -382.584665)
			(xy 80.293647 -382.56748) (xy 80.287876 -382.560322) (xy 80.266003 -382.534664) (xy 80.227916 -382.479028)
			(xy 80.196767 -382.419231) (xy 80.173005 -382.356133) (xy 80.156971 -382.290643) (xy 80.148896 -382.223704)
			(xy 76.870825 -382.223704) (xy 76.862789 -382.290466) (xy 76.846818 -382.355847) (xy 76.823147 -382.418851)
			(xy 76.792117 -382.478575) (xy 76.75417 -382.534162) (xy 76.732384 -382.559814) (xy 76.726597 -382.566966)
			(xy 76.720077 -382.584151) (xy 76.719684 -382.593342) (xy 76.719684 -383.086864) (xy 76.720115 -383.096049)
			(xy 76.726615 -383.113233) (xy 76.732384 -383.120392) (xy 76.754187 -383.146031) (xy 76.792134 -383.20162)
			(xy 76.823165 -383.261346) (xy 76.846624 -383.323787) (xy 77.948717 -383.323787) (xy 77.94872 -383.256359)
			(xy 77.9568 -383.189418) (xy 77.97284 -383.123927) (xy 77.99661 -383.060828) (xy 78.027766 -383.001031)
			(xy 78.065861 -382.945397) (xy 78.087728 -382.919732) (xy 78.09354 -382.912598) (xy 78.100045 -382.895399)
			(xy 78.100428 -382.886204) (xy 78.100428 -382.728724) (xy 78.100836 -382.7186) (xy 78.108582 -382.699891)
			(xy 78.122901 -382.685575) (xy 78.141611 -382.677834) (xy 78.151736 -382.677416) (xy 78.868016 -382.677416)
			(xy 78.878142 -382.677803) (xy 78.896849 -382.685559) (xy 78.911163 -382.699885) (xy 78.918905 -382.718598)
			(xy 78.919324 -382.728724) (xy 78.919324 -382.886204) (xy 78.919727 -382.895392) (xy 78.926245 -382.912577)
			(xy 78.932024 -382.919732) (xy 78.953852 -382.945427) (xy 78.99194 -383.001058) (xy 79.023091 -383.06085)
			(xy 79.046856 -383.123943) (xy 79.062893 -383.189428) (xy 79.070972 -383.256363) (xy 79.070975 -383.323783)
			(xy 79.062903 -383.390719) (xy 79.046872 -383.456205) (xy 79.023113 -383.519301) (xy 78.991968 -383.579096)
			(xy 78.953885 -383.63473) (xy 78.932024 -383.660396) (xy 78.926249 -383.667557) (xy 78.919721 -383.684735)
			(xy 78.919324 -383.693924) (xy 78.919324 -384.186176) (xy 78.91974 -384.195363) (xy 78.926249 -384.212547)
			(xy 78.932024 -384.219704) (xy 78.953922 -384.24534) (xy 78.992009 -384.30098) (xy 79.023156 -384.36078)
			(xy 79.046917 -384.423881) (xy 79.06295 -384.489373) (xy 79.071022 -384.556314) (xy 79.071019 -384.62374)
			(xy 79.06294 -384.69068) (xy 79.046901 -384.756171) (xy 79.023134 -384.819269) (xy 78.991981 -384.879067)
			(xy 78.953889 -384.934702) (xy 78.932024 -384.960368) (xy 78.926219 -384.967507) (xy 78.919709 -384.984702)
			(xy 78.919324 -384.993896) (xy 78.919324 -385.151376) (xy 78.918865 -385.161494) (xy 78.911129 -385.180193)
			(xy 78.896826 -385.194507) (xy 78.878134 -385.202257) (xy 78.868016 -385.202684) (xy 78.151736 -385.202684)
			(xy 78.141614 -385.202254) (xy 78.122908 -385.194515) (xy 78.108592 -385.180202) (xy 78.100848 -385.161498)
			(xy 78.100428 -385.151376) (xy 78.100428 -384.993896) (xy 78.100014 -384.984709) (xy 78.093502 -384.967525)
			(xy 78.087728 -384.960368) (xy 78.065898 -384.934674) (xy 78.027807 -384.879044) (xy 77.996653 -384.819252)
			(xy 77.972886 -384.756159) (xy 77.956847 -384.690673) (xy 77.948768 -384.623738) (xy 77.948764 -384.556316)
			(xy 77.956837 -384.48938) (xy 77.972869 -384.423893) (xy 77.996631 -384.360797) (xy 78.027779 -384.301002)
			(xy 78.065865 -384.245369) (xy 78.087728 -384.219704) (xy 78.093509 -384.212548) (xy 78.100032 -384.195366)
			(xy 78.100428 -384.186176) (xy 78.100428 -383.693924) (xy 78.1 -383.684739) (xy 78.093498 -383.667555)
			(xy 78.087728 -383.660396) (xy 78.065828 -383.63476) (xy 78.027738 -383.579122) (xy 77.996587 -383.519322)
			(xy 77.972824 -383.456221) (xy 77.95679 -383.390728) (xy 77.948717 -383.323787) (xy 76.846624 -383.323787)
			(xy 76.846836 -383.324352) (xy 76.862807 -383.389735) (xy 76.870849 -383.456559) (xy 76.870848 -383.523865)
			(xy 76.862803 -383.590688) (xy 76.846829 -383.656071) (xy 76.823155 -383.719076) (xy 76.792121 -383.7788)
			(xy 76.754172 -383.834388) (xy 76.732384 -383.86004) (xy 76.726586 -383.867184) (xy 76.720073 -383.884376)
			(xy 76.719684 -383.893568) (xy 76.719684 -384.051556) (xy 76.719242 -384.061709) (xy 76.711458 -384.080464)
			(xy 76.697067 -384.094789) (xy 76.678277 -384.102488) (xy 76.668122 -384.102864) (xy 75.951842 -384.102864)
			(xy 75.941718 -384.102339) (xy 75.922999 -384.094626) (xy 75.908642 -384.080351) (xy 75.90082 -384.061677)
			(xy 75.90028 -384.051556) (xy 75.90028 -383.893568) (xy 75.89989 -383.884379) (xy 75.893363 -383.867194)
			(xy 75.88758 -383.86004) (xy 75.865807 -383.834375) (xy 75.827855 -383.778792) (xy 75.796819 -383.71907)
			(xy 75.773143 -383.656067) (xy 75.757168 -383.590686) (xy 75.749122 -383.523864) (xy 75.74912 -383.45656)
			(xy 75.757164 -383.389738) (xy 75.773136 -383.324356) (xy 75.796809 -383.261352) (xy 75.827842 -383.201629)
			(xy 75.865792 -383.146044) (xy 75.88758 -383.120392) (xy 75.89336 -383.113235) (xy 75.899885 -383.096054)
			(xy 75.90028 -383.086864) (xy 75.90028 -382.593342) (xy 75.899854 -382.584156) (xy 75.893352 -382.566972)
			(xy 75.88758 -382.559814) (xy 75.865781 -382.53417) (xy 75.82783 -382.478584) (xy 75.796795 -382.418859)
			(xy 75.773121 -382.355854) (xy 75.757147 -382.29047) (xy 75.749104 -382.223646) (xy 72.471064 -382.223646)
			(xy 72.471064 -382.223704) (xy 72.462989 -382.290642) (xy 72.446954 -382.356131) (xy 72.42319 -382.419227)
			(xy 72.39204 -382.479023) (xy 72.353952 -382.534657) (xy 72.332088 -382.560322) (xy 72.326298 -382.567472)
			(xy 72.31978 -382.584659) (xy 72.319388 -382.59385) (xy 72.319388 -383.086356) (xy 72.319822 -383.095541)
			(xy 72.326319 -383.112725) (xy 72.332088 -383.119884) (xy 72.353968 -383.145536) (xy 72.392057 -383.201172)
			(xy 72.423208 -383.26097) (xy 72.446843 -383.323727) (xy 73.548949 -383.323727) (xy 73.548952 -383.256419)
			(xy 73.556999 -383.189594) (xy 73.572976 -383.12421) (xy 73.596652 -383.061204) (xy 73.62769 -383.001479)
			(xy 73.665642 -382.945892) (xy 73.687432 -382.92024) (xy 73.693241 -382.913103) (xy 73.699747 -382.895906)
			(xy 73.700132 -382.886712) (xy 73.700132 -382.728724) (xy 73.700542 -382.718567) (xy 73.708335 -382.699809)
			(xy 73.722736 -382.685484) (xy 73.741535 -382.677789) (xy 73.751694 -382.677416) (xy 74.467974 -382.677416)
			(xy 74.478096 -382.677947) (xy 74.496812 -382.685662) (xy 74.511169 -382.699934) (xy 74.518993 -382.718605)
			(xy 74.519536 -382.728724) (xy 74.519536 -382.886712) (xy 74.519955 -382.895898) (xy 74.526464 -382.913082)
			(xy 74.532236 -382.92024) (xy 74.553989 -382.945921) (xy 74.591941 -383.001503) (xy 74.622977 -383.061222)
			(xy 74.646653 -383.124223) (xy 74.662629 -383.189602) (xy 74.670676 -383.256422) (xy 74.670679 -383.323724)
			(xy 74.662639 -383.390545) (xy 74.646669 -383.455925) (xy 74.622999 -383.518928) (xy 74.591968 -383.578651)
			(xy 74.554022 -383.634236) (xy 74.532236 -383.659888) (xy 74.526412 -383.667013) (xy 74.519915 -383.684219)
			(xy 74.519536 -383.693416) (xy 74.519536 -384.186684) (xy 74.519968 -384.195869) (xy 74.526468 -384.213052)
			(xy 74.532236 -384.220212) (xy 74.55406 -384.245835) (xy 74.592009 -384.301425) (xy 74.623043 -384.361152)
			(xy 74.646714 -384.424161) (xy 74.662686 -384.489547) (xy 74.670727 -384.556373) (xy 74.670724 -384.623681)
			(xy 74.662676 -384.690507) (xy 74.646698 -384.755891) (xy 74.623021 -384.818897) (xy 74.591982 -384.878622)
			(xy 74.554027 -384.934208) (xy 74.532236 -384.95986) (xy 74.526424 -384.966994) (xy 74.51992 -384.984193)
			(xy 74.519536 -384.993388) (xy 74.519536 -385.151376) (xy 74.51906 -385.161524) (xy 74.511279 -385.180269)
			(xy 74.496899 -385.194592) (xy 74.478124 -385.202299) (xy 74.467974 -385.202684) (xy 73.751694 -385.202684)
			(xy 73.74157 -385.202179) (xy 73.722853 -385.194454) (xy 73.708498 -385.180173) (xy 73.700675 -385.161497)
			(xy 73.700132 -385.151376) (xy 73.700132 -384.993388) (xy 73.699721 -384.984201) (xy 73.693207 -384.967017)
			(xy 73.687432 -384.95986) (xy 73.66568 -384.934178) (xy 73.627731 -384.878596) (xy 73.596696 -384.818877)
			(xy 73.573022 -384.755876) (xy 73.557047 -384.690497) (xy 73.549 -384.623678) (xy 73.548996 -384.556376)
			(xy 73.557037 -384.489556) (xy 73.573006 -384.424176) (xy 73.596674 -384.361173) (xy 73.627703 -384.30145)
			(xy 73.665647 -384.245864) (xy 73.687432 -384.220212) (xy 73.693253 -384.213084) (xy 73.699752 -384.19588)
			(xy 73.700132 -384.186684) (xy 73.700132 -383.693416) (xy 73.699707 -383.684231) (xy 73.693203 -383.667046)
			(xy 73.687432 -383.659888) (xy 73.665609 -383.634265) (xy 73.627662 -383.578674) (xy 73.59663 -383.518946)
			(xy 73.57296 -383.455938) (xy 73.55699 -383.390553) (xy 73.548949 -383.323727) (xy 72.446843 -383.323727)
			(xy 72.446972 -383.324069) (xy 72.463006 -383.38956) (xy 72.471081 -383.456499) (xy 72.47108 -383.523925)
			(xy 72.463002 -383.590864) (xy 72.446964 -383.656354) (xy 72.423198 -383.719452) (xy 72.392045 -383.779248)
			(xy 72.353953 -383.834883) (xy 72.332088 -383.860548) (xy 72.326287 -383.86769) (xy 72.319775 -383.884883)
			(xy 72.319388 -383.894076) (xy 72.319388 -384.051556) (xy 72.318948 -384.061677) (xy 72.311212 -384.080382)
			(xy 72.296902 -384.094698) (xy 72.278201 -384.102443) (xy 72.26808 -384.102864) (xy 71.5518 -384.102864)
			(xy 71.541673 -384.102483) (xy 71.522963 -384.094728) (xy 71.508647 -384.0804) (xy 71.500908 -384.061683)
			(xy 71.500492 -384.051556) (xy 71.500492 -383.894076) (xy 71.500095 -383.884887) (xy 71.493572 -383.867703)
			(xy 71.487792 -383.860548) (xy 71.465944 -383.83487) (xy 71.427855 -383.779237) (xy 71.396704 -383.719442)
			(xy 71.37294 -383.656347) (xy 71.356903 -383.59086) (xy 71.348826 -383.523923) (xy 71.348825 -383.456501)
			(xy 71.356899 -383.389564) (xy 71.372933 -383.324076) (xy 71.396695 -383.26098) (xy 71.427843 -383.201184)
			(xy 71.465929 -383.145549) (xy 71.487792 -383.119884) (xy 71.493577 -383.11273) (xy 71.500099 -383.095546)
			(xy 71.500492 -383.086356) (xy 71.500492 -382.59385) (xy 71.50006 -382.584665) (xy 71.493562 -382.56748)
			(xy 71.487792 -382.560322) (xy 71.465918 -382.534665) (xy 71.427831 -382.479029) (xy 71.396681 -382.419231)
			(xy 71.372918 -382.356134) (xy 71.356883 -382.290644) (xy 71.348808 -382.223705) (xy 46.070794 -382.223705)
			(xy 46.062758 -382.290467) (xy 46.046786 -382.355849) (xy 46.023113 -382.418853) (xy 45.99208 -382.478576)
			(xy 45.954131 -382.534162) (xy 45.932344 -382.559814) (xy 45.926552 -382.566962) (xy 45.920036 -382.584151)
			(xy 45.919644 -382.593342) (xy 45.919644 -383.086864) (xy 45.920084 -383.096048) (xy 45.926578 -383.113232)
			(xy 45.932344 -383.120392) (xy 45.954148 -383.146031) (xy 45.992098 -383.201619) (xy 46.023131 -383.261344)
			(xy 46.04657 -383.323727) (xy 47.149191 -383.323727) (xy 47.149195 -383.256419) (xy 47.157243 -383.189593)
			(xy 47.173221 -383.124208) (xy 47.1969 -383.061202) (xy 47.22794 -383.001477) (xy 47.265897 -382.945892)
			(xy 47.287688 -382.92024) (xy 47.293491 -382.913099) (xy 47.300002 -382.895905) (xy 47.300388 -382.886712)
			(xy 47.300388 -382.728724) (xy 47.300841 -382.718573) (xy 47.308626 -382.699823) (xy 47.323013 -382.685499)
			(xy 47.341797 -382.677797) (xy 47.35195 -382.677416) (xy 48.06823 -382.677416) (xy 48.078356 -382.677901)
			(xy 48.097073 -382.685634) (xy 48.111427 -382.699921) (xy 48.11925 -382.718601) (xy 48.119792 -382.728724)
			(xy 48.119792 -382.886712) (xy 48.120198 -382.8959) (xy 48.126715 -382.913084) (xy 48.132492 -382.92024)
			(xy 48.154243 -382.945922) (xy 48.192191 -383.001505) (xy 48.223224 -383.061224) (xy 48.246898 -383.124225)
			(xy 48.262872 -383.189603) (xy 48.270919 -383.256422) (xy 48.270922 -383.323724) (xy 48.262882 -383.390543)
			(xy 48.246914 -383.455923) (xy 48.223247 -383.518926) (xy 48.192219 -383.578649) (xy 48.154277 -383.634236)
			(xy 48.132492 -383.659888) (xy 48.126675 -383.667018) (xy 48.120173 -383.68422) (xy 48.119792 -383.693416)
			(xy 48.119792 -384.186684) (xy 48.120212 -384.19587) (xy 48.126719 -384.213054) (xy 48.132492 -384.220212)
			(xy 48.154314 -384.245835) (xy 48.19226 -384.301427) (xy 48.22329 -384.361155) (xy 48.246959 -384.424163)
			(xy 48.262929 -384.489548) (xy 48.27097 -384.556373) (xy 48.270966 -384.623681) (xy 48.262919 -384.690505)
			(xy 48.246943 -384.755889) (xy 48.223268 -384.818895) (xy 48.192232 -384.87862) (xy 48.154281 -384.934207)
			(xy 48.132492 -384.95986) (xy 48.126687 -384.966999) (xy 48.120177 -384.984194) (xy 48.119792 -384.993388)
			(xy 48.119792 -385.151376) (xy 48.119359 -385.16153) (xy 48.11157 -385.180283) (xy 48.097176 -385.194608)
			(xy 48.078386 -385.202307) (xy 48.06823 -385.202684) (xy 47.35195 -385.202684) (xy 47.341829 -385.202133)
			(xy 47.323114 -385.194426) (xy 47.308757 -385.18016) (xy 47.300932 -385.161493) (xy 47.300388 -385.151376)
			(xy 47.300388 -384.993388) (xy 47.299986 -384.9842) (xy 47.293467 -384.967016) (xy 47.287688 -384.95986)
			(xy 47.265934 -384.934179) (xy 47.227981 -384.878598) (xy 47.196944 -384.818879) (xy 47.173267 -384.755878)
			(xy 47.15729 -384.690499) (xy 47.149242 -384.623679) (xy 47.149239 -384.556376) (xy 47.15728 -384.489554)
			(xy 47.173251 -384.424174) (xy 47.196921 -384.361171) (xy 47.227953 -384.301448) (xy 47.265901 -384.245863)
			(xy 47.287688 -384.220212) (xy 47.293503 -384.21308) (xy 47.300007 -384.195879) (xy 47.300388 -384.186684)
			(xy 47.300388 -383.693416) (xy 47.299973 -383.684229) (xy 47.293463 -383.667045) (xy 47.287688 -383.659888)
			(xy 47.265863 -383.634266) (xy 47.227913 -383.578676) (xy 47.196878 -383.518949) (xy 47.173205 -383.45594)
			(xy 47.157233 -383.390554) (xy 47.149191 -383.323727) (xy 46.04657 -383.323727) (xy 46.046804 -383.32435)
			(xy 46.062776 -383.389734) (xy 46.070819 -383.456559) (xy 46.070818 -383.523865) (xy 46.062772 -383.590689)
			(xy 46.046797 -383.656073) (xy 46.023121 -383.719078) (xy 45.992085 -383.778802) (xy 45.954133 -383.834388)
			(xy 45.932344 -383.86004) (xy 45.926541 -383.86718) (xy 45.920032 -383.884375) (xy 45.919644 -383.893568)
			(xy 45.919644 -384.051556) (xy 45.919143 -384.061702) (xy 45.91137 -384.080445) (xy 45.896998 -384.094768)
			(xy 45.878229 -384.102477) (xy 45.868082 -384.102864) (xy 45.151802 -384.102864) (xy 45.141676 -384.102372)
			(xy 45.122956 -384.094645) (xy 45.108599 -384.080361) (xy 45.100779 -384.06168) (xy 45.10024 -384.051556)
			(xy 45.10024 -383.893568) (xy 45.099836 -383.88438) (xy 45.093317 -383.867197) (xy 45.08754 -383.86004)
			(xy 45.065768 -383.834375) (xy 45.027819 -383.77879) (xy 44.996785 -383.719068) (xy 44.973111 -383.656066)
			(xy 44.957137 -383.590685) (xy 44.949092 -383.523864) (xy 44.94909 -383.45656) (xy 44.957133 -383.389739)
			(xy 44.973104 -383.324357) (xy 44.996775 -383.261354) (xy 45.027806 -383.20163) (xy 45.065753 -383.146044)
			(xy 45.08754 -383.120392) (xy 45.093328 -383.113241) (xy 45.099847 -383.096055) (xy 45.10024 -383.086864)
			(xy 45.10024 -382.593342) (xy 45.0998 -382.584158) (xy 45.093306 -382.566974) (xy 45.08754 -382.559814)
			(xy 45.065742 -382.53417) (xy 45.027794 -382.478582) (xy 44.996761 -382.418858) (xy 44.973088 -382.355852)
			(xy 44.957116 -382.290469) (xy 44.949073 -382.223645) (xy 41.671034 -382.223645) (xy 41.671034 -382.223704)
			(xy 41.662958 -382.290643) (xy 41.646922 -382.356132) (xy 41.623157 -382.419229) (xy 41.592004 -382.479024)
			(xy 41.553913 -382.534658) (xy 41.532048 -382.560322) (xy 41.526253 -382.567468) (xy 41.519739 -382.584658)
			(xy 41.519348 -382.59385) (xy 41.519348 -383.086356) (xy 41.519791 -383.095539) (xy 41.526283 -383.112723)
			(xy 41.532048 -383.119884) (xy 41.55393 -383.145535) (xy 41.592021 -383.201171) (xy 41.623174 -383.260968)
			(xy 41.646834 -383.323786) (xy 42.748896 -383.323786) (xy 42.748899 -383.25636) (xy 42.756978 -383.189419)
			(xy 42.773018 -383.123928) (xy 42.796786 -383.06083) (xy 42.827941 -383.001032) (xy 42.866034 -382.945397)
			(xy 42.8879 -382.919732) (xy 42.893708 -382.912595) (xy 42.900216 -382.895398) (xy 42.9006 -382.886204)
			(xy 42.9006 -382.728724) (xy 42.901035 -382.718603) (xy 42.908776 -382.6999) (xy 42.923086 -382.685585)
			(xy 42.941787 -382.677839) (xy 42.951908 -382.677416) (xy 43.668188 -382.677416) (xy 43.678312 -382.677826)
			(xy 43.697018 -382.685573) (xy 43.711333 -382.699892) (xy 43.719076 -382.7186) (xy 43.719496 -382.728724)
			(xy 43.719496 -382.886204) (xy 43.719905 -382.895391) (xy 43.72642 -382.912575) (xy 43.732196 -382.919732)
			(xy 43.754025 -382.945426) (xy 43.792115 -383.001057) (xy 43.823267 -383.060849) (xy 43.847034 -383.123942)
			(xy 43.863072 -383.189427) (xy 43.871151 -383.256363) (xy 43.871154 -383.323783) (xy 43.863081 -383.390719)
			(xy 43.84705 -383.456206) (xy 43.823289 -383.519302) (xy 43.792143 -383.579097) (xy 43.754058 -383.634731)
			(xy 43.732196 -383.660396) (xy 43.726418 -383.667554) (xy 43.719892 -383.684735) (xy 43.719496 -383.693924)
			(xy 43.719496 -384.186176) (xy 43.719919 -384.195362) (xy 43.726424 -384.212546) (xy 43.732196 -384.219704)
			(xy 43.754095 -384.24534) (xy 43.792183 -384.300979) (xy 43.823333 -384.360779) (xy 43.847095 -384.42388)
			(xy 43.863128 -384.489372) (xy 43.871201 -384.556314) (xy 43.871198 -384.62374) (xy 43.863118 -384.690681)
			(xy 43.847079 -384.756172) (xy 43.823311 -384.819271) (xy 43.792156 -384.879068) (xy 43.754062 -384.934703)
			(xy 43.732196 -384.960368) (xy 43.726388 -384.967505) (xy 43.71988 -384.984702) (xy 43.719496 -384.993896)
			(xy 43.719496 -385.151376) (xy 43.719064 -385.161497) (xy 43.711323 -385.180201) (xy 43.697011 -385.194517)
			(xy 43.678309 -385.202262) (xy 43.668188 -385.202684) (xy 42.951908 -385.202684) (xy 42.941784 -385.202277)
			(xy 42.923078 -385.194529) (xy 42.908762 -385.180209) (xy 42.90102 -385.1615) (xy 42.9006 -385.151376)
			(xy 42.9006 -384.993896) (xy 42.900192 -384.984709) (xy 42.893677 -384.967524) (xy 42.8879 -384.960368)
			(xy 42.866071 -384.934674) (xy 42.827982 -384.879043) (xy 42.796829 -384.819251) (xy 42.773063 -384.756158)
			(xy 42.757025 -384.690672) (xy 42.748946 -384.623737) (xy 42.748943 -384.556317) (xy 42.757015 -384.489381)
			(xy 42.773047 -384.423894) (xy 42.796807 -384.360798) (xy 42.827954 -384.301003) (xy 42.866038 -384.245369)
			(xy 42.8879 -384.219704) (xy 42.893677 -384.212545) (xy 42.900204 -384.195365) (xy 42.9006 -384.186176)
			(xy 42.9006 -383.693924) (xy 42.900178 -383.684738) (xy 42.893673 -383.667554) (xy 42.8879 -383.660396)
			(xy 42.866001 -383.63476) (xy 42.827913 -383.579121) (xy 42.796764 -383.519321) (xy 42.773002 -383.45622)
			(xy 42.756969 -383.390728) (xy 42.748896 -383.323786) (xy 41.646834 -383.323786) (xy 41.64694 -383.324067)
			(xy 41.662976 -383.389558) (xy 41.671051 -383.456499) (xy 41.67105 -383.523925) (xy 41.662971 -383.590865)
			(xy 41.646933 -383.656356) (xy 41.623164 -383.719454) (xy 41.592009 -383.77925) (xy 41.553915 -383.834884)
			(xy 41.532048 -383.860548) (xy 41.526242 -383.867686) (xy 41.519734 -383.884882) (xy 41.519348 -383.894076)
			(xy 41.519348 -384.051556) (xy 41.518849 -384.06167) (xy 41.511124 -384.080363) (xy 41.496834 -384.094677)
			(xy 41.478153 -384.102432) (xy 41.46804 -384.102864) (xy 40.75176 -384.102864) (xy 40.74163 -384.102516)
			(xy 40.722919 -384.094748) (xy 40.708605 -384.08041) (xy 40.700868 -384.061686) (xy 40.700452 -384.051556)
			(xy 40.700452 -383.894076) (xy 40.700042 -383.884889) (xy 40.693527 -383.867705) (xy 40.687752 -383.860548)
			(xy 40.665902 -383.834871) (xy 40.627809 -383.779239) (xy 40.596655 -383.719445) (xy 40.572888 -383.65635)
			(xy 40.556849 -383.590862) (xy 40.548772 -383.523924) (xy 40.54877 -383.4565) (xy 40.556845 -383.389562)
			(xy 40.572881 -383.324073) (xy 40.596645 -383.260977) (xy 40.627797 -383.201182) (xy 40.665887 -383.145548)
			(xy 40.687752 -383.119884) (xy 40.693544 -383.112736) (xy 40.70006 -383.095547) (xy 40.700452 -383.086356)
			(xy 40.700452 -382.59385) (xy 40.700006 -382.584667) (xy 40.693516 -382.567483) (xy 40.687752 -382.560322)
			(xy 40.665876 -382.534666) (xy 40.627785 -382.479031) (xy 40.596631 -382.419234) (xy 40.572865 -382.356136)
			(xy 40.556829 -382.290645) (xy 40.548753 -382.223705) (xy 37.271243 -382.223705) (xy 37.263167 -382.290643)
			(xy 37.247132 -382.356132) (xy 37.223367 -382.419228) (xy 37.192215 -382.479024) (xy 37.154125 -382.534657)
			(xy 37.13226 -382.560322) (xy 37.126467 -382.567469) (xy 37.119951 -382.584658) (xy 37.11956 -382.59385)
			(xy 37.11956 -383.086356) (xy 37.12 -383.09554) (xy 37.126494 -383.112724) (xy 37.13226 -383.119884)
			(xy 37.154141 -383.145536) (xy 37.192232 -383.201171) (xy 37.223384 -383.260969) (xy 37.247021 -383.323727)
			(xy 38.349127 -383.323727) (xy 38.349131 -383.256419) (xy 38.357178 -383.189595) (xy 38.373154 -383.124211)
			(xy 38.396829 -383.061205) (xy 38.427864 -383.00148) (xy 38.465815 -382.945893) (xy 38.487604 -382.92024)
			(xy 38.493409 -382.913101) (xy 38.499919 -382.895906) (xy 38.500304 -382.886712) (xy 38.500304 -382.728724)
			(xy 38.500741 -382.718571) (xy 38.50853 -382.699818) (xy 38.522922 -382.685494) (xy 38.541711 -382.677794)
			(xy 38.551866 -382.677416) (xy 39.268146 -382.677416) (xy 39.278273 -382.677888) (xy 39.29699 -382.685627)
			(xy 39.311344 -382.699917) (xy 39.319166 -382.7186) (xy 39.319708 -382.728724) (xy 39.319708 -382.886712)
			(xy 39.320111 -382.8959) (xy 39.326629 -382.913084) (xy 39.332408 -382.92024) (xy 39.354162 -382.945921)
			(xy 39.392115 -383.001502) (xy 39.423153 -383.061221) (xy 39.44683 -383.124222) (xy 39.462807 -383.189601)
			(xy 39.470855 -383.256421) (xy 39.470858 -383.323725) (xy 39.462817 -383.390546) (xy 39.446846 -383.455926)
			(xy 39.423175 -383.51893) (xy 39.392143 -383.578652) (xy 39.354195 -383.634237) (xy 39.332408 -383.659888)
			(xy 39.326592 -383.66702) (xy 39.320089 -383.684221) (xy 39.319708 -383.693416) (xy 39.319708 -384.186684)
			(xy 39.320124 -384.195871) (xy 39.326633 -384.213055) (xy 39.332408 -384.220212) (xy 39.354233 -384.245834)
			(xy 39.392184 -384.301424) (xy 39.423219 -384.361151) (xy 39.446892 -384.42416) (xy 39.462864 -384.489546)
			(xy 39.470906 -384.556373) (xy 39.470902 -384.623682) (xy 39.462854 -384.690507) (xy 39.446876 -384.755892)
			(xy 39.423196 -384.818898) (xy 39.392156 -384.878623) (xy 39.354199 -384.934209) (xy 39.332408 -384.95986)
			(xy 39.326604 -384.967) (xy 39.320094 -384.984195) (xy 39.319708 -384.993388) (xy 39.319708 -385.151376)
			(xy 39.319259 -385.161528) (xy 39.311473 -385.180278) (xy 39.297085 -385.194602) (xy 39.278299 -385.202304)
			(xy 39.268146 -385.202684) (xy 38.551866 -385.202684) (xy 38.54174 -385.202202) (xy 38.523023 -385.194468)
			(xy 38.508668 -385.18018) (xy 38.500846 -385.1615) (xy 38.500304 -385.151376) (xy 38.500304 -384.993388)
			(xy 38.499899 -384.9842) (xy 38.493381 -384.967016) (xy 38.487604 -384.95986) (xy 38.465853 -384.934178)
			(xy 38.427905 -384.878595) (xy 38.396872 -384.818875) (xy 38.373199 -384.755875) (xy 38.357224 -384.690497)
			(xy 38.349178 -384.623678) (xy 38.349175 -384.556376) (xy 38.357215 -384.489557) (xy 38.373183 -384.424177)
			(xy 38.39685 -384.361174) (xy 38.427877 -384.301451) (xy 38.465819 -384.245865) (xy 38.487604 -384.220212)
			(xy 38.493421 -384.213081) (xy 38.499923 -384.19588) (xy 38.500304 -384.186684) (xy 38.500304 -383.693416)
			(xy 38.499885 -383.68423) (xy 38.493377 -383.667045) (xy 38.487604 -383.659888) (xy 38.465782 -383.634264)
			(xy 38.427837 -383.578673) (xy 38.396807 -383.518945) (xy 38.373138 -383.455937) (xy 38.357168 -383.390552)
			(xy 38.349127 -383.323727) (xy 37.247021 -383.323727) (xy 37.247149 -383.324068) (xy 37.263185 -383.389559)
			(xy 37.27126 -383.456499) (xy 37.271259 -383.523925) (xy 37.263181 -383.590865) (xy 37.247142 -383.656355)
			(xy 37.223374 -383.719453) (xy 37.19222 -383.77925) (xy 37.154126 -383.834883) (xy 37.13226 -383.860548)
			(xy 37.126456 -383.867687) (xy 37.119947 -383.884883) (xy 37.11956 -383.894076) (xy 37.11956 -384.051556)
			(xy 37.119147 -384.061681) (xy 37.111406 -384.080391) (xy 37.097087 -384.094708) (xy 37.078377 -384.102448)
			(xy 37.068252 -384.102864) (xy 36.351972 -384.102864) (xy 36.341843 -384.102506) (xy 36.323132 -384.094742)
			(xy 36.308817 -384.080407) (xy 36.30108 -384.061685) (xy 36.300664 -384.051556) (xy 36.300664 -383.894076)
			(xy 36.300251 -383.884889) (xy 36.293738 -383.867706) (xy 36.287964 -383.860548) (xy 36.266117 -383.834869)
			(xy 36.22803 -383.779236) (xy 36.196881 -383.719441) (xy 36.173117 -383.656346) (xy 36.157082 -383.590859)
			(xy 36.149005 -383.523923) (xy 36.149004 -383.456501) (xy 36.157078 -383.389565) (xy 36.17311 -383.324077)
			(xy 36.196871 -383.260981) (xy 36.228018 -383.201185) (xy 36.266102 -383.14555) (xy 36.287964 -383.119884)
			(xy 36.293758 -383.112737) (xy 36.300272 -383.095548) (xy 36.300664 -383.086356) (xy 36.300664 -382.59385)
			(xy 36.300216 -382.584667) (xy 36.293727 -382.567483) (xy 36.287964 -382.560322) (xy 36.266091 -382.534664)
			(xy 36.228005 -382.479028) (xy 36.196857 -382.41923) (xy 36.173095 -382.356132) (xy 36.157061 -382.290643)
			(xy 36.148987 -382.223704) (xy 32.870916 -382.223704) (xy 32.86288 -382.290466) (xy 32.846909 -382.355848)
			(xy 32.823237 -382.418852) (xy 32.792206 -382.478575) (xy 32.754259 -382.534162) (xy 32.732472 -382.559814)
			(xy 32.726683 -382.566965) (xy 32.720165 -382.584151) (xy 32.719772 -382.593342) (xy 32.719772 -383.086864)
			(xy 32.720206 -383.096049) (xy 32.726704 -383.113233) (xy 32.732472 -383.120392) (xy 32.754275 -383.146031)
			(xy 32.792223 -383.20162) (xy 32.823255 -383.261345) (xy 32.846714 -383.323786) (xy 33.948808 -383.323786)
			(xy 33.948811 -383.25636) (xy 33.956891 -383.189419) (xy 33.972931 -383.123927) (xy 33.996699 -383.060829)
			(xy 34.027855 -383.001032) (xy 34.065949 -382.945397) (xy 34.087816 -382.919732) (xy 34.093626 -382.912596)
			(xy 34.100132 -382.895398) (xy 34.100516 -382.886204) (xy 34.100516 -382.728724) (xy 34.100936 -382.718601)
			(xy 34.108679 -382.699895) (xy 34.122995 -382.685579) (xy 34.141701 -382.677836) (xy 34.151824 -382.677416)
			(xy 34.868104 -382.677416) (xy 34.878229 -382.677813) (xy 34.896935 -382.685566) (xy 34.91125 -382.699888)
			(xy 34.918992 -382.718599) (xy 34.919412 -382.728724) (xy 34.919412 -382.886204) (xy 34.919818 -382.895392)
			(xy 34.926334 -382.912576) (xy 34.932112 -382.919732) (xy 34.95394 -382.945427) (xy 34.992029 -383.001057)
			(xy 35.023181 -383.060849) (xy 35.046946 -383.123942) (xy 35.062984 -383.189428) (xy 35.071063 -383.256363)
			(xy 35.071066 -383.323783) (xy 35.062994 -383.390719) (xy 35.046962 -383.456206) (xy 35.023203 -383.519301)
			(xy 34.992057 -383.579096) (xy 34.953973 -383.634731) (xy 34.932112 -383.660396) (xy 34.926336 -383.667556)
			(xy 34.919809 -383.684735) (xy 34.919412 -383.693924) (xy 34.919412 -384.186176) (xy 34.919831 -384.195362)
			(xy 34.926338 -384.212547) (xy 34.932112 -384.219704) (xy 34.954011 -384.24534) (xy 34.992098 -384.300979)
			(xy 35.023246 -384.36078) (xy 35.047008 -384.42388) (xy 35.06304 -384.489373) (xy 35.071113 -384.556314)
			(xy 35.07111 -384.62374) (xy 35.063031 -384.690681) (xy 35.046992 -384.756172) (xy 35.023224 -384.81927)
			(xy 34.99207 -384.879067) (xy 34.953978 -384.934703) (xy 34.932112 -384.960368) (xy 34.926305 -384.967506)
			(xy 34.919796 -384.984702) (xy 34.919412 -384.993896) (xy 34.919412 -385.151376) (xy 34.918965 -385.161495)
			(xy 34.911227 -385.180196) (xy 34.89692 -385.194511) (xy 34.878223 -385.202259) (xy 34.868104 -385.202684)
			(xy 34.151824 -385.202684) (xy 34.141701 -385.202264) (xy 34.122995 -385.194521) (xy 34.108679 -385.180205)
			(xy 34.100936 -385.161499) (xy 34.100516 -385.151376) (xy 34.100516 -384.993896) (xy 34.100104 -384.984709)
			(xy 34.093591 -384.967525) (xy 34.087816 -384.960368) (xy 34.065987 -384.934674) (xy 34.027896 -384.879044)
			(xy 33.996743 -384.819252) (xy 33.972976 -384.756159) (xy 33.956937 -384.690673) (xy 33.948858 -384.623738)
			(xy 33.948855 -384.556316) (xy 33.956928 -384.48938) (xy 33.97296 -384.423893) (xy 33.996721 -384.360798)
			(xy 34.027868 -384.301003) (xy 34.065954 -384.245369) (xy 34.087816 -384.219704) (xy 34.093595 -384.212547)
			(xy 34.10012 -384.195365) (xy 34.100516 -384.186176) (xy 34.100516 -383.693924) (xy 34.100091 -383.684739)
			(xy 34.093587 -383.667554) (xy 34.087816 -383.660396) (xy 34.065916 -383.63476) (xy 34.027827 -383.579122)
			(xy 33.996677 -383.519322) (xy 33.972915 -383.456221) (xy 33.956881 -383.390728) (xy 33.948808 -383.323786)
			(xy 32.846714 -383.323786) (xy 32.846926 -383.324351) (xy 32.862898 -383.389735) (xy 32.87094 -383.456559)
			(xy 32.870939 -383.523865) (xy 32.862893 -383.590689) (xy 32.846919 -383.656072) (xy 32.823245 -383.719077)
			(xy 32.79221 -383.778801) (xy 32.75426 -383.834388) (xy 32.732472 -383.86004) (xy 32.726672 -383.867183)
			(xy 32.72016 -383.884375) (xy 32.719772 -383.893568) (xy 32.719772 -384.051556) (xy 32.719342 -384.061711)
			(xy 32.711555 -384.080468) (xy 32.697161 -384.094793) (xy 32.678367 -384.10249) (xy 32.66821 -384.102864)
			(xy 31.95193 -384.102864) (xy 31.941806 -384.102349) (xy 31.923086 -384.094632) (xy 31.908729 -384.080354)
			(xy 31.900908 -384.061678) (xy 31.900368 -384.051556) (xy 31.900368 -383.893568) (xy 31.899958 -383.884381)
			(xy 31.893443 -383.867197) (xy 31.887668 -383.86004) (xy 31.865895 -383.834375) (xy 31.827944 -383.778791)
			(xy 31.796908 -383.71907) (xy 31.773234 -383.656067) (xy 31.757259 -383.590686) (xy 31.749213 -383.523864)
			(xy 31.749211 -383.45656) (xy 31.757254 -383.389738) (xy 31.773226 -383.324356) (xy 31.796899 -383.261352)
			(xy 31.827932 -383.201629) (xy 31.86588 -383.146044) (xy 31.887668 -383.120392) (xy 31.893459 -383.113243)
			(xy 31.899975 -383.096055) (xy 31.900368 -383.086864) (xy 31.900368 -382.593342) (xy 31.899923 -382.584159)
			(xy 31.893432 -382.566975) (xy 31.887668 -382.559814) (xy 31.86587 -382.53417) (xy 31.827919 -382.478583)
			(xy 31.796885 -382.418859) (xy 31.773211 -382.355853) (xy 31.757238 -382.29047) (xy 31.749194 -382.223646)
			(xy 28.471155 -382.223646) (xy 28.471155 -382.223704) (xy 28.463079 -382.290642) (xy 28.447044 -382.356131)
			(xy 28.42328 -382.419228) (xy 28.392129 -382.479023) (xy 28.35404 -382.534657) (xy 28.332176 -382.560322)
			(xy 28.326385 -382.567471) (xy 28.319868 -382.584659) (xy 28.319476 -382.59385) (xy 28.319476 -383.086356)
			(xy 28.319913 -383.09554) (xy 28.326409 -383.112725) (xy 28.332176 -383.119884) (xy 28.354057 -383.145536)
			(xy 28.392146 -383.201172) (xy 28.423298 -383.26097) (xy 28.446934 -383.323727) (xy 29.549039 -383.323727)
			(xy 29.549043 -383.256419) (xy 29.55709 -383.189594) (xy 29.573066 -383.12421) (xy 29.596742 -383.061205)
			(xy 29.627779 -383.00148) (xy 29.665731 -382.945892) (xy 29.68752 -382.92024) (xy 29.693327 -382.913102)
			(xy 29.699835 -382.895906) (xy 29.70022 -382.886712) (xy 29.70022 -382.728724) (xy 29.700636 -382.718601)
			(xy 29.70838 -382.699894) (xy 29.722697 -382.685578) (xy 29.741405 -382.677835) (xy 29.751528 -382.677416)
			(xy 30.468062 -382.677416) (xy 30.478183 -382.677957) (xy 30.496899 -382.685668) (xy 30.511256 -382.699938)
			(xy 30.51908 -382.718606) (xy 30.519624 -382.728724) (xy 30.519624 -382.886712) (xy 30.520023 -382.8959)
			(xy 30.526544 -382.913085) (xy 30.532324 -382.92024) (xy 30.554077 -382.945921) (xy 30.59203 -383.001502)
			(xy 30.623067 -383.061222) (xy 30.646743 -383.124222) (xy 30.66272 -383.189601) (xy 30.670767 -383.256421)
			(xy 30.67077 -383.323724) (xy 30.662729 -383.390545) (xy 30.646759 -383.455926) (xy 30.623089 -383.518929)
			(xy 30.592058 -383.578651) (xy 30.554111 -383.634236) (xy 30.532324 -383.659888) (xy 30.52651 -383.667021)
			(xy 30.520005 -383.684221) (xy 30.519624 -383.693416) (xy 30.519624 -384.186684) (xy 30.520036 -384.195871)
			(xy 30.526548 -384.213056) (xy 30.532324 -384.220212) (xy 30.554149 -384.245834) (xy 30.592099 -384.301424)
			(xy 30.623132 -384.361152) (xy 30.646805 -384.42416) (xy 30.662776 -384.489546) (xy 30.670818 -384.556373)
			(xy 30.670815 -384.623681) (xy 30.662767 -384.690507) (xy 30.646789 -384.755892) (xy 30.62311 -384.818898)
			(xy 30.592071 -384.878622) (xy 30.554115 -384.934209) (xy 30.532324 -384.95986) (xy 30.526522 -384.967002)
			(xy 30.52001 -384.984195) (xy 30.519624 -384.993388) (xy 30.519624 -385.151376) (xy 30.519165 -385.161494)
			(xy 30.511429 -385.180193) (xy 30.497126 -385.194507) (xy 30.478434 -385.202257) (xy 30.468316 -385.202684)
			(xy 29.751782 -385.202684) (xy 29.741657 -385.202189) (xy 29.72294 -385.19446) (xy 29.708585 -385.180177)
			(xy 29.700762 -385.161498) (xy 29.70022 -385.151376) (xy 29.70022 -384.993388) (xy 29.699811 -384.984201)
			(xy 29.693296 -384.967017) (xy 29.68752 -384.95986) (xy 29.665769 -384.934178) (xy 29.62782 -384.878596)
			(xy 29.596786 -384.818876) (xy 29.573112 -384.755875) (xy 29.557137 -384.690497) (xy 29.549091 -384.623678)
			(xy 29.549087 -384.556376) (xy 29.557128 -384.489556) (xy 29.573096 -384.424176) (xy 29.596764 -384.361174)
			(xy 29.627792 -384.301451) (xy 29.665735 -384.245865) (xy 29.68752 -384.220212) (xy 29.693339 -384.213083)
			(xy 29.69984 -384.19588) (xy 29.70022 -384.186684) (xy 29.70022 -383.693416) (xy 29.699797 -383.68423)
			(xy 29.693292 -383.667046) (xy 29.68752 -383.659888) (xy 29.665697 -383.634265) (xy 29.627751 -383.578674)
			(xy 29.59672 -383.518946) (xy 29.57305 -383.455938) (xy 29.55708 -383.390552) (xy 29.549039 -383.323727)
			(xy 28.446934 -383.323727) (xy 28.447062 -383.324068) (xy 28.463097 -383.389559) (xy 28.471172 -383.456499)
			(xy 28.471171 -383.523925) (xy 28.463093 -383.590865) (xy 28.447055 -383.656355) (xy 28.423288 -383.719452)
			(xy 28.392134 -383.779249) (xy 28.354042 -383.834883) (xy 28.332176 -383.860548) (xy 28.326374 -383.867689)
			(xy 28.319863 -383.884883) (xy 28.319476 -383.894076) (xy 28.319476 -384.051556) (xy 28.319047 -384.061679)
			(xy 28.311309 -384.080386) (xy 28.296996 -384.094702) (xy 28.27829 -384.102445) (xy 28.268168 -384.102864)
			(xy 27.551888 -384.102864) (xy 27.54176 -384.102493) (xy 27.523049 -384.094734) (xy 27.508734 -384.080404)
			(xy 27.500996 -384.061684) (xy 27.50058 -384.051556) (xy 27.50058 -383.894076) (xy 27.500186 -383.884887)
			(xy 27.493661 -383.867703) (xy 27.48788 -383.860548) (xy 27.466032 -383.834869) (xy 27.427945 -383.779236)
			(xy 27.396794 -383.719442) (xy 27.37303 -383.656347) (xy 27.356994 -383.59086) (xy 27.348917 -383.523923)
			(xy 27.348916 -383.456501) (xy 27.35699 -383.389564) (xy 27.373023 -383.324076) (xy 27.396784 -383.26098)
			(xy 27.427932 -383.201184) (xy 27.466018 -383.14555) (xy 27.48788 -383.119884) (xy 27.493664 -383.112729)
			(xy 27.500187 -383.095546) (xy 27.50058 -383.086356) (xy 27.50058 -382.59385) (xy 27.50015 -382.584665)
			(xy 27.49365 -382.56748) (xy 27.48788 -382.560322) (xy 27.466007 -382.534665) (xy 27.42792 -382.479028)
			(xy 27.396771 -382.419231) (xy 27.373008 -382.356133) (xy 27.356974 -382.290643) (xy 27.348899 -382.223705)
			(xy 0.508 -382.223705) (xy 0.508 -385.583938) (xy 100.447856 -385.583938) (xy 100.447856 -384.720338)
			(xy 100.448346 -384.690354) (xy 100.456174 -384.630898) (xy 100.471695 -384.572973) (xy 100.494644 -384.517569)
			(xy 100.524628 -384.465635) (xy 100.561134 -384.418059) (xy 100.603539 -384.375654) (xy 100.651115 -384.339148)
			(xy 100.703049 -384.309164) (xy 100.758453 -384.286215) (xy 100.816378 -384.270694) (xy 100.875834 -384.262866)
			(xy 100.935802 -384.262866) (xy 100.995258 -384.270694) (xy 101.053183 -384.286215) (xy 101.108587 -384.309164)
			(xy 101.160521 -384.339148) (xy 101.208097 -384.375654) (xy 101.250502 -384.418059) (xy 101.287008 -384.465635)
			(xy 101.316992 -384.517569) (xy 101.339941 -384.572973) (xy 101.355462 -384.630898) (xy 101.36329 -384.690354)
			(xy 101.36378 -384.720338) (xy 101.36378 -385.319283) (xy 104.635826 -385.319283) (xy 104.635826 -385.259317)
			(xy 104.643653 -385.199864) (xy 104.659172 -385.141942) (xy 104.682119 -385.08654) (xy 104.7121 -385.034608)
			(xy 104.748603 -384.987032) (xy 104.791004 -384.944628) (xy 104.838576 -384.908121) (xy 104.890506 -384.878136)
			(xy 104.945906 -384.855184) (xy 105.003827 -384.83966) (xy 105.063279 -384.831828) (xy 105.093262 -384.831336)
			(xy 105.956862 -384.831336) (xy 105.986849 -384.831807) (xy 106.046311 -384.83963) (xy 106.104243 -384.855149)
			(xy 106.159653 -384.878097) (xy 106.211594 -384.908081) (xy 106.259176 -384.944589) (xy 106.301586 -384.986995)
			(xy 106.338098 -385.034574) (xy 106.368087 -385.086513) (xy 106.391039 -385.141921) (xy 106.406562 -385.199852)
			(xy 106.414391 -385.259313) (xy 106.414391 -385.319287) (xy 106.406562 -385.378748) (xy 106.391039 -385.436679)
			(xy 106.368087 -385.492087) (xy 106.338098 -385.544026) (xy 106.301586 -385.591605) (xy 106.259176 -385.634011)
			(xy 106.211594 -385.670519) (xy 106.159653 -385.700503) (xy 106.104243 -385.723451) (xy 106.046311 -385.73897)
			(xy 105.986849 -385.746793) (xy 105.956862 -385.74726) (xy 105.093262 -385.74726) (xy 105.063279 -385.746772)
			(xy 105.003827 -385.73894) (xy 104.945906 -385.723416) (xy 104.890506 -385.700464) (xy 104.838576 -385.670479)
			(xy 104.791004 -385.633972) (xy 104.748603 -385.591568) (xy 104.7121 -385.543992) (xy 104.682119 -385.49206)
			(xy 104.659172 -385.436658) (xy 104.643653 -385.378736) (xy 104.635826 -385.319283) (xy 101.36378 -385.319283)
			(xy 101.36378 -385.583938) (xy 101.36329 -385.613922) (xy 101.355462 -385.673378) (xy 101.339941 -385.731303)
			(xy 101.316992 -385.786707) (xy 101.287008 -385.838641) (xy 101.250502 -385.886217) (xy 101.208097 -385.928622)
			(xy 101.160521 -385.965128) (xy 101.108587 -385.995112) (xy 101.053183 -386.018061) (xy 100.995258 -386.033582)
			(xy 100.935802 -386.04141) (xy 100.875834 -386.04141) (xy 100.816378 -386.033582) (xy 100.758453 -386.018061)
			(xy 100.703049 -385.995112) (xy 100.651115 -385.965128) (xy 100.603539 -385.928622) (xy 100.561134 -385.886217)
			(xy 100.524628 -385.838641) (xy 100.494644 -385.786707) (xy 100.471695 -385.731303) (xy 100.456174 -385.673378)
			(xy 100.448346 -385.613922) (xy 100.447856 -385.583938) (xy 0.508 -385.583938) (xy 0.508 -388.37489)
			(xy 1.56972 -388.37489) (xy 1.56972 -387.51129) (xy 1.57021 -387.481322) (xy 1.578033 -387.4219)
			(xy 1.593546 -387.364007) (xy 1.616482 -387.308634) (xy 1.646449 -387.256728) (xy 1.682936 -387.209178)
			(xy 1.725316 -387.166798) (xy 1.772866 -387.130311) (xy 1.824772 -387.100344) (xy 1.880145 -387.077408)
			(xy 1.938038 -387.061895) (xy 1.99746 -387.054072) (xy 2.057396 -387.054072) (xy 2.116818 -387.061895)
			(xy 2.174711 -387.077408) (xy 2.230084 -387.100344) (xy 2.28199 -387.130311) (xy 2.32954 -387.166798)
			(xy 2.37192 -387.209178) (xy 2.408407 -387.256728) (xy 2.438374 -387.308634) (xy 2.46131 -387.364007)
			(xy 2.476823 -387.4219) (xy 2.484646 -387.481322) (xy 2.485136 -387.51129) (xy 2.485136 -388.37489)
			(xy 2.484646 -388.404858) (xy 2.476823 -388.46428) (xy 2.46131 -388.522173) (xy 2.438374 -388.577546)
			(xy 2.408407 -388.629452) (xy 2.37192 -388.677002) (xy 2.32954 -388.719382) (xy 2.28199 -388.755869)
			(xy 2.230084 -388.785836) (xy 2.174711 -388.808772) (xy 2.116818 -388.824285) (xy 2.057396 -388.832108)
			(xy 1.99746 -388.832108) (xy 1.938038 -388.824285) (xy 1.880145 -388.808772) (xy 1.824772 -388.785836)
			(xy 1.772866 -388.755869) (xy 1.725316 -388.719382) (xy 1.682936 -388.677002) (xy 1.646449 -388.629452)
			(xy 1.616482 -388.577546) (xy 1.593546 -388.522173) (xy 1.578033 -388.46428) (xy 1.57021 -388.404858)
			(xy 1.56972 -388.37489) (xy 0.508 -388.37489) (xy 0.508 -398.164722) (xy 3.141726 -398.164722) (xy 3.141726 -398.035362)
			(xy 3.149849 -397.906256) (xy 3.166062 -397.777916) (xy 3.190302 -397.650846) (xy 3.222472 -397.52555)
			(xy 3.262447 -397.40252) (xy 3.310068 -397.282244) (xy 3.365147 -397.165195) (xy 3.427467 -397.051835)
			(xy 3.496782 -396.942612) (xy 3.572818 -396.837957) (xy 3.655276 -396.738283) (xy 3.743829 -396.643983)
			(xy 3.838129 -396.55543) (xy 3.937803 -396.472972) (xy 4.042458 -396.396936) (xy 4.151681 -396.327621)
			(xy 4.265041 -396.265301) (xy 4.38209 -396.210222) (xy 4.502366 -396.162601) (xy 4.625396 -396.122626)
			(xy 4.750692 -396.090456) (xy 4.877762 -396.066216) (xy 5.006102 -396.050003) (xy 5.135208 -396.04188)
			(xy 5.199888 -396.041372) (xy 6.800088 -396.041372) (xy 6.864769 -396.041866) (xy 6.993875 -396.049988)
			(xy 7.122217 -396.066201) (xy 7.249287 -396.090441) (xy 7.374584 -396.122612) (xy 7.497614 -396.162587)
			(xy 7.617892 -396.210208) (xy 7.734942 -396.265287) (xy 7.848302 -396.327608) (xy 7.957526 -396.396923)
			(xy 8.062181 -396.47296) (xy 8.161856 -396.555418) (xy 8.256157 -396.643972) (xy 8.344711 -396.738272)
			(xy 8.427169 -396.837947) (xy 8.503206 -396.942603) (xy 8.572521 -397.051826) (xy 8.634842 -397.165187)
			(xy 8.689921 -397.282236) (xy 8.737543 -397.402514) (xy 8.777518 -397.525544) (xy 8.809688 -397.650841)
			(xy 8.833928 -397.777911) (xy 8.839736 -397.823885) (xy 27.348879 -397.823885) (xy 27.348883 -397.756458)
			(xy 27.356962 -397.689518) (xy 27.373001 -397.624027) (xy 27.396769 -397.560929) (xy 27.427923 -397.501131)
			(xy 27.466014 -397.445496) (xy 27.48788 -397.41983) (xy 27.493686 -397.412692) (xy 27.500196 -397.395496)
			(xy 27.50058 -397.386302) (xy 27.50058 -396.89405) (xy 27.50015 -396.884865) (xy 27.49365 -396.86768)
			(xy 27.48788 -396.860522) (xy 27.466007 -396.834865) (xy 27.42792 -396.779228) (xy 27.396771 -396.719431)
			(xy 27.373008 -396.656333) (xy 27.356974 -396.590843) (xy 27.348899 -396.523905) (xy 27.3489 -396.45648)
			(xy 27.356976 -396.389542) (xy 27.373012 -396.324053) (xy 27.396777 -396.260955) (xy 27.427928 -396.201159)
			(xy 27.466016 -396.145524) (xy 27.48788 -396.119858) (xy 27.493675 -396.112711) (xy 27.500191 -396.095522)
			(xy 27.50058 -396.08633) (xy 27.50058 -395.92885) (xy 27.501069 -395.918722) (xy 27.508787 -395.899994)
			(xy 27.523074 -395.885635) (xy 27.541762 -395.877821) (xy 27.551888 -395.877288) (xy 28.268168 -395.877288)
			(xy 28.278319 -395.877747) (xy 28.297068 -395.88553) (xy 28.311392 -395.899915) (xy 28.319095 -395.918698)
			(xy 28.319476 -395.92885) (xy 28.319476 -396.08633) (xy 28.319877 -396.095518) (xy 28.326398 -396.112702)
			(xy 28.332176 -396.119858) (xy 28.354031 -396.145531) (xy 28.392122 -396.201164) (xy 28.423274 -396.260959)
			(xy 28.44704 -396.324055) (xy 28.463077 -396.389543) (xy 28.471154 -396.456481) (xy 28.471155 -396.523904)
			(xy 28.463079 -396.590842) (xy 28.447044 -396.656331) (xy 28.42328 -396.719428) (xy 28.392129 -396.779223)
			(xy 28.35404 -396.834857) (xy 28.332176 -396.860522) (xy 28.326385 -396.867671) (xy 28.319868 -396.884859)
			(xy 28.319476 -396.89405) (xy 28.319476 -397.386302) (xy 28.31989 -397.395489) (xy 28.326402 -397.412673)
			(xy 28.332176 -397.41983) (xy 28.354003 -397.445526) (xy 28.392095 -397.501155) (xy 28.420857 -397.556356)
			(xy 29.549071 -397.556356) (xy 29.557114 -397.489534) (xy 29.573085 -397.424153) (xy 29.596756 -397.361149)
			(xy 29.627787 -397.301425) (xy 29.665733 -397.245838) (xy 29.68752 -397.220186) (xy 29.693307 -397.213034)
			(xy 29.699827 -397.195849) (xy 29.70022 -397.186658) (xy 29.70022 -397.028924) (xy 29.700641 -397.018769)
			(xy 29.708433 -397.000013) (xy 29.72283 -396.985688) (xy 29.741625 -396.977991) (xy 29.751782 -396.977616)
			(xy 30.468062 -396.977616) (xy 30.478183 -396.978157) (xy 30.496899 -396.985868) (xy 30.511256 -397.000138)
			(xy 30.51908 -397.018806) (xy 30.519624 -397.028924) (xy 30.519624 -397.186658) (xy 30.520049 -397.195844)
			(xy 30.526552 -397.213029) (xy 30.532324 -397.220186) (xy 30.554123 -397.24583) (xy 30.592074 -397.301416)
			(xy 30.623108 -397.361141) (xy 30.646782 -397.424147) (xy 30.662756 -397.48953) (xy 30.6708 -397.556354)
			(xy 30.670799 -397.623661) (xy 30.662753 -397.690485) (xy 30.646778 -397.755868) (xy 30.623102 -397.818873)
			(xy 30.620528 -397.823826) (xy 31.749174 -397.823826) (xy 31.749178 -397.756517) (xy 31.757226 -397.689691)
			(xy 31.773204 -397.624307) (xy 31.796882 -397.5613) (xy 31.827922 -397.501576) (xy 31.865877 -397.44599)
			(xy 31.887668 -397.420338) (xy 31.893482 -397.413205) (xy 31.899984 -397.396005) (xy 31.900368 -397.38681)
			(xy 31.900368 -396.893542) (xy 31.899923 -396.884359) (xy 31.893432 -396.867175) (xy 31.887668 -396.860014)
			(xy 31.86587 -396.83437) (xy 31.827919 -396.778783) (xy 31.796885 -396.719059) (xy 31.773211 -396.656053)
			(xy 31.757238 -396.59067) (xy 31.749194 -396.523846) (xy 31.749195 -396.456539) (xy 31.757241 -396.389716)
			(xy 31.773216 -396.324332) (xy 31.796891 -396.261327) (xy 31.827927 -396.201604) (xy 31.865879 -396.146018)
			(xy 31.887668 -396.120366) (xy 31.89347 -396.113225) (xy 31.899979 -396.096031) (xy 31.900368 -396.086838)
			(xy 31.900368 -395.92885) (xy 31.900805 -395.918678) (xy 31.90858 -395.899879) (xy 31.922962 -395.885491)
			(xy 31.941758 -395.877709) (xy 31.95193 -395.877288) (xy 32.66821 -395.877288) (xy 32.678388 -395.877657)
			(xy 32.697193 -395.885455) (xy 32.711579 -395.899858) (xy 32.719355 -395.918671) (xy 32.719772 -395.92885)
			(xy 32.719772 -396.086838) (xy 32.72017 -396.096026) (xy 32.726693 -396.11321) (xy 32.732472 -396.120366)
			(xy 32.75425 -396.146026) (xy 32.792198 -396.201612) (xy 32.823231 -396.261334) (xy 32.846904 -396.324338)
			(xy 32.862877 -396.389719) (xy 32.870922 -396.45654) (xy 32.870923 -396.523845) (xy 32.86288 -396.590666)
			(xy 32.846909 -396.656048) (xy 32.823237 -396.719052) (xy 32.792206 -396.778775) (xy 32.754259 -396.834362)
			(xy 32.732472 -396.860014) (xy 32.726683 -396.867165) (xy 32.720165 -396.884351) (xy 32.719772 -396.893542)
			(xy 32.719772 -397.38681) (xy 32.720183 -397.395997) (xy 32.726697 -397.413181) (xy 32.732472 -397.420338)
			(xy 32.754222 -397.446021) (xy 32.792171 -397.501603) (xy 32.820593 -397.556296) (xy 33.948839 -397.556296)
			(xy 33.956914 -397.489358) (xy 33.972949 -397.423869) (xy 33.996713 -397.360773) (xy 34.027863 -397.300977)
			(xy 34.065952 -397.245343) (xy 34.087816 -397.219678) (xy 34.093606 -397.212528) (xy 34.100124 -397.195341)
			(xy 34.100516 -397.18615) (xy 34.100516 -397.028924) (xy 34.100936 -397.018801) (xy 34.108679 -397.000095)
			(xy 34.122995 -396.985779) (xy 34.141701 -396.978036) (xy 34.151824 -396.977616) (xy 34.868104 -396.977616)
			(xy 34.878229 -396.978013) (xy 34.896935 -396.985766) (xy 34.91125 -397.000088) (xy 34.918992 -397.018799)
			(xy 34.919412 -397.028924) (xy 34.919412 -397.18615) (xy 34.919843 -397.195335) (xy 34.926342 -397.21252)
			(xy 34.932112 -397.219678) (xy 34.953985 -397.245335) (xy 34.992073 -397.300971) (xy 35.023223 -397.360769)
			(xy 35.046986 -397.423867) (xy 35.06302 -397.489356) (xy 35.071095 -397.556295) (xy 35.071094 -397.62372)
			(xy 35.063017 -397.690658) (xy 35.046981 -397.756148) (xy 35.023216 -397.819245) (xy 35.020799 -397.823884)
			(xy 36.148967 -397.823884) (xy 36.148971 -397.756458) (xy 36.15705 -397.689518) (xy 36.173088 -397.624028)
			(xy 36.196855 -397.560929) (xy 36.228008 -397.501132) (xy 36.266099 -397.445496) (xy 36.287964 -397.41983)
			(xy 36.293781 -397.412699) (xy 36.300282 -397.395497) (xy 36.300664 -397.386302) (xy 36.300664 -396.89405)
			(xy 36.300216 -396.884867) (xy 36.293727 -396.867683) (xy 36.287964 -396.860522) (xy 36.266091 -396.834864)
			(xy 36.228005 -396.779228) (xy 36.196857 -396.71943) (xy 36.173095 -396.656332) (xy 36.157061 -396.590843)
			(xy 36.148987 -396.523904) (xy 36.148988 -396.456481) (xy 36.157064 -396.389542) (xy 36.1731 -396.324053)
			(xy 36.196863 -396.260956) (xy 36.228013 -396.201159) (xy 36.266101 -396.145524) (xy 36.287964 -396.119858)
			(xy 36.293769 -396.112719) (xy 36.300277 -396.095523) (xy 36.300664 -396.08633) (xy 36.300664 -395.92885)
			(xy 36.301168 -395.918724) (xy 36.308884 -395.899999) (xy 36.323166 -395.88564) (xy 36.341848 -395.877823)
			(xy 36.351972 -395.877288) (xy 37.068252 -395.877288) (xy 37.078402 -395.877761) (xy 37.097151 -395.885538)
			(xy 37.111475 -395.899919) (xy 37.119179 -395.918699) (xy 37.11956 -395.92885) (xy 37.11956 -396.08633)
			(xy 37.119965 -396.095518) (xy 37.126483 -396.112701) (xy 37.13226 -396.119858) (xy 37.154116 -396.145531)
			(xy 37.192207 -396.201163) (xy 37.223361 -396.260958) (xy 37.247127 -396.324054) (xy 37.263164 -396.389543)
			(xy 37.271242 -396.456481) (xy 37.271243 -396.523904) (xy 37.263167 -396.590843) (xy 37.247132 -396.656332)
			(xy 37.223367 -396.719428) (xy 37.192215 -396.779224) (xy 37.154125 -396.834857) (xy 37.13226 -396.860522)
			(xy 37.126467 -396.867669) (xy 37.119951 -396.884858) (xy 37.11956 -396.89405) (xy 37.11956 -397.386302)
			(xy 37.119978 -397.395488) (xy 37.126487 -397.412672) (xy 37.13226 -397.41983) (xy 37.154088 -397.445525)
			(xy 37.192181 -397.501155) (xy 37.220943 -397.556356) (xy 38.349159 -397.556356) (xy 38.357201 -397.489534)
			(xy 38.373172 -397.424153) (xy 38.396842 -397.361149) (xy 38.427873 -397.301426) (xy 38.465818 -397.245839)
			(xy 38.487604 -397.220186) (xy 38.493389 -397.213033) (xy 38.499911 -397.195848) (xy 38.500304 -397.186658)
			(xy 38.500304 -397.028924) (xy 38.500741 -397.018771) (xy 38.50853 -397.000018) (xy 38.522922 -396.985694)
			(xy 38.541711 -396.977994) (xy 38.551866 -396.977616) (xy 39.268146 -396.977616) (xy 39.278273 -396.978088)
			(xy 39.29699 -396.985827) (xy 39.311344 -397.000117) (xy 39.319166 -397.0188) (xy 39.319708 -397.028924)
			(xy 39.319708 -397.186658) (xy 39.320136 -397.195843) (xy 39.326637 -397.213028) (xy 39.332408 -397.220186)
			(xy 39.354207 -397.245829) (xy 39.392159 -397.301416) (xy 39.423195 -397.36114) (xy 39.446869 -397.424146)
			(xy 39.462843 -397.48953) (xy 39.470887 -397.556354) (xy 39.470887 -397.623661) (xy 39.462841 -397.690485)
			(xy 39.446865 -397.755869) (xy 39.423189 -397.818874) (xy 39.420585 -397.823885) (xy 40.548734 -397.823885)
			(xy 40.548737 -397.756458) (xy 40.556817 -397.689516) (xy 40.572859 -397.624024) (xy 40.596629 -397.560925)
			(xy 40.627787 -397.501128) (xy 40.665884 -397.445494) (xy 40.687752 -397.41983) (xy 40.693567 -397.412698)
			(xy 40.700069 -397.395497) (xy 40.700452 -397.386302) (xy 40.700452 -396.89405) (xy 40.700006 -396.884867)
			(xy 40.693516 -396.867683) (xy 40.687752 -396.860522) (xy 40.665876 -396.834866) (xy 40.627785 -396.779231)
			(xy 40.596631 -396.719434) (xy 40.572865 -396.656336) (xy 40.556829 -396.590845) (xy 40.548753 -396.523905)
			(xy 40.548754 -396.45648) (xy 40.556832 -396.38954) (xy 40.57287 -396.32405) (xy 40.596638 -396.260952)
			(xy 40.627792 -396.201156) (xy 40.665886 -396.145522) (xy 40.687752 -396.119858) (xy 40.693555 -396.112718)
			(xy 40.700065 -396.095523) (xy 40.700452 -396.08633) (xy 40.700452 -395.92885) (xy 40.700968 -395.918725)
			(xy 40.708682 -395.900003) (xy 40.722959 -395.885644) (xy 40.741638 -395.877825) (xy 40.75176 -395.877288)
			(xy 41.46804 -395.877288) (xy 41.478195 -395.877689) (xy 41.496946 -395.885495) (xy 41.511268 -395.899898)
			(xy 41.518968 -395.918693) (xy 41.519348 -395.92885) (xy 41.519348 -396.08633) (xy 41.519755 -396.095517)
			(xy 41.526272 -396.112701) (xy 41.532048 -396.119858) (xy 41.553904 -396.14553) (xy 41.591996 -396.201163)
			(xy 41.62315 -396.260957) (xy 41.646917 -396.324053) (xy 41.662955 -396.389542) (xy 41.671033 -396.456481)
			(xy 41.671034 -396.523904) (xy 41.662958 -396.590843) (xy 41.646922 -396.656332) (xy 41.623157 -396.719429)
			(xy 41.592004 -396.779224) (xy 41.553913 -396.834858) (xy 41.532048 -396.860522) (xy 41.526253 -396.867668)
			(xy 41.519739 -396.884858) (xy 41.519348 -396.89405) (xy 41.519348 -397.386302) (xy 41.519769 -397.395488)
			(xy 41.526276 -397.412672) (xy 41.532048 -397.41983) (xy 41.553876 -397.445525) (xy 41.59197 -397.501154)
			(xy 41.620702 -397.556296) (xy 42.748927 -397.556296) (xy 42.757002 -397.489358) (xy 42.773037 -397.42387)
			(xy 42.7968 -397.360774) (xy 42.827949 -397.300978) (xy 42.866037 -397.245343) (xy 42.8879 -397.219678)
			(xy 42.893688 -397.212527) (xy 42.900208 -397.195341) (xy 42.9006 -397.18615) (xy 42.9006 -397.028924)
			(xy 42.901035 -397.018803) (xy 42.908776 -397.0001) (xy 42.923086 -396.985785) (xy 42.941787 -396.978039)
			(xy 42.951908 -396.977616) (xy 43.668188 -396.977616) (xy 43.678312 -396.978026) (xy 43.697018 -396.985773)
			(xy 43.711333 -397.000092) (xy 43.719076 -397.0188) (xy 43.719496 -397.028924) (xy 43.719496 -397.18615)
			(xy 43.719931 -397.195335) (xy 43.726427 -397.212519) (xy 43.732196 -397.219678) (xy 43.75407 -397.245335)
			(xy 43.792159 -397.300971) (xy 43.823309 -397.360768) (xy 43.847073 -397.423866) (xy 43.863108 -397.489356)
			(xy 43.871183 -397.556295) (xy 43.871182 -397.62372) (xy 43.863105 -397.690659) (xy 43.847068 -397.756148)
			(xy 43.823303 -397.819246) (xy 43.820917 -397.823825) (xy 44.949053 -397.823825) (xy 44.949057 -397.756517)
			(xy 44.957105 -397.689692) (xy 44.973082 -397.624308) (xy 44.996759 -397.561302) (xy 45.027796 -397.501577)
			(xy 45.06575 -397.44599) (xy 45.08754 -397.420338) (xy 45.09335 -397.413203) (xy 45.099856 -397.396004)
			(xy 45.10024 -397.38681) (xy 45.10024 -396.893542) (xy 45.0998 -396.884358) (xy 45.093306 -396.867174)
			(xy 45.08754 -396.860014) (xy 45.065742 -396.83437) (xy 45.027794 -396.778782) (xy 44.996761 -396.719058)
			(xy 44.973088 -396.656052) (xy 44.957116 -396.590669) (xy 44.949073 -396.523845) (xy 44.949074 -396.45654)
			(xy 44.957119 -396.389716) (xy 44.973093 -396.324333) (xy 44.996767 -396.261328) (xy 45.027801 -396.201605)
			(xy 45.065751 -396.146018) (xy 45.08754 -396.120366) (xy 45.093339 -396.113222) (xy 45.099851 -396.096031)
			(xy 45.10024 -396.086838) (xy 45.10024 -395.92885) (xy 45.100705 -395.918681) (xy 45.108474 -395.899887)
			(xy 45.122847 -395.885501) (xy 45.141634 -395.877714) (xy 45.151802 -395.877288) (xy 45.868082 -395.877288)
			(xy 45.878259 -395.87768) (xy 45.897063 -395.885468) (xy 45.91145 -395.899864) (xy 45.919227 -395.918673)
			(xy 45.919644 -395.92885) (xy 45.919644 -396.086838) (xy 45.920049 -396.096026) (xy 45.926568 -396.113209)
			(xy 45.932344 -396.120366) (xy 45.954122 -396.146026) (xy 45.992072 -396.201611) (xy 46.023107 -396.261333)
			(xy 46.046781 -396.324337) (xy 46.062755 -396.389718) (xy 46.070801 -396.45654) (xy 46.070801 -396.523845)
			(xy 46.062758 -396.590667) (xy 46.046786 -396.656049) (xy 46.023113 -396.719053) (xy 45.99208 -396.778776)
			(xy 45.954131 -396.834362) (xy 45.932344 -396.860014) (xy 45.926552 -396.867162) (xy 45.920036 -396.884351)
			(xy 45.919644 -396.893542) (xy 45.919644 -397.38681) (xy 45.920062 -397.395996) (xy 45.926572 -397.41318)
			(xy 45.932344 -397.420338) (xy 45.954095 -397.446021) (xy 45.992046 -397.501602) (xy 46.020501 -397.556355)
			(xy 47.149223 -397.556355) (xy 47.157267 -397.489532) (xy 47.17324 -397.42415) (xy 47.196914 -397.361146)
			(xy 47.227949 -397.301423) (xy 47.265899 -397.245837) (xy 47.287688 -397.220186) (xy 47.293472 -397.213032)
			(xy 47.299994 -397.195848) (xy 47.300388 -397.186658) (xy 47.300388 -397.028924) (xy 47.300841 -397.018773)
			(xy 47.308626 -397.000023) (xy 47.323013 -396.985699) (xy 47.341797 -396.977997) (xy 47.35195 -396.977616)
			(xy 48.06823 -396.977616) (xy 48.078356 -396.978101) (xy 48.097073 -396.985834) (xy 48.111427 -397.000121)
			(xy 48.11925 -397.018801) (xy 48.119792 -397.028924) (xy 48.119792 -397.186658) (xy 48.120224 -397.195843)
			(xy 48.126723 -397.213027) (xy 48.132492 -397.220186) (xy 48.154289 -397.24583) (xy 48.192235 -397.301419)
			(xy 48.223266 -397.361144) (xy 48.246937 -397.424149) (xy 48.262908 -397.489532) (xy 48.270951 -397.556355)
			(xy 48.27095 -397.62366) (xy 48.262906 -397.690483) (xy 48.246933 -397.755865) (xy 48.22326 -397.81887)
			(xy 48.192227 -397.878594) (xy 48.154279 -397.934181) (xy 48.132492 -397.959834) (xy 48.126698 -397.966981)
			(xy 48.120182 -397.98417) (xy 48.119792 -397.993362) (xy 48.119792 -398.486884) (xy 48.120212 -398.49607)
			(xy 48.126719 -398.513254) (xy 48.132492 -398.520412) (xy 48.154314 -398.546035) (xy 48.19226 -398.601627)
			(xy 48.22329 -398.661355) (xy 48.246959 -398.724363) (xy 48.262929 -398.789748) (xy 48.27097 -398.856573)
			(xy 48.270966 -398.923881) (xy 48.262919 -398.990705) (xy 48.246943 -399.056089) (xy 48.223268 -399.119095)
			(xy 48.192232 -399.17882) (xy 48.154281 -399.234407) (xy 48.132492 -399.26006) (xy 48.126687 -399.267199)
			(xy 48.120177 -399.284394) (xy 48.119792 -399.293588) (xy 48.119792 -399.451576) (xy 48.119359 -399.46173)
			(xy 48.11157 -399.480483) (xy 48.097176 -399.494808) (xy 48.078386 -399.502507) (xy 48.06823 -399.502884)
			(xy 47.35195 -399.502884) (xy 47.341829 -399.502333) (xy 47.323114 -399.494626) (xy 47.308757 -399.48036)
			(xy 47.300932 -399.461693) (xy 47.300388 -399.451576) (xy 47.300388 -399.293588) (xy 47.299986 -399.2844)
			(xy 47.293467 -399.267216) (xy 47.287688 -399.26006) (xy 47.265934 -399.234379) (xy 47.227981 -399.178798)
			(xy 47.196944 -399.119079) (xy 47.173267 -399.056078) (xy 47.15729 -398.990699) (xy 47.149242 -398.923879)
			(xy 47.149239 -398.856576) (xy 47.15728 -398.789754) (xy 47.173251 -398.724374) (xy 47.196921 -398.661371)
			(xy 47.227953 -398.601648) (xy 47.265901 -398.546063) (xy 47.287688 -398.520412) (xy 47.293503 -398.51328)
			(xy 47.300007 -398.496079) (xy 47.300388 -398.486884) (xy 47.300388 -397.993362) (xy 47.299999 -397.984172)
			(xy 47.293471 -397.966988) (xy 47.287688 -397.959834) (xy 47.265909 -397.934174) (xy 47.227956 -397.87859)
			(xy 47.19692 -397.818868) (xy 47.173244 -397.755864) (xy 47.157269 -397.690483) (xy 47.149224 -397.62366)
			(xy 47.149223 -397.556355) (xy 46.020501 -397.556355) (xy 46.023082 -397.561322) (xy 46.046757 -397.624322)
			(xy 46.062733 -397.689701) (xy 46.070781 -397.75652) (xy 46.070784 -397.823823) (xy 46.062744 -397.890643)
			(xy 46.046774 -397.956023) (xy 46.023105 -398.019026) (xy 45.992075 -398.078748) (xy 45.95413 -398.134334)
			(xy 45.932344 -398.159986) (xy 45.926522 -398.167113) (xy 45.920024 -398.184318) (xy 45.919644 -398.193514)
			(xy 45.919644 -398.351502) (xy 45.919237 -398.361676) (xy 45.911448 -398.380474) (xy 45.897057 -398.39486)
			(xy 45.878256 -398.402641) (xy 45.868082 -398.403064) (xy 45.151802 -398.403064) (xy 45.141645 -398.402565)
			(xy 45.122876 -398.394792) (xy 45.108511 -398.380427) (xy 45.100736 -398.361659) (xy 45.10024 -398.351502)
			(xy 45.10024 -398.193514) (xy 45.099814 -398.184329) (xy 45.093311 -398.167145) (xy 45.08754 -398.159986)
			(xy 45.065715 -398.134365) (xy 45.027767 -398.078774) (xy 44.996735 -398.019046) (xy 44.973065 -397.956037)
			(xy 44.957094 -397.890651) (xy 44.949053 -397.823825) (xy 43.820917 -397.823825) (xy 43.792151 -397.879042)
			(xy 43.754061 -397.934677) (xy 43.732196 -397.960342) (xy 43.726399 -397.967487) (xy 43.719885 -397.984678)
			(xy 43.719496 -397.99387) (xy 43.719496 -398.486376) (xy 43.719919 -398.495562) (xy 43.726424 -398.512746)
			(xy 43.732196 -398.519904) (xy 43.754095 -398.54554) (xy 43.792183 -398.601179) (xy 43.823333 -398.660979)
			(xy 43.847095 -398.72408) (xy 43.863128 -398.789572) (xy 43.871201 -398.856514) (xy 43.871198 -398.92394)
			(xy 43.863118 -398.990881) (xy 43.847079 -399.056372) (xy 43.823311 -399.119471) (xy 43.792156 -399.179268)
			(xy 43.754062 -399.234903) (xy 43.732196 -399.260568) (xy 43.726388 -399.267705) (xy 43.71988 -399.284902)
			(xy 43.719496 -399.294096) (xy 43.719496 -399.451576) (xy 43.719064 -399.461697) (xy 43.711323 -399.480401)
			(xy 43.697011 -399.494717) (xy 43.678309 -399.502462) (xy 43.668188 -399.502884) (xy 42.951908 -399.502884)
			(xy 42.941784 -399.502477) (xy 42.923078 -399.494729) (xy 42.908762 -399.480409) (xy 42.90102 -399.4617)
			(xy 42.9006 -399.451576) (xy 42.9006 -399.294096) (xy 42.900192 -399.284909) (xy 42.893677 -399.267724)
			(xy 42.8879 -399.260568) (xy 42.866071 -399.234874) (xy 42.827982 -399.179243) (xy 42.796829 -399.119451)
			(xy 42.773063 -399.056358) (xy 42.757025 -398.990872) (xy 42.748946 -398.923937) (xy 42.748943 -398.856517)
			(xy 42.757015 -398.789581) (xy 42.773047 -398.724094) (xy 42.796807 -398.660998) (xy 42.827954 -398.601203)
			(xy 42.866038 -398.545569) (xy 42.8879 -398.519904) (xy 42.893677 -398.512745) (xy 42.900204 -398.495565)
			(xy 42.9006 -398.486376) (xy 42.9006 -397.99387) (xy 42.900204 -397.984681) (xy 42.893681 -397.967497)
			(xy 42.8879 -397.960342) (xy 42.866046 -397.934669) (xy 42.827957 -397.879035) (xy 42.796806 -397.81924)
			(xy 42.773041 -397.756144) (xy 42.757005 -397.690656) (xy 42.748928 -397.623719) (xy 42.748927 -397.556296)
			(xy 41.620702 -397.556296) (xy 41.623125 -397.560946) (xy 41.646894 -397.624039) (xy 41.662933 -397.689525)
			(xy 41.671013 -397.756461) (xy 41.671016 -397.823882) (xy 41.662944 -397.890819) (xy 41.646911 -397.956307)
			(xy 41.623148 -398.019402) (xy 41.591999 -398.079197) (xy 41.553912 -398.13483) (xy 41.532048 -398.160494)
			(xy 41.526265 -398.167649) (xy 41.519744 -398.184832) (xy 41.519348 -398.194022) (xy 41.519348 -398.351502)
			(xy 41.518875 -398.36163) (xy 41.511144 -398.380354) (xy 41.496853 -398.39471) (xy 41.478166 -398.402527)
			(xy 41.46804 -398.403064) (xy 40.75176 -398.403064) (xy 40.741599 -398.40271) (xy 40.722839 -398.394895)
			(xy 40.708515 -398.380477) (xy 40.700824 -398.361666) (xy 40.700452 -398.351502) (xy 40.700452 -398.194022)
			(xy 40.70002 -398.184837) (xy 40.69352 -398.167653) (xy 40.687752 -398.160494) (xy 40.665849 -398.13486)
			(xy 40.627758 -398.079223) (xy 40.596606 -398.019423) (xy 40.572842 -397.956321) (xy 40.556807 -397.890828)
			(xy 40.548734 -397.823885) (xy 39.420585 -397.823885) (xy 39.392151 -397.878597) (xy 39.354198 -397.934183)
			(xy 39.332408 -397.959834) (xy 39.326615 -397.966982) (xy 39.320098 -397.98417) (xy 39.319708 -397.993362)
			(xy 39.319708 -398.486884) (xy 39.320124 -398.496071) (xy 39.326633 -398.513255) (xy 39.332408 -398.520412)
			(xy 39.354233 -398.546034) (xy 39.392184 -398.601624) (xy 39.423219 -398.661351) (xy 39.446892 -398.72436)
			(xy 39.462864 -398.789746) (xy 39.470906 -398.856573) (xy 39.470902 -398.923882) (xy 39.462854 -398.990707)
			(xy 39.446876 -399.056092) (xy 39.423196 -399.119098) (xy 39.392156 -399.178823) (xy 39.354199 -399.234409)
			(xy 39.332408 -399.26006) (xy 39.326604 -399.2672) (xy 39.320094 -399.284395) (xy 39.319708 -399.293588)
			(xy 39.319708 -399.451576) (xy 39.319259 -399.461728) (xy 39.311473 -399.480478) (xy 39.297085 -399.494802)
			(xy 39.278299 -399.502504) (xy 39.268146 -399.502884) (xy 38.551866 -399.502884) (xy 38.54174 -399.502402)
			(xy 38.523023 -399.494668) (xy 38.508668 -399.48038) (xy 38.500846 -399.4617) (xy 38.500304 -399.451576)
			(xy 38.500304 -399.293588) (xy 38.499899 -399.2844) (xy 38.493381 -399.267216) (xy 38.487604 -399.26006)
			(xy 38.465853 -399.234378) (xy 38.427905 -399.178795) (xy 38.396872 -399.119075) (xy 38.373199 -399.056075)
			(xy 38.357224 -398.990697) (xy 38.349178 -398.923878) (xy 38.349175 -398.856576) (xy 38.357215 -398.789757)
			(xy 38.373183 -398.724377) (xy 38.39685 -398.661374) (xy 38.427877 -398.601651) (xy 38.465819 -398.546065)
			(xy 38.487604 -398.520412) (xy 38.493421 -398.513281) (xy 38.499923 -398.49608) (xy 38.500304 -398.486884)
			(xy 38.500304 -397.993362) (xy 38.499911 -397.984173) (xy 38.493385 -397.966989) (xy 38.487604 -397.959834)
			(xy 38.465827 -397.934173) (xy 38.42788 -397.878587) (xy 38.396849 -397.818865) (xy 38.373177 -397.755861)
			(xy 38.357204 -397.69048) (xy 38.34916 -397.623659) (xy 38.349159 -397.556356) (xy 37.220943 -397.556356)
			(xy 37.223335 -397.560946) (xy 37.247103 -397.624039) (xy 37.263142 -397.689525) (xy 37.271222 -397.756461)
			(xy 37.271225 -397.823882) (xy 37.263153 -397.890819) (xy 37.24712 -397.956306) (xy 37.223358 -398.019402)
			(xy 37.19221 -398.079196) (xy 37.154123 -398.134829) (xy 37.13226 -398.160494) (xy 37.126478 -398.16765)
			(xy 37.119956 -398.184832) (xy 37.11956 -398.194022) (xy 37.11956 -398.351502) (xy 37.119075 -398.361629)
			(xy 37.111347 -398.38035) (xy 37.09706 -398.394706) (xy 37.078376 -398.402525) (xy 37.068252 -398.403064)
			(xy 36.351972 -398.403064) (xy 36.341812 -398.402701) (xy 36.323052 -398.394889) (xy 36.308728 -398.380474)
			(xy 36.301036 -398.361665) (xy 36.300664 -398.351502) (xy 36.300664 -398.194022) (xy 36.300229 -398.184838)
			(xy 36.293731 -398.167654) (xy 36.287964 -398.160494) (xy 36.266064 -398.134859) (xy 36.227979 -398.079219)
			(xy 36.196832 -398.019419) (xy 36.173071 -397.956318) (xy 36.15704 -397.890825) (xy 36.148967 -397.823884)
			(xy 35.020799 -397.823884) (xy 34.992065 -397.879042) (xy 34.953976 -397.934677) (xy 34.932112 -397.960342)
			(xy 34.926316 -397.967488) (xy 34.919801 -397.984678) (xy 34.919412 -397.99387) (xy 34.919412 -398.486376)
			(xy 34.919831 -398.495562) (xy 34.926338 -398.512747) (xy 34.932112 -398.519904) (xy 34.954011 -398.54554)
			(xy 34.992098 -398.601179) (xy 35.023246 -398.66098) (xy 35.047008 -398.72408) (xy 35.06304 -398.789573)
			(xy 35.071113 -398.856514) (xy 35.07111 -398.92394) (xy 35.063031 -398.990881) (xy 35.046992 -399.056372)
			(xy 35.023224 -399.11947) (xy 34.99207 -399.179267) (xy 34.953978 -399.234903) (xy 34.932112 -399.260568)
			(xy 34.926305 -399.267706) (xy 34.919796 -399.284902) (xy 34.919412 -399.294096) (xy 34.919412 -399.451576)
			(xy 34.918965 -399.461695) (xy 34.911227 -399.480396) (xy 34.89692 -399.494711) (xy 34.878223 -399.502459)
			(xy 34.868104 -399.502884) (xy 34.151824 -399.502884) (xy 34.141701 -399.502464) (xy 34.122995 -399.494721)
			(xy 34.108679 -399.480405) (xy 34.100936 -399.461699) (xy 34.100516 -399.451576) (xy 34.100516 -399.294096)
			(xy 34.100104 -399.284909) (xy 34.093591 -399.267725) (xy 34.087816 -399.260568) (xy 34.065987 -399.234874)
			(xy 34.027896 -399.179244) (xy 33.996743 -399.119452) (xy 33.972976 -399.056359) (xy 33.956937 -398.990873)
			(xy 33.948858 -398.923938) (xy 33.948855 -398.856516) (xy 33.956928 -398.78958) (xy 33.97296 -398.724093)
			(xy 33.996721 -398.660998) (xy 34.027868 -398.601203) (xy 34.065954 -398.545569) (xy 34.087816 -398.519904)
			(xy 34.093595 -398.512747) (xy 34.10012 -398.495565) (xy 34.100516 -398.486376) (xy 34.100516 -397.99387)
			(xy 34.100117 -397.984682) (xy 34.093595 -397.967498) (xy 34.087816 -397.960342) (xy 34.065961 -397.934669)
			(xy 34.027871 -397.879036) (xy 33.996719 -397.819241) (xy 33.972954 -397.756145) (xy 33.956917 -397.690657)
			(xy 33.94884 -397.623719) (xy 33.948839 -397.556296) (xy 32.820593 -397.556296) (xy 32.823205 -397.561323)
			(xy 32.84688 -397.624323) (xy 32.862855 -397.689702) (xy 32.870902 -397.756521) (xy 32.870905 -397.823822)
			(xy 32.862865 -397.890642) (xy 32.846897 -397.956022) (xy 32.823229 -398.019025) (xy 32.7922 -398.078747)
			(xy 32.754257 -398.134334) (xy 32.732472 -398.159986) (xy 32.726653 -398.167115) (xy 32.720152 -398.184318)
			(xy 32.719772 -398.193514) (xy 32.719772 -398.351502) (xy 32.719268 -398.361659) (xy 32.711495 -398.380426)
			(xy 32.697133 -398.394791) (xy 32.678367 -398.402567) (xy 32.66821 -398.403064) (xy 31.95193 -398.403064)
			(xy 31.941761 -398.402611) (xy 31.922967 -398.394837) (xy 31.908581 -398.38046) (xy 31.900795 -398.361671)
			(xy 31.900368 -398.351502) (xy 31.900368 -398.193514) (xy 31.899936 -398.184329) (xy 31.893436 -398.167146)
			(xy 31.887668 -398.159986) (xy 31.865842 -398.134365) (xy 31.827892 -398.078775) (xy 31.796859 -398.019047)
			(xy 31.773187 -397.956039) (xy 31.757216 -397.890652) (xy 31.749174 -397.823826) (xy 30.620528 -397.823826)
			(xy 30.592066 -397.878596) (xy 30.554113 -397.934182) (xy 30.532324 -397.959834) (xy 30.526533 -397.966984)
			(xy 30.520014 -397.984171) (xy 30.519624 -397.993362) (xy 30.519624 -398.486884) (xy 30.520036 -398.496071)
			(xy 30.526548 -398.513256) (xy 30.532324 -398.520412) (xy 30.554149 -398.546034) (xy 30.592099 -398.601624)
			(xy 30.623132 -398.661352) (xy 30.646805 -398.72436) (xy 30.662776 -398.789746) (xy 30.670818 -398.856573)
			(xy 30.670815 -398.923881) (xy 30.662767 -398.990707) (xy 30.646789 -399.056092) (xy 30.62311 -399.119098)
			(xy 30.592071 -399.178822) (xy 30.554115 -399.234409) (xy 30.532324 -399.26006) (xy 30.526522 -399.267202)
			(xy 30.52001 -399.284395) (xy 30.519624 -399.293588) (xy 30.519624 -399.451576) (xy 30.519159 -399.461726)
			(xy 30.511376 -399.480473) (xy 30.496993 -399.494796) (xy 30.478213 -399.502501) (xy 30.468062 -399.502884)
			(xy 29.751782 -399.502884) (xy 29.741657 -399.502389) (xy 29.72294 -399.49466) (xy 29.708585 -399.480377)
			(xy 29.700762 -399.461698) (xy 29.70022 -399.451576) (xy 29.70022 -399.293588) (xy 29.699811 -399.284401)
			(xy 29.693296 -399.267217) (xy 29.68752 -399.26006) (xy 29.665769 -399.234378) (xy 29.62782 -399.178796)
			(xy 29.596786 -399.119076) (xy 29.573112 -399.056075) (xy 29.557137 -398.990697) (xy 29.549091 -398.923878)
			(xy 29.549087 -398.856576) (xy 29.557128 -398.789756) (xy 29.573096 -398.724376) (xy 29.596764 -398.661374)
			(xy 29.627792 -398.601651) (xy 29.665735 -398.546065) (xy 29.68752 -398.520412) (xy 29.693339 -398.513283)
			(xy 29.69984 -398.49608) (xy 29.70022 -398.486884) (xy 29.70022 -397.993362) (xy 29.699824 -397.984173)
			(xy 29.6933 -397.966989) (xy 29.68752 -397.959834) (xy 29.665743 -397.934174) (xy 29.627795 -397.878588)
			(xy 29.596762 -397.818865) (xy 29.57309 -397.755862) (xy 29.557116 -397.690481) (xy 29.549072 -397.623659)
			(xy 29.549071 -397.556356) (xy 28.420857 -397.556356) (xy 28.423249 -397.560947) (xy 28.447016 -397.62404)
			(xy 28.463055 -397.689526) (xy 28.471134 -397.756461) (xy 28.471138 -397.823882) (xy 28.463065 -397.890818)
			(xy 28.447033 -397.956305) (xy 28.423272 -398.019401) (xy 28.392124 -398.079196) (xy 28.354039 -398.134829)
			(xy 28.332176 -398.160494) (xy 28.326397 -398.167651) (xy 28.319873 -398.184833) (xy 28.319476 -398.194022)
			(xy 28.319476 -398.351502) (xy 28.318975 -398.361627) (xy 28.31125 -398.380345) (xy 28.296968 -398.394701)
			(xy 28.27829 -398.402523) (xy 28.268168 -398.403064) (xy 27.551888 -398.403064) (xy 27.541729 -398.402688)
			(xy 27.522969 -398.394881) (xy 27.508645 -398.38047) (xy 27.500952 -398.361664) (xy 27.50058 -398.351502)
			(xy 27.50058 -398.194022) (xy 27.500164 -398.184835) (xy 27.493655 -398.167651) (xy 27.48788 -398.160494)
			(xy 27.465979 -398.134859) (xy 27.427893 -398.07922) (xy 27.396745 -398.019419) (xy 27.372984 -397.956318)
			(xy 27.356952 -397.890826) (xy 27.348879 -397.823885) (xy 8.839736 -397.823885) (xy 8.850142 -397.906253)
			(xy 8.858264 -398.035359) (xy 8.858264 -398.164721) (xy 8.850142 -398.293827) (xy 8.833928 -398.422169)
			(xy 8.809688 -398.549239) (xy 8.777518 -398.674536) (xy 8.737543 -398.797566) (xy 8.689921 -398.917844)
			(xy 8.634842 -399.034893) (xy 8.572521 -399.148254) (xy 8.503206 -399.257477) (xy 8.427169 -399.362133)
			(xy 8.344711 -399.461808) (xy 8.256157 -399.556108) (xy 8.161856 -399.644662) (xy 8.062181 -399.72712)
			(xy 7.957526 -399.803157) (xy 7.848302 -399.872472) (xy 7.734942 -399.934793) (xy 7.617892 -399.989872)
			(xy 7.497614 -400.037493) (xy 7.374584 -400.077468) (xy 7.249287 -400.109639) (xy 7.122217 -400.133879)
			(xy 6.993875 -400.150092) (xy 6.864769 -400.158214) (xy 6.800088 -400.158712) (xy 5.199888 -400.158712)
			(xy 5.135208 -400.158204) (xy 5.006102 -400.150081) (xy 4.877762 -400.133868) (xy 4.750692 -400.109628)
			(xy 4.625396 -400.077458) (xy 4.502366 -400.037483) (xy 4.38209 -399.989862) (xy 4.265041 -399.934783)
			(xy 4.151681 -399.872463) (xy 4.042458 -399.803148) (xy 3.937803 -399.727112) (xy 3.838129 -399.644654)
			(xy 3.743829 -399.556101) (xy 3.655276 -399.461801) (xy 3.572818 -399.362127) (xy 3.496782 -399.257472)
			(xy 3.427467 -399.148249) (xy 3.365147 -399.034889) (xy 3.310068 -398.91784) (xy 3.262447 -398.797564)
			(xy 3.222472 -398.674534) (xy 3.190302 -398.549238) (xy 3.166062 -398.422168) (xy 3.149849 -398.293828)
			(xy 3.141726 -398.164722) (xy 0.508 -398.164722) (xy 0.508 -401.723796) (xy 27.348891 -401.723796)
			(xy 27.348893 -401.656371) (xy 27.35697 -401.589432) (xy 27.373007 -401.523942) (xy 27.396773 -401.460844)
			(xy 27.427925 -401.401047) (xy 27.466015 -401.345412) (xy 27.48788 -401.319746) (xy 27.49368 -401.312603)
			(xy 27.500193 -401.295411) (xy 27.50058 -401.286218) (xy 27.50058 -400.793966) (xy 27.500191 -400.784777)
			(xy 27.493663 -400.767592) (xy 27.48788 -400.760438) (xy 27.466023 -400.734768) (xy 27.427935 -400.679133)
			(xy 27.396785 -400.619338) (xy 27.373022 -400.556241) (xy 27.356986 -400.490753) (xy 27.34891 -400.423816)
			(xy 27.34891 -400.356393) (xy 27.356985 -400.289456) (xy 27.373019 -400.223967) (xy 27.396782 -400.160871)
			(xy 27.42793 -400.101074) (xy 27.466017 -400.04544) (xy 27.48788 -400.019774) (xy 27.493668 -400.012622)
			(xy 27.500188 -399.995437) (xy 27.50058 -399.986246) (xy 27.50058 -399.828766) (xy 27.501 -399.818632)
			(xy 27.508746 -399.799903) (xy 27.523053 -399.785546) (xy 27.541756 -399.777735) (xy 27.551888 -399.777204)
			(xy 28.268168 -399.777204) (xy 28.278321 -399.777648) (xy 28.297073 -399.785433) (xy 28.311398 -399.799824)
			(xy 28.319098 -399.818612) (xy 28.319476 -399.828766) (xy 28.319476 -399.986246) (xy 28.319918 -399.99543)
			(xy 28.32641 -400.012614) (xy 28.332176 -400.019774) (xy 28.354047 -400.045434) (xy 28.392137 -400.101069)
			(xy 28.423289 -400.160865) (xy 28.447053 -400.223963) (xy 28.463089 -400.289453) (xy 28.471165 -400.356392)
			(xy 28.471165 -400.423817) (xy 28.463088 -400.490756) (xy 28.447051 -400.556246) (xy 28.423285 -400.619343)
			(xy 28.392132 -400.679139) (xy 28.354041 -400.734773) (xy 28.332176 -400.760438) (xy 28.326378 -400.767582)
			(xy 28.319865 -400.784774) (xy 28.319476 -400.793966) (xy 28.319476 -401.286218) (xy 28.319883 -401.295405)
			(xy 28.326399 -401.31259) (xy 28.332176 -401.319746) (xy 28.354019 -401.345429) (xy 28.39211 -401.40106)
			(xy 28.423263 -401.460854) (xy 28.446989 -401.523838) (xy 29.549051 -401.523838) (xy 29.549053 -401.456532)
			(xy 29.557098 -401.389708) (xy 29.573073 -401.324325) (xy 29.596747 -401.26132) (xy 29.627782 -401.201596)
			(xy 29.665732 -401.146008) (xy 29.68752 -401.120356) (xy 29.69332 -401.113213) (xy 29.699832 -401.096021)
			(xy 29.70022 -401.086828) (xy 29.70022 -400.92884) (xy 29.700655 -400.918686) (xy 29.708441 -400.899931)
			(xy 29.722834 -400.885605) (xy 29.741626 -400.877908) (xy 29.751782 -400.877532) (xy 30.468062 -400.877532)
			(xy 30.478185 -400.878058) (xy 30.496904 -400.885771) (xy 30.511261 -400.900046) (xy 30.519083 -400.91872)
			(xy 30.519624 -400.92884) (xy 30.519624 -401.086828) (xy 30.520015 -401.096017) (xy 30.526542 -401.113202)
			(xy 30.532324 -401.120356) (xy 30.554093 -401.146024) (xy 30.592045 -401.201607) (xy 30.623081 -401.261328)
			(xy 30.646757 -401.324331) (xy 30.662732 -401.389711) (xy 30.670778 -401.456533) (xy 30.67078 -401.523837)
			(xy 30.662738 -401.590659) (xy 30.646766 -401.65604) (xy 30.623093 -401.719044) (xy 30.620654 -401.723737)
			(xy 31.749186 -401.723737) (xy 31.749188 -401.65643) (xy 31.757235 -401.589605) (xy 31.773211 -401.524221)
			(xy 31.796887 -401.461216) (xy 31.827925 -401.401492) (xy 31.865878 -401.345906) (xy 31.887668 -401.320254)
			(xy 31.893475 -401.313116) (xy 31.899981 -401.29592) (xy 31.900368 -401.286726) (xy 31.900368 -400.793458)
			(xy 31.899963 -400.784271) (xy 31.893444 -400.767087) (xy 31.887668 -400.75993) (xy 31.865885 -400.734273)
			(xy 31.827935 -400.678688) (xy 31.796899 -400.618966) (xy 31.773225 -400.555962) (xy 31.757251 -400.49058)
			(xy 31.749206 -400.423757) (xy 31.749205 -400.356452) (xy 31.757249 -400.289629) (xy 31.773222 -400.224247)
			(xy 31.796896 -400.161243) (xy 31.82793 -400.10152) (xy 31.86588 -400.045934) (xy 31.887668 -400.020282)
			(xy 31.893463 -400.013136) (xy 31.899977 -399.995946) (xy 31.900368 -399.986754) (xy 31.900368 -399.828766)
			(xy 31.900806 -399.818602) (xy 31.908597 -399.799827) (xy 31.92298 -399.785462) (xy 31.941766 -399.777694)
			(xy 31.95193 -399.777204) (xy 32.66821 -399.777204) (xy 32.678364 -399.777725) (xy 32.697127 -399.785496)
			(xy 32.711491 -399.799853) (xy 32.719271 -399.818612) (xy 32.719772 -399.828766) (xy 32.719772 -399.986754)
			(xy 32.720211 -399.995938) (xy 32.726705 -400.013122) (xy 32.732472 -400.020282) (xy 32.754265 -400.045929)
			(xy 32.792213 -400.101517) (xy 32.823246 -400.161241) (xy 32.846918 -400.224246) (xy 32.86289 -400.289629)
			(xy 32.870933 -400.356452) (xy 32.870933 -400.423757) (xy 32.862888 -400.49058) (xy 32.846915 -400.555962)
			(xy 32.823242 -400.618967) (xy 32.792209 -400.678691) (xy 32.75426 -400.734278) (xy 32.732472 -400.75993)
			(xy 32.726677 -400.767076) (xy 32.720162 -400.784266) (xy 32.719772 -400.793458) (xy 32.719772 -401.286726)
			(xy 32.720176 -401.295914) (xy 32.726695 -401.313098) (xy 32.732472 -401.320254) (xy 32.754237 -401.345924)
			(xy 32.792186 -401.401508) (xy 32.82322 -401.46123) (xy 32.846893 -401.524232) (xy 32.862868 -401.589612)
			(xy 32.870913 -401.656432) (xy 32.870915 -401.723735) (xy 32.862873 -401.790556) (xy 32.846903 -401.855937)
			(xy 32.823233 -401.91894) (xy 32.792203 -401.978663) (xy 32.754258 -402.03425) (xy 32.732472 -402.059902)
			(xy 32.726688 -402.067056) (xy 32.720167 -402.08424) (xy 32.719772 -402.09343) (xy 32.719772 -402.251418)
			(xy 32.719282 -402.261576) (xy 32.711503 -402.280343) (xy 32.697137 -402.294708) (xy 32.678368 -402.302483)
			(xy 32.66821 -402.30298) (xy 31.95193 -402.30298) (xy 31.941763 -402.302512) (xy 31.922972 -402.29474)
			(xy 31.908587 -402.280368) (xy 31.900798 -402.261585) (xy 31.900368 -402.251418) (xy 31.900368 -402.09343)
			(xy 31.899928 -402.084246) (xy 31.893434 -402.067062) (xy 31.887668 -402.059902) (xy 31.865858 -402.034268)
			(xy 31.827908 -401.97868) (xy 31.796874 -401.918954) (xy 31.773201 -401.855947) (xy 31.757229 -401.790562)
			(xy 31.749186 -401.723737) (xy 30.620654 -401.723737) (xy 30.59206 -401.778767) (xy 30.554112 -401.834352)
			(xy 30.532324 -401.860004) (xy 30.526546 -401.867163) (xy 30.520019 -401.884343) (xy 30.519624 -401.893532)
			(xy 30.519624 -402.3868) (xy 30.520029 -402.395988) (xy 30.526546 -402.413172) (xy 30.532324 -402.420328)
			(xy 30.554114 -402.445978) (xy 30.592063 -402.501565) (xy 30.623097 -402.561289) (xy 30.64677 -402.624293)
			(xy 30.662743 -402.689676) (xy 30.670787 -402.756499) (xy 30.670787 -402.823804) (xy 30.670778 -402.823878)
			(xy 33.948799 -402.823878) (xy 33.948804 -402.75645) (xy 33.956885 -402.689508) (xy 33.972926 -402.624016)
			(xy 33.996696 -402.560917) (xy 34.027853 -402.50112) (xy 34.065949 -402.445485) (xy 34.087816 -402.41982)
			(xy 34.093631 -402.412688) (xy 34.100134 -402.395487) (xy 34.100516 -402.386292) (xy 34.100516 -401.89404)
			(xy 34.100083 -401.884855) (xy 34.093585 -401.867671) (xy 34.087816 -401.860512) (xy 34.065932 -401.834863)
			(xy 34.027843 -401.779227) (xy 33.996692 -401.719428) (xy 33.972928 -401.656329) (xy 33.956894 -401.590838)
			(xy 33.948819 -401.523898) (xy 33.948821 -401.456472) (xy 33.956899 -401.389532) (xy 33.972937 -401.324042)
			(xy 33.996704 -401.260944) (xy 34.027858 -401.201147) (xy 34.06595 -401.145513) (xy 34.087816 -401.119848)
			(xy 34.093619 -401.112707) (xy 34.100129 -401.095513) (xy 34.100516 -401.08632) (xy 34.100516 -400.92884)
			(xy 34.100949 -400.918718) (xy 34.108687 -400.900012) (xy 34.122999 -400.885696) (xy 34.141702 -400.877952)
			(xy 34.151824 -400.877532) (xy 34.868104 -400.877532) (xy 34.878231 -400.877914) (xy 34.89694 -400.885669)
			(xy 34.911256 -400.899997) (xy 34.918995 -400.918713) (xy 34.919412 -400.92884) (xy 34.919412 -401.08632)
			(xy 34.91981 -401.095509) (xy 34.926332 -401.112693) (xy 34.932112 -401.119848) (xy 34.953956 -401.14553)
			(xy 34.992044 -401.201162) (xy 35.023195 -401.260956) (xy 35.04696 -401.324051) (xy 35.062997 -401.389538)
			(xy 35.071074 -401.456474) (xy 35.071076 -401.523896) (xy 35.063002 -401.590833) (xy 35.046969 -401.65632)
			(xy 35.023208 -401.719416) (xy 35.020926 -401.723796) (xy 36.148978 -401.723796) (xy 36.14898 -401.656371)
			(xy 36.157058 -401.589432) (xy 36.173095 -401.523942) (xy 36.19686 -401.460845) (xy 36.228011 -401.401047)
			(xy 36.2661 -401.345412) (xy 36.287964 -401.319746) (xy 36.293774 -401.312611) (xy 36.300279 -401.295412)
			(xy 36.300664 -401.286218) (xy 36.300664 -400.793966) (xy 36.300256 -400.784779) (xy 36.293739 -400.767595)
			(xy 36.287964 -400.760438) (xy 36.266107 -400.734767) (xy 36.228021 -400.679133) (xy 36.196872 -400.619337)
			(xy 36.173109 -400.556241) (xy 36.157074 -400.490753) (xy 36.148998 -400.423816) (xy 36.148998 -400.356393)
			(xy 36.157072 -400.289456) (xy 36.173106 -400.223968) (xy 36.196868 -400.160871) (xy 36.228016 -400.101075)
			(xy 36.266102 -400.04544) (xy 36.287964 -400.019774) (xy 36.293762 -400.01263) (xy 36.300274 -399.995438)
			(xy 36.300664 -399.986246) (xy 36.300664 -399.828766) (xy 36.301099 -399.818634) (xy 36.308843 -399.799908)
			(xy 36.323145 -399.785552) (xy 36.341842 -399.777738) (xy 36.351972 -399.777204) (xy 37.068252 -399.777204)
			(xy 37.078404 -399.777661) (xy 37.097156 -399.785442) (xy 37.111481 -399.799828) (xy 37.119181 -399.818613)
			(xy 37.11956 -399.828766) (xy 37.11956 -399.986246) (xy 37.120005 -399.995429) (xy 37.126496 -400.012613)
			(xy 37.13226 -400.019774) (xy 37.154131 -400.045434) (xy 37.192222 -400.101068) (xy 37.223375 -400.160865)
			(xy 37.247141 -400.223962) (xy 37.263177 -400.289453) (xy 37.271253 -400.356392) (xy 37.271252 -400.423817)
			(xy 37.263175 -400.490756) (xy 37.247138 -400.556246) (xy 37.223371 -400.619344) (xy 37.192218 -400.67914)
			(xy 37.154126 -400.734773) (xy 37.13226 -400.760438) (xy 37.12646 -400.76758) (xy 37.119948 -400.784773)
			(xy 37.11956 -400.793966) (xy 37.11956 -401.286218) (xy 37.11997 -401.295405) (xy 37.126485 -401.312589)
			(xy 37.13226 -401.319746) (xy 37.154104 -401.345428) (xy 37.192196 -401.40106) (xy 37.22335 -401.460853)
			(xy 37.247117 -401.523948) (xy 37.263155 -401.589435) (xy 37.271233 -401.656372) (xy 37.271235 -401.723795)
			(xy 37.263161 -401.790732) (xy 37.247127 -401.856221) (xy 37.223363 -401.919317) (xy 37.192213 -401.979112)
			(xy 37.154124 -402.034745) (xy 37.13226 -402.06041) (xy 37.126472 -402.067561) (xy 37.119953 -402.084747)
			(xy 37.11956 -402.093938) (xy 37.11956 -402.251418) (xy 37.119088 -402.261546) (xy 37.111355 -402.280268)
			(xy 37.097064 -402.294623) (xy 37.078378 -402.302442) (xy 37.068252 -402.30298) (xy 36.351972 -402.30298)
			(xy 36.341814 -402.302601) (xy 36.323057 -402.294792) (xy 36.308734 -402.280383) (xy 36.301038 -402.261579)
			(xy 36.300664 -402.251418) (xy 36.300664 -402.093938) (xy 36.300221 -402.084755) (xy 36.293729 -402.067571)
			(xy 36.287964 -402.06041) (xy 36.26608 -402.034762) (xy 36.227994 -401.979124) (xy 36.196846 -401.919325)
			(xy 36.173085 -401.856226) (xy 36.157052 -401.790735) (xy 36.148978 -401.723796) (xy 35.020926 -401.723796)
			(xy 34.99206 -401.779212) (xy 34.953974 -401.834847) (xy 34.932112 -401.860512) (xy 34.926329 -401.867667)
			(xy 34.919806 -401.88485) (xy 34.919412 -401.89404) (xy 34.919412 -402.386292) (xy 34.919823 -402.395479)
			(xy 34.926336 -402.412664) (xy 34.932112 -402.41982) (xy 34.953928 -402.445524) (xy 34.992018 -402.501154)
			(xy 35.02317 -402.560944) (xy 35.046936 -402.624036) (xy 35.062975 -402.68952) (xy 35.071054 -402.756454)
			(xy 35.071059 -402.823818) (xy 38.349119 -402.823818) (xy 38.349123 -402.75651) (xy 38.357172 -402.689685)
			(xy 38.373149 -402.6243) (xy 38.396825 -402.561294) (xy 38.427862 -402.501569) (xy 38.465814 -402.445981)
			(xy 38.487604 -402.420328) (xy 38.493414 -402.413192) (xy 38.499921 -402.395995) (xy 38.500304 -402.3868)
			(xy 38.500304 -401.893532) (xy 38.499878 -401.884347) (xy 38.493375 -401.867162) (xy 38.487604 -401.860004)
			(xy 38.465798 -401.834368) (xy 38.427852 -401.778778) (xy 38.396821 -401.719052) (xy 38.373151 -401.656045)
			(xy 38.357181 -401.590662) (xy 38.349139 -401.523838) (xy 38.34914 -401.456532) (xy 38.357186 -401.389709)
			(xy 38.37316 -401.324326) (xy 38.396834 -401.261321) (xy 38.427867 -401.201596) (xy 38.465816 -401.146009)
			(xy 38.487604 -401.120356) (xy 38.493402 -401.113212) (xy 38.499916 -401.096021) (xy 38.500304 -401.086828)
			(xy 38.500304 -400.92884) (xy 38.500755 -400.918688) (xy 38.508538 -400.899936) (xy 38.522926 -400.885611)
			(xy 38.541712 -400.87791) (xy 38.551866 -400.877532) (xy 39.268146 -400.877532) (xy 39.278275 -400.877989)
			(xy 39.296995 -400.88573) (xy 39.31135 -400.900025) (xy 39.319169 -400.918714) (xy 39.319708 -400.92884)
			(xy 39.319708 -401.086828) (xy 39.320103 -401.096017) (xy 39.326627 -401.113201) (xy 39.332408 -401.120356)
			(xy 39.354178 -401.146024) (xy 39.392131 -401.201607) (xy 39.423168 -401.261328) (xy 39.446844 -401.32433)
			(xy 39.46282 -401.389711) (xy 39.470866 -401.456533) (xy 39.470868 -401.523837) (xy 39.462825 -401.590659)
			(xy 39.446853 -401.656041) (xy 39.42318 -401.719045) (xy 39.420711 -401.723797) (xy 40.548745 -401.723797)
			(xy 40.548747 -401.65637) (xy 40.556826 -401.58943) (xy 40.572865 -401.523939) (xy 40.596634 -401.460841)
			(xy 40.62779 -401.401044) (xy 40.665885 -401.34541) (xy 40.687752 -401.319746) (xy 40.69356 -401.312609)
			(xy 40.700067 -401.295412) (xy 40.700452 -401.286218) (xy 40.700452 -400.793966) (xy 40.700046 -400.784779)
			(xy 40.693528 -400.767595) (xy 40.687752 -400.760438) (xy 40.665892 -400.734769) (xy 40.6278 -400.679136)
			(xy 40.596646 -400.619341) (xy 40.572879 -400.556244) (xy 40.556842 -400.490755) (xy 40.548764 -400.423817)
			(xy 40.548764 -400.356392) (xy 40.55684 -400.289454) (xy 40.572876 -400.223964) (xy 40.596642 -400.160867)
			(xy 40.627795 -400.101072) (xy 40.665887 -400.045438) (xy 40.687752 -400.019774) (xy 40.693549 -400.012629)
			(xy 40.700062 -399.995438) (xy 40.700452 -399.986246) (xy 40.700452 -399.828766) (xy 40.700899 -399.818636)
			(xy 40.70864 -399.799911) (xy 40.722939 -399.785556) (xy 40.741632 -399.77774) (xy 40.75176 -399.777204)
			(xy 41.46804 -399.777204) (xy 41.478197 -399.777589) (xy 41.496951 -399.785399) (xy 41.511273 -399.799806)
			(xy 41.518971 -399.818606) (xy 41.519348 -399.828766) (xy 41.519348 -399.986246) (xy 41.519796 -399.995429)
			(xy 41.526285 -400.012613) (xy 41.532048 -400.019774) (xy 41.55392 -400.045433) (xy 41.592012 -400.101068)
			(xy 41.623165 -400.160864) (xy 41.646931 -400.223962) (xy 41.662968 -400.289452) (xy 41.671044 -400.356392)
			(xy 41.671043 -400.423817) (xy 41.662966 -400.490757) (xy 41.646928 -400.556247) (xy 41.623161 -400.619344)
			(xy 41.592007 -400.67914) (xy 41.553914 -400.734774) (xy 41.532048 -400.760438) (xy 41.526246 -400.767579)
			(xy 41.519736 -400.784773) (xy 41.519348 -400.793966) (xy 41.519348 -401.286218) (xy 41.519761 -401.295405)
			(xy 41.526274 -401.312588) (xy 41.532048 -401.319746) (xy 41.553892 -401.345428) (xy 41.591985 -401.401059)
			(xy 41.62314 -401.460852) (xy 41.646907 -401.523947) (xy 41.662946 -401.589435) (xy 41.671024 -401.656372)
			(xy 41.671026 -401.723795) (xy 41.662952 -401.790733) (xy 41.646917 -401.856221) (xy 41.623153 -401.919317)
			(xy 41.592002 -401.979113) (xy 41.553912 -402.034746) (xy 41.532048 -402.06041) (xy 41.526258 -402.06756)
			(xy 41.519741 -402.084747) (xy 41.519348 -402.093938) (xy 41.519348 -402.251418) (xy 41.518888 -402.261547)
			(xy 41.511152 -402.280271) (xy 41.496858 -402.294627) (xy 41.478167 -402.302444) (xy 41.46804 -402.30298)
			(xy 40.75176 -402.30298) (xy 40.741601 -402.302611) (xy 40.722844 -402.294798) (xy 40.708521 -402.280385)
			(xy 40.700826 -402.26158) (xy 40.700452 -402.251418) (xy 40.700452 -402.093938) (xy 40.700012 -402.084754)
			(xy 40.693518 -402.06757) (xy 40.687752 -402.06041) (xy 40.665865 -402.034763) (xy 40.627773 -401.979127)
			(xy 40.59662 -401.919329) (xy 40.572855 -401.85623) (xy 40.55682 -401.790738) (xy 40.548745 -401.723797)
			(xy 39.420711 -401.723797) (xy 39.392146 -401.778768) (xy 39.354196 -401.834353) (xy 39.332408 -401.860004)
			(xy 39.326628 -401.867161) (xy 39.320103 -401.884342) (xy 39.319708 -401.893532) (xy 39.319708 -402.3868)
			(xy 39.320116 -402.395987) (xy 39.326631 -402.413172) (xy 39.332408 -402.420328) (xy 39.35415 -402.446018)
			(xy 39.392104 -402.501598) (xy 39.423142 -402.561316) (xy 39.44682 -402.624315) (xy 39.462798 -402.689694)
			(xy 39.470847 -402.756513) (xy 39.470851 -402.823815) (xy 39.470843 -402.823878) (xy 42.748887 -402.823878)
			(xy 42.748892 -402.75645) (xy 42.756972 -402.689509) (xy 42.773013 -402.624017) (xy 42.796782 -402.560918)
			(xy 42.827939 -402.501121) (xy 42.866033 -402.445485) (xy 42.8879 -402.41982) (xy 42.893713 -402.412686)
			(xy 42.900218 -402.395487) (xy 42.9006 -402.386292) (xy 42.9006 -401.89404) (xy 42.900171 -401.884855)
			(xy 42.89367 -401.86767) (xy 42.8879 -401.860512) (xy 42.866016 -401.834863) (xy 42.827928 -401.779226)
			(xy 42.796778 -401.719428) (xy 42.773015 -401.656329) (xy 42.756981 -401.590838) (xy 42.748907 -401.523898)
			(xy 42.748909 -401.456472) (xy 42.756987 -401.389533) (xy 42.773024 -401.324043) (xy 42.796791 -401.260945)
			(xy 42.827944 -401.201148) (xy 42.866035 -401.145513) (xy 42.8879 -401.119848) (xy 42.893701 -401.112706)
			(xy 42.900213 -401.095513) (xy 42.9006 -401.08632) (xy 42.9006 -400.92884) (xy 42.901049 -400.91872)
			(xy 42.908784 -400.900017) (xy 42.923091 -400.885702) (xy 42.941788 -400.877955) (xy 42.951908 -400.877532)
			(xy 43.668188 -400.877532) (xy 43.678314 -400.877927) (xy 43.697023 -400.885677) (xy 43.711339 -400.9)
			(xy 43.719079 -400.918714) (xy 43.719496 -400.92884) (xy 43.719496 -401.08632) (xy 43.719897 -401.095508)
			(xy 43.726417 -401.112692) (xy 43.732196 -401.119848) (xy 43.75404 -401.145529) (xy 43.79213 -401.201162)
			(xy 43.823282 -401.260955) (xy 43.847047 -401.32405) (xy 43.863084 -401.389537) (xy 43.871162 -401.456474)
			(xy 43.871164 -401.523896) (xy 43.86309 -401.590833) (xy 43.847056 -401.656321) (xy 43.823294 -401.719417)
			(xy 43.821044 -401.723737) (xy 44.949064 -401.723737) (xy 44.949066 -401.65643) (xy 44.957113 -401.589606)
			(xy 44.973088 -401.524222) (xy 44.996763 -401.461217) (xy 45.027799 -401.401493) (xy 45.065751 -401.345906)
			(xy 45.08754 -401.320254) (xy 45.093344 -401.313114) (xy 45.099853 -401.295919) (xy 45.10024 -401.286726)
			(xy 45.10024 -400.793458) (xy 45.099841 -400.78427) (xy 45.093319 -400.767086) (xy 45.08754 -400.75993)
			(xy 45.065758 -400.734273) (xy 45.027809 -400.678687) (xy 44.996776 -400.618964) (xy 44.973103 -400.55596)
			(xy 44.957129 -400.490579) (xy 44.949085 -400.423757) (xy 44.949084 -400.356452) (xy 44.957128 -400.28963)
			(xy 44.9731 -400.224248) (xy 44.996772 -400.161244) (xy 45.027805 -400.101521) (xy 45.065753 -400.045934)
			(xy 45.08754 -400.020282) (xy 45.093332 -400.013134) (xy 45.099848 -399.995945) (xy 45.10024 -399.986754)
			(xy 45.10024 -399.828766) (xy 45.100706 -399.818606) (xy 45.108492 -399.799835) (xy 45.122866 -399.785471)
			(xy 45.141641 -399.777698) (xy 45.151802 -399.777204) (xy 45.868082 -399.777204) (xy 45.878234 -399.777747)
			(xy 45.896997 -399.785509) (xy 45.911361 -399.79986) (xy 45.919143 -399.818614) (xy 45.919644 -399.828766)
			(xy 45.919644 -399.986754) (xy 45.920089 -399.995937) (xy 45.92658 -400.013121) (xy 45.932344 -400.020282)
			(xy 45.954138 -400.045929) (xy 45.992088 -400.101516) (xy 46.023122 -400.16124) (xy 46.046795 -400.224245)
			(xy 46.062768 -400.289628) (xy 46.070812 -400.356452) (xy 46.070811 -400.423757) (xy 46.062766 -400.490581)
			(xy 46.046792 -400.555963) (xy 46.023118 -400.618968) (xy 45.992083 -400.678692) (xy 45.954132 -400.734278)
			(xy 45.932344 -400.75993) (xy 45.926545 -400.767073) (xy 45.920033 -400.784266) (xy 45.919644 -400.793458)
			(xy 45.919644 -401.286726) (xy 45.920054 -401.295913) (xy 45.926569 -401.313097) (xy 45.932344 -401.320254)
			(xy 45.95411 -401.345924) (xy 45.992061 -401.401507) (xy 46.023096 -401.461228) (xy 46.046771 -401.524231)
			(xy 46.062746 -401.589611) (xy 46.070792 -401.656432) (xy 46.070794 -401.723735) (xy 46.062752 -401.790557)
			(xy 46.046781 -401.855938) (xy 46.02311 -401.918941) (xy 45.992078 -401.978664) (xy 45.954131 -402.03425)
			(xy 45.932344 -402.059902) (xy 45.926557 -402.067054) (xy 45.920038 -402.084239) (xy 45.919644 -402.09343)
			(xy 45.919644 -402.251418) (xy 45.919181 -402.261579) (xy 45.911397 -402.280352) (xy 45.897022 -402.294718)
			(xy 45.878244 -402.302488) (xy 45.868082 -402.30298) (xy 45.151802 -402.30298) (xy 45.141647 -402.302465)
			(xy 45.122881 -402.294695) (xy 45.108516 -402.280336) (xy 45.100739 -402.261573) (xy 45.10024 -402.251418)
			(xy 45.10024 -402.09343) (xy 45.099806 -402.084246) (xy 45.093308 -402.067061) (xy 45.08754 -402.059902)
			(xy 45.06573 -402.034268) (xy 45.027782 -401.978679) (xy 44.99675 -401.918953) (xy 44.973078 -401.855946)
			(xy 44.957107 -401.790561) (xy 44.949064 -401.723737) (xy 43.821044 -401.723737) (xy 43.792146 -401.779213)
			(xy 43.754059 -401.834847) (xy 43.732196 -401.860512) (xy 43.726411 -401.867666) (xy 43.71989 -401.88485)
			(xy 43.719496 -401.89404) (xy 43.719496 -402.386292) (xy 43.719911 -402.395479) (xy 43.726421 -402.412663)
			(xy 43.732196 -402.41982) (xy 43.754013 -402.445524) (xy 43.792103 -402.501153) (xy 43.823256 -402.560944)
			(xy 43.847023 -402.624036) (xy 43.863062 -402.68952) (xy 43.871142 -402.756454) (xy 43.871146 -402.823874)
			(xy 43.863075 -402.890809) (xy 43.847045 -402.956295) (xy 43.823286 -403.01939) (xy 43.792141 -403.079185)
			(xy 43.754057 -403.134819) (xy 43.732196 -403.160484) (xy 43.726381 -403.167616) (xy 43.719877 -403.184817)
			(xy 43.719496 -403.194012) (xy 43.719496 -403.351492) (xy 43.719077 -403.361614) (xy 43.711331 -403.380319)
			(xy 43.697015 -403.394633) (xy 43.67831 -403.402378) (xy 43.668188 -403.4028) (xy 42.951908 -403.4028)
			(xy 42.941786 -403.402377) (xy 42.923083 -403.394632) (xy 42.908768 -403.380317) (xy 42.901023 -403.361614)
			(xy 42.9006 -403.351492) (xy 42.9006 -403.194012) (xy 42.900184 -403.184825) (xy 42.893674 -403.167641)
			(xy 42.8879 -403.160484) (xy 42.865989 -403.134858) (xy 42.827902 -403.079218) (xy 42.796753 -403.019416)
			(xy 42.772992 -402.956314) (xy 42.756959 -402.89082) (xy 42.748887 -402.823878) (xy 39.470843 -402.823878)
			(xy 39.462811 -402.890635) (xy 39.446841 -402.956016) (xy 39.423172 -403.019018) (xy 39.392141 -403.07874)
			(xy 39.354194 -403.134325) (xy 39.332408 -403.159976) (xy 39.326598 -403.167111) (xy 39.320091 -403.184309)
			(xy 39.319708 -403.193504) (xy 39.319708 -403.351492) (xy 39.319272 -403.361645) (xy 39.311481 -403.380395)
			(xy 39.297088 -403.394719) (xy 39.278301 -403.40242) (xy 39.268146 -403.4028) (xy 38.551866 -403.4028)
			(xy 38.541742 -403.402303) (xy 38.523028 -403.394571) (xy 38.508674 -403.380289) (xy 38.500849 -403.361613)
			(xy 38.500304 -403.351492) (xy 38.500304 -403.193504) (xy 38.499891 -403.184317) (xy 38.493379 -403.167133)
			(xy 38.487604 -403.159976) (xy 38.46577 -403.134362) (xy 38.427825 -403.078769) (xy 38.396796 -403.01904)
			(xy 38.373127 -402.956031) (xy 38.357159 -402.890644) (xy 38.349119 -402.823818) (xy 35.071059 -402.823818)
			(xy 35.071059 -402.823874) (xy 35.062988 -402.890809) (xy 35.046958 -402.956295) (xy 35.023199 -403.01939)
			(xy 34.992055 -403.079185) (xy 34.953973 -403.134819) (xy 34.932112 -403.160484) (xy 34.926299 -403.167617)
			(xy 34.919794 -403.184817) (xy 34.919412 -403.194012) (xy 34.919412 -403.351492) (xy 34.918978 -403.361612)
			(xy 34.911234 -403.380314) (xy 34.896924 -403.394628) (xy 34.878224 -403.402375) (xy 34.868104 -403.4028)
			(xy 34.151824 -403.4028) (xy 34.141703 -403.402365) (xy 34.123 -403.394624) (xy 34.108685 -403.380314)
			(xy 34.100939 -403.361613) (xy 34.100516 -403.351492) (xy 34.100516 -403.194012) (xy 34.100096 -403.184826)
			(xy 34.093589 -403.167642) (xy 34.087816 -403.160484) (xy 34.065904 -403.134858) (xy 34.027816 -403.079218)
			(xy 33.996666 -403.019417) (xy 33.972904 -402.956315) (xy 33.956872 -402.890821) (xy 33.948799 -402.823878)
			(xy 30.670778 -402.823878) (xy 30.662742 -402.890627) (xy 30.646769 -402.956009) (xy 30.623096 -403.019014)
			(xy 30.592062 -403.078738) (xy 30.554112 -403.134324) (xy 30.532324 -403.159976) (xy 30.526515 -403.167113)
			(xy 30.520007 -403.18431) (xy 30.519624 -403.193504) (xy 30.519624 -403.351492) (xy 30.519172 -403.361643)
			(xy 30.511384 -403.38039) (xy 30.496997 -403.394713) (xy 30.478214 -403.402417) (xy 30.468062 -403.4028)
			(xy 29.751782 -403.4028) (xy 29.741659 -403.40229) (xy 29.722945 -403.394563) (xy 29.708591 -403.380285)
			(xy 29.700765 -403.361612) (xy 29.70022 -403.351492) (xy 29.70022 -403.193504) (xy 29.699804 -403.184318)
			(xy 29.693294 -403.167133) (xy 29.68752 -403.159976) (xy 29.665734 -403.134322) (xy 29.627785 -403.078736)
			(xy 29.596752 -403.019013) (xy 29.573079 -402.956008) (xy 29.557106 -402.890626) (xy 29.549061 -402.823804)
			(xy 29.549061 -402.756499) (xy 29.557105 -402.689677) (xy 29.573078 -402.624294) (xy 29.59675 -402.56129)
			(xy 29.627784 -402.501566) (xy 29.665732 -402.44598) (xy 29.68752 -402.420328) (xy 29.693332 -402.413194)
			(xy 29.699837 -402.395995) (xy 29.70022 -402.3868) (xy 29.70022 -401.893532) (xy 29.69979 -401.884347)
			(xy 29.69329 -401.867163) (xy 29.68752 -401.860004) (xy 29.665713 -401.834368) (xy 29.627766 -401.778779)
			(xy 29.596735 -401.719053) (xy 29.573064 -401.656046) (xy 29.557093 -401.590662) (xy 29.549051 -401.523838)
			(xy 28.446989 -401.523838) (xy 28.44703 -401.523948) (xy 28.463067 -401.589436) (xy 28.471145 -401.656372)
			(xy 28.471147 -401.723795) (xy 28.463073 -401.790732) (xy 28.447039 -401.85622) (xy 28.423277 -401.919316)
			(xy 28.392127 -401.979111) (xy 28.354039 -402.034745) (xy 28.332176 -402.06041) (xy 28.32639 -402.067562)
			(xy 28.31987 -402.084748) (xy 28.319476 -402.093938) (xy 28.319476 -402.251418) (xy 28.318989 -402.261544)
			(xy 28.311258 -402.280263) (xy 28.296972 -402.294618) (xy 28.278291 -402.302439) (xy 28.268168 -402.30298)
			(xy 27.551888 -402.30298) (xy 27.541731 -402.302588) (xy 27.522974 -402.294785) (xy 27.50865 -402.280379)
			(xy 27.500954 -402.261578) (xy 27.50058 -402.251418) (xy 27.50058 -402.093938) (xy 27.500156 -402.084752)
			(xy 27.493653 -402.067567) (xy 27.48788 -402.06041) (xy 27.465995 -402.034762) (xy 27.427908 -401.979125)
			(xy 27.39676 -401.919326) (xy 27.372998 -401.856227) (xy 27.356964 -401.790736) (xy 27.348891 -401.723796)
			(xy 0.508 -401.723796) (xy 0.508 -405.623707) (xy 27.348902 -405.623707) (xy 27.348902 -405.556284)
			(xy 27.356979 -405.489345) (xy 27.373014 -405.423856) (xy 27.396778 -405.360759) (xy 27.427928 -405.300963)
			(xy 27.466016 -405.245328) (xy 27.48788 -405.219662) (xy 27.493673 -405.212514) (xy 27.50019 -405.195326)
			(xy 27.50058 -405.186134) (xy 27.50058 -404.693882) (xy 27.500183 -404.684693) (xy 27.493661 -404.667509)
			(xy 27.48788 -404.660354) (xy 27.466038 -404.634671) (xy 27.42795 -404.579038) (xy 27.3968 -404.519244)
			(xy 27.373035 -404.45615) (xy 27.356999 -404.390663) (xy 27.348922 -404.323727) (xy 27.34892 -404.256306)
			(xy 27.356993 -404.189369) (xy 27.373025 -404.123882) (xy 27.396786 -404.060786) (xy 27.427933 -404.00099)
			(xy 27.466018 -403.945356) (xy 27.48788 -403.91969) (xy 27.493661 -403.912534) (xy 27.500186 -403.895352)
			(xy 27.50058 -403.886162) (xy 27.50058 -403.728682) (xy 27.501013 -403.718549) (xy 27.508754 -403.69982)
			(xy 27.523057 -403.685463) (xy 27.541757 -403.677651) (xy 27.551888 -403.67712) (xy 28.268168 -403.67712)
			(xy 28.278323 -403.677548) (xy 28.297078 -403.685337) (xy 28.311404 -403.699732) (xy 28.319101 -403.718525)
			(xy 28.319476 -403.728682) (xy 28.319476 -403.886162) (xy 28.31991 -403.895347) (xy 28.326408 -403.912531)
			(xy 28.332176 -403.91969) (xy 28.354062 -403.945337) (xy 28.392152 -404.000974) (xy 28.423303 -404.060772)
			(xy 28.447067 -404.123871) (xy 28.463102 -404.189363) (xy 28.471176 -404.256304) (xy 28.471174 -404.323729)
			(xy 28.463096 -404.39067) (xy 28.447057 -404.45616) (xy 28.42329 -404.519258) (xy 28.392135 -404.579055)
			(xy 28.354042 -404.634689) (xy 28.332176 -404.660354) (xy 28.326371 -404.667493) (xy 28.319862 -404.684688)
			(xy 28.319476 -404.693882) (xy 28.319476 -405.186134) (xy 28.319875 -405.195322) (xy 28.326397 -405.212506)
			(xy 28.332176 -405.219662) (xy 28.354035 -405.245332) (xy 28.392125 -405.300965) (xy 28.423278 -405.36076)
			(xy 28.447043 -405.423857) (xy 28.46308 -405.489345) (xy 28.471157 -405.556284) (xy 28.471157 -405.623707)
			(xy 28.463081 -405.690646) (xy 28.447046 -405.756135) (xy 28.423281 -405.819231) (xy 28.39213 -405.879027)
			(xy 28.35404 -405.934661) (xy 28.332176 -405.960326) (xy 28.326383 -405.967474) (xy 28.319867 -405.984662)
			(xy 28.319476 -405.993854) (xy 28.319476 -406.151334) (xy 28.319002 -406.161461) (xy 28.311266 -406.18018)
			(xy 28.296976 -406.194534) (xy 28.278293 -406.202355) (xy 28.268168 -406.202896) (xy 27.551888 -406.202896)
			(xy 27.541733 -406.202488) (xy 27.522979 -406.194688) (xy 27.508656 -406.180287) (xy 27.500957 -406.161492)
			(xy 27.50058 -406.151334) (xy 27.50058 -405.993854) (xy 27.500148 -405.984669) (xy 27.49365 -405.967484)
			(xy 27.48788 -405.960326) (xy 27.466011 -405.934665) (xy 27.427924 -405.87903) (xy 27.396774 -405.819233)
			(xy 27.373011 -405.756135) (xy 27.356977 -405.690646) (xy 27.348902 -405.623707) (xy 0.508 -405.623707)
			(xy 0.508 -406.72373) (xy 29.549042 -406.72373) (xy 29.549045 -406.656422) (xy 29.557092 -406.589598)
			(xy 29.573068 -406.524214) (xy 29.596744 -406.461208) (xy 29.627779 -406.401484) (xy 29.665731 -406.345896)
			(xy 29.68752 -406.320244) (xy 29.693325 -406.313105) (xy 29.699834 -406.29591) (xy 29.70022 -406.286716)
			(xy 29.70022 -405.793448) (xy 29.699782 -405.784264) (xy 29.693287 -405.767079) (xy 29.68752 -405.75992)
			(xy 29.665729 -405.734271) (xy 29.627781 -405.678684) (xy 29.596749 -405.618959) (xy 29.573078 -405.555955)
			(xy 29.557105 -405.490572) (xy 29.549062 -405.423749) (xy 29.549062 -405.356444) (xy 29.557107 -405.289622)
			(xy 29.573079 -405.22424) (xy 29.596752 -405.161235) (xy 29.627784 -405.101511) (xy 29.665733 -405.045924)
			(xy 29.68752 -405.020272) (xy 29.693313 -405.013125) (xy 29.699829 -404.995936) (xy 29.70022 -404.986744)
			(xy 29.70022 -404.828756) (xy 29.700586 -404.818597) (xy 29.7084 -404.799839) (xy 29.722814 -404.785517)
			(xy 29.74162 -404.777822) (xy 29.751782 -404.777448) (xy 30.468062 -404.777448) (xy 30.478187 -404.777958)
			(xy 30.496909 -404.785675) (xy 30.511267 -404.799954) (xy 30.519086 -404.818634) (xy 30.519624 -404.828756)
			(xy 30.519624 -404.986744) (xy 30.520008 -404.995934) (xy 30.526539 -405.013118) (xy 30.532324 -405.020272)
			(xy 30.554109 -405.045927) (xy 30.59206 -405.101512) (xy 30.623096 -405.161235) (xy 30.64677 -405.224239)
			(xy 30.662745 -405.289621) (xy 30.67079 -405.356444) (xy 30.67079 -405.42375) (xy 30.662746 -405.490573)
			(xy 30.646772 -405.555955) (xy 30.623098 -405.61896) (xy 30.620661 -405.623649) (xy 31.749197 -405.623649)
			(xy 31.749198 -405.556342) (xy 31.757243 -405.489519) (xy 31.773217 -405.424136) (xy 31.796892 -405.361131)
			(xy 31.827928 -405.301408) (xy 31.865879 -405.245822) (xy 31.887668 -405.22017) (xy 31.893468 -405.213028)
			(xy 31.899979 -405.195835) (xy 31.900368 -405.186642) (xy 31.900368 -404.693374) (xy 31.899955 -404.684187)
			(xy 31.893441 -404.667004) (xy 31.887668 -404.659846) (xy 31.865901 -404.634176) (xy 31.82795 -404.578593)
			(xy 31.796914 -404.518872) (xy 31.773239 -404.45587) (xy 31.757263 -404.39049) (xy 31.749217 -404.323668)
			(xy 31.749215 -404.256365) (xy 31.757257 -404.189543) (xy 31.773229 -404.124162) (xy 31.7969 -404.061158)
			(xy 31.827933 -404.001435) (xy 31.865881 -403.94585) (xy 31.887668 -403.920198) (xy 31.893456 -403.913047)
			(xy 31.899974 -403.895861) (xy 31.900368 -403.88667) (xy 31.900368 -403.728682) (xy 31.90075 -403.718506)
			(xy 31.908547 -403.699705) (xy 31.922945 -403.68532) (xy 31.941753 -403.677541) (xy 31.95193 -403.67712)
			(xy 32.66821 -403.67712) (xy 32.678366 -403.677625) (xy 32.697132 -403.685399) (xy 32.711496 -403.699761)
			(xy 32.719273 -403.718526) (xy 32.719772 -403.728682) (xy 32.719772 -403.88667) (xy 32.720203 -403.895855)
			(xy 32.726703 -403.913039) (xy 32.732472 -403.920198) (xy 32.754281 -403.945832) (xy 32.792229 -404.001422)
			(xy 32.82326 -404.061148) (xy 32.846931 -404.124155) (xy 32.862902 -404.189539) (xy 32.870945 -404.256363)
			(xy 32.870943 -404.32367) (xy 32.862897 -404.390494) (xy 32.846922 -404.455877) (xy 32.823247 -404.518882)
			(xy 32.792212 -404.578607) (xy 32.754261 -404.634194) (xy 32.732472 -404.659846) (xy 32.72667 -404.666987)
			(xy 32.720159 -404.684181) (xy 32.719772 -404.693374) (xy 32.719772 -405.186642) (xy 32.720168 -405.195831)
			(xy 32.726692 -405.213014) (xy 32.732472 -405.22017) (xy 32.754254 -405.245827) (xy 32.792202 -405.301413)
			(xy 32.823235 -405.361136) (xy 32.846907 -405.42414) (xy 32.862881 -405.489521) (xy 32.870925 -405.556343)
			(xy 32.870926 -405.623648) (xy 32.862882 -405.69047) (xy 32.84691 -405.755851) (xy 32.823239 -405.818856)
			(xy 32.792207 -405.878579) (xy 32.754259 -405.934166) (xy 32.732472 -405.959818) (xy 32.726682 -405.966967)
			(xy 32.720164 -405.984155) (xy 32.719772 -405.993346) (xy 32.719772 -406.151334) (xy 32.719295 -406.161493)
			(xy 32.711511 -406.180261) (xy 32.697141 -406.194624) (xy 32.678369 -406.202399) (xy 32.66821 -406.202896)
			(xy 31.95193 -406.202896) (xy 31.941778 -406.202343) (xy 31.923016 -406.194585) (xy 31.908651 -406.180237)
			(xy 31.900869 -406.161485) (xy 31.900368 -406.151334) (xy 31.900368 -405.993346) (xy 31.899921 -405.984163)
			(xy 31.893431 -405.966979) (xy 31.887668 -405.959818) (xy 31.865874 -405.934171) (xy 31.827923 -405.878584)
			(xy 31.796888 -405.81886) (xy 31.773215 -405.755855) (xy 31.757241 -405.690472) (xy 31.749197 -405.623649)
			(xy 30.620661 -405.623649) (xy 30.592063 -405.678683) (xy 30.554113 -405.734268) (xy 30.532324 -405.75992)
			(xy 30.526539 -405.767074) (xy 30.520017 -405.784258) (xy 30.519624 -405.793448) (xy 30.519624 -406.286716)
			(xy 30.520021 -406.295905) (xy 30.526543 -406.313089) (xy 30.532324 -406.320244) (xy 30.554081 -406.345922)
			(xy 30.592034 -406.401503) (xy 30.62307 -406.461223) (xy 30.646746 -406.524224) (xy 30.662723 -406.589604)
			(xy 30.67077 -406.656424) (xy 30.670773 -406.723728) (xy 30.670766 -406.723789) (xy 33.948811 -406.723789)
			(xy 33.948814 -406.656363) (xy 33.956893 -406.589422) (xy 33.972932 -406.523931) (xy 33.996701 -406.460833)
			(xy 34.027856 -406.401036) (xy 34.06595 -406.345401) (xy 34.087816 -406.319736) (xy 34.093624 -406.312599)
			(xy 34.100131 -406.295402) (xy 34.100516 -406.286208) (xy 34.100516 -405.793956) (xy 34.100123 -405.784767)
			(xy 34.093597 -405.767583) (xy 34.087816 -405.760428) (xy 34.065948 -405.734766) (xy 34.027858 -405.679132)
			(xy 33.996706 -405.619335) (xy 33.972942 -405.556238) (xy 33.956906 -405.490748) (xy 33.94883 -405.423809)
			(xy 33.948831 -405.356385) (xy 33.956907 -405.289446) (xy 33.972944 -405.223957) (xy 33.996709 -405.160859)
			(xy 34.027861 -405.101063) (xy 34.065951 -405.045429) (xy 34.087816 -405.019764) (xy 34.093612 -405.012619)
			(xy 34.100127 -404.995428) (xy 34.100516 -404.986236) (xy 34.100516 -404.828756) (xy 34.10095 -404.818642)
			(xy 34.108705 -404.79996) (xy 34.123017 -404.785666) (xy 34.14171 -404.777936) (xy 34.151824 -404.777448)
			(xy 34.868104 -404.777448) (xy 34.878207 -404.777981) (xy 34.896875 -404.78571) (xy 34.911168 -404.799992)
			(xy 34.918911 -404.818654) (xy 34.919412 -404.828756) (xy 34.919412 -404.986236) (xy 34.919802 -404.995425)
			(xy 34.926329 -405.01261) (xy 34.932112 -405.019764) (xy 34.953972 -405.045433) (xy 34.99206 -405.101067)
			(xy 35.02321 -405.160863) (xy 35.046974 -405.223959) (xy 35.063009 -405.289448) (xy 35.071085 -405.356385)
			(xy 35.071085 -405.423809) (xy 35.06301 -405.490746) (xy 35.046976 -405.556235) (xy 35.023212 -405.619332)
			(xy 35.020933 -405.623707) (xy 36.14899 -405.623707) (xy 36.14899 -405.556284) (xy 36.157066 -405.489346)
			(xy 36.173101 -405.423857) (xy 36.196864 -405.36076) (xy 36.228014 -405.300963) (xy 36.266101 -405.245328)
			(xy 36.287964 -405.219662) (xy 36.293767 -405.212522) (xy 36.300276 -405.195327) (xy 36.300664 -405.186134)
			(xy 36.300664 -404.693882) (xy 36.300248 -404.684696) (xy 36.293737 -404.667512) (xy 36.287964 -404.660354)
			(xy 36.266123 -404.63467) (xy 36.228036 -404.579038) (xy 36.196886 -404.519244) (xy 36.173122 -404.456149)
			(xy 36.157087 -404.390663) (xy 36.149009 -404.323727) (xy 36.149007 -404.256306) (xy 36.157081 -404.18937)
			(xy 36.173113 -404.123882) (xy 36.196873 -404.060787) (xy 36.228019 -404.000991) (xy 36.266103 -403.945356)
			(xy 36.287964 -403.91969) (xy 36.293755 -403.912541) (xy 36.300271 -403.895353) (xy 36.300664 -403.886162)
			(xy 36.300664 -403.728682) (xy 36.301112 -403.718551) (xy 36.30885 -403.699825) (xy 36.323149 -403.685468)
			(xy 36.341843 -403.677654) (xy 36.351972 -403.67712) (xy 37.068252 -403.67712) (xy 37.078405 -403.677561)
			(xy 37.097161 -403.685345) (xy 37.111486 -403.699736) (xy 37.119184 -403.718527) (xy 37.11956 -403.728682)
			(xy 37.11956 -403.886162) (xy 37.119998 -403.895346) (xy 37.126493 -403.91253) (xy 37.13226 -403.91969)
			(xy 37.154147 -403.945337) (xy 37.192238 -404.000973) (xy 37.22339 -404.060771) (xy 37.247154 -404.123871)
			(xy 37.26319 -404.189362) (xy 37.271264 -404.256303) (xy 37.271262 -404.32373) (xy 37.263184 -404.39067)
			(xy 37.247145 -404.456161) (xy 37.223376 -404.519259) (xy 37.192221 -404.579055) (xy 37.154127 -404.634689)
			(xy 37.13226 -404.660354) (xy 37.126453 -404.667492) (xy 37.119946 -404.684688) (xy 37.11956 -404.693882)
			(xy 37.11956 -405.186134) (xy 37.119963 -405.195322) (xy 37.126483 -405.212506) (xy 37.13226 -405.219662)
			(xy 37.154119 -405.245331) (xy 37.192211 -405.300964) (xy 37.223364 -405.36076) (xy 37.24713 -405.423856)
			(xy 37.263168 -405.489345) (xy 37.271245 -405.556284) (xy 37.271245 -405.623707) (xy 37.263169 -405.690646)
			(xy 37.247133 -405.756135) (xy 37.223368 -405.819232) (xy 37.192216 -405.879028) (xy 37.154125 -405.934661)
			(xy 37.13226 -405.960326) (xy 37.126465 -405.967472) (xy 37.11995 -405.984662) (xy 37.11956 -405.993854)
			(xy 37.11956 -406.151334) (xy 37.119101 -406.161463) (xy 37.111362 -406.180185) (xy 37.097068 -406.19454)
			(xy 37.078379 -406.202358) (xy 37.068252 -406.202896) (xy 36.351972 -406.202896) (xy 36.341816 -406.202501)
			(xy 36.323062 -406.194696) (xy 36.308739 -406.180291) (xy 36.301041 -406.161493) (xy 36.300664 -406.151334)
			(xy 36.300664 -405.993854) (xy 36.300214 -405.984671) (xy 36.293726 -405.967487) (xy 36.287964 -405.960326)
			(xy 36.266095 -405.934665) (xy 36.228009 -405.879029) (xy 36.196861 -405.819232) (xy 36.173099 -405.756135)
			(xy 36.157065 -405.690645) (xy 36.14899 -405.623707) (xy 35.020933 -405.623707) (xy 34.992063 -405.679128)
			(xy 34.953975 -405.734763) (xy 34.932112 -405.760428) (xy 34.926322 -405.767578) (xy 34.919803 -405.784765)
			(xy 34.919412 -405.793956) (xy 34.919412 -406.286208) (xy 34.919816 -406.295396) (xy 34.926334 -406.31258)
			(xy 34.932112 -406.319736) (xy 34.953944 -406.345427) (xy 34.992033 -406.401058) (xy 35.023184 -406.460851)
			(xy 35.04695 -406.523945) (xy 35.062987 -406.58943) (xy 35.071065 -406.656366) (xy 35.071068 -406.723729)
			(xy 38.34913 -406.723729) (xy 38.349133 -406.656422) (xy 38.35718 -406.589598) (xy 38.373155 -406.524215)
			(xy 38.39683 -406.461209) (xy 38.427865 -406.401484) (xy 38.465815 -406.345897) (xy 38.487604 -406.320244)
			(xy 38.493407 -406.313104) (xy 38.499918 -406.295909) (xy 38.500304 -406.286716) (xy 38.500304 -405.793448)
			(xy 38.49987 -405.784263) (xy 38.493373 -405.767079) (xy 38.487604 -405.75992) (xy 38.465813 -405.734271)
			(xy 38.427867 -405.678683) (xy 38.396836 -405.618959) (xy 38.373165 -405.555954) (xy 38.357193 -405.490572)
			(xy 38.34915 -405.423749) (xy 38.34915 -405.356445) (xy 38.357194 -405.289622) (xy 38.373167 -405.22424)
			(xy 38.396838 -405.161236) (xy 38.42787 -405.101512) (xy 38.465817 -405.045925) (xy 38.487604 -405.020272)
			(xy 38.493395 -405.013123) (xy 38.499913 -404.995935) (xy 38.500304 -404.986744) (xy 38.500304 -404.828756)
			(xy 38.500686 -404.818599) (xy 38.508497 -404.799844) (xy 38.522905 -404.785523) (xy 38.541706 -404.777825)
			(xy 38.551866 -404.777448) (xy 39.268146 -404.777448) (xy 39.278277 -404.777889) (xy 39.297 -404.785634)
			(xy 39.311355 -404.799934) (xy 39.319171 -404.818627) (xy 39.319708 -404.828756) (xy 39.319708 -404.986744)
			(xy 39.320095 -404.995934) (xy 39.326624 -405.013118) (xy 39.332408 -405.020272) (xy 39.354193 -405.045927)
			(xy 39.392146 -405.101512) (xy 39.423182 -405.161234) (xy 39.446858 -405.224239) (xy 39.462832 -405.289621)
			(xy 39.470878 -405.356444) (xy 39.470878 -405.42375) (xy 39.462833 -405.490573) (xy 39.446859 -405.555956)
			(xy 39.423185 -405.61896) (xy 39.420718 -405.623708) (xy 40.548756 -405.623708) (xy 40.548757 -405.556283)
			(xy 40.556834 -405.489343) (xy 40.572872 -405.423853) (xy 40.596639 -405.360756) (xy 40.627793 -405.30096)
			(xy 40.665886 -405.245326) (xy 40.687752 -405.219662) (xy 40.693554 -405.212521) (xy 40.700064 -405.195327)
			(xy 40.700452 -405.186134) (xy 40.700452 -404.693882) (xy 40.700039 -404.684695) (xy 40.693526 -404.667512)
			(xy 40.687752 -404.660354) (xy 40.665908 -404.634672) (xy 40.627815 -404.579041) (xy 40.59666 -404.519248)
			(xy 40.572893 -404.456153) (xy 40.556854 -404.390665) (xy 40.548776 -404.323728) (xy 40.548774 -404.256305)
			(xy 40.556848 -404.189367) (xy 40.572883 -404.123879) (xy 40.596647 -404.060783) (xy 40.627798 -404.000987)
			(xy 40.665888 -403.945354) (xy 40.687752 -403.91969) (xy 40.693542 -403.91254) (xy 40.700059 -403.895353)
			(xy 40.700452 -403.886162) (xy 40.700452 -403.728682) (xy 40.700912 -403.718553) (xy 40.708648 -403.699829)
			(xy 40.722942 -403.685473) (xy 40.741633 -403.677656) (xy 40.75176 -403.67712) (xy 41.46804 -403.67712)
			(xy 41.478199 -403.677489) (xy 41.496956 -403.685302) (xy 41.511279 -403.699715) (xy 41.518974 -403.71852)
			(xy 41.519348 -403.728682) (xy 41.519348 -403.886162) (xy 41.519788 -403.895346) (xy 41.526282 -403.91253)
			(xy 41.532048 -403.91969) (xy 41.553935 -403.945337) (xy 41.592027 -404.000973) (xy 41.62318 -404.060771)
			(xy 41.646945 -404.12387) (xy 41.66298 -404.189362) (xy 41.671055 -404.256303) (xy 41.671053 -404.32373)
			(xy 41.662974 -404.39067) (xy 41.646935 -404.456161) (xy 41.623166 -404.519259) (xy 41.59201 -404.579056)
			(xy 41.553915 -404.63469) (xy 41.532048 -404.660354) (xy 41.52624 -404.667491) (xy 41.519733 -404.684688)
			(xy 41.519348 -404.693882) (xy 41.519348 -405.186134) (xy 41.519754 -405.195321) (xy 41.526272 -405.212505)
			(xy 41.532048 -405.219662) (xy 41.553908 -405.245331) (xy 41.592 -405.300964) (xy 41.623154 -405.360759)
			(xy 41.646921 -405.423856) (xy 41.662958 -405.489345) (xy 41.671036 -405.556283) (xy 41.671036 -405.623708)
			(xy 41.66296 -405.690646) (xy 41.646924 -405.756136) (xy 41.623158 -405.819233) (xy 41.592005 -405.879028)
			(xy 41.553913 -405.934662) (xy 41.532048 -405.960326) (xy 41.526251 -405.967471) (xy 41.519738 -405.984662)
			(xy 41.519348 -405.993854) (xy 41.519348 -406.151334) (xy 41.518901 -406.161464) (xy 41.51116 -406.180189)
			(xy 41.496861 -406.194544) (xy 41.478168 -406.20236) (xy 41.46804 -406.202896) (xy 40.75176 -406.202896)
			(xy 40.741603 -406.202511) (xy 40.722849 -406.194701) (xy 40.708527 -406.180294) (xy 40.700829 -406.161494)
			(xy 40.700452 -406.151334) (xy 40.700452 -405.993854) (xy 40.700004 -405.984671) (xy 40.693515 -405.967487)
			(xy 40.687752 -405.960326) (xy 40.66588 -405.934667) (xy 40.627788 -405.879032) (xy 40.596635 -405.819236)
			(xy 40.572869 -405.756138) (xy 40.556832 -405.690648) (xy 40.548756 -405.623708) (xy 39.420718 -405.623708)
			(xy 39.392149 -405.678683) (xy 39.354197 -405.734269) (xy 39.332408 -405.75992) (xy 39.326621 -405.767072)
			(xy 39.3201 -405.784257) (xy 39.319708 -405.793448) (xy 39.319708 -406.286716) (xy 39.320109 -406.295904)
			(xy 39.326629 -406.313088) (xy 39.332408 -406.320244) (xy 39.354166 -406.345921) (xy 39.392119 -406.401503)
			(xy 39.423157 -406.461222) (xy 39.446834 -406.524224) (xy 39.46281 -406.589604) (xy 39.470858 -406.656424)
			(xy 39.470861 -406.723728) (xy 39.470854 -406.723789) (xy 42.748899 -406.723789) (xy 42.748901 -406.656363)
			(xy 42.756981 -406.589422) (xy 42.773019 -406.523932) (xy 42.796787 -406.460833) (xy 42.827942 -406.401036)
			(xy 42.866034 -406.345401) (xy 42.8879 -406.319736) (xy 42.893706 -406.312598) (xy 42.900215 -406.295402)
			(xy 42.9006 -406.286208) (xy 42.9006 -405.793956) (xy 42.900211 -405.784767) (xy 42.893683 -405.767582)
			(xy 42.8879 -405.760428) (xy 42.866032 -405.734766) (xy 42.827944 -405.679131) (xy 42.796793 -405.619334)
			(xy 42.773029 -405.556237) (xy 42.756994 -405.490748) (xy 42.748918 -405.423809) (xy 42.748919 -405.356385)
			(xy 42.756995 -405.289446) (xy 42.773031 -405.223957) (xy 42.796795 -405.16086) (xy 42.827947 -405.101064)
			(xy 42.866036 -405.045429) (xy 42.8879 -405.019764) (xy 42.893694 -405.012617) (xy 42.90021 -404.995428)
			(xy 42.9006 -404.986236) (xy 42.9006 -404.828756) (xy 42.901049 -404.818644) (xy 42.908801 -404.799965)
			(xy 42.923109 -404.785672) (xy 42.941796 -404.777939) (xy 42.951908 -404.777448) (xy 43.668188 -404.777448)
			(xy 43.67829 -404.777994) (xy 43.696958 -404.785718) (xy 43.711251 -404.799995) (xy 43.718995 -404.818655)
			(xy 43.719496 -404.828756) (xy 43.719496 -404.986236) (xy 43.71989 -404.995425) (xy 43.726415 -405.012609)
			(xy 43.732196 -405.019764) (xy 43.754056 -405.045432) (xy 43.792145 -405.101066) (xy 43.823296 -405.160862)
			(xy 43.847061 -405.223959) (xy 43.863097 -405.289447) (xy 43.871173 -405.356385) (xy 43.871173 -405.423809)
			(xy 43.863098 -405.490747) (xy 43.847063 -405.556236) (xy 43.823299 -405.619332) (xy 43.792148 -405.679128)
			(xy 43.75406 -405.734763) (xy 43.732196 -405.760428) (xy 43.726405 -405.767577) (xy 43.719887 -405.784765)
			(xy 43.719496 -405.793956) (xy 43.719496 -406.286208) (xy 43.719903 -406.295395) (xy 43.726419 -406.31258)
			(xy 43.732196 -406.319736) (xy 43.754029 -406.345427) (xy 43.792119 -406.401058) (xy 43.823271 -406.46085)
			(xy 43.847037 -406.523944) (xy 43.863075 -406.58943) (xy 43.871153 -406.656365) (xy 43.871156 -406.72373)
			(xy 47.149194 -406.72373) (xy 47.149197 -406.656422) (xy 47.157245 -406.589596) (xy 47.173223 -406.524212)
			(xy 47.196901 -406.461206) (xy 47.227941 -406.401481) (xy 47.265897 -406.345896) (xy 47.287688 -406.320244)
			(xy 47.293489 -406.313102) (xy 47.300002 -406.295909) (xy 47.300388 -406.286716) (xy 47.300388 -405.793448)
			(xy 47.299958 -405.784263) (xy 47.293458 -405.767078) (xy 47.287688 -405.75992) (xy 47.265895 -405.734272)
			(xy 47.227943 -405.678686) (xy 47.196907 -405.618962) (xy 47.173232 -405.555957) (xy 47.157258 -405.490574)
			(xy 47.149214 -405.42375) (xy 47.149214 -405.356444) (xy 47.157259 -405.28962) (xy 47.173234 -405.224237)
			(xy 47.19691 -405.161232) (xy 47.227946 -405.101509) (xy 47.265899 -405.045924) (xy 47.287688 -405.020272)
			(xy 47.293478 -405.013122) (xy 47.299997 -404.995935) (xy 47.300388 -404.986744) (xy 47.300388 -404.828756)
			(xy 47.300785 -404.818601) (xy 47.308593 -404.79985) (xy 47.322997 -404.785528) (xy 47.341792 -404.777828)
			(xy 47.35195 -404.777448) (xy 48.06823 -404.777448) (xy 48.07836 -404.777902) (xy 48.097083 -404.785641)
			(xy 48.111439 -404.799937) (xy 48.119255 -404.818629) (xy 48.119792 -404.828756) (xy 48.119792 -404.986744)
			(xy 48.120183 -404.995933) (xy 48.12671 -405.013117) (xy 48.132492 -405.020272) (xy 48.154275 -405.045928)
			(xy 48.192222 -405.101514) (xy 48.223254 -405.161238) (xy 48.246925 -405.224242) (xy 48.262897 -405.289623)
			(xy 48.270941 -405.356445) (xy 48.270942 -405.423749) (xy 48.262899 -405.490571) (xy 48.246927 -405.555952)
			(xy 48.223256 -405.618957) (xy 48.192225 -405.67868) (xy 48.154279 -405.734267) (xy 48.132492 -405.75992)
			(xy 48.126704 -405.767071) (xy 48.120184 -405.784257) (xy 48.119792 -405.793448) (xy 48.119792 -406.286716)
			(xy 48.120196 -406.295904) (xy 48.126714 -406.313088) (xy 48.132492 -406.320244) (xy 48.154247 -406.345922)
			(xy 48.192195 -406.401506) (xy 48.223228 -406.461226) (xy 48.246901 -406.524227) (xy 48.262876 -406.589606)
			(xy 48.270922 -406.656425) (xy 48.270925 -406.723727) (xy 48.262884 -406.790547) (xy 48.246916 -406.855927)
			(xy 48.223248 -406.91893) (xy 48.19222 -406.978653) (xy 48.154277 -407.034239) (xy 48.132492 -407.059892)
			(xy 48.126715 -407.067051) (xy 48.120189 -407.084231) (xy 48.119792 -407.09342) (xy 48.119792 -407.251408)
			(xy 48.119385 -407.261564) (xy 48.111585 -407.280318) (xy 48.097184 -407.294641) (xy 48.078388 -407.302339)
			(xy 48.06823 -407.302716) (xy 47.35195 -407.302716) (xy 47.341821 -407.302231) (xy 47.323093 -407.294512)
			(xy 47.308733 -407.280224) (xy 47.30092 -407.261534) (xy 47.300388 -407.251408) (xy 47.300388 -407.09342)
			(xy 47.299971 -407.084233) (xy 47.293462 -407.067049) (xy 47.287688 -407.059892) (xy 47.265867 -407.034266)
			(xy 47.227916 -406.978677) (xy 47.196882 -406.91895) (xy 47.173209 -406.855942) (xy 47.157236 -406.790556)
			(xy 47.149194 -406.72373) (xy 43.871156 -406.72373) (xy 43.871156 -406.723787) (xy 43.863084 -406.790723)
			(xy 43.847051 -406.85621) (xy 43.823291 -406.919306) (xy 43.792143 -406.979101) (xy 43.754058 -407.034735)
			(xy 43.732196 -407.0604) (xy 43.726416 -407.067557) (xy 43.719892 -407.084739) (xy 43.719496 -407.093928)
			(xy 43.719496 -407.251408) (xy 43.71909 -407.261531) (xy 43.711339 -407.280236) (xy 43.697019 -407.29455)
			(xy 43.678312 -407.302294) (xy 43.668188 -407.302716) (xy 42.951908 -407.302716) (xy 42.941802 -407.302209)
			(xy 42.923127 -407.294477) (xy 42.908832 -407.280187) (xy 42.901094 -407.261514) (xy 42.9006 -407.251408)
			(xy 42.9006 -407.093928) (xy 42.900176 -407.084742) (xy 42.893672 -407.067558) (xy 42.8879 -407.0604)
			(xy 42.866005 -407.034761) (xy 42.827917 -406.979122) (xy 42.796768 -406.919323) (xy 42.773005 -406.856222)
			(xy 42.756972 -406.79073) (xy 42.748899 -406.723789) (xy 39.470854 -406.723789) (xy 39.462819 -406.790549)
			(xy 39.446848 -406.85593) (xy 39.423176 -406.918933) (xy 39.392144 -406.978656) (xy 39.354195 -407.034241)
			(xy 39.332408 -407.059892) (xy 39.326633 -407.067053) (xy 39.320105 -407.084231) (xy 39.319708 -407.09342)
			(xy 39.319708 -407.251408) (xy 39.319285 -407.261562) (xy 39.311488 -407.280313) (xy 39.297092 -407.294635)
			(xy 39.278302 -407.302336) (xy 39.268146 -407.302716) (xy 38.551866 -407.302716) (xy 38.541732 -407.3023)
			(xy 38.523001 -407.294553) (xy 38.508645 -407.280245) (xy 38.500835 -407.261541) (xy 38.500304 -407.251408)
			(xy 38.500304 -407.09342) (xy 38.499883 -407.084234) (xy 38.493377 -407.06705) (xy 38.487604 -407.059892)
			(xy 38.465786 -407.034265) (xy 38.42784 -406.978674) (xy 38.39681 -406.918947) (xy 38.373141 -406.855939)
			(xy 38.357171 -406.790554) (xy 38.34913 -406.723729) (xy 35.071068 -406.723729) (xy 35.071068 -406.723786)
			(xy 35.062996 -406.790722) (xy 35.046964 -406.856209) (xy 35.023204 -406.919305) (xy 34.992058 -406.9791)
			(xy 34.953974 -407.034735) (xy 34.932112 -407.0604) (xy 34.926334 -407.067559) (xy 34.919808 -407.084739)
			(xy 34.919412 -407.093928) (xy 34.919412 -407.251408) (xy 34.918922 -407.261516) (xy 34.911184 -407.280192)
			(xy 34.896888 -407.294486) (xy 34.878212 -407.302222) (xy 34.868104 -407.302716) (xy 34.151824 -407.302716)
			(xy 34.141705 -407.302265) (xy 34.123005 -407.294528) (xy 34.10869 -407.280222) (xy 34.100941 -407.261527)
			(xy 34.100516 -407.251408) (xy 34.100516 -407.093928) (xy 34.100089 -407.084743) (xy 34.093586 -407.067558)
			(xy 34.087816 -407.0604) (xy 34.06592 -407.034761) (xy 34.027831 -406.979123) (xy 33.996681 -406.919323)
			(xy 33.972918 -406.856223) (xy 33.956884 -406.790731) (xy 33.948811 -406.723789) (xy 30.670766 -406.723789)
			(xy 30.662731 -406.790549) (xy 30.646761 -406.855929) (xy 30.62309 -406.918933) (xy 30.592058 -406.978655)
			(xy 30.554111 -407.03424) (xy 30.532324 -407.059892) (xy 30.526551 -407.067054) (xy 30.520022 -407.084232)
			(xy 30.519624 -407.09342) (xy 30.519624 -407.251408) (xy 30.519185 -407.26156) (xy 30.511392 -407.280307)
			(xy 30.497001 -407.29463) (xy 30.478216 -407.302333) (xy 30.468062 -407.302716) (xy 29.751782 -407.302716)
			(xy 29.741649 -407.302287) (xy 29.722919 -407.294545) (xy 29.708561 -407.280241) (xy 29.700751 -407.261539)
			(xy 29.70022 -407.251408) (xy 29.70022 -407.09342) (xy 29.699796 -407.084234) (xy 29.693291 -407.06705)
			(xy 29.68752 -407.059892) (xy 29.665701 -407.034265) (xy 29.627755 -406.978675) (xy 29.596724 -406.918948)
			(xy 29.573054 -406.85594) (xy 29.557084 -406.790555) (xy 29.549042 -406.72373) (xy 0.508 -406.72373)
			(xy 0.508 -409.523886) (xy 27.348881 -409.523886) (xy 27.348884 -409.45646) (xy 27.356963 -409.38952)
			(xy 27.373002 -409.324029) (xy 27.396769 -409.26093) (xy 27.427923 -409.201133) (xy 27.466015 -409.145498)
			(xy 27.48788 -409.119832) (xy 27.493686 -409.112693) (xy 27.500196 -409.095498) (xy 27.50058 -409.086304)
			(xy 27.50058 -408.594052) (xy 27.500149 -408.584867) (xy 27.49365 -408.567682) (xy 27.48788 -408.560524)
			(xy 27.466009 -408.534865) (xy 27.427922 -408.479229) (xy 27.396772 -408.419432) (xy 27.37301 -408.356334)
			(xy 27.356975 -408.290845) (xy 27.3489 -408.223906) (xy 27.348901 -408.156482) (xy 27.356977 -408.089544)
			(xy 27.373013 -408.024054) (xy 27.396777 -407.960957) (xy 27.427928 -407.901161) (xy 27.466016 -407.845526)
			(xy 27.48788 -407.81986) (xy 27.493674 -407.812713) (xy 27.500191 -407.795524) (xy 27.50058 -407.786332)
			(xy 27.50058 -407.628852) (xy 27.501045 -407.618743) (xy 27.508795 -407.600067) (xy 27.523098 -407.585775)
			(xy 27.541778 -407.578038) (xy 27.551888 -407.577544) (xy 28.268168 -407.577544) (xy 28.278268 -407.57811)
			(xy 28.296935 -407.585826) (xy 28.311229 -407.600098) (xy 28.318975 -407.618753) (xy 28.319476 -407.628852)
			(xy 28.319476 -407.786332) (xy 28.319876 -407.79552) (xy 28.326397 -407.812704) (xy 28.332176 -407.81986)
			(xy 28.354033 -407.845531) (xy 28.392123 -407.901164) (xy 28.423276 -407.96096) (xy 28.447042 -408.024056)
			(xy 28.463078 -408.089544) (xy 28.471155 -408.156482) (xy 28.471156 -408.223906) (xy 28.46308 -408.290844)
			(xy 28.447045 -408.356333) (xy 28.423281 -408.419429) (xy 28.39213 -408.479225) (xy 28.35404 -408.534859)
			(xy 28.332176 -408.560524) (xy 28.326384 -408.567672) (xy 28.319867 -408.584861) (xy 28.319476 -408.594052)
			(xy 28.319476 -409.086304) (xy 28.319889 -409.095491) (xy 28.326401 -409.112675) (xy 28.332176 -409.119832)
			(xy 28.354005 -409.145526) (xy 28.392097 -409.201156) (xy 28.42325 -409.260948) (xy 28.447018 -409.324041)
			(xy 28.463056 -409.389527) (xy 28.471135 -409.456462) (xy 28.471139 -409.523884) (xy 28.463066 -409.59082)
			(xy 28.447034 -409.656307) (xy 28.423273 -409.719403) (xy 28.392125 -409.779198) (xy 28.354039 -409.834831)
			(xy 28.332176 -409.860496) (xy 28.326396 -409.867653) (xy 28.319872 -409.884835) (xy 28.319476 -409.894024)
			(xy 28.319476 -410.051504) (xy 28.319087 -410.06163) (xy 28.311333 -410.080338) (xy 28.297008 -410.094653)
			(xy 28.278294 -410.102394) (xy 28.268168 -410.102812) (xy 27.551888 -410.102812) (xy 27.54178 -410.102325)
			(xy 27.523104 -410.094585) (xy 27.50881 -410.080289) (xy 27.501074 -410.061612) (xy 27.50058 -410.051504)
			(xy 27.50058 -409.894024) (xy 27.500163 -409.884837) (xy 27.493655 -409.867653) (xy 27.48788 -409.860496)
			(xy 27.465981 -409.83486) (xy 27.427895 -409.77922) (xy 27.396747 -409.71942) (xy 27.372986 -409.656319)
			(xy 27.356953 -409.590827) (xy 27.348881 -409.523886) (xy 0.508 -409.523886) (xy 0.508 -410.623641)
			(xy 29.549054 -410.623641) (xy 29.549055 -410.556335) (xy 29.5571 -410.489512) (xy 29.573074 -410.424129)
			(xy 29.596748 -410.361124) (xy 29.627782 -410.301399) (xy 29.665732 -410.245812) (xy 29.68752 -410.22016)
			(xy 29.693318 -410.213016) (xy 29.699831 -410.195825) (xy 29.70022 -410.186632) (xy 29.70022 -409.693364)
			(xy 29.699823 -409.684176) (xy 29.6933 -409.666992) (xy 29.68752 -409.659836) (xy 29.665745 -409.634174)
			(xy 29.627797 -409.578588) (xy 29.596764 -409.518866) (xy 29.573091 -409.455863) (xy 29.557118 -409.390482)
			(xy 29.549073 -409.323661) (xy 29.549072 -409.256357) (xy 29.557115 -409.189536) (xy 29.573086 -409.124154)
			(xy 29.596757 -409.06115) (xy 29.627787 -409.001427) (xy 29.665734 -408.94584) (xy 29.68752 -408.920188)
			(xy 29.693306 -408.913036) (xy 29.699827 -408.895851) (xy 29.70022 -408.88666) (xy 29.70022 -408.728672)
			(xy 29.700599 -408.718514) (xy 29.708408 -408.699757) (xy 29.722817 -408.685434) (xy 29.741621 -408.677738)
			(xy 29.751782 -408.677364) (xy 30.468062 -408.677364) (xy 30.478189 -408.677859) (xy 30.496914 -408.685578)
			(xy 30.511272 -408.699863) (xy 30.519089 -408.718547) (xy 30.519624 -408.728672) (xy 30.519624 -408.88666)
			(xy 30.520048 -408.895846) (xy 30.526551 -408.913031) (xy 30.532324 -408.920188) (xy 30.554125 -408.94583)
			(xy 30.592075 -409.001417) (xy 30.62311 -409.061142) (xy 30.646784 -409.124148) (xy 30.662757 -409.189531)
			(xy 30.670801 -409.256356) (xy 30.6708 -409.323662) (xy 30.662754 -409.390486) (xy 30.646779 -409.45587)
			(xy 30.623103 -409.518875) (xy 30.62053 -409.523827) (xy 31.749176 -409.523827) (xy 31.749179 -409.456519)
			(xy 31.757227 -409.389693) (xy 31.773205 -409.324309) (xy 31.796883 -409.261302) (xy 31.827922 -409.201578)
			(xy 31.865877 -409.145992) (xy 31.887668 -409.12034) (xy 31.893481 -409.113207) (xy 31.899984 -409.096007)
			(xy 31.900368 -409.086812) (xy 31.900368 -408.593544) (xy 31.899922 -408.584361) (xy 31.893432 -408.567177)
			(xy 31.887668 -408.560016) (xy 31.865872 -408.534371) (xy 31.827921 -408.478784) (xy 31.796887 -408.41906)
			(xy 31.773213 -408.356054) (xy 31.75724 -408.290671) (xy 31.749196 -408.223847) (xy 31.749197 -408.156541)
			(xy 31.757242 -408.089717) (xy 31.773217 -408.024334) (xy 31.796892 -407.961329) (xy 31.827927 -407.901606)
			(xy 31.865879 -407.84602) (xy 31.887668 -407.820368) (xy 31.893469 -407.813226) (xy 31.899979 -407.796033)
			(xy 31.900368 -407.78684) (xy 31.900368 -407.628852) (xy 31.900782 -407.618699) (xy 31.908587 -407.599952)
			(xy 31.922985 -407.585631) (xy 31.941775 -407.577927) (xy 31.95193 -407.577544) (xy 32.66821 -407.577544)
			(xy 32.678338 -407.578019) (xy 32.69706 -407.58575) (xy 32.711416 -407.60004) (xy 32.719234 -407.618727)
			(xy 32.719772 -407.628852) (xy 32.719772 -407.78684) (xy 32.720169 -407.796028) (xy 32.726693 -407.813212)
			(xy 32.732472 -407.820368) (xy 32.754252 -407.846027) (xy 32.7922 -407.901612) (xy 32.823233 -407.961335)
			(xy 32.846906 -408.024339) (xy 32.862879 -408.08972) (xy 32.870924 -408.156542) (xy 32.870924 -408.223846)
			(xy 32.862881 -408.290668) (xy 32.846909 -408.35605) (xy 32.823238 -408.419054) (xy 32.792206 -408.478777)
			(xy 32.754259 -408.534364) (xy 32.732472 -408.560016) (xy 32.726682 -408.567166) (xy 32.720164 -408.584353)
			(xy 32.719772 -408.593544) (xy 32.719772 -409.086812) (xy 32.720183 -409.095999) (xy 32.726697 -409.113183)
			(xy 32.732472 -409.12034) (xy 32.754224 -409.146022) (xy 32.792173 -409.201604) (xy 32.823207 -409.261324)
			(xy 32.846881 -409.324324) (xy 32.862857 -409.389703) (xy 32.870903 -409.456522) (xy 32.870907 -409.523824)
			(xy 32.862866 -409.590644) (xy 32.846897 -409.656024) (xy 32.823229 -409.719027) (xy 32.792201 -409.778749)
			(xy 32.754257 -409.834336) (xy 32.732472 -409.859988) (xy 32.726652 -409.867116) (xy 32.720152 -409.88432)
			(xy 32.719772 -409.893516) (xy 32.719772 -410.051504) (xy 32.719381 -410.061662) (xy 32.711579 -410.08042)
			(xy 32.697172 -410.094744) (xy 32.67837 -410.102438) (xy 32.66821 -410.102812) (xy 31.95193 -410.102812)
			(xy 31.941812 -410.102251) (xy 31.923101 -410.094542) (xy 31.908745 -410.080279) (xy 31.900916 -410.061619)
			(xy 31.900368 -410.051504) (xy 31.900368 -409.893516) (xy 31.899935 -409.884332) (xy 31.893436 -409.867148)
			(xy 31.887668 -409.859988) (xy 31.865844 -409.834366) (xy 31.827894 -409.778775) (xy 31.796861 -409.719048)
			(xy 31.773189 -409.65604) (xy 31.757217 -409.590654) (xy 31.749176 -409.523827) (xy 30.62053 -409.523827)
			(xy 30.592066 -409.578598) (xy 30.554113 -409.634184) (xy 30.532324 -409.659836) (xy 30.526532 -409.666985)
			(xy 30.520014 -409.684172) (xy 30.519624 -409.693364) (xy 30.519624 -410.186632) (xy 30.520014 -410.195821)
			(xy 30.526541 -410.213006) (xy 30.532324 -410.22016) (xy 30.554097 -410.245825) (xy 30.592049 -410.301408)
			(xy 30.623085 -410.36113) (xy 30.64676 -410.424133) (xy 30.662735 -410.489514) (xy 30.670781 -410.556336)
			(xy 30.670783 -410.62364) (xy 30.670776 -410.623701) (xy 33.948822 -410.623701) (xy 33.948823 -410.556275)
			(xy 33.956901 -410.489336) (xy 33.972939 -410.423846) (xy 33.996705 -410.360748) (xy 34.027859 -410.300951)
			(xy 34.065951 -410.245317) (xy 34.087816 -410.219652) (xy 34.093617 -410.21251) (xy 34.100129 -410.195317)
			(xy 34.100516 -410.186124) (xy 34.100516 -409.693872) (xy 34.100116 -409.684684) (xy 34.093595 -409.6675)
			(xy 34.087816 -409.660344) (xy 34.065963 -409.634669) (xy 34.027873 -409.579037) (xy 33.996721 -409.519242)
			(xy 33.972955 -409.456146) (xy 33.956919 -409.390658) (xy 33.948842 -409.323721) (xy 33.948841 -409.256297)
			(xy 33.956915 -409.18936) (xy 33.97295 -409.123871) (xy 33.996714 -409.060775) (xy 34.027864 -409.000979)
			(xy 34.065952 -408.945345) (xy 34.087816 -408.91968) (xy 34.093605 -408.91253) (xy 34.100124 -408.895343)
			(xy 34.100516 -408.886152) (xy 34.100516 -408.728672) (xy 34.100962 -408.718559) (xy 34.108712 -408.699878)
			(xy 34.123021 -408.685583) (xy 34.141711 -408.677852) (xy 34.151824 -408.677364) (xy 34.868104 -408.677364)
			(xy 34.878209 -408.677881) (xy 34.89688 -408.685613) (xy 34.911173 -408.6999) (xy 34.918914 -408.718568)
			(xy 34.919412 -408.728672) (xy 34.919412 -408.886152) (xy 34.919842 -408.895337) (xy 34.926342 -408.912522)
			(xy 34.932112 -408.91968) (xy 34.953987 -408.945336) (xy 34.992075 -409.000972) (xy 35.023224 -409.06077)
			(xy 35.046987 -409.123868) (xy 35.063022 -409.189358) (xy 35.071096 -409.256297) (xy 35.071095 -409.323721)
			(xy 35.063018 -409.39066) (xy 35.046982 -409.45615) (xy 35.023217 -409.519247) (xy 35.0208 -409.523886)
			(xy 36.148969 -409.523886) (xy 36.148972 -409.45646) (xy 36.157051 -409.38952) (xy 36.173089 -409.324029)
			(xy 36.196856 -409.260931) (xy 36.228009 -409.201134) (xy 36.266099 -409.145498) (xy 36.287964 -409.119832)
			(xy 36.29378 -409.112701) (xy 36.300281 -409.095499) (xy 36.300664 -409.086304) (xy 36.300664 -408.594052)
			(xy 36.300215 -408.584869) (xy 36.293727 -408.567685) (xy 36.287964 -408.560524) (xy 36.266093 -408.534865)
			(xy 36.228007 -408.479228) (xy 36.196859 -408.419431) (xy 36.173097 -408.356334) (xy 36.157063 -408.290844)
			(xy 36.148988 -408.223906) (xy 36.148989 -408.156482) (xy 36.157065 -408.089544) (xy 36.1731 -408.024055)
			(xy 36.196864 -407.960958) (xy 36.228014 -407.901161) (xy 36.266101 -407.845526) (xy 36.287964 -407.81986)
			(xy 36.293768 -407.81272) (xy 36.300276 -407.795525) (xy 36.300664 -407.786332) (xy 36.300664 -407.628852)
			(xy 36.301145 -407.618745) (xy 36.308892 -407.600072) (xy 36.323189 -407.585781) (xy 36.341864 -407.578041)
			(xy 36.351972 -407.577544) (xy 37.068252 -407.577544) (xy 37.078351 -407.578123) (xy 37.097017 -407.585835)
			(xy 37.111312 -407.600102) (xy 37.119058 -407.618754) (xy 37.11956 -407.628852) (xy 37.11956 -407.786332)
			(xy 37.119964 -407.79552) (xy 37.126483 -407.812703) (xy 37.13226 -407.81986) (xy 37.154118 -407.845531)
			(xy 37.192209 -407.901164) (xy 37.223362 -407.960959) (xy 37.247129 -408.024055) (xy 37.263166 -408.089544)
			(xy 37.271243 -408.156482) (xy 37.271244 -408.223906) (xy 37.263168 -408.290844) (xy 37.247132 -408.356333)
			(xy 37.223367 -408.41943) (xy 37.192215 -408.479226) (xy 37.154125 -408.534859) (xy 37.13226 -408.560524)
			(xy 37.126466 -408.567671) (xy 37.119951 -408.58486) (xy 37.11956 -408.594052) (xy 37.11956 -409.086304)
			(xy 37.119977 -409.09549) (xy 37.126487 -409.112674) (xy 37.13226 -409.119832) (xy 37.15409 -409.145526)
			(xy 37.192182 -409.201155) (xy 37.223337 -409.260947) (xy 37.247105 -409.32404) (xy 37.263144 -409.389526)
			(xy 37.271223 -409.456462) (xy 37.271227 -409.523884) (xy 37.263154 -409.59082) (xy 37.247121 -409.656308)
			(xy 37.223359 -409.719403) (xy 37.19221 -409.779198) (xy 37.154123 -409.834831) (xy 37.13226 -409.860496)
			(xy 37.126478 -409.867651) (xy 37.119955 -409.884834) (xy 37.11956 -409.894024) (xy 37.11956 -410.051504)
			(xy 37.119186 -410.061632) (xy 37.111429 -410.080343) (xy 37.097099 -410.094659) (xy 37.07838 -410.102396)
			(xy 37.068252 -410.102812) (xy 36.351972 -410.102812) (xy 36.341863 -410.102338) (xy 36.323186 -410.094594)
			(xy 36.308893 -410.080293) (xy 36.301157 -410.061613) (xy 36.300664 -410.051504) (xy 36.300664 -409.894024)
			(xy 36.300228 -409.88484) (xy 36.293731 -409.867656) (xy 36.287964 -409.860496) (xy 36.266066 -409.834859)
			(xy 36.227981 -409.77922) (xy 36.196834 -409.719419) (xy 36.173073 -409.656319) (xy 36.157041 -409.590827)
			(xy 36.148969 -409.523886) (xy 35.0208 -409.523886) (xy 34.992066 -409.579044) (xy 34.953976 -409.634679)
			(xy 34.932112 -409.660344) (xy 34.926316 -409.667489) (xy 34.9198 -409.68468) (xy 34.919412 -409.693872)
			(xy 34.919412 -410.186124) (xy 34.919808 -410.195313) (xy 34.926331 -410.212497) (xy 34.932112 -410.219652)
			(xy 34.95396 -410.24533) (xy 34.992048 -410.300963) (xy 35.023199 -410.360758) (xy 35.046964 -410.423853)
			(xy 35.063 -410.48934) (xy 35.071077 -410.556277) (xy 35.071078 -410.623641) (xy 38.349141 -410.623641)
			(xy 38.349143 -410.556335) (xy 38.357188 -410.489512) (xy 38.373162 -410.424129) (xy 38.396835 -410.361124)
			(xy 38.427868 -410.3014) (xy 38.465816 -410.245813) (xy 38.487604 -410.22016) (xy 38.493401 -410.213015)
			(xy 38.499915 -410.195824) (xy 38.500304 -410.186632) (xy 38.500304 -409.693364) (xy 38.49991 -409.684175)
			(xy 38.493385 -409.666991) (xy 38.487604 -409.659836) (xy 38.465829 -409.634174) (xy 38.427882 -409.578588)
			(xy 38.39685 -409.518865) (xy 38.373178 -409.455862) (xy 38.357206 -409.390482) (xy 38.349161 -409.323661)
			(xy 38.34916 -409.256357) (xy 38.357202 -409.189536) (xy 38.373173 -409.124155) (xy 38.396843 -409.061151)
			(xy 38.427873 -409.001428) (xy 38.465818 -408.945841) (xy 38.487604 -408.920188) (xy 38.493389 -408.913034)
			(xy 38.49991 -408.89585) (xy 38.500304 -408.88666) (xy 38.500304 -408.728672) (xy 38.500699 -408.718516)
			(xy 38.508504 -408.699762) (xy 38.522909 -408.685439) (xy 38.541707 -408.677741) (xy 38.551866 -408.677364)
			(xy 39.268146 -408.677364) (xy 39.278279 -408.67779) (xy 39.297005 -408.685537) (xy 39.311361 -408.699842)
			(xy 39.319174 -408.718541) (xy 39.319708 -408.728672) (xy 39.319708 -408.88666) (xy 39.320136 -408.895845)
			(xy 39.326637 -408.91303) (xy 39.332408 -408.920188) (xy 39.354209 -408.94583) (xy 39.392161 -409.001416)
			(xy 39.423197 -409.061141) (xy 39.446871 -409.124147) (xy 39.462845 -409.189531) (xy 39.470889 -409.256356)
			(xy 39.470888 -409.323663) (xy 39.462842 -409.390487) (xy 39.446866 -409.45587) (xy 39.423189 -409.518876)
			(xy 39.420585 -409.523887) (xy 40.548735 -409.523887) (xy 40.548738 -409.456459) (xy 40.556818 -409.389518)
			(xy 40.572859 -409.324026) (xy 40.59663 -409.260927) (xy 40.627788 -409.20113) (xy 40.665884 -409.145496)
			(xy 40.687752 -409.119832) (xy 40.693566 -409.1127) (xy 40.700069 -409.095499) (xy 40.700452 -409.086304)
			(xy 40.700452 -408.594052) (xy 40.700005 -408.584869) (xy 40.693516 -408.567685) (xy 40.687752 -408.560524)
			(xy 40.665878 -408.534866) (xy 40.627786 -408.479232) (xy 40.596633 -408.419435) (xy 40.572867 -408.356337)
			(xy 40.556831 -408.290847) (xy 40.548755 -408.223907) (xy 40.548755 -408.156481) (xy 40.556833 -408.089542)
			(xy 40.572871 -408.024051) (xy 40.596638 -407.960954) (xy 40.627793 -407.901158) (xy 40.665886 -407.845524)
			(xy 40.687752 -407.81986) (xy 40.693554 -407.812719) (xy 40.700064 -407.795525) (xy 40.700452 -407.786332)
			(xy 40.700452 -407.628852) (xy 40.700945 -407.618746) (xy 40.708689 -407.600076) (xy 40.722983 -407.585785)
			(xy 40.741654 -407.578043) (xy 40.75176 -407.577544) (xy 41.46804 -407.577544) (xy 41.478144 -407.578051)
			(xy 41.496813 -407.585791) (xy 41.511104 -407.600081) (xy 41.518847 -407.618748) (xy 41.519348 -407.628852)
			(xy 41.519348 -407.786332) (xy 41.519755 -407.795519) (xy 41.526272 -407.812703) (xy 41.532048 -407.81986)
			(xy 41.553906 -407.845531) (xy 41.591998 -407.901163) (xy 41.623152 -407.960958) (xy 41.646919 -408.024055)
			(xy 41.662957 -408.089543) (xy 41.671034 -408.156482) (xy 41.671035 -408.223906) (xy 41.662959 -408.290845)
			(xy 41.646923 -408.356334) (xy 41.623157 -408.419431) (xy 41.592004 -408.479226) (xy 41.553913 -408.53486)
			(xy 41.532048 -408.560524) (xy 41.526252 -408.56767) (xy 41.519739 -408.58486) (xy 41.519348 -408.594052)
			(xy 41.519348 -409.086304) (xy 41.519768 -409.09549) (xy 41.526276 -409.112674) (xy 41.532048 -409.119832)
			(xy 41.553878 -409.145526) (xy 41.591972 -409.201155) (xy 41.623127 -409.260947) (xy 41.646895 -409.32404)
			(xy 41.662935 -409.389526) (xy 41.671014 -409.456462) (xy 41.671018 -409.523884) (xy 41.662945 -409.590821)
			(xy 41.646911 -409.656308) (xy 41.623149 -409.719404) (xy 41.591999 -409.779199) (xy 41.553912 -409.834832)
			(xy 41.532048 -409.860496) (xy 41.526264 -409.86765) (xy 41.519743 -409.884834) (xy 41.519348 -409.894024)
			(xy 41.519348 -410.051504) (xy 41.518819 -410.061607) (xy 41.511089 -410.080276) (xy 41.496806 -410.094569)
			(xy 41.478143 -410.102312) (xy 41.46804 -410.102812) (xy 40.75176 -410.102812) (xy 40.74165 -410.102348)
			(xy 40.722973 -410.094599) (xy 40.70868 -410.080296) (xy 40.700945 -410.061614) (xy 40.700452 -410.051504)
			(xy 40.700452 -409.894024) (xy 40.700019 -409.884839) (xy 40.69352 -409.867655) (xy 40.687752 -409.860496)
			(xy 40.665851 -409.834861) (xy 40.62776 -409.779223) (xy 40.596608 -409.719423) (xy 40.572843 -409.656322)
			(xy 40.556809 -409.590829) (xy 40.548735 -409.523887) (xy 39.420585 -409.523887) (xy 39.392152 -409.578599)
			(xy 39.354198 -409.634185) (xy 39.332408 -409.659836) (xy 39.326615 -409.666984) (xy 39.320098 -409.684172)
			(xy 39.319708 -409.693364) (xy 39.319708 -410.186632) (xy 39.320101 -410.195821) (xy 39.326626 -410.213005)
			(xy 39.332408 -410.22016) (xy 39.354182 -410.245824) (xy 39.392134 -410.301408) (xy 39.423171 -410.361129)
			(xy 39.446847 -410.424132) (xy 39.462823 -410.489513) (xy 39.470869 -410.556336) (xy 39.470871 -410.62364)
			(xy 39.470864 -410.6237) (xy 42.74891 -410.6237) (xy 42.748911 -410.556276) (xy 42.756989 -410.489336)
			(xy 42.773026 -410.423846) (xy 42.796792 -410.360749) (xy 42.827944 -410.300952) (xy 42.866035 -410.245317)
			(xy 42.8879 -410.219652) (xy 42.893699 -410.212509) (xy 42.900212 -410.195317) (xy 42.9006 -410.186124)
			(xy 42.9006 -409.693872) (xy 42.900204 -409.684683) (xy 42.89368 -409.667499) (xy 42.8879 -409.660344)
			(xy 42.866048 -409.634669) (xy 42.827959 -409.579036) (xy 42.796808 -409.519241) (xy 42.773043 -409.456145)
			(xy 42.757006 -409.390658) (xy 42.74893 -409.32372) (xy 42.748928 -409.256298) (xy 42.757003 -409.18936)
			(xy 42.773037 -409.123872) (xy 42.7968 -409.060775) (xy 42.827949 -409.00098) (xy 42.866037 -408.945345)
			(xy 42.8879 -408.91968) (xy 42.893688 -408.912528) (xy 42.900208 -408.895343) (xy 42.9006 -408.886152)
			(xy 42.9006 -408.728672) (xy 42.901062 -408.718561) (xy 42.908809 -408.699883) (xy 42.923113 -408.685589)
			(xy 42.941797 -408.677855) (xy 42.951908 -408.677364) (xy 43.668188 -408.677364) (xy 43.678292 -408.677894)
			(xy 43.696963 -408.685621) (xy 43.711257 -408.699904) (xy 43.718998 -408.718569) (xy 43.719496 -408.728672)
			(xy 43.719496 -408.886152) (xy 43.71993 -408.895337) (xy 43.726427 -408.912521) (xy 43.732196 -408.91968)
			(xy 43.754072 -408.945335) (xy 43.792161 -409.000971) (xy 43.823311 -409.060769) (xy 43.847075 -409.123867)
			(xy 43.863109 -409.189357) (xy 43.871184 -409.256297) (xy 43.871183 -409.323721) (xy 43.863106 -409.390661)
			(xy 43.847069 -409.45615) (xy 43.823304 -409.519248) (xy 43.792151 -409.579044) (xy 43.754061 -409.634679)
			(xy 43.732196 -409.660344) (xy 43.726398 -409.667488) (xy 43.719884 -409.684679) (xy 43.719496 -409.693872)
			(xy 43.719496 -410.186124) (xy 43.719895 -410.195312) (xy 43.726417 -410.212497) (xy 43.732196 -410.219652)
			(xy 43.754044 -410.24533) (xy 43.792134 -410.300963) (xy 43.823285 -410.360757) (xy 43.847051 -410.423852)
			(xy 43.863087 -410.48934) (xy 43.871165 -410.556277) (xy 43.871166 -410.623642) (xy 47.149205 -410.623642)
			(xy 47.149207 -410.556334) (xy 47.157253 -410.48951) (xy 47.173229 -410.424126) (xy 47.196906 -410.361121)
			(xy 47.227944 -410.301397) (xy 47.265898 -410.245812) (xy 47.287688 -410.22016) (xy 47.293483 -410.213013)
			(xy 47.299999 -410.195824) (xy 47.300388 -410.186632) (xy 47.300388 -409.693364) (xy 47.299998 -409.684175)
			(xy 47.293471 -409.66699) (xy 47.287688 -409.659836) (xy 47.265911 -409.634175) (xy 47.227958 -409.578591)
			(xy 47.196922 -409.518869) (xy 47.173246 -409.455866) (xy 47.157271 -409.390484) (xy 47.149225 -409.323662)
			(xy 47.149224 -409.256357) (xy 47.157268 -409.189534) (xy 47.173241 -409.124152) (xy 47.196914 -409.061148)
			(xy 47.227949 -409.001425) (xy 47.2659 -408.945839) (xy 47.287688 -408.920188) (xy 47.293471 -408.913033)
			(xy 47.299994 -408.89585) (xy 47.300388 -408.88666) (xy 47.300388 -408.728672) (xy 47.300798 -408.718518)
			(xy 47.308601 -408.699767) (xy 47.323001 -408.685445) (xy 47.341793 -408.677744) (xy 47.35195 -408.677364)
			(xy 48.06823 -408.677364) (xy 48.078362 -408.677803) (xy 48.097088 -408.685545) (xy 48.111444 -408.699846)
			(xy 48.119258 -408.718542) (xy 48.119792 -408.728672) (xy 48.119792 -408.88666) (xy 48.120223 -408.895845)
			(xy 48.126722 -408.913029) (xy 48.132492 -408.920188) (xy 48.154291 -408.945831) (xy 48.192237 -409.001419)
			(xy 48.223268 -409.061145) (xy 48.246939 -409.12415) (xy 48.26291 -409.189533) (xy 48.270953 -409.256356)
			(xy 48.270952 -409.323662) (xy 48.262907 -409.390485) (xy 48.246933 -409.455867) (xy 48.223261 -409.518872)
			(xy 48.192228 -409.578596) (xy 48.15428 -409.634183) (xy 48.132492 -409.659836) (xy 48.126697 -409.666982)
			(xy 48.120182 -409.684172) (xy 48.119792 -409.693364) (xy 48.119792 -410.186632) (xy 48.120188 -410.195821)
			(xy 48.126712 -410.213005) (xy 48.132492 -410.22016) (xy 48.154263 -410.245825) (xy 48.19221 -410.301411)
			(xy 48.223243 -410.361133) (xy 48.246915 -410.424135) (xy 48.262888 -410.489516) (xy 48.270933 -410.556336)
			(xy 48.270934 -410.62364) (xy 48.262892 -410.690461) (xy 48.246922 -410.755842) (xy 48.223252 -410.818845)
			(xy 48.192223 -410.878569) (xy 48.154278 -410.934155) (xy 48.132492 -410.959808) (xy 48.126709 -410.966963)
			(xy 48.120186 -410.984146) (xy 48.119792 -410.993336) (xy 48.119792 -411.151324) (xy 48.119398 -411.161481)
			(xy 48.111593 -411.180235) (xy 48.097188 -411.194558) (xy 48.078389 -411.202255) (xy 48.06823 -411.202632)
			(xy 47.35195 -411.202632) (xy 47.341823 -411.202132) (xy 47.323098 -411.194415) (xy 47.308739 -411.180132)
			(xy 47.300923 -411.161448) (xy 47.300388 -411.151324) (xy 47.300388 -410.993336) (xy 47.299963 -410.98415)
			(xy 47.29346 -410.966966) (xy 47.287688 -410.959808) (xy 47.265883 -410.934169) (xy 47.227932 -410.878582)
			(xy 47.196896 -410.818857) (xy 47.173222 -410.755851) (xy 47.157249 -410.690466) (xy 47.149205 -410.623642)
			(xy 43.871166 -410.623642) (xy 43.871166 -410.623699) (xy 43.863092 -410.690636) (xy 43.847058 -410.756125)
			(xy 43.823295 -410.819221) (xy 43.792146 -410.879017) (xy 43.754059 -410.934651) (xy 43.732196 -410.960316)
			(xy 43.72641 -410.967468) (xy 43.719889 -410.984653) (xy 43.719496 -410.993844) (xy 43.719496 -411.151324)
			(xy 43.719035 -411.161435) (xy 43.711288 -411.180114) (xy 43.696984 -411.194408) (xy 43.678299 -411.202142)
			(xy 43.668188 -411.202632) (xy 42.951908 -411.202632) (xy 42.941804 -411.202109) (xy 42.923132 -411.19438)
			(xy 42.908838 -411.180095) (xy 42.901097 -411.161428) (xy 42.9006 -411.151324) (xy 42.9006 -410.993844)
			(xy 42.900169 -410.984659) (xy 42.89367 -410.967474) (xy 42.8879 -410.960316) (xy 42.86602 -410.934664)
			(xy 42.827932 -410.879027) (xy 42.796782 -410.819229) (xy 42.773019 -410.756131) (xy 42.756984 -410.69064)
			(xy 42.74891 -410.6237) (xy 39.470864 -410.6237) (xy 39.462827 -410.690463) (xy 39.446854 -410.755845)
			(xy 39.423181 -410.818849) (xy 39.392147 -410.878572) (xy 39.354196 -410.934157) (xy 39.332408 -410.959808)
			(xy 39.326626 -410.966964) (xy 39.320103 -410.984146) (xy 39.319708 -410.993336) (xy 39.319708 -411.151324)
			(xy 39.319298 -411.161479) (xy 39.311496 -411.18023) (xy 39.297096 -411.194552) (xy 39.278303 -411.202253)
			(xy 39.268146 -411.202632) (xy 38.551866 -411.202632) (xy 38.541734 -411.202201) (xy 38.523006 -411.194456)
			(xy 38.50865 -411.180153) (xy 38.500837 -411.161454) (xy 38.500304 -411.151324) (xy 38.500304 -410.993336)
			(xy 38.499876 -410.984151) (xy 38.493375 -410.966966) (xy 38.487604 -410.959808) (xy 38.465802 -410.934168)
			(xy 38.427856 -410.878579) (xy 38.396825 -410.818854) (xy 38.373155 -410.755848) (xy 38.357184 -410.690464)
			(xy 38.349141 -410.623641) (xy 35.071078 -410.623641) (xy 35.071078 -410.623699) (xy 35.063004 -410.690636)
			(xy 35.046971 -410.756124) (xy 35.023209 -410.81922) (xy 34.992061 -410.879016) (xy 34.953975 -410.934651)
			(xy 34.932112 -410.960316) (xy 34.926328 -410.96747) (xy 34.919805 -410.984654) (xy 34.919412 -410.993844)
			(xy 34.919412 -411.151324) (xy 34.918935 -411.161433) (xy 34.911192 -411.180109) (xy 34.896893 -411.194403)
			(xy 34.878213 -411.202139) (xy 34.868104 -411.202632) (xy 34.151824 -411.202632) (xy 34.141721 -411.202096)
			(xy 34.123049 -411.194372) (xy 34.108755 -411.180091) (xy 34.101013 -411.161427) (xy 34.100516 -411.151324)
			(xy 34.100516 -410.993844) (xy 34.100081 -410.98466) (xy 34.093584 -410.967475) (xy 34.087816 -410.960316)
			(xy 34.065936 -410.934664) (xy 34.027846 -410.879028) (xy 33.996696 -410.81923) (xy 33.972932 -410.756131)
			(xy 33.956897 -410.690641) (xy 33.948822 -410.623701) (xy 30.670776 -410.623701) (xy 30.66274 -410.690462)
			(xy 30.646767 -410.755844) (xy 30.623095 -410.818848) (xy 30.592061 -410.878571) (xy 30.554112 -410.934156)
			(xy 30.532324 -410.959808) (xy 30.526544 -410.966965) (xy 30.520019 -410.984146) (xy 30.519624 -410.993336)
			(xy 30.519624 -411.151324) (xy 30.519199 -411.161477) (xy 30.5114 -411.180225) (xy 30.497005 -411.194547)
			(xy 30.478217 -411.20225) (xy 30.468062 -411.202632) (xy 29.751782 -411.202632) (xy 29.741651 -411.202188)
			(xy 29.722924 -411.194449) (xy 29.708567 -411.180149) (xy 29.700753 -411.161453) (xy 29.70022 -411.151324)
			(xy 29.70022 -410.993336) (xy 29.699788 -410.984151) (xy 29.693289 -410.966967) (xy 29.68752 -410.959808)
			(xy 29.665717 -410.934169) (xy 29.62777 -410.87858) (xy 29.596738 -410.818854) (xy 29.573067 -410.755848)
			(xy 29.557096 -410.690465) (xy 29.549054 -410.623641) (xy 0.508 -410.623641) (xy 0.508 -416.589972)
			(xy 0.508522 -416.645779) (xy 0.516863 -416.757081) (xy 0.533498 -416.867448) (xy 0.558335 -416.976264)
			(xy 0.591234 -417.082919) (xy 0.632011 -417.186818) (xy 0.680438 -417.287379) (xy 0.681656 -417.289488)
			(xy 53.073808 -417.289488) (xy 53.073808 -394.27912) (xy 66.477388 -394.27912) (xy 66.525648 -394.32738)
			(xy 66.525648 -397.823885) (xy 71.348788 -397.823885) (xy 71.348792 -397.756458) (xy 71.356871 -397.689518)
			(xy 71.372911 -397.624026) (xy 71.396679 -397.560928) (xy 71.427833 -397.501131) (xy 71.465926 -397.445495)
			(xy 71.487792 -397.41983) (xy 71.4936 -397.412693) (xy 71.500108 -397.395496) (xy 71.500492 -397.386302)
			(xy 71.500492 -396.89405) (xy 71.50006 -396.884865) (xy 71.493562 -396.86768) (xy 71.487792 -396.860522)
			(xy 71.465918 -396.834865) (xy 71.427831 -396.779229) (xy 71.396681 -396.719431) (xy 71.372918 -396.656334)
			(xy 71.356883 -396.590844) (xy 71.348808 -396.523905) (xy 71.348809 -396.45648) (xy 71.356886 -396.389542)
			(xy 71.372922 -396.324052) (xy 71.396687 -396.260955) (xy 71.427838 -396.201158) (xy 71.465928 -396.145523)
			(xy 71.487792 -396.119858) (xy 71.493588 -396.112712) (xy 71.500103 -396.095522) (xy 71.500492 -396.08633)
			(xy 71.500492 -395.92885) (xy 71.501066 -395.918732) (xy 71.508769 -395.900021) (xy 71.523028 -395.885665)
			(xy 71.541686 -395.877836) (xy 71.5518 -395.877288) (xy 72.26808 -395.877288) (xy 72.278231 -395.877738)
			(xy 72.296981 -395.885524) (xy 72.311305 -395.899912) (xy 72.319007 -395.918697) (xy 72.319388 -395.92885)
			(xy 72.319388 -396.08633) (xy 72.319786 -396.095518) (xy 72.326308 -396.112703) (xy 72.332088 -396.119858)
			(xy 72.353943 -396.145531) (xy 72.392032 -396.201164) (xy 72.423184 -396.260959) (xy 72.446949 -396.324055)
			(xy 72.462986 -396.389543) (xy 72.471063 -396.456481) (xy 72.471064 -396.523904) (xy 72.462989 -396.590842)
			(xy 72.446954 -396.656331) (xy 72.42319 -396.719427) (xy 72.39204 -396.779223) (xy 72.353952 -396.834857)
			(xy 72.332088 -396.860522) (xy 72.326298 -396.867672) (xy 72.31978 -396.884859) (xy 72.319388 -396.89405)
			(xy 72.319388 -397.386302) (xy 72.3198 -397.395489) (xy 72.326313 -397.412673) (xy 72.332088 -397.41983)
			(xy 72.353915 -397.445526) (xy 72.392006 -397.501156) (xy 72.420766 -397.556355) (xy 73.54898 -397.556355)
			(xy 73.557023 -397.489534) (xy 73.572995 -397.424152) (xy 73.596666 -397.361148) (xy 73.627698 -397.301425)
			(xy 73.665645 -397.245838) (xy 73.687432 -397.220186) (xy 73.693221 -397.213036) (xy 73.69974 -397.195849)
			(xy 73.700132 -397.186658) (xy 73.700132 -397.028924) (xy 73.700542 -397.018767) (xy 73.708335 -397.000009)
			(xy 73.722736 -396.985684) (xy 73.741535 -396.977989) (xy 73.751694 -396.977616) (xy 74.467974 -396.977616)
			(xy 74.478096 -396.978147) (xy 74.496812 -396.985862) (xy 74.511169 -397.000134) (xy 74.518993 -397.018805)
			(xy 74.519536 -397.028924) (xy 74.519536 -397.186658) (xy 74.519981 -397.195841) (xy 74.526472 -397.213025)
			(xy 74.532236 -397.220186) (xy 74.554034 -397.24583) (xy 74.591984 -397.301417) (xy 74.623019 -397.361141)
			(xy 74.646692 -397.424147) (xy 74.662665 -397.48953) (xy 74.670709 -397.556354) (xy 74.670708 -397.623661)
			(xy 74.662662 -397.690484) (xy 74.646687 -397.755867) (xy 74.623012 -397.818872) (xy 74.620438 -397.823826)
			(xy 75.749084 -397.823826) (xy 75.749087 -397.756517) (xy 75.757136 -397.689691) (xy 75.773114 -397.624306)
			(xy 75.796793 -397.5613) (xy 75.827833 -397.501576) (xy 75.865789 -397.44599) (xy 75.88758 -397.420338)
			(xy 75.893383 -397.413197) (xy 75.899895 -397.396003) (xy 75.90028 -397.38681) (xy 75.90028 -396.893542)
			(xy 75.899854 -396.884356) (xy 75.893352 -396.867172) (xy 75.88758 -396.860014) (xy 75.865781 -396.83437)
			(xy 75.82783 -396.778784) (xy 75.796795 -396.719059) (xy 75.773121 -396.656054) (xy 75.757147 -396.59067)
			(xy 75.749104 -396.523846) (xy 75.749104 -396.456539) (xy 75.75715 -396.389715) (xy 75.773125 -396.324332)
			(xy 75.796801 -396.261327) (xy 75.827838 -396.201603) (xy 75.86579 -396.146018) (xy 75.88758 -396.120366)
			(xy 75.893371 -396.113217) (xy 75.89989 -396.096029) (xy 75.90028 -396.086838) (xy 75.90028 -395.92885)
			(xy 75.900706 -395.918676) (xy 75.908482 -395.899875) (xy 75.922868 -395.885487) (xy 75.941668 -395.877707)
			(xy 75.951842 -395.877288) (xy 76.668122 -395.877288) (xy 76.678301 -395.877647) (xy 76.697106 -395.885449)
			(xy 76.711492 -395.899855) (xy 76.719267 -395.91867) (xy 76.719684 -395.92885) (xy 76.719684 -396.086838)
			(xy 76.720079 -396.096027) (xy 76.726604 -396.113211) (xy 76.732384 -396.120366) (xy 76.754161 -396.146026)
			(xy 76.792109 -396.201612) (xy 76.823141 -396.261335) (xy 76.846814 -396.324338) (xy 76.862787 -396.389719)
			(xy 76.870831 -396.456541) (xy 76.870832 -396.523844) (xy 76.862789 -396.590666) (xy 76.846818 -396.656047)
			(xy 76.823147 -396.719051) (xy 76.792117 -396.778775) (xy 76.75417 -396.834362) (xy 76.732384 -396.860014)
			(xy 76.726597 -396.867166) (xy 76.720077 -396.884351) (xy 76.719684 -396.893542) (xy 76.719684 -397.38681)
			(xy 76.720093 -397.395997) (xy 76.726608 -397.413181) (xy 76.732384 -397.420338) (xy 76.754133 -397.446021)
			(xy 76.792082 -397.501604) (xy 76.820503 -397.556296) (xy 77.948748 -397.556296) (xy 77.956824 -397.489358)
			(xy 77.972859 -397.423869) (xy 77.996623 -397.360772) (xy 78.027774 -397.300977) (xy 78.065864 -397.245343)
			(xy 78.087728 -397.219678) (xy 78.09352 -397.21253) (xy 78.100037 -397.195341) (xy 78.100428 -397.18615)
			(xy 78.100428 -397.028924) (xy 78.100836 -397.0188) (xy 78.108582 -397.000091) (xy 78.122901 -396.985775)
			(xy 78.141611 -396.978034) (xy 78.151736 -396.977616) (xy 78.868016 -396.977616) (xy 78.878142 -396.978003)
			(xy 78.896849 -396.985759) (xy 78.911163 -397.000085) (xy 78.918905 -397.018798) (xy 78.919324 -397.028924)
			(xy 78.919324 -397.18615) (xy 78.919753 -397.195335) (xy 78.926253 -397.21252) (xy 78.932024 -397.219678)
			(xy 78.953897 -397.245336) (xy 78.991984 -397.300972) (xy 79.023133 -397.360769) (xy 79.046895 -397.423867)
			(xy 79.062929 -397.489357) (xy 79.071004 -397.556296) (xy 79.071003 -397.62372) (xy 79.062927 -397.690658)
			(xy 79.046891 -397.756147) (xy 79.023127 -397.819245) (xy 79.02071 -397.823885) (xy 80.148876 -397.823885)
			(xy 80.14888 -397.756458) (xy 80.156959 -397.689518) (xy 80.172998 -397.624027) (xy 80.196765 -397.560929)
			(xy 80.227919 -397.501131) (xy 80.266011 -397.445496) (xy 80.287876 -397.41983) (xy 80.293682 -397.412691)
			(xy 80.300192 -397.395496) (xy 80.300576 -397.386302) (xy 80.300576 -396.89405) (xy 80.300147 -396.884865)
			(xy 80.293647 -396.86768) (xy 80.287876 -396.860522) (xy 80.266003 -396.834864) (xy 80.227916 -396.779228)
			(xy 80.196767 -396.719431) (xy 80.173005 -396.656333) (xy 80.156971 -396.590843) (xy 80.148896 -396.523904)
			(xy 80.148897 -396.45648) (xy 80.156973 -396.389542) (xy 80.173009 -396.324053) (xy 80.196773 -396.260955)
			(xy 80.227924 -396.201159) (xy 80.266012 -396.145524) (xy 80.287876 -396.119858) (xy 80.29367 -396.112711)
			(xy 80.300187 -396.095522) (xy 80.300576 -396.08633) (xy 80.300576 -395.92885) (xy 80.301069 -395.918722)
			(xy 80.308787 -395.899995) (xy 80.323072 -395.885636) (xy 80.341759 -395.877821) (xy 80.351884 -395.877288)
			(xy 81.068164 -395.877288) (xy 81.078314 -395.877751) (xy 81.097063 -395.885532) (xy 81.111388 -395.899917)
			(xy 81.119091 -395.918698) (xy 81.119472 -395.92885) (xy 81.119472 -396.08633) (xy 81.119874 -396.095518)
			(xy 81.126394 -396.112702) (xy 81.132172 -396.119858) (xy 81.154027 -396.145531) (xy 81.192118 -396.201164)
			(xy 81.223271 -396.260959) (xy 81.247037 -396.324054) (xy 81.263074 -396.389543) (xy 81.271151 -396.456481)
			(xy 81.271152 -396.523904) (xy 81.263076 -396.590842) (xy 81.247041 -396.656331) (xy 81.223277 -396.719428)
			(xy 81.192126 -396.779223) (xy 81.154036 -396.834857) (xy 81.132172 -396.860522) (xy 81.12638 -396.86767)
			(xy 81.119863 -396.884859) (xy 81.119472 -396.89405) (xy 81.119472 -397.386302) (xy 81.119887 -397.395489)
			(xy 81.126398 -397.412673) (xy 81.132172 -397.41983) (xy 81.154 -397.445526) (xy 81.192091 -397.501155)
			(xy 81.220853 -397.556356) (xy 82.349068 -397.556356) (xy 82.357111 -397.489534) (xy 82.373082 -397.424153)
			(xy 82.396753 -397.361149) (xy 82.427783 -397.301425) (xy 82.46573 -397.245838) (xy 82.487516 -397.220186)
			(xy 82.493303 -397.213034) (xy 82.499823 -397.195849) (xy 82.500216 -397.186658) (xy 82.500216 -397.028924)
			(xy 82.500641 -397.018769) (xy 82.508432 -397.000014) (xy 82.522828 -396.98569) (xy 82.541621 -396.977992)
			(xy 82.551778 -396.977616) (xy 83.268058 -396.977616) (xy 83.278179 -396.97816) (xy 83.296895 -396.98587)
			(xy 83.311252 -397.000138) (xy 83.319076 -397.018806) (xy 83.31962 -397.028924) (xy 83.31962 -397.186658)
			(xy 83.320046 -397.195844) (xy 83.326548 -397.213028) (xy 83.33232 -397.220186) (xy 83.354119 -397.24583)
			(xy 83.39207 -397.301416) (xy 83.423105 -397.361141) (xy 83.446779 -397.424146) (xy 83.462753 -397.48953)
			(xy 83.470796 -397.556354) (xy 83.470796 -397.623661) (xy 83.46275 -397.690485) (xy 83.446775 -397.755868)
			(xy 83.423099 -397.818873) (xy 83.420495 -397.823884) (xy 84.548667 -397.823884) (xy 84.548671 -397.756458)
			(xy 84.55675 -397.689518) (xy 84.572788 -397.624028) (xy 84.596555 -397.560929) (xy 84.627708 -397.501132)
			(xy 84.665799 -397.445496) (xy 84.687664 -397.41983) (xy 84.693481 -397.412699) (xy 84.699982 -397.395497)
			(xy 84.700364 -397.386302) (xy 84.700364 -396.89405) (xy 84.699916 -396.884867) (xy 84.693427 -396.867683)
			(xy 84.687664 -396.860522) (xy 84.665791 -396.834864) (xy 84.627705 -396.779228) (xy 84.596557 -396.71943)
			(xy 84.572795 -396.656332) (xy 84.556761 -396.590843) (xy 84.548687 -396.523904) (xy 84.548688 -396.456481)
			(xy 84.556764 -396.389542) (xy 84.5728 -396.324053) (xy 84.596563 -396.260956) (xy 84.627713 -396.201159)
			(xy 84.665801 -396.145524) (xy 84.687664 -396.119858) (xy 84.693469 -396.112719) (xy 84.699977 -396.095523)
			(xy 84.700364 -396.08633) (xy 84.700364 -395.92885) (xy 84.700868 -395.918724) (xy 84.708584 -395.899999)
			(xy 84.722866 -395.88564) (xy 84.741548 -395.877823) (xy 84.751672 -395.877288) (xy 85.467952 -395.877288)
			(xy 85.478102 -395.877761) (xy 85.496851 -395.885538) (xy 85.511175 -395.899919) (xy 85.518879 -395.918699)
			(xy 85.51926 -395.92885) (xy 85.51926 -396.08633) (xy 85.519665 -396.095518) (xy 85.526183 -396.112701)
			(xy 85.53196 -396.119858) (xy 85.553816 -396.145531) (xy 85.591907 -396.201163) (xy 85.623061 -396.260958)
			(xy 85.646827 -396.324054) (xy 85.662864 -396.389543) (xy 85.670942 -396.456481) (xy 85.670943 -396.523904)
			(xy 85.662867 -396.590843) (xy 85.646832 -396.656332) (xy 85.623067 -396.719428) (xy 85.591915 -396.779224)
			(xy 85.553825 -396.834857) (xy 85.53196 -396.860522) (xy 85.526167 -396.867669) (xy 85.519651 -396.884858)
			(xy 85.51926 -396.89405) (xy 85.51926 -397.386302) (xy 85.519678 -397.395488) (xy 85.526187 -397.412672)
			(xy 85.53196 -397.41983) (xy 85.553788 -397.445525) (xy 85.591881 -397.501155) (xy 85.620612 -397.556296)
			(xy 86.748836 -397.556296) (xy 86.756911 -397.489358) (xy 86.772946 -397.423869) (xy 86.79671 -397.360773)
			(xy 86.82786 -397.300977) (xy 86.865948 -397.245343) (xy 86.887812 -397.219678) (xy 86.893602 -397.212528)
			(xy 86.90012 -397.195341) (xy 86.900512 -397.18615) (xy 86.900512 -397.028924) (xy 86.900936 -397.018802)
			(xy 86.908678 -397.000096) (xy 86.922993 -396.985781) (xy 86.941698 -396.978037) (xy 86.95182 -396.977616)
			(xy 87.6681 -396.977616) (xy 87.678224 -396.978016) (xy 87.696931 -396.985768) (xy 87.711246 -397.000089)
			(xy 87.718988 -397.018799) (xy 87.719408 -397.028924) (xy 87.719408 -397.18615) (xy 87.71984 -397.195335)
			(xy 87.726338 -397.21252) (xy 87.732108 -397.219678) (xy 87.753982 -397.245335) (xy 87.792069 -397.300971)
			(xy 87.823219 -397.360769) (xy 87.846982 -397.423866) (xy 87.863017 -397.489356) (xy 87.871092 -397.556295)
			(xy 87.871091 -397.62372) (xy 87.863014 -397.690658) (xy 87.846978 -397.756148) (xy 87.823213 -397.819245)
			(xy 87.820827 -397.823826) (xy 88.948962 -397.823826) (xy 88.948966 -397.756517) (xy 88.957014 -397.689692)
			(xy 88.972991 -397.624307) (xy 88.996669 -397.561301) (xy 89.027707 -397.501577) (xy 89.065661 -397.44599)
			(xy 89.087452 -397.420338) (xy 89.093264 -397.413204) (xy 89.099768 -397.396005) (xy 89.100152 -397.38681)
			(xy 89.100152 -396.893542) (xy 89.09971 -396.884358) (xy 89.093217 -396.867175) (xy 89.087452 -396.860014)
			(xy 89.065654 -396.83437) (xy 89.027704 -396.778783) (xy 88.996671 -396.719058) (xy 88.972998 -396.656053)
			(xy 88.957025 -396.590669) (xy 88.948982 -396.523846) (xy 88.948983 -396.456539) (xy 88.957028 -396.389716)
			(xy 88.973003 -396.324333) (xy 88.996677 -396.261328) (xy 89.027712 -396.201604) (xy 89.065663 -396.146018)
			(xy 89.087452 -396.120366) (xy 89.093252 -396.113223) (xy 89.099763 -396.096031) (xy 89.100152 -396.086838)
			(xy 89.100152 -395.92885) (xy 89.100605 -395.91868) (xy 89.108376 -395.899884) (xy 89.122753 -395.885496)
			(xy 89.141544 -395.877712) (xy 89.151714 -395.877288) (xy 89.867994 -395.877288) (xy 89.878171 -395.87767)
			(xy 89.896976 -395.885462) (xy 89.911362 -395.899861) (xy 89.919139 -395.918672) (xy 89.919556 -395.92885)
			(xy 89.919556 -396.086838) (xy 89.919958 -396.096026) (xy 89.926478 -396.11321) (xy 89.932256 -396.120366)
			(xy 89.954034 -396.146026) (xy 89.991983 -396.201611) (xy 90.023017 -396.261334) (xy 90.046691 -396.324337)
			(xy 90.062665 -396.389719) (xy 90.07071 -396.45654) (xy 90.070711 -396.523845) (xy 90.062667 -396.590667)
			(xy 90.046695 -396.656048) (xy 90.023023 -396.719052) (xy 89.991991 -396.778776) (xy 89.954043 -396.834362)
			(xy 89.932256 -396.860014) (xy 89.926465 -396.867163) (xy 89.919948 -396.884351) (xy 89.919556 -396.893542)
			(xy 89.919556 -397.38681) (xy 89.919971 -397.395996) (xy 89.926482 -397.41318) (xy 89.932256 -397.420338)
			(xy 89.954006 -397.446021) (xy 89.991957 -397.501603) (xy 90.020411 -397.556356) (xy 91.149156 -397.556356)
			(xy 91.157198 -397.489535) (xy 91.173169 -397.424153) (xy 91.196839 -397.361149) (xy 91.227869 -397.301426)
			(xy 91.265814 -397.245839) (xy 91.2876 -397.220186) (xy 91.293385 -397.213033) (xy 91.299907 -397.195848)
			(xy 91.3003 -397.186658) (xy 91.3003 -397.028924) (xy 91.300741 -397.018771) (xy 91.308529 -397.000019)
			(xy 91.32292 -396.985695) (xy 91.341708 -396.977995) (xy 91.351862 -396.977616) (xy 92.068142 -396.977616)
			(xy 92.078268 -396.978091) (xy 92.096986 -396.985829) (xy 92.11134 -397.000118) (xy 92.119162 -397.0188)
			(xy 92.119704 -397.028924) (xy 92.119704 -397.186658) (xy 92.120133 -397.195843) (xy 92.126634 -397.213028)
			(xy 92.132404 -397.220186) (xy 92.1542 -397.245831) (xy 92.192146 -397.301419) (xy 92.223176 -397.361144)
			(xy 92.246847 -397.42415) (xy 92.262818 -397.489532) (xy 92.27086 -397.556355) (xy 92.270859 -397.62366)
			(xy 92.262815 -397.690483) (xy 92.246842 -397.755865) (xy 92.22317 -397.81887) (xy 92.220595 -397.823825)
			(xy 115.349226 -397.823825) (xy 115.349229 -397.756518) (xy 115.357277 -397.689693) (xy 115.373253 -397.624309)
			(xy 115.396928 -397.561303) (xy 115.427964 -397.501578) (xy 115.465915 -397.445991) (xy 115.487704 -397.420338)
			(xy 115.49351 -397.413199) (xy 115.500019 -397.396004) (xy 115.500404 -397.38681) (xy 115.500404 -396.893542)
			(xy 115.499973 -396.884357) (xy 115.493474 -396.867173) (xy 115.487704 -396.860014) (xy 115.465908 -396.834369)
			(xy 115.427961 -396.778781) (xy 115.39693 -396.719056) (xy 115.37326 -396.656051) (xy 115.357288 -396.590668)
			(xy 115.349246 -396.523845) (xy 115.349247 -396.45654) (xy 115.357291 -396.389717) (xy 115.373264 -396.324335)
			(xy 115.396937 -396.26133) (xy 115.427969 -396.201606) (xy 115.465917 -396.146019) (xy 115.487704 -396.120366)
			(xy 115.493498 -396.113219) (xy 115.500014 -396.09603) (xy 115.500404 -396.086838) (xy 115.500404 -395.92885)
			(xy 115.500904 -395.918686) (xy 115.508666 -395.899899) (xy 115.523028 -395.885513) (xy 115.541803 -395.87772)
			(xy 115.551966 -395.877288) (xy 116.268246 -395.877288) (xy 116.278427 -395.877627) (xy 116.297232 -395.885437)
			(xy 116.311617 -395.899849) (xy 116.319392 -395.918668) (xy 116.319808 -395.92885) (xy 116.319808 -396.086838)
			(xy 116.320198 -396.096027) (xy 116.326725 -396.113212) (xy 116.332508 -396.120366) (xy 116.354288 -396.146026)
			(xy 116.39224 -396.20161) (xy 116.423277 -396.261332) (xy 116.446952 -396.324335) (xy 116.462928 -396.389717)
			(xy 116.470973 -396.45654) (xy 116.470974 -396.523845) (xy 116.46293 -396.590668) (xy 116.446957 -396.65605)
			(xy 116.423283 -396.719055) (xy 116.392248 -396.778777) (xy 116.354297 -396.834363) (xy 116.332508 -396.860014)
			(xy 116.326724 -396.867168) (xy 116.320202 -396.884352) (xy 116.319808 -396.893542) (xy 116.319808 -397.38681)
			(xy 116.320212 -397.395998) (xy 116.32673 -397.413182) (xy 116.332508 -397.420338) (xy 116.35426 -397.44602)
			(xy 116.392213 -397.501601) (xy 116.42064 -397.556296) (xy 117.548866 -397.556296) (xy 117.556942 -397.489357)
			(xy 117.572978 -397.423868) (xy 117.596743 -397.360771) (xy 117.627896 -397.300976) (xy 117.665987 -397.245342)
			(xy 117.687852 -397.219678) (xy 117.693647 -397.212532) (xy 117.700161 -397.195342) (xy 117.700552 -397.18615)
			(xy 117.700552 -397.028924) (xy 117.701103 -397.018823) (xy 117.708824 -397.000154) (xy 117.7231 -396.98586)
			(xy 117.741759 -396.978116) (xy 117.75186 -396.977616) (xy 118.46814 -396.977616) (xy 118.478253 -396.978053)
			(xy 118.496935 -396.985807) (xy 118.511229 -397.000118) (xy 118.51896 -397.01881) (xy 118.519448 -397.028924)
			(xy 118.519448 -397.18615) (xy 118.519894 -397.195333) (xy 118.526384 -397.212517) (xy 118.532148 -397.219678)
			(xy 118.554024 -397.245334) (xy 118.592115 -397.300969) (xy 118.623269 -397.360766) (xy 118.647035 -397.423864)
			(xy 118.663071 -397.489355) (xy 118.671147 -397.556295) (xy 118.671146 -397.62372) (xy 118.663068 -397.69066)
			(xy 118.64703 -397.75615) (xy 118.623262 -397.819248) (xy 118.620846 -397.823885) (xy 119.748994 -397.823885)
			(xy 119.748998 -397.756458) (xy 119.757077 -397.689517) (xy 119.773117 -397.624026) (xy 119.796885 -397.560928)
			(xy 119.828041 -397.50113) (xy 119.866134 -397.445495) (xy 119.888 -397.41983) (xy 119.893809 -397.412693)
			(xy 119.900316 -397.395496) (xy 119.9007 -397.386302) (xy 119.9007 -396.89405) (xy 119.900266 -396.884865)
			(xy 119.893769 -396.867681) (xy 119.888 -396.860522) (xy 119.866126 -396.834865) (xy 119.828038 -396.779229)
			(xy 119.796888 -396.719432) (xy 119.773124 -396.656334) (xy 119.757089 -396.590844) (xy 119.749014 -396.523905)
			(xy 119.749015 -396.45648) (xy 119.757092 -396.389541) (xy 119.773128 -396.324052) (xy 119.796894 -396.260954)
			(xy 119.828046 -396.201158) (xy 119.866135 -396.145523) (xy 119.888 -396.119858) (xy 119.893797 -396.112713)
			(xy 119.900311 -396.095522) (xy 119.9007 -396.08633) (xy 119.9007 -395.92885) (xy 119.901266 -395.918731)
			(xy 119.90897 -395.900019) (xy 119.923232 -395.885662) (xy 119.941893 -395.877834) (xy 119.952008 -395.877288)
			(xy 120.668288 -395.877288) (xy 120.678408 -395.877725) (xy 120.697109 -395.885467) (xy 120.711424 -395.899777)
			(xy 120.719171 -395.918476) (xy 120.719596 -395.928596) (xy 120.719596 -396.08633) (xy 120.719992 -396.095519)
			(xy 120.726516 -396.112703) (xy 120.732296 -396.119858) (xy 120.75415 -396.145531) (xy 120.79224 -396.201165)
			(xy 120.823391 -396.26096) (xy 120.847156 -396.324055) (xy 120.863192 -396.389544) (xy 120.871269 -396.456481)
			(xy 120.87127 -396.523904) (xy 120.863195 -396.590842) (xy 120.84716 -396.65633) (xy 120.823397 -396.719427)
			(xy 120.792247 -396.779223) (xy 120.75416 -396.834857) (xy 120.732296 -396.860522) (xy 120.726507 -396.867673)
			(xy 120.719988 -396.884859) (xy 120.719596 -396.89405) (xy 120.719596 -397.386302) (xy 120.720006 -397.395489)
			(xy 120.72652 -397.412673) (xy 120.732296 -397.41983) (xy 120.754123 -397.445526) (xy 120.792213 -397.501156)
			(xy 120.820972 -397.556355) (xy 121.949186 -397.556355) (xy 121.95723 -397.489533) (xy 121.973202 -397.424152)
			(xy 121.996873 -397.361148) (xy 122.027905 -397.301425) (xy 122.065853 -397.245838) (xy 122.08764 -397.220186)
			(xy 122.09343 -397.213036) (xy 122.099948 -397.195849) (xy 122.10034 -397.186658) (xy 122.10034 -397.028924)
			(xy 122.100736 -397.018798) (xy 122.108484 -397.000087) (xy 122.122807 -396.985771) (xy 122.141522 -396.978032)
			(xy 122.151648 -396.977616) (xy 122.868182 -396.977616) (xy 122.878305 -396.978141) (xy 122.897021 -396.985858)
			(xy 122.911377 -397.000132) (xy 122.919201 -397.018804) (xy 122.919744 -397.028924) (xy 122.919744 -397.186658)
			(xy 122.920187 -397.195841) (xy 122.926679 -397.213026) (xy 122.932444 -397.220186) (xy 122.954242 -397.24583)
			(xy 122.992192 -397.301417) (xy 123.023225 -397.361142) (xy 123.046898 -397.424147) (xy 123.062871 -397.489531)
			(xy 123.070915 -397.556354) (xy 123.070914 -397.623661) (xy 123.062868 -397.690484) (xy 123.046894 -397.755867)
			(xy 123.023219 -397.818872) (xy 123.020645 -397.823826) (xy 124.14929 -397.823826) (xy 124.149293 -397.756517)
			(xy 124.157342 -397.689691) (xy 124.17332 -397.624306) (xy 124.197 -397.5613) (xy 124.22804 -397.501575)
			(xy 124.265997 -397.44599) (xy 124.287788 -397.420338) (xy 124.293592 -397.413198) (xy 124.300103 -397.396004)
			(xy 124.300488 -397.38681) (xy 124.300488 -396.893542) (xy 124.30006 -396.884357) (xy 124.293559 -396.867172)
			(xy 124.287788 -396.860014) (xy 124.265989 -396.834371) (xy 124.228037 -396.778784) (xy 124.197002 -396.71906)
			(xy 124.173327 -396.656054) (xy 124.157354 -396.59067) (xy 124.14931 -396.523846) (xy 124.14931 -396.456539)
			(xy 124.157356 -396.389715) (xy 124.173332 -396.324332) (xy 124.197008 -396.261327) (xy 124.228045 -396.201603)
			(xy 124.265998 -396.146018) (xy 124.287788 -396.120366) (xy 124.29358 -396.113218) (xy 124.300098 -396.09603)
			(xy 124.300488 -396.086838) (xy 124.300488 -395.92885) (xy 124.300906 -395.918675) (xy 124.308684 -395.899872)
			(xy 124.323072 -395.885484) (xy 124.341875 -395.877706) (xy 124.35205 -395.877288) (xy 125.06833 -395.877288)
			(xy 125.07851 -395.87764) (xy 125.097315 -395.885445) (xy 125.1117 -395.899852) (xy 125.119475 -395.91867)
			(xy 125.119892 -395.92885) (xy 125.119892 -396.086838) (xy 125.120286 -396.096027) (xy 125.126811 -396.113211)
			(xy 125.132592 -396.120366) (xy 125.154369 -396.146027) (xy 125.192316 -396.201613) (xy 125.223348 -396.261335)
			(xy 125.24702 -396.324339) (xy 125.262993 -396.389719) (xy 125.271037 -396.456541) (xy 125.271038 -396.523844)
			(xy 125.262995 -396.590666) (xy 125.247025 -396.656047) (xy 125.223354 -396.719051) (xy 125.192324 -396.778774)
			(xy 125.154378 -396.834361) (xy 125.132592 -396.860014) (xy 125.126806 -396.867167) (xy 125.120285 -396.884351)
			(xy 125.119892 -396.893542) (xy 125.119892 -397.38681) (xy 125.120299 -397.395998) (xy 125.126815 -397.413182)
			(xy 125.132592 -397.420338) (xy 125.154341 -397.446021) (xy 125.192289 -397.501604) (xy 125.22071 -397.556296)
			(xy 126.348954 -397.556296) (xy 126.35703 -397.489357) (xy 126.373065 -397.423869) (xy 126.39683 -397.360772)
			(xy 126.427981 -397.300976) (xy 126.466071 -397.245343) (xy 126.487936 -397.219678) (xy 126.493729 -397.21253)
			(xy 126.500245 -397.195342) (xy 126.500636 -397.18615) (xy 126.500636 -397.028924) (xy 126.501036 -397.018799)
			(xy 126.508783 -397.000089) (xy 126.523105 -396.985772) (xy 126.541818 -396.978032) (xy 126.551944 -396.977616)
			(xy 127.268224 -396.977616) (xy 127.278336 -396.978066) (xy 127.297018 -396.985814) (xy 127.311313 -397.000122)
			(xy 127.319044 -397.018811) (xy 127.319532 -397.028924) (xy 127.319532 -397.18615) (xy 127.319981 -397.195333)
			(xy 127.326469 -397.212517) (xy 127.332232 -397.219678) (xy 127.354105 -397.245336) (xy 127.392191 -397.300972)
			(xy 127.423339 -397.36077) (xy 127.447102 -397.423867) (xy 127.463135 -397.489357) (xy 127.47121 -397.556296)
			(xy 127.471209 -397.623719) (xy 127.463133 -397.690658) (xy 127.447097 -397.756147) (xy 127.423333 -397.819244)
			(xy 127.420946 -397.823826) (xy 128.54908 -397.823826) (xy 128.549084 -397.756517) (xy 128.557132 -397.689691)
			(xy 128.57311 -397.624306) (xy 128.596789 -397.5613) (xy 128.627829 -397.501576) (xy 128.665785 -397.445989)
			(xy 128.687576 -397.420338) (xy 128.693379 -397.413197) (xy 128.69989 -397.396003) (xy 128.700276 -397.38681)
			(xy 128.700276 -396.893542) (xy 128.699851 -396.884356) (xy 128.693348 -396.867171) (xy 128.687576 -396.860014)
			(xy 128.665777 -396.83437) (xy 128.627826 -396.778784) (xy 128.596792 -396.719059) (xy 128.573118 -396.656053)
			(xy 128.557144 -396.59067) (xy 128.5491 -396.523846) (xy 128.549101 -396.456539) (xy 128.557147 -396.389715)
			(xy 128.573122 -396.324332) (xy 128.596798 -396.261327) (xy 128.627834 -396.201604) (xy 128.665787 -396.146018)
			(xy 128.687576 -396.120366) (xy 128.693367 -396.113216) (xy 128.699886 -396.096029) (xy 128.700276 -396.086838)
			(xy 128.700276 -395.92885) (xy 128.700706 -395.918677) (xy 128.708481 -395.899876) (xy 128.722866 -395.885488)
			(xy 128.741665 -395.877708) (xy 128.751838 -395.877288) (xy 129.468118 -395.877288) (xy 129.478297 -395.87765)
			(xy 129.497102 -395.885451) (xy 129.511487 -395.899856) (xy 129.519263 -395.91867) (xy 129.51968 -395.92885)
			(xy 129.51968 -396.086838) (xy 129.520076 -396.096027) (xy 129.5266 -396.113211) (xy 129.53238 -396.120366)
			(xy 129.554157 -396.146026) (xy 129.592105 -396.201612) (xy 129.623138 -396.261335) (xy 129.64681 -396.324338)
			(xy 129.662784 -396.389719) (xy 129.670828 -396.456541) (xy 129.670829 -396.523844) (xy 129.662786 -396.590666)
			(xy 129.646815 -396.656047) (xy 129.623144 -396.719051) (xy 129.592113 -396.778775) (xy 129.554167 -396.834362)
			(xy 129.53238 -396.860014) (xy 129.526593 -396.867166) (xy 129.520073 -396.884351) (xy 129.51968 -396.893542)
			(xy 129.51968 -397.38681) (xy 129.52009 -397.395997) (xy 129.526604 -397.413181) (xy 129.53238 -397.420338)
			(xy 129.55413 -397.446021) (xy 129.592078 -397.501604) (xy 129.620531 -397.556356) (xy 130.749274 -397.556356)
			(xy 130.757317 -397.489534) (xy 130.773288 -397.424152) (xy 130.796959 -397.361148) (xy 130.827991 -397.301425)
			(xy 130.865937 -397.245838) (xy 130.887724 -397.220186) (xy 130.893512 -397.213035) (xy 130.900031 -397.195849)
			(xy 130.900424 -397.186658) (xy 130.900424 -397.028924) (xy 130.900842 -397.018768) (xy 130.908634 -397.000012)
			(xy 130.923032 -396.985687) (xy 130.941828 -396.97799) (xy 130.951986 -396.977616) (xy 131.668266 -396.977616)
			(xy 131.678388 -396.978154) (xy 131.697103 -396.985866) (xy 131.71146 -397.000137) (xy 131.719284 -397.018806)
			(xy 131.719828 -397.028924) (xy 131.719828 -397.186658) (xy 131.720252 -397.195844) (xy 131.726756 -397.213029)
			(xy 131.732528 -397.220186) (xy 131.754326 -397.24583) (xy 131.792277 -397.301417) (xy 131.823312 -397.361141)
			(xy 131.846985 -397.424147) (xy 131.862959 -397.48953) (xy 131.871003 -397.556354) (xy 131.871002 -397.623661)
			(xy 131.862956 -397.690485) (xy 131.846981 -397.755868) (xy 131.823306 -397.818873) (xy 131.792269 -397.878596)
			(xy 131.754317 -397.934182) (xy 131.732528 -397.959834) (xy 131.726726 -397.966975) (xy 131.720217 -397.984169)
			(xy 131.719828 -397.993362) (xy 131.719828 -398.486884) (xy 131.720239 -398.496071) (xy 131.726751 -398.513256)
			(xy 131.732528 -398.520412) (xy 131.754352 -398.546034) (xy 131.792302 -398.601624) (xy 131.823336 -398.661352)
			(xy 131.847008 -398.72436) (xy 131.86298 -398.789746) (xy 131.871021 -398.856573) (xy 131.871018 -398.923881)
			(xy 131.86297 -398.990707) (xy 131.846992 -399.056092) (xy 131.823314 -399.119098) (xy 131.792274 -399.178822)
			(xy 131.754319 -399.234408) (xy 131.732528 -399.26006) (xy 131.726715 -399.267193) (xy 131.720212 -399.284393)
			(xy 131.719828 -399.293588) (xy 131.719828 -399.451576) (xy 131.719359 -399.461725) (xy 131.711577 -399.480472)
			(xy 131.697195 -399.494795) (xy 131.678417 -399.502501) (xy 131.668266 -399.502884) (xy 130.951986 -399.502884)
			(xy 130.941861 -399.502385) (xy 130.923145 -399.494657) (xy 130.90879 -399.480375) (xy 130.900967 -399.461698)
			(xy 130.900424 -399.451576) (xy 130.900424 -399.293588) (xy 130.900014 -399.284401) (xy 130.8935 -399.267217)
			(xy 130.887724 -399.26006) (xy 130.865972 -399.234378) (xy 130.828023 -399.178796) (xy 130.796989 -399.119076)
			(xy 130.773315 -399.056076) (xy 130.75734 -398.990697) (xy 130.749294 -398.923878) (xy 130.74929 -398.856576)
			(xy 130.757331 -398.789756) (xy 130.773299 -398.724376) (xy 130.796967 -398.661373) (xy 130.827996 -398.601651)
			(xy 130.865939 -398.546065) (xy 130.887724 -398.520412) (xy 130.893543 -398.513283) (xy 130.900044 -398.49608)
			(xy 130.900424 -398.486884) (xy 130.900424 -397.993362) (xy 130.900027 -397.984174) (xy 130.893504 -397.96699)
			(xy 130.887724 -397.959834) (xy 130.865946 -397.934174) (xy 130.827998 -397.878588) (xy 130.796965 -397.818865)
			(xy 130.773293 -397.755862) (xy 130.75732 -397.690481) (xy 130.749275 -397.62366) (xy 130.749274 -397.556356)
			(xy 129.620531 -397.556356) (xy 129.623112 -397.561323) (xy 129.646786 -397.624324) (xy 129.662761 -397.689702)
			(xy 129.670808 -397.756521) (xy 129.670811 -397.823822) (xy 129.662771 -397.890642) (xy 129.646803 -397.956022)
			(xy 129.623135 -398.019025) (xy 129.592108 -398.078747) (xy 129.554165 -398.134333) (xy 129.53238 -398.159986)
			(xy 129.526562 -398.167116) (xy 129.520061 -398.184318) (xy 129.51968 -398.193514) (xy 129.51968 -398.351502)
			(xy 129.519169 -398.361658) (xy 129.511397 -398.380423) (xy 129.497037 -398.394788) (xy 129.478274 -398.402565)
			(xy 129.468118 -398.403064) (xy 128.751838 -398.403064) (xy 128.741669 -398.402605) (xy 128.722876 -398.394833)
			(xy 128.70849 -398.380458) (xy 128.700703 -398.361671) (xy 128.700276 -398.351502) (xy 128.700276 -398.193514)
			(xy 128.699865 -398.184327) (xy 128.693352 -398.167142) (xy 128.687576 -398.159986) (xy 128.66575 -398.134365)
			(xy 128.627799 -398.078775) (xy 128.596766 -398.019048) (xy 128.573093 -397.956039) (xy 128.557122 -397.890652)
			(xy 128.54908 -397.823826) (xy 127.420946 -397.823826) (xy 127.392183 -397.879041) (xy 127.354095 -397.934676)
			(xy 127.332232 -397.960342) (xy 127.326427 -397.967481) (xy 127.319919 -397.984676) (xy 127.319532 -397.99387)
			(xy 127.319532 -398.486376) (xy 127.319969 -398.49556) (xy 127.326466 -398.512744) (xy 127.332232 -398.519904)
			(xy 127.35413 -398.545541) (xy 127.392216 -398.60118) (xy 127.423363 -398.66098) (xy 127.447124 -398.724081)
			(xy 127.463156 -398.789573) (xy 127.471228 -398.856514) (xy 127.471225 -398.92394) (xy 127.463146 -398.99088)
			(xy 127.447108 -399.056371) (xy 127.423341 -399.119469) (xy 127.392188 -399.179266) (xy 127.354097 -399.234902)
			(xy 127.332232 -399.260568) (xy 127.326416 -399.267699) (xy 127.319915 -399.284901) (xy 127.319532 -399.294096)
			(xy 127.319532 -399.451576) (xy 127.318996 -399.461679) (xy 127.311272 -399.480351) (xy 127.296991 -399.494645)
			(xy 127.278327 -399.502387) (xy 127.268224 -399.502884) (xy 126.551944 -399.502884) (xy 126.541822 -399.502447)
			(xy 126.523117 -399.494711) (xy 126.5088 -399.4804) (xy 126.501056 -399.461697) (xy 126.500636 -399.451576)
			(xy 126.500636 -399.294096) (xy 126.50022 -399.28491) (xy 126.49371 -399.267726) (xy 126.487936 -399.260568)
			(xy 126.466106 -399.234874) (xy 126.428014 -399.179245) (xy 126.39686 -399.119453) (xy 126.373092 -399.056359)
			(xy 126.357053 -398.990873) (xy 126.348974 -398.923938) (xy 126.34897 -398.856516) (xy 126.357043 -398.78958)
			(xy 126.373076 -398.724092) (xy 126.396838 -398.660997) (xy 126.427986 -398.601202) (xy 126.466073 -398.545569)
			(xy 126.487936 -398.519904) (xy 126.493718 -398.512749) (xy 126.50024 -398.495566) (xy 126.500636 -398.486376)
			(xy 126.500636 -397.99387) (xy 126.500232 -397.984682) (xy 126.493713 -397.967498) (xy 126.487936 -397.960342)
			(xy 126.466081 -397.934669) (xy 126.427989 -397.879037) (xy 126.396836 -397.819242) (xy 126.37307 -397.756146)
			(xy 126.357032 -397.690657) (xy 126.348955 -397.623719) (xy 126.348954 -397.556296) (xy 125.22071 -397.556296)
			(xy 125.223323 -397.561324) (xy 125.246996 -397.624324) (xy 125.262971 -397.689702) (xy 125.271018 -397.756521)
			(xy 125.271021 -397.823822) (xy 125.262981 -397.890642) (xy 125.247013 -397.956021) (xy 125.223346 -398.019024)
			(xy 125.192319 -398.078747) (xy 125.154377 -398.134334) (xy 125.132592 -398.159986) (xy 125.126775 -398.167117)
			(xy 125.120273 -398.184318) (xy 125.119892 -398.193514) (xy 125.119892 -398.351502) (xy 125.119369 -398.361656)
			(xy 125.111599 -398.38042) (xy 125.097243 -398.394784) (xy 125.078484 -398.402563) (xy 125.06833 -398.403064)
			(xy 124.35205 -398.403064) (xy 124.341882 -398.402595) (xy 124.323089 -398.394827) (xy 124.308702 -398.380455)
			(xy 124.300915 -398.36167) (xy 124.300488 -398.351502) (xy 124.300488 -398.193514) (xy 124.300074 -398.184327)
			(xy 124.293563 -398.167143) (xy 124.287788 -398.159986) (xy 124.265961 -398.134365) (xy 124.228011 -398.078775)
			(xy 124.196976 -398.019048) (xy 124.173304 -397.956039) (xy 124.157332 -397.890653) (xy 124.14929 -397.823826)
			(xy 123.020645 -397.823826) (xy 122.992184 -397.878596) (xy 122.954233 -397.934182) (xy 122.932444 -397.959834)
			(xy 122.926644 -397.966976) (xy 122.920133 -397.984169) (xy 122.919744 -397.993362) (xy 122.919744 -398.486884)
			(xy 122.920174 -398.496069) (xy 122.926675 -398.513253) (xy 122.932444 -398.520412) (xy 122.954268 -398.546035)
			(xy 122.992217 -398.601625) (xy 123.023249 -398.661352) (xy 123.046921 -398.724361) (xy 123.062892 -398.789747)
			(xy 123.070933 -398.856573) (xy 123.07093 -398.923881) (xy 123.062882 -398.990707) (xy 123.046905 -399.056091)
			(xy 123.023227 -399.119097) (xy 122.992189 -399.178822) (xy 122.954235 -399.234408) (xy 122.932444 -399.26006)
			(xy 122.926633 -399.267194) (xy 122.920128 -399.284393) (xy 122.919744 -399.293588) (xy 122.919744 -399.451576)
			(xy 122.919196 -399.461678) (xy 122.911475 -399.480347) (xy 122.897197 -399.494641) (xy 122.878537 -399.502385)
			(xy 122.868436 -399.502884) (xy 122.151902 -399.502884) (xy 122.141778 -399.502372) (xy 122.123062 -399.49465)
			(xy 122.108706 -399.480371) (xy 122.100883 -399.461697) (xy 122.10034 -399.451576) (xy 122.10034 -399.293588)
			(xy 122.099927 -399.284401) (xy 122.093414 -399.267217) (xy 122.08764 -399.26006) (xy 122.065888 -399.234379)
			(xy 122.027938 -399.178796) (xy 121.996903 -399.119077) (xy 121.973228 -399.056076) (xy 121.957253 -398.990698)
			(xy 121.949206 -398.923878) (xy 121.949202 -398.856576) (xy 121.957243 -398.789756) (xy 121.973212 -398.724376)
			(xy 121.996881 -398.661373) (xy 122.02791 -398.60165) (xy 122.065855 -398.546064) (xy 122.08764 -398.520412)
			(xy 122.093461 -398.513285) (xy 122.09996 -398.49608) (xy 122.10034 -398.486884) (xy 122.10034 -397.993362)
			(xy 122.099939 -397.984174) (xy 122.093418 -397.96699) (xy 122.08764 -397.959834) (xy 122.065862 -397.934174)
			(xy 122.027913 -397.878588) (xy 121.996879 -397.818866) (xy 121.973206 -397.755863) (xy 121.957232 -397.690481)
			(xy 121.949187 -397.62366) (xy 121.949186 -397.556355) (xy 120.820972 -397.556355) (xy 120.823365 -397.560948)
			(xy 120.847132 -397.624041) (xy 120.86317 -397.689526) (xy 120.871249 -397.756461) (xy 120.871253 -397.823882)
			(xy 120.86318 -397.890818) (xy 120.847149 -397.956305) (xy 120.823389 -398.0194) (xy 120.792242 -398.079195)
			(xy 120.754158 -398.134829) (xy 120.732296 -398.160494) (xy 120.726519 -398.167653) (xy 120.719993 -398.184833)
			(xy 120.719596 -398.194022) (xy 120.719596 -398.351502) (xy 120.719076 -398.361624) (xy 120.711354 -398.380339)
			(xy 120.697079 -398.394694) (xy 120.678408 -398.402519) (xy 120.668288 -398.403064) (xy 119.952008 -398.403064)
			(xy 119.941882 -398.402677) (xy 119.923171 -398.394924) (xy 119.908855 -398.380599) (xy 119.901116 -398.361883)
			(xy 119.9007 -398.351756) (xy 119.9007 -398.194022) (xy 119.900279 -398.184836) (xy 119.893773 -398.167651)
			(xy 119.888 -398.160494) (xy 119.866099 -398.13486) (xy 119.828011 -398.079221) (xy 119.796862 -398.01942)
			(xy 119.7731 -397.956319) (xy 119.757067 -397.890826) (xy 119.748994 -397.823885) (xy 118.620846 -397.823885)
			(xy 118.592108 -397.879044) (xy 118.554014 -397.934678) (xy 118.532148 -397.960342) (xy 118.526345 -397.967482)
			(xy 118.519835 -397.984677) (xy 118.519448 -397.99387) (xy 118.519448 -398.486376) (xy 118.519881 -398.495561)
			(xy 118.52638 -398.512745) (xy 118.532148 -398.519904) (xy 118.554049 -398.545539) (xy 118.59214 -398.601177)
			(xy 118.623292 -398.660977) (xy 118.647057 -398.724078) (xy 118.663091 -398.789571) (xy 118.671165 -398.856513)
			(xy 118.671162 -398.923941) (xy 118.663082 -398.990882) (xy 118.647041 -399.056374) (xy 118.62327 -399.119473)
			(xy 118.592112 -399.17927) (xy 118.554016 -399.234904) (xy 118.532148 -399.260568) (xy 118.526334 -399.2677)
			(xy 118.519831 -399.284901) (xy 118.519448 -399.294096) (xy 118.519448 -399.451576) (xy 118.518897 -399.461677)
			(xy 118.511176 -399.480346) (xy 118.4969 -399.49464) (xy 118.478241 -399.502384) (xy 118.46814 -399.502884)
			(xy 117.75186 -399.502884) (xy 117.741747 -399.502447) (xy 117.723065 -399.494693) (xy 117.708771 -399.480382)
			(xy 117.70104 -399.46169) (xy 117.700552 -399.451576) (xy 117.700552 -399.294096) (xy 117.700132 -399.28491)
			(xy 117.693624 -399.267726) (xy 117.687852 -399.260568) (xy 117.666022 -399.234874) (xy 117.627928 -399.179245)
			(xy 117.596773 -399.119453) (xy 117.573005 -399.05636) (xy 117.556965 -398.990874) (xy 117.548886 -398.923938)
			(xy 117.548882 -398.856516) (xy 117.556955 -398.789579) (xy 117.572989 -398.724092) (xy 117.596751 -398.660996)
			(xy 117.627901 -398.601201) (xy 117.665988 -398.545568) (xy 117.687852 -398.519904) (xy 117.693636 -398.51275)
			(xy 117.700157 -398.495566) (xy 117.700552 -398.486376) (xy 117.700552 -397.99387) (xy 117.700145 -397.984683)
			(xy 117.693628 -397.967499) (xy 117.687852 -397.960342) (xy 117.665996 -397.93467) (xy 117.627904 -397.879037)
			(xy 117.59675 -397.819243) (xy 117.572983 -397.756147) (xy 117.556945 -397.690658) (xy 117.548867 -397.623719)
			(xy 117.548866 -397.556296) (xy 116.42064 -397.556296) (xy 116.423251 -397.56132) (xy 116.446929 -397.624321)
			(xy 116.462906 -397.6897) (xy 116.470954 -397.75652) (xy 116.470957 -397.823823) (xy 116.462916 -397.890644)
			(xy 116.446945 -397.956025) (xy 116.423275 -398.019028) (xy 116.392243 -398.07875) (xy 116.354295 -398.134335)
			(xy 116.332508 -398.159986) (xy 116.326693 -398.167118) (xy 116.320189 -398.184319) (xy 116.319808 -398.193514)
			(xy 116.319808 -398.351502) (xy 116.319269 -398.361654) (xy 116.311503 -398.380415) (xy 116.297152 -398.394778)
			(xy 116.278398 -398.402561) (xy 116.268246 -398.403064) (xy 115.551966 -398.403064) (xy 115.541806 -398.402595)
			(xy 115.523037 -398.394809) (xy 115.508673 -398.380436) (xy 115.500899 -398.361662) (xy 115.500404 -398.351502)
			(xy 115.500404 -398.193514) (xy 115.499986 -398.184328) (xy 115.493478 -398.167143) (xy 115.487704 -398.159986)
			(xy 115.46588 -398.134364) (xy 115.427935 -398.078772) (xy 115.396905 -398.019044) (xy 115.373236 -397.956036)
			(xy 115.357267 -397.89065) (xy 115.349226 -397.823825) (xy 92.220595 -397.823825) (xy 92.192138 -397.878594)
			(xy 92.154191 -397.934181) (xy 92.132404 -397.959834) (xy 92.126611 -397.966982) (xy 92.120094 -397.98417)
			(xy 92.119704 -397.993362) (xy 92.119704 -398.486884) (xy 92.120121 -398.49607) (xy 92.12663 -398.513255)
			(xy 92.132404 -398.520412) (xy 92.154226 -398.546036) (xy 92.192171 -398.601627) (xy 92.2232 -398.661355)
			(xy 92.246869 -398.724363) (xy 92.262838 -398.789748) (xy 92.270879 -398.856574) (xy 92.270875 -398.923881)
			(xy 92.262828 -398.990705) (xy 92.246853 -399.056089) (xy 92.223178 -399.119094) (xy 92.192143 -399.178819)
			(xy 92.154193 -399.234407) (xy 92.132404 -399.26006) (xy 92.1266 -399.2672) (xy 92.12009 -399.284394)
			(xy 92.119704 -399.293588) (xy 92.119704 -399.451576) (xy 92.119259 -399.461728) (xy 92.111472 -399.480479)
			(xy 92.097082 -399.494803) (xy 92.078296 -399.502505) (xy 92.068142 -399.502884) (xy 91.351862 -399.502884)
			(xy 91.341736 -399.502405) (xy 91.323018 -399.494669) (xy 91.308664 -399.480381) (xy 91.300842 -399.4617)
			(xy 91.3003 -399.451576) (xy 91.3003 -399.293588) (xy 91.299895 -399.2844) (xy 91.293378 -399.267216)
			(xy 91.2876 -399.26006) (xy 91.265849 -399.234378) (xy 91.227901 -399.178795) (xy 91.196869 -399.119075)
			(xy 91.173196 -399.056075) (xy 91.157221 -398.990697) (xy 91.149175 -398.923878) (xy 91.149172 -398.856576)
			(xy 91.157212 -398.789757) (xy 91.17318 -398.724377) (xy 91.196847 -398.661374) (xy 91.227874 -398.601651)
			(xy 91.265816 -398.546065) (xy 91.2876 -398.520412) (xy 91.293416 -398.513281) (xy 91.299919 -398.49608)
			(xy 91.3003 -398.486884) (xy 91.3003 -397.993362) (xy 91.299908 -397.984173) (xy 91.293382 -397.966989)
			(xy 91.2876 -397.959834) (xy 91.265823 -397.934173) (xy 91.227877 -397.878587) (xy 91.196845 -397.818864)
			(xy 91.173174 -397.755861) (xy 91.157201 -397.69048) (xy 91.149157 -397.623659) (xy 91.149156 -397.556356)
			(xy 90.020411 -397.556356) (xy 90.022992 -397.561322) (xy 90.046667 -397.624323) (xy 90.062643 -397.689701)
			(xy 90.07069 -397.75652) (xy 90.070693 -397.823822) (xy 90.062653 -397.890643) (xy 90.046684 -397.956023)
			(xy 90.023015 -398.019026) (xy 89.991986 -398.078748) (xy 89.954041 -398.134334) (xy 89.932256 -398.159986)
			(xy 89.926435 -398.167114) (xy 89.919936 -398.184318) (xy 89.919556 -398.193514) (xy 89.919556 -398.351502)
			(xy 89.919138 -398.361674) (xy 89.911351 -398.38047) (xy 89.896964 -398.394855) (xy 89.878167 -398.402639)
			(xy 89.867994 -398.403064) (xy 89.151714 -398.403064) (xy 89.141544 -398.402625) (xy 89.122749 -398.394845)
			(xy 89.108364 -398.380464) (xy 89.100578 -398.361672) (xy 89.100152 -398.351502) (xy 89.100152 -398.193514)
			(xy 89.099724 -398.184329) (xy 89.093221 -398.167145) (xy 89.087452 -398.159986) (xy 89.065626 -398.134365)
			(xy 89.027678 -398.078774) (xy 88.996645 -398.019047) (xy 88.972974 -397.956038) (xy 88.957004 -397.890652)
			(xy 88.948962 -397.823826) (xy 87.820827 -397.823826) (xy 87.792062 -397.879042) (xy 87.753972 -397.934677)
			(xy 87.732108 -397.960342) (xy 87.726312 -397.967488) (xy 87.719797 -397.984678) (xy 87.719408 -397.99387)
			(xy 87.719408 -398.486376) (xy 87.719828 -398.495562) (xy 87.726335 -398.512747) (xy 87.732108 -398.519904)
			(xy 87.754007 -398.54554) (xy 87.792094 -398.601179) (xy 87.823243 -398.660979) (xy 87.847005 -398.72408)
			(xy 87.863037 -398.789573) (xy 87.87111 -398.856514) (xy 87.871107 -398.92394) (xy 87.863028 -398.990881)
			(xy 87.846989 -399.056372) (xy 87.823221 -399.11947) (xy 87.792066 -399.179267) (xy 87.753974 -399.234903)
			(xy 87.732108 -399.260568) (xy 87.726301 -399.267706) (xy 87.719792 -399.284902) (xy 87.719408 -399.294096)
			(xy 87.719408 -399.451576) (xy 87.718965 -399.461696) (xy 87.711226 -399.480398) (xy 87.696918 -399.494712)
			(xy 87.67822 -399.50246) (xy 87.6681 -399.502884) (xy 86.95182 -399.502884) (xy 86.941697 -399.502467)
			(xy 86.922991 -399.494723) (xy 86.908675 -399.480406) (xy 86.900932 -399.461699) (xy 86.900512 -399.451576)
			(xy 86.900512 -399.294096) (xy 86.900101 -399.284909) (xy 86.893587 -399.267725) (xy 86.887812 -399.260568)
			(xy 86.865983 -399.234874) (xy 86.827892 -399.179244) (xy 86.796739 -399.119452) (xy 86.772973 -399.056358)
			(xy 86.756934 -398.990873) (xy 86.748855 -398.923938) (xy 86.748852 -398.856516) (xy 86.756925 -398.78958)
			(xy 86.772957 -398.724093) (xy 86.796717 -398.660998) (xy 86.827865 -398.601203) (xy 86.86595 -398.545569)
			(xy 86.887812 -398.519904) (xy 86.893591 -398.512746) (xy 86.900116 -398.495565) (xy 86.900512 -398.486376)
			(xy 86.900512 -397.99387) (xy 86.900114 -397.984682) (xy 86.893592 -397.967497) (xy 86.887812 -397.960342)
			(xy 86.865957 -397.934669) (xy 86.827868 -397.879036) (xy 86.796716 -397.819241) (xy 86.772951 -397.756145)
			(xy 86.756914 -397.690657) (xy 86.748837 -397.623719) (xy 86.748836 -397.556296) (xy 85.620612 -397.556296)
			(xy 85.623035 -397.560946) (xy 85.646803 -397.624039) (xy 85.662842 -397.689525) (xy 85.670922 -397.756461)
			(xy 85.670925 -397.823882) (xy 85.662853 -397.890819) (xy 85.64682 -397.956306) (xy 85.623058 -398.019402)
			(xy 85.59191 -398.079196) (xy 85.553823 -398.134829) (xy 85.53196 -398.160494) (xy 85.526178 -398.16765)
			(xy 85.519656 -398.184832) (xy 85.51926 -398.194022) (xy 85.51926 -398.351502) (xy 85.518775 -398.361629)
			(xy 85.511047 -398.38035) (xy 85.49676 -398.394706) (xy 85.478076 -398.402525) (xy 85.467952 -398.403064)
			(xy 84.751672 -398.403064) (xy 84.741512 -398.402701) (xy 84.722752 -398.394889) (xy 84.708428 -398.380474)
			(xy 84.700736 -398.361665) (xy 84.700364 -398.351502) (xy 84.700364 -398.194022) (xy 84.699929 -398.184838)
			(xy 84.693431 -398.167654) (xy 84.687664 -398.160494) (xy 84.665764 -398.134859) (xy 84.627679 -398.079219)
			(xy 84.596532 -398.019419) (xy 84.572771 -397.956318) (xy 84.55674 -397.890825) (xy 84.548667 -397.823884)
			(xy 83.420495 -397.823884) (xy 83.392062 -397.878597) (xy 83.35411 -397.934182) (xy 83.33232 -397.959834)
			(xy 83.326529 -397.966983) (xy 83.32001 -397.984171) (xy 83.31962 -397.993362) (xy 83.31962 -398.486884)
			(xy 83.320033 -398.496071) (xy 83.326544 -398.513256) (xy 83.33232 -398.520412) (xy 83.354144 -398.546035)
			(xy 83.392095 -398.601624) (xy 83.423129 -398.661352) (xy 83.446801 -398.72436) (xy 83.462773 -398.789746)
			(xy 83.470815 -398.856573) (xy 83.470812 -398.923881) (xy 83.462763 -398.990707) (xy 83.446785 -399.056092)
			(xy 83.423107 -399.119098) (xy 83.392067 -399.178822) (xy 83.354111 -399.234408) (xy 83.33232 -399.26006)
			(xy 83.326518 -399.267201) (xy 83.320006 -399.284395) (xy 83.31962 -399.293588) (xy 83.31962 -399.451576)
			(xy 83.319159 -399.461726) (xy 83.311375 -399.480474) (xy 83.296991 -399.494798) (xy 83.27821 -399.502502)
			(xy 83.268058 -399.502884) (xy 82.551778 -399.502884) (xy 82.541653 -399.502392) (xy 82.522936 -399.494662)
			(xy 82.508581 -399.480378) (xy 82.500758 -399.461699) (xy 82.500216 -399.451576) (xy 82.500216 -399.293588)
			(xy 82.499808 -399.284401) (xy 82.493293 -399.267216) (xy 82.487516 -399.26006) (xy 82.465765 -399.234378)
			(xy 82.427816 -399.178795) (xy 82.396783 -399.119076) (xy 82.373109 -399.056075) (xy 82.357134 -398.990697)
			(xy 82.349088 -398.923878) (xy 82.349084 -398.856576) (xy 82.357125 -398.789756) (xy 82.373093 -398.724377)
			(xy 82.396761 -398.661374) (xy 82.427788 -398.601651) (xy 82.465731 -398.546065) (xy 82.487516 -398.520412)
			(xy 82.493334 -398.513282) (xy 82.499835 -398.49608) (xy 82.500216 -398.486884) (xy 82.500216 -397.993362)
			(xy 82.499821 -397.984173) (xy 82.493296 -397.966989) (xy 82.487516 -397.959834) (xy 82.465739 -397.934174)
			(xy 82.427791 -397.878588) (xy 82.396759 -397.818865) (xy 82.373086 -397.755862) (xy 82.357113 -397.690481)
			(xy 82.349069 -397.623659) (xy 82.349068 -397.556356) (xy 81.220853 -397.556356) (xy 81.223245 -397.560947)
			(xy 81.247013 -397.62404) (xy 81.263052 -397.689525) (xy 81.271131 -397.756461) (xy 81.271135 -397.823882)
			(xy 81.263062 -397.890818) (xy 81.24703 -397.956306) (xy 81.223269 -398.019401) (xy 81.192121 -398.079196)
			(xy 81.154035 -398.134829) (xy 81.132172 -398.160494) (xy 81.126392 -398.167651) (xy 81.119868 -398.184832)
			(xy 81.119472 -398.194022) (xy 81.119472 -398.351502) (xy 81.118975 -398.361627) (xy 81.111249 -398.380346)
			(xy 81.096966 -398.394702) (xy 81.078287 -398.402523) (xy 81.068164 -398.403064) (xy 80.351884 -398.403064)
			(xy 80.341724 -398.402691) (xy 80.322965 -398.394883) (xy 80.30864 -398.380471) (xy 80.300948 -398.361664)
			(xy 80.300576 -398.351502) (xy 80.300576 -398.194022) (xy 80.300161 -398.184835) (xy 80.293651 -398.16765)
			(xy 80.287876 -398.160494) (xy 80.265976 -398.134859) (xy 80.22789 -398.07922) (xy 80.196742 -398.019419)
			(xy 80.172981 -397.956318) (xy 80.156949 -397.890826) (xy 80.148876 -397.823885) (xy 79.02071 -397.823885)
			(xy 78.991976 -397.879041) (xy 78.953888 -397.934676) (xy 78.932024 -397.960342) (xy 78.92623 -397.967489)
			(xy 78.919713 -397.984678) (xy 78.919324 -397.99387) (xy 78.919324 -398.486376) (xy 78.91974 -398.495563)
			(xy 78.926249 -398.512747) (xy 78.932024 -398.519904) (xy 78.953922 -398.54554) (xy 78.992009 -398.60118)
			(xy 79.023156 -398.66098) (xy 79.046917 -398.724081) (xy 79.06295 -398.789573) (xy 79.071022 -398.856514)
			(xy 79.071019 -398.92394) (xy 79.06294 -398.99088) (xy 79.046901 -399.056371) (xy 79.023134 -399.119469)
			(xy 78.991981 -399.179267) (xy 78.953889 -399.234902) (xy 78.932024 -399.260568) (xy 78.926219 -399.267707)
			(xy 78.919709 -399.284902) (xy 78.919324 -399.294096) (xy 78.919324 -399.451576) (xy 78.918865 -399.461694)
			(xy 78.911129 -399.480393) (xy 78.896826 -399.494707) (xy 78.878134 -399.502457) (xy 78.868016 -399.502884)
			(xy 78.151736 -399.502884) (xy 78.141614 -399.502454) (xy 78.122908 -399.494715) (xy 78.108592 -399.480402)
			(xy 78.100848 -399.461698) (xy 78.100428 -399.451576) (xy 78.100428 -399.294096) (xy 78.100014 -399.284909)
			(xy 78.093502 -399.267725) (xy 78.087728 -399.260568) (xy 78.065898 -399.234874) (xy 78.027807 -399.179244)
			(xy 77.996653 -399.119452) (xy 77.972886 -399.056359) (xy 77.956847 -398.990873) (xy 77.948768 -398.923938)
			(xy 77.948764 -398.856516) (xy 77.956837 -398.78958) (xy 77.972869 -398.724093) (xy 77.996631 -398.660997)
			(xy 78.027779 -398.601202) (xy 78.065865 -398.545569) (xy 78.087728 -398.519904) (xy 78.093509 -398.512748)
			(xy 78.100032 -398.495566) (xy 78.100428 -398.486376) (xy 78.100428 -397.99387) (xy 78.100026 -397.984682)
			(xy 78.093506 -397.967498) (xy 78.087728 -397.960342) (xy 78.065873 -397.934669) (xy 78.027782 -397.879036)
			(xy 77.996629 -397.819241) (xy 77.972863 -397.756146) (xy 77.956826 -397.690657) (xy 77.948749 -397.623719)
			(xy 77.948748 -397.556296) (xy 76.820503 -397.556296) (xy 76.823115 -397.561323) (xy 76.846789 -397.624324)
			(xy 76.862764 -397.689702) (xy 76.870811 -397.756521) (xy 76.870814 -397.823822) (xy 76.862774 -397.890642)
			(xy 76.846806 -397.956022) (xy 76.823139 -398.019024) (xy 76.792111 -398.078747) (xy 76.754168 -398.134333)
			(xy 76.732384 -398.159986) (xy 76.726567 -398.167116) (xy 76.720065 -398.184318) (xy 76.719684 -398.193514)
			(xy 76.719684 -398.351502) (xy 76.719169 -398.361657) (xy 76.711398 -398.380422) (xy 76.697039 -398.394787)
			(xy 76.678277 -398.402565) (xy 76.668122 -398.403064) (xy 75.951842 -398.403064) (xy 75.941673 -398.402602)
			(xy 75.92288 -398.394831) (xy 75.908494 -398.380457) (xy 75.900707 -398.36167) (xy 75.90028 -398.351502)
			(xy 75.90028 -398.193514) (xy 75.899868 -398.184327) (xy 75.893356 -398.167142) (xy 75.88758 -398.159986)
			(xy 75.865754 -398.134365) (xy 75.827803 -398.078775) (xy 75.79677 -398.019048) (xy 75.773097 -397.956039)
			(xy 75.757126 -397.890653) (xy 75.749084 -397.823826) (xy 74.620438 -397.823826) (xy 74.591977 -397.878596)
			(xy 74.554025 -397.934182) (xy 74.532236 -397.959834) (xy 74.526435 -397.966975) (xy 74.519925 -397.984169)
			(xy 74.519536 -397.993362) (xy 74.519536 -398.486884) (xy 74.519968 -398.496069) (xy 74.526468 -398.513252)
			(xy 74.532236 -398.520412) (xy 74.55406 -398.546035) (xy 74.592009 -398.601625) (xy 74.623043 -398.661352)
			(xy 74.646714 -398.724361) (xy 74.662686 -398.789747) (xy 74.670727 -398.856573) (xy 74.670724 -398.923881)
			(xy 74.662676 -398.990707) (xy 74.646698 -399.056091) (xy 74.623021 -399.119097) (xy 74.591982 -399.178822)
			(xy 74.554027 -399.234408) (xy 74.532236 -399.26006) (xy 74.526424 -399.267194) (xy 74.51992 -399.284393)
			(xy 74.519536 -399.293588) (xy 74.519536 -399.451576) (xy 74.51906 -399.461724) (xy 74.511279 -399.480469)
			(xy 74.496899 -399.494792) (xy 74.478124 -399.502499) (xy 74.467974 -399.502884) (xy 73.751694 -399.502884)
			(xy 73.74157 -399.502379) (xy 73.722853 -399.494654) (xy 73.708498 -399.480373) (xy 73.700675 -399.461697)
			(xy 73.700132 -399.451576) (xy 73.700132 -399.293588) (xy 73.699721 -399.284401) (xy 73.693207 -399.267217)
			(xy 73.687432 -399.26006) (xy 73.66568 -399.234378) (xy 73.627731 -399.178796) (xy 73.596696 -399.119077)
			(xy 73.573022 -399.056076) (xy 73.557047 -398.990697) (xy 73.549 -398.923878) (xy 73.548996 -398.856576)
			(xy 73.557037 -398.789756) (xy 73.573006 -398.724376) (xy 73.596674 -398.661373) (xy 73.627703 -398.60165)
			(xy 73.665647 -398.546064) (xy 73.687432 -398.520412) (xy 73.693253 -398.513284) (xy 73.699752 -398.49608)
			(xy 73.700132 -398.486884) (xy 73.700132 -397.993362) (xy 73.699733 -397.984174) (xy 73.693211 -397.96699)
			(xy 73.687432 -397.959834) (xy 73.665654 -397.934174) (xy 73.627705 -397.878588) (xy 73.596672 -397.818866)
			(xy 73.572999 -397.755862) (xy 73.557026 -397.690481) (xy 73.548981 -397.62366) (xy 73.54898 -397.556355)
			(xy 72.420766 -397.556355) (xy 72.423159 -397.560948) (xy 72.446926 -397.62404) (xy 72.462964 -397.689526)
			(xy 72.471043 -397.756461) (xy 72.471047 -397.823882) (xy 72.462974 -397.890818) (xy 72.446942 -397.956305)
			(xy 72.423182 -398.0194) (xy 72.392035 -398.079195) (xy 72.35395 -398.134829) (xy 72.332088 -398.160494)
			(xy 72.32631 -398.167652) (xy 72.319785 -398.184833) (xy 72.319388 -398.194022) (xy 72.319388 -398.351502)
			(xy 72.318876 -398.361625) (xy 72.311153 -398.380341) (xy 72.296875 -398.394696) (xy 72.278201 -398.40252)
			(xy 72.26808 -398.403064) (xy 71.5518 -398.403064) (xy 71.541641 -398.402678) (xy 71.522882 -398.394875)
			(xy 71.508557 -398.380467) (xy 71.500864 -398.361663) (xy 71.500492 -398.351502) (xy 71.500492 -398.194022)
			(xy 71.500073 -398.184836) (xy 71.493566 -398.167651) (xy 71.487792 -398.160494) (xy 71.465891 -398.134859)
			(xy 71.427804 -398.07922) (xy 71.396655 -398.01942) (xy 71.372894 -397.956319) (xy 71.356861 -397.890826)
			(xy 71.348788 -397.823885) (xy 66.525648 -397.823885) (xy 66.525648 -401.723796) (xy 71.3488 -401.723796)
			(xy 71.348802 -401.656371) (xy 71.35688 -401.589431) (xy 71.372917 -401.523941) (xy 71.396683 -401.460843)
			(xy 71.427836 -401.401046) (xy 71.465927 -401.345411) (xy 71.487792 -401.319746) (xy 71.493593 -401.312604)
			(xy 71.500105 -401.295411) (xy 71.500492 -401.286218) (xy 71.500492 -400.793966) (xy 71.5001 -400.784777)
			(xy 71.493574 -400.767592) (xy 71.487792 -400.760438) (xy 71.465934 -400.734768) (xy 71.427846 -400.679134)
			(xy 71.396695 -400.619338) (xy 71.372931 -400.556242) (xy 71.356896 -400.490754) (xy 71.348819 -400.423816)
			(xy 71.348819 -400.356393) (xy 71.356894 -400.289455) (xy 71.372928 -400.223967) (xy 71.396692 -400.16087)
			(xy 71.427841 -400.101074) (xy 71.465929 -400.045439) (xy 71.487792 -400.019774) (xy 71.493581 -400.012623)
			(xy 71.500101 -399.995437) (xy 71.500492 -399.986246) (xy 71.500492 -399.828766) (xy 71.500997 -399.818643)
			(xy 71.508727 -399.79993) (xy 71.523007 -399.785577) (xy 71.54168 -399.77775) (xy 71.5518 -399.777204)
			(xy 72.26808 -399.777204) (xy 72.278233 -399.777638) (xy 72.296986 -399.785428) (xy 72.31131 -399.799821)
			(xy 72.31901 -399.818611) (xy 72.319388 -399.828766) (xy 72.319388 -399.986246) (xy 72.319827 -399.99543)
			(xy 72.326321 -400.012615) (xy 72.332088 -400.019774) (xy 72.353958 -400.045434) (xy 72.392048 -400.101069)
			(xy 72.423199 -400.160866) (xy 72.446963 -400.223963) (xy 72.462999 -400.289453) (xy 72.471074 -400.356392)
			(xy 72.471074 -400.423817) (xy 72.462997 -400.490756) (xy 72.44696 -400.556245) (xy 72.423195 -400.619342)
			(xy 72.392043 -400.679139) (xy 72.353953 -400.734773) (xy 72.332088 -400.760438) (xy 72.326291 -400.767583)
			(xy 72.319777 -400.784774) (xy 72.319388 -400.793966) (xy 72.319388 -401.286218) (xy 72.319792 -401.295406)
			(xy 72.32631 -401.31259) (xy 72.332088 -401.319746) (xy 72.353931 -401.345429) (xy 72.392021 -401.401061)
			(xy 72.423173 -401.460854) (xy 72.446939 -401.523949) (xy 72.462977 -401.589436) (xy 72.471054 -401.656372)
			(xy 72.471056 -401.723795) (xy 72.462982 -401.790732) (xy 72.446949 -401.85622) (xy 72.423187 -401.919316)
			(xy 72.392038 -401.979111) (xy 72.353951 -402.034745) (xy 72.332088 -402.06041) (xy 72.326303 -402.067564)
			(xy 72.319782 -402.084748) (xy 72.319388 -402.093938) (xy 72.319388 -402.251418) (xy 72.318889 -402.261542)
			(xy 72.311161 -402.280259) (xy 72.296879 -402.294614) (xy 72.278202 -402.302437) (xy 72.26808 -402.30298)
			(xy 71.5518 -402.30298) (xy 71.541643 -402.302578) (xy 71.522887 -402.294779) (xy 71.508563 -402.280376)
			(xy 71.500867 -402.261577) (xy 71.500492 -402.251418) (xy 71.500492 -402.093938) (xy 71.500065 -402.084753)
			(xy 71.493563 -402.067568) (xy 71.487792 -402.06041) (xy 71.465907 -402.034762) (xy 71.427819 -401.979125)
			(xy 71.39667 -401.919326) (xy 71.372907 -401.856227) (xy 71.356874 -401.790736) (xy 71.3488 -401.723796)
			(xy 66.525648 -401.723796) (xy 66.525648 -402.823818) (xy 73.54894 -402.823818) (xy 73.548944 -402.75651)
			(xy 73.556993 -402.689684) (xy 73.572971 -402.624299) (xy 73.596649 -402.561293) (xy 73.627687 -402.501568)
			(xy 73.665642 -402.44598) (xy 73.687432 -402.420328) (xy 73.693246 -402.413195) (xy 73.699749 -402.395995)
			(xy 73.700132 -402.3868) (xy 73.700132 -401.893532) (xy 73.699699 -401.884347) (xy 73.6932 -401.867163)
			(xy 73.687432 -401.860004) (xy 73.665625 -401.834368) (xy 73.627677 -401.778779) (xy 73.596645 -401.719053)
			(xy 73.572974 -401.656047) (xy 73.557002 -401.590662) (xy 73.54896 -401.523838) (xy 73.548962 -401.456532)
			(xy 73.557008 -401.389708) (xy 73.572982 -401.324325) (xy 73.596657 -401.261319) (xy 73.627692 -401.201595)
			(xy 73.665643 -401.146008) (xy 73.687432 -401.120356) (xy 73.693234 -401.113215) (xy 73.699745 -401.096021)
			(xy 73.700132 -401.086828) (xy 73.700132 -400.92884) (xy 73.700555 -400.918685) (xy 73.708343 -400.899927)
			(xy 73.722741 -400.885601) (xy 73.741537 -400.877906) (xy 73.751694 -400.877532) (xy 74.467974 -400.877532)
			(xy 74.478098 -400.878047) (xy 74.496817 -400.885765) (xy 74.511174 -400.900043) (xy 74.518996 -400.918719)
			(xy 74.519536 -400.92884) (xy 74.519536 -401.086828) (xy 74.519947 -401.096015) (xy 74.526462 -401.113198)
			(xy 74.532236 -401.120356) (xy 74.554005 -401.146024) (xy 74.591956 -401.201608) (xy 74.622991 -401.261329)
			(xy 74.646666 -401.324331) (xy 74.662641 -401.389712) (xy 74.670687 -401.456533) (xy 74.670689 -401.523837)
			(xy 74.662647 -401.590659) (xy 74.646675 -401.65604) (xy 74.623004 -401.719044) (xy 74.620565 -401.723737)
			(xy 75.749095 -401.723737) (xy 75.749097 -401.65643) (xy 75.757144 -401.589605) (xy 75.773121 -401.524221)
			(xy 75.796798 -401.461215) (xy 75.827836 -401.401492) (xy 75.86579 -401.345906) (xy 75.88758 -401.320254)
			(xy 75.893376 -401.313108) (xy 75.899892 -401.295918) (xy 75.90028 -401.286726) (xy 75.90028 -400.793458)
			(xy 75.899895 -400.784268) (xy 75.893364 -400.767084) (xy 75.88758 -400.75993) (xy 75.865797 -400.734274)
			(xy 75.827845 -400.678689) (xy 75.79681 -400.618966) (xy 75.773135 -400.555962) (xy 75.75716 -400.49058)
			(xy 75.749115 -400.423757) (xy 75.749114 -400.356452) (xy 75.757158 -400.289629) (xy 75.773132 -400.224247)
			(xy 75.796806 -400.161242) (xy 75.827841 -400.101519) (xy 75.865791 -400.045934) (xy 75.88758 -400.020282)
			(xy 75.893364 -400.013128) (xy 75.899887 -399.995944) (xy 75.90028 -399.986754) (xy 75.90028 -399.828766)
			(xy 75.900637 -399.818587) (xy 75.908441 -399.799783) (xy 75.922847 -399.785398) (xy 75.941662 -399.777622)
			(xy 75.951842 -399.777204) (xy 76.668122 -399.777204) (xy 76.678277 -399.777714) (xy 76.69704 -399.78549)
			(xy 76.711404 -399.79985) (xy 76.719183 -399.818611) (xy 76.719684 -399.828766) (xy 76.719684 -399.986754)
			(xy 76.72012 -399.995938) (xy 76.726616 -400.013123) (xy 76.732384 -400.020282) (xy 76.754177 -400.04593)
			(xy 76.792124 -400.101517) (xy 76.823156 -400.161242) (xy 76.846827 -400.224247) (xy 76.862799 -400.289629)
			(xy 76.870842 -400.356452) (xy 76.870842 -400.423757) (xy 76.862798 -400.49058) (xy 76.846825 -400.555962)
			(xy 76.823152 -400.618967) (xy 76.792119 -400.678691) (xy 76.754171 -400.734278) (xy 76.732384 -400.75993)
			(xy 76.72659 -400.767077) (xy 76.720074 -400.784266) (xy 76.719684 -400.793458) (xy 76.719684 -401.286726)
			(xy 76.720085 -401.295914) (xy 76.726605 -401.313098) (xy 76.732384 -401.320254) (xy 76.754149 -401.345924)
			(xy 76.792097 -401.401509) (xy 76.82313 -401.46123) (xy 76.846803 -401.524232) (xy 76.862777 -401.589612)
			(xy 76.870823 -401.656432) (xy 76.870825 -401.723735) (xy 76.862783 -401.790556) (xy 76.846813 -401.855936)
			(xy 76.823144 -401.91894) (xy 76.792114 -401.978663) (xy 76.75417 -402.03425) (xy 76.732384 -402.059902)
			(xy 76.726602 -402.067058) (xy 76.720079 -402.08424) (xy 76.719684 -402.09343) (xy 76.719684 -402.251418)
			(xy 76.719182 -402.261574) (xy 76.711406 -402.28034) (xy 76.697043 -402.294704) (xy 76.678278 -402.302481)
			(xy 76.668122 -402.30298) (xy 75.951842 -402.30298) (xy 75.941675 -402.302502) (xy 75.922885 -402.294734)
			(xy 75.908499 -402.280365) (xy 75.90071 -402.261584) (xy 75.90028 -402.251418) (xy 75.90028 -402.09343)
			(xy 75.89986 -402.084244) (xy 75.893354 -402.067059) (xy 75.88758 -402.059902) (xy 75.865769 -402.034268)
			(xy 75.827819 -401.97868) (xy 75.796784 -401.918954) (xy 75.773111 -401.855947) (xy 75.757138 -401.790562)
			(xy 75.749095 -401.723737) (xy 74.620565 -401.723737) (xy 74.591971 -401.778767) (xy 74.554023 -401.834352)
			(xy 74.532236 -401.860004) (xy 74.526447 -401.867155) (xy 74.51993 -401.884341) (xy 74.519536 -401.893532)
			(xy 74.519536 -402.3868) (xy 74.519961 -402.395985) (xy 74.526466 -402.413169) (xy 74.532236 -402.420328)
			(xy 74.553977 -402.446019) (xy 74.591929 -402.501599) (xy 74.622966 -402.561317) (xy 74.646642 -402.624317)
			(xy 74.662619 -402.689694) (xy 74.670668 -402.756513) (xy 74.670672 -402.823815) (xy 74.670664 -402.823878)
			(xy 77.948708 -402.823878) (xy 77.948713 -402.75645) (xy 77.956794 -402.689508) (xy 77.972835 -402.624016)
			(xy 77.996606 -402.560917) (xy 78.027764 -402.501119) (xy 78.06586 -402.445485) (xy 78.087728 -402.41982)
			(xy 78.093545 -402.412689) (xy 78.100047 -402.395488) (xy 78.100428 -402.386292) (xy 78.100428 -401.89404)
			(xy 78.099992 -401.884856) (xy 78.093496 -401.867671) (xy 78.087728 -401.860512) (xy 78.065843 -401.834863)
			(xy 78.027753 -401.779227) (xy 77.996602 -401.719429) (xy 77.972838 -401.65633) (xy 77.956803 -401.590838)
			(xy 77.948728 -401.523898) (xy 77.94873 -401.456472) (xy 77.956808 -401.389532) (xy 77.972847 -401.324041)
			(xy 77.996614 -401.260944) (xy 78.027769 -401.201147) (xy 78.065862 -401.145513) (xy 78.087728 -401.119848)
			(xy 78.093533 -401.112709) (xy 78.100042 -401.095514) (xy 78.100428 -401.08632) (xy 78.100428 -400.92884)
			(xy 78.10085 -400.918717) (xy 78.10859 -400.900009) (xy 78.122905 -400.885692) (xy 78.141613 -400.87795)
			(xy 78.151736 -400.877532) (xy 78.868016 -400.877532) (xy 78.878144 -400.877903) (xy 78.896854 -400.885663)
			(xy 78.911169 -400.899993) (xy 78.918908 -400.918712) (xy 78.919324 -400.92884) (xy 78.919324 -401.08632)
			(xy 78.919719 -401.095509) (xy 78.926243 -401.112693) (xy 78.932024 -401.119848) (xy 78.953867 -401.14553)
			(xy 78.991955 -401.201163) (xy 79.023105 -401.260957) (xy 79.04687 -401.324051) (xy 79.062906 -401.389538)
			(xy 79.070983 -401.456474) (xy 79.070985 -401.523896) (xy 79.062911 -401.590832) (xy 79.046879 -401.65632)
			(xy 79.023118 -401.719416) (xy 79.020837 -401.723796) (xy 80.148888 -401.723796) (xy 80.14889 -401.656371)
			(xy 80.156967 -401.589432) (xy 80.173004 -401.523942) (xy 80.19677 -401.460844) (xy 80.227922 -401.401047)
			(xy 80.266012 -401.345412) (xy 80.287876 -401.319746) (xy 80.293675 -401.312603) (xy 80.300189 -401.295411)
			(xy 80.300576 -401.286218) (xy 80.300576 -400.793966) (xy 80.300187 -400.784776) (xy 80.293659 -400.767592)
			(xy 80.287876 -400.760438) (xy 80.266019 -400.734767) (xy 80.227931 -400.679133) (xy 80.196782 -400.619337)
			(xy 80.173018 -400.556241) (xy 80.156983 -400.490753) (xy 80.148907 -400.423816) (xy 80.148907 -400.356393)
			(xy 80.156982 -400.289456) (xy 80.173016 -400.223967) (xy 80.196778 -400.160871) (xy 80.227927 -400.101075)
			(xy 80.266013 -400.04544) (xy 80.287876 -400.019774) (xy 80.293663 -400.012622) (xy 80.300184 -399.995437)
			(xy 80.300576 -399.986246) (xy 80.300576 -399.828766) (xy 80.301 -399.818633) (xy 80.308745 -399.799904)
			(xy 80.323051 -399.785548) (xy 80.341753 -399.777736) (xy 80.351884 -399.777204) (xy 81.068164 -399.777204)
			(xy 81.078316 -399.777651) (xy 81.097069 -399.785436) (xy 81.111393 -399.799825) (xy 81.119094 -399.818612)
			(xy 81.119472 -399.828766) (xy 81.119472 -399.986246) (xy 81.119914 -399.99543) (xy 81.126406 -400.012614)
			(xy 81.132172 -400.019774) (xy 81.154043 -400.045434) (xy 81.192133 -400.101069) (xy 81.223285 -400.160865)
			(xy 81.24705 -400.223963) (xy 81.263086 -400.289453) (xy 81.271162 -400.356392) (xy 81.271161 -400.423817)
			(xy 81.263085 -400.490756) (xy 81.247048 -400.556246) (xy 81.223282 -400.619343) (xy 81.192129 -400.679139)
			(xy 81.154037 -400.734773) (xy 81.132172 -400.760438) (xy 81.126373 -400.767581) (xy 81.11986 -400.784773)
			(xy 81.119472 -400.793966) (xy 81.119472 -401.286218) (xy 81.11988 -401.295405) (xy 81.126396 -401.312589)
			(xy 81.132172 -401.319746) (xy 81.154015 -401.345429) (xy 81.192107 -401.40106) (xy 81.22326 -401.460854)
			(xy 81.247026 -401.523948) (xy 81.263064 -401.589435) (xy 81.271142 -401.656372) (xy 81.271144 -401.723795)
			(xy 81.26307 -401.790732) (xy 81.247036 -401.85622) (xy 81.223273 -401.919316) (xy 81.192124 -401.979112)
			(xy 81.154036 -402.034745) (xy 81.132172 -402.06041) (xy 81.126385 -402.067562) (xy 81.119865 -402.084747)
			(xy 81.119472 -402.093938) (xy 81.119472 -402.251418) (xy 81.118989 -402.261544) (xy 81.111257 -402.280264)
			(xy 81.09697 -402.294619) (xy 81.078288 -402.30244) (xy 81.068164 -402.30298) (xy 80.351884 -402.30298)
			(xy 80.341726 -402.302591) (xy 80.32297 -402.294787) (xy 80.308646 -402.28038) (xy 80.30095 -402.261578)
			(xy 80.300576 -402.251418) (xy 80.300576 -402.093938) (xy 80.300153 -402.084752) (xy 80.293649 -402.067567)
			(xy 80.287876 -402.06041) (xy 80.265991 -402.034762) (xy 80.227905 -401.979125) (xy 80.196756 -401.919326)
			(xy 80.172994 -401.856227) (xy 80.156961 -401.790736) (xy 80.148888 -401.723796) (xy 79.020837 -401.723796)
			(xy 78.991971 -401.779212) (xy 78.953886 -401.834846) (xy 78.932024 -401.860512) (xy 78.926243 -401.867668)
			(xy 78.919718 -401.88485) (xy 78.919324 -401.89404) (xy 78.919324 -402.386292) (xy 78.919733 -402.395479)
			(xy 78.926247 -402.412664) (xy 78.932024 -402.41982) (xy 78.95384 -402.445525) (xy 78.991929 -402.501154)
			(xy 79.02308 -402.560945) (xy 79.046846 -402.624037) (xy 79.062884 -402.689521) (xy 79.070963 -402.756454)
			(xy 79.070968 -402.823818) (xy 82.349028 -402.823818) (xy 82.349032 -402.75651) (xy 82.357081 -402.689684)
			(xy 82.373058 -402.6243) (xy 82.396735 -402.561293) (xy 82.427773 -402.501568) (xy 82.465726 -402.44598)
			(xy 82.487516 -402.420328) (xy 82.493327 -402.413193) (xy 82.499833 -402.395995) (xy 82.500216 -402.3868)
			(xy 82.500216 -401.893532) (xy 82.499787 -401.884347) (xy 82.493286 -401.867163) (xy 82.487516 -401.860004)
			(xy 82.465709 -401.834368) (xy 82.427763 -401.778778) (xy 82.396731 -401.719052) (xy 82.373061 -401.656046)
			(xy 82.35709 -401.590662) (xy 82.349048 -401.523838) (xy 82.34905 -401.456532) (xy 82.357095 -401.389708)
			(xy 82.37307 -401.324325) (xy 82.396744 -401.26132) (xy 82.427778 -401.201596) (xy 82.465728 -401.146008)
			(xy 82.487516 -401.120356) (xy 82.493316 -401.113213) (xy 82.499828 -401.096021) (xy 82.500216 -401.086828)
			(xy 82.500216 -400.92884) (xy 82.500655 -400.918687) (xy 82.50844 -400.899932) (xy 82.522832 -400.885607)
			(xy 82.541623 -400.877908) (xy 82.551778 -400.877532) (xy 83.268058 -400.877532) (xy 83.278181 -400.878061)
			(xy 83.2969 -400.885773) (xy 83.311257 -400.900047) (xy 83.319079 -400.91872) (xy 83.31962 -400.92884)
			(xy 83.31962 -401.086828) (xy 83.320012 -401.096017) (xy 83.326538 -401.113202) (xy 83.33232 -401.120356)
			(xy 83.354089 -401.146024) (xy 83.392041 -401.201607) (xy 83.423078 -401.261328) (xy 83.446753 -401.324331)
			(xy 83.462729 -401.389711) (xy 83.470775 -401.456533) (xy 83.470777 -401.523837) (xy 83.462734 -401.590659)
			(xy 83.446762 -401.656041) (xy 83.42309 -401.719044) (xy 83.420621 -401.723796) (xy 84.548678 -401.723796)
			(xy 84.54868 -401.656371) (xy 84.556758 -401.589432) (xy 84.572795 -401.523942) (xy 84.59656 -401.460845)
			(xy 84.627711 -401.401047) (xy 84.6658 -401.345412) (xy 84.687664 -401.319746) (xy 84.693474 -401.312611)
			(xy 84.699979 -401.295412) (xy 84.700364 -401.286218) (xy 84.700364 -400.793966) (xy 84.699956 -400.784779)
			(xy 84.693439 -400.767595) (xy 84.687664 -400.760438) (xy 84.665807 -400.734767) (xy 84.627721 -400.679133)
			(xy 84.596572 -400.619337) (xy 84.572809 -400.556241) (xy 84.556774 -400.490753) (xy 84.548698 -400.423816)
			(xy 84.548698 -400.356393) (xy 84.556772 -400.289456) (xy 84.572806 -400.223968) (xy 84.596568 -400.160871)
			(xy 84.627716 -400.101075) (xy 84.665802 -400.04544) (xy 84.687664 -400.019774) (xy 84.693462 -400.01263)
			(xy 84.699974 -399.995438) (xy 84.700364 -399.986246) (xy 84.700364 -399.828766) (xy 84.700799 -399.818634)
			(xy 84.708543 -399.799908) (xy 84.722845 -399.785552) (xy 84.741542 -399.777738) (xy 84.751672 -399.777204)
			(xy 85.467952 -399.777204) (xy 85.478104 -399.777661) (xy 85.496856 -399.785442) (xy 85.511181 -399.799828)
			(xy 85.518881 -399.818613) (xy 85.51926 -399.828766) (xy 85.51926 -399.986246) (xy 85.519705 -399.995429)
			(xy 85.526196 -400.012613) (xy 85.53196 -400.019774) (xy 85.553831 -400.045434) (xy 85.591922 -400.101068)
			(xy 85.623075 -400.160865) (xy 85.646841 -400.223962) (xy 85.662877 -400.289453) (xy 85.670953 -400.356392)
			(xy 85.670952 -400.423817) (xy 85.662875 -400.490756) (xy 85.646838 -400.556246) (xy 85.623071 -400.619344)
			(xy 85.591918 -400.67914) (xy 85.553826 -400.734773) (xy 85.53196 -400.760438) (xy 85.52616 -400.76758)
			(xy 85.519648 -400.784773) (xy 85.51926 -400.793966) (xy 85.51926 -401.286218) (xy 85.51967 -401.295405)
			(xy 85.526185 -401.312589) (xy 85.53196 -401.319746) (xy 85.553804 -401.345428) (xy 85.591896 -401.40106)
			(xy 85.62305 -401.460853) (xy 85.646817 -401.523948) (xy 85.662855 -401.589435) (xy 85.670933 -401.656372)
			(xy 85.670935 -401.723795) (xy 85.662861 -401.790732) (xy 85.646827 -401.856221) (xy 85.623063 -401.919317)
			(xy 85.591913 -401.979112) (xy 85.553824 -402.034745) (xy 85.53196 -402.06041) (xy 85.526172 -402.067561)
			(xy 85.519653 -402.084747) (xy 85.51926 -402.093938) (xy 85.51926 -402.251418) (xy 85.518788 -402.261546)
			(xy 85.511055 -402.280268) (xy 85.496764 -402.294623) (xy 85.478078 -402.302442) (xy 85.467952 -402.30298)
			(xy 84.751672 -402.30298) (xy 84.741514 -402.302601) (xy 84.722757 -402.294792) (xy 84.708434 -402.280383)
			(xy 84.700738 -402.261579) (xy 84.700364 -402.251418) (xy 84.700364 -402.093938) (xy 84.699921 -402.084755)
			(xy 84.693429 -402.067571) (xy 84.687664 -402.06041) (xy 84.66578 -402.034762) (xy 84.627694 -401.979124)
			(xy 84.596546 -401.919325) (xy 84.572785 -401.856226) (xy 84.556752 -401.790735) (xy 84.548678 -401.723796)
			(xy 83.420621 -401.723796) (xy 83.392057 -401.778767) (xy 83.354108 -401.834352) (xy 83.33232 -401.860004)
			(xy 83.326542 -401.867162) (xy 83.320015 -401.884343) (xy 83.31962 -401.893532) (xy 83.31962 -402.3868)
			(xy 83.320026 -402.395988) (xy 83.326542 -402.413172) (xy 83.33232 -402.420328) (xy 83.354062 -402.446018)
			(xy 83.392015 -402.501598) (xy 83.423052 -402.561316) (xy 83.44673 -402.624316) (xy 83.462707 -402.689694)
			(xy 83.470756 -402.756513) (xy 83.47076 -402.823815) (xy 83.470752 -402.823878) (xy 86.748796 -402.823878)
			(xy 86.748801 -402.75645) (xy 86.756882 -402.689508) (xy 86.772922 -402.624016) (xy 86.796693 -402.560918)
			(xy 86.82785 -402.50112) (xy 86.865945 -402.445485) (xy 86.887812 -402.41982) (xy 86.893626 -402.412687)
			(xy 86.90013 -402.395487) (xy 86.900512 -402.386292) (xy 86.900512 -401.89404) (xy 86.90008 -401.884855)
			(xy 86.893581 -401.867671) (xy 86.887812 -401.860512) (xy 86.865928 -401.834863) (xy 86.827839 -401.779227)
			(xy 86.796689 -401.719428) (xy 86.772925 -401.656329) (xy 86.756891 -401.590838) (xy 86.748816 -401.523898)
			(xy 86.748818 -401.456472) (xy 86.756896 -401.389532) (xy 86.772934 -401.324042) (xy 86.796701 -401.260944)
			(xy 86.827855 -401.201148) (xy 86.865946 -401.145513) (xy 86.887812 -401.119848) (xy 86.893615 -401.112707)
			(xy 86.900125 -401.095513) (xy 86.900512 -401.08632) (xy 86.900512 -400.92884) (xy 86.900949 -400.918719)
			(xy 86.908686 -400.900014) (xy 86.922997 -400.885698) (xy 86.941699 -400.877953) (xy 86.95182 -400.877532)
			(xy 87.6681 -400.877532) (xy 87.678226 -400.877917) (xy 87.696936 -400.885671) (xy 87.711252 -400.899997)
			(xy 87.718991 -400.918713) (xy 87.719408 -400.92884) (xy 87.719408 -401.08632) (xy 87.719807 -401.095508)
			(xy 87.726328 -401.112693) (xy 87.732108 -401.119848) (xy 87.753952 -401.14553) (xy 87.792041 -401.201162)
			(xy 87.823192 -401.260956) (xy 87.846957 -401.324051) (xy 87.862994 -401.389538) (xy 87.871071 -401.456474)
			(xy 87.871073 -401.523896) (xy 87.862999 -401.590833) (xy 87.846966 -401.656321) (xy 87.823204 -401.719417)
			(xy 87.820954 -401.723737) (xy 115.349237 -401.723737) (xy 115.349239 -401.65643) (xy 115.357285 -401.589607)
			(xy 115.373259 -401.524224) (xy 115.396933 -401.461219) (xy 115.427967 -401.401494) (xy 115.465916 -401.345907)
			(xy 115.487704 -401.320254) (xy 115.493503 -401.313111) (xy 115.500016 -401.295919) (xy 115.500404 -401.286726)
			(xy 115.500404 -400.793458) (xy 115.500013 -400.784269) (xy 115.493486 -400.767085) (xy 115.487704 -400.75993)
			(xy 115.465923 -400.734273) (xy 115.427977 -400.678686) (xy 115.396945 -400.618963) (xy 115.373273 -400.555959)
			(xy 115.357301 -400.490578) (xy 115.349257 -400.423756) (xy 115.349256 -400.356453) (xy 115.357299 -400.289631)
			(xy 115.373271 -400.22425) (xy 115.396941 -400.161245) (xy 115.427972 -400.101522) (xy 115.465918 -400.045935)
			(xy 115.487704 -400.020282) (xy 115.493491 -400.01313) (xy 115.500011 -399.995945) (xy 115.500404 -399.986754)
			(xy 115.500404 -399.828766) (xy 115.500905 -399.81861) (xy 115.508684 -399.799847) (xy 115.523047 -399.785484)
			(xy 115.54181 -399.777705) (xy 115.551966 -399.777204) (xy 116.268246 -399.777204) (xy 116.278403 -399.777695)
			(xy 116.297166 -399.785478) (xy 116.311529 -399.799844) (xy 116.319307 -399.818609) (xy 116.319808 -399.828766)
			(xy 116.319808 -399.986754) (xy 116.320238 -399.995939) (xy 116.326738 -400.013124) (xy 116.332508 -400.020282)
			(xy 116.354303 -400.045929) (xy 116.392255 -400.101515) (xy 116.423291 -400.161238) (xy 116.446966 -400.224244)
			(xy 116.46294 -400.289627) (xy 116.470985 -400.356451) (xy 116.470984 -400.423758) (xy 116.462939 -400.490582)
			(xy 116.446963 -400.555965) (xy 116.423288 -400.61897) (xy 116.392251 -400.678693) (xy 116.354298 -400.734279)
			(xy 116.332508 -400.75993) (xy 116.326717 -400.767079) (xy 116.320199 -400.784267) (xy 116.319808 -400.793458)
			(xy 116.319808 -401.286726) (xy 116.320204 -401.295915) (xy 116.326727 -401.313099) (xy 116.332508 -401.320254)
			(xy 116.354276 -401.345923) (xy 116.392229 -401.401506) (xy 116.423266 -401.461227) (xy 116.446942 -401.524229)
			(xy 116.462918 -401.58961) (xy 116.470965 -401.656431) (xy 116.470967 -401.723736) (xy 116.462924 -401.790558)
			(xy 116.446952 -401.855939) (xy 116.423279 -401.918943) (xy 116.392246 -401.978666) (xy 116.354296 -402.034251)
			(xy 116.332508 -402.059902) (xy 116.326729 -402.06706) (xy 116.320204 -402.084241) (xy 116.319808 -402.09343)
			(xy 116.319808 -402.251418) (xy 116.319283 -402.261571) (xy 116.311511 -402.280332) (xy 116.297156 -402.294695)
			(xy 116.278399 -402.302477) (xy 116.268246 -402.30298) (xy 115.551966 -402.30298) (xy 115.541808 -402.302495)
			(xy 115.523042 -402.294713) (xy 115.508678 -402.280345) (xy 115.500902 -402.261576) (xy 115.500404 -402.251418)
			(xy 115.500404 -402.09343) (xy 115.499978 -402.084244) (xy 115.493475 -402.06706) (xy 115.487704 -402.059902)
			(xy 115.465896 -402.034267) (xy 115.42795 -401.978677) (xy 115.396919 -401.918951) (xy 115.373249 -401.855944)
			(xy 115.357279 -401.79056) (xy 115.349237 -401.723737) (xy 87.820954 -401.723737) (xy 87.792056 -401.779212)
			(xy 87.75397 -401.834847) (xy 87.732108 -401.860512) (xy 87.726325 -401.867667) (xy 87.719802 -401.88485)
			(xy 87.719408 -401.89404) (xy 87.719408 -402.386292) (xy 87.71982 -402.395479) (xy 87.726332 -402.412663)
			(xy 87.732108 -402.41982) (xy 87.753925 -402.445524) (xy 87.792014 -402.501153) (xy 87.823166 -402.560944)
			(xy 87.846933 -402.624036) (xy 87.862972 -402.68952) (xy 87.871051 -402.756454) (xy 87.871055 -402.823874)
			(xy 87.871055 -402.823878) (xy 117.548826 -402.823878) (xy 117.548831 -402.75645) (xy 117.556912 -402.689507)
			(xy 117.572954 -402.624015) (xy 117.596726 -402.560916) (xy 117.627885 -402.501119) (xy 117.665983 -402.445484)
			(xy 117.687852 -402.41982) (xy 117.693671 -402.412691) (xy 117.700171 -402.395488) (xy 117.700552 -402.386292)
			(xy 117.700552 -401.89404) (xy 117.700111 -401.884856) (xy 117.693618 -401.867672) (xy 117.687852 -401.860512)
			(xy 117.665967 -401.834864) (xy 117.627875 -401.779228) (xy 117.596722 -401.71943) (xy 117.572957 -401.656331)
			(xy 117.556921 -401.590839) (xy 117.548846 -401.523898) (xy 117.548848 -401.456472) (xy 117.556927 -401.389531)
			(xy 117.572966 -401.32404) (xy 117.596735 -401.260943) (xy 117.627891 -401.201146) (xy 117.665985 -401.145512)
			(xy 117.687852 -401.119848) (xy 117.69366 -401.112711) (xy 117.700166 -401.095514) (xy 117.700552 -401.08632)
			(xy 117.700552 -400.92884) (xy 117.701117 -400.91874) (xy 117.708832 -400.900072) (xy 117.723105 -400.885777)
			(xy 117.741761 -400.878033) (xy 117.75186 -400.877532) (xy 118.46814 -400.877532) (xy 118.478255 -400.877953)
			(xy 118.49694 -400.88571) (xy 118.511235 -400.900027) (xy 118.518963 -400.918724) (xy 118.519448 -400.92884)
			(xy 118.519448 -401.08632) (xy 118.51986 -401.095507) (xy 118.526374 -401.11269) (xy 118.532148 -401.119848)
			(xy 118.553994 -401.145529) (xy 118.592087 -401.20116) (xy 118.623241 -401.260953) (xy 118.647009 -401.324048)
			(xy 118.663047 -401.389536) (xy 118.671126 -401.456473) (xy 118.671127 -401.523897) (xy 118.663053 -401.590834)
			(xy 118.647018 -401.656323) (xy 118.623254 -401.719419) (xy 118.620974 -401.723796) (xy 119.749006 -401.723796)
			(xy 119.749008 -401.656371) (xy 119.757086 -401.589431) (xy 119.773123 -401.523941) (xy 119.79689 -401.460843)
			(xy 119.828043 -401.401046) (xy 119.866135 -401.345411) (xy 119.888 -401.319746) (xy 119.893802 -401.312605)
			(xy 119.900313 -401.295411) (xy 119.9007 -401.286218) (xy 119.9007 -400.793966) (xy 119.900306 -400.784777)
			(xy 119.893781 -400.767593) (xy 119.888 -400.760438) (xy 119.866142 -400.734768) (xy 119.828053 -400.679134)
			(xy 119.796902 -400.619339) (xy 119.773138 -400.556242) (xy 119.757102 -400.490754) (xy 119.749025 -400.423816)
			(xy 119.749025 -400.356393) (xy 119.7571 -400.289455) (xy 119.773135 -400.223966) (xy 119.796898 -400.16087)
			(xy 119.828048 -400.101074) (xy 119.866136 -400.045439) (xy 119.888 -400.019774) (xy 119.89379 -400.012624)
			(xy 119.900309 -399.995437) (xy 119.9007 -399.986246) (xy 119.9007 -399.828766) (xy 119.901197 -399.818642)
			(xy 119.908929 -399.799928) (xy 119.923211 -399.785574) (xy 119.941887 -399.777749) (xy 119.952008 -399.777204)
			(xy 120.668288 -399.777204) (xy 120.67841 -399.777626) (xy 120.697114 -399.785371) (xy 120.711429 -399.799686)
			(xy 120.719174 -399.81839) (xy 120.719596 -399.828512) (xy 120.719596 -399.986246) (xy 120.720033 -399.99543)
			(xy 120.726528 -400.012615) (xy 120.732296 -400.019774) (xy 120.754166 -400.045434) (xy 120.792255 -400.101069)
			(xy 120.823405 -400.160866) (xy 120.847169 -400.223964) (xy 120.863205 -400.289454) (xy 120.87128 -400.356392)
			(xy 120.87128 -400.423817) (xy 120.863203 -400.490755) (xy 120.847167 -400.556245) (xy 120.823402 -400.619342)
			(xy 120.79225 -400.679138) (xy 120.75416 -400.734773) (xy 120.732296 -400.760438) (xy 120.7265 -400.767584)
			(xy 120.719985 -400.784774) (xy 120.719596 -400.793966) (xy 120.719596 -401.286218) (xy 120.719998 -401.295406)
			(xy 120.726517 -401.31259) (xy 120.732296 -401.319746) (xy 120.754138 -401.345429) (xy 120.792228 -401.401061)
			(xy 120.82338 -401.460855) (xy 120.847146 -401.523949) (xy 120.863183 -401.589436) (xy 120.87126 -401.656372)
			(xy 120.871262 -401.723794) (xy 120.863189 -401.790731) (xy 120.847155 -401.856219) (xy 120.823394 -401.919315)
			(xy 120.792245 -401.979111) (xy 120.754159 -402.034745) (xy 120.732296 -402.06041) (xy 120.726512 -402.067564)
			(xy 120.71999 -402.084748) (xy 120.719596 -402.093938) (xy 120.719596 -402.251418) (xy 120.719089 -402.261541)
			(xy 120.711362 -402.280256) (xy 120.697083 -402.294611) (xy 120.678409 -402.302436) (xy 120.668288 -402.30298)
			(xy 119.952008 -402.30298) (xy 119.941884 -402.302577) (xy 119.923176 -402.294828) (xy 119.908861 -402.280507)
			(xy 119.901119 -402.261797) (xy 119.9007 -402.251672) (xy 119.9007 -402.093938) (xy 119.900272 -402.084753)
			(xy 119.893771 -402.067568) (xy 119.888 -402.06041) (xy 119.866114 -402.034763) (xy 119.828026 -401.979126)
			(xy 119.796877 -401.919327) (xy 119.773114 -401.856228) (xy 119.75708 -401.790736) (xy 119.749006 -401.723796)
			(xy 118.620974 -401.723796) (xy 118.592102 -401.779215) (xy 118.554013 -401.834848) (xy 118.532148 -401.860512)
			(xy 118.526357 -401.867661) (xy 118.519841 -401.884849) (xy 118.519448 -401.89404) (xy 118.519448 -402.386292)
			(xy 118.519874 -402.395477) (xy 118.526378 -402.412661) (xy 118.532148 -402.41982) (xy 118.553967 -402.445523)
			(xy 118.59206 -402.501151) (xy 118.623216 -402.560942) (xy 118.646985 -402.624034) (xy 118.663025 -402.689519)
			(xy 118.671106 -402.756454) (xy 118.67111 -402.823818) (xy 121.949146 -402.823818) (xy 121.94915 -402.756509)
			(xy 121.957199 -402.689684) (xy 121.973177 -402.624299) (xy 121.996856 -402.561292) (xy 122.027895 -402.501567)
			(xy 122.065849 -402.44598) (xy 122.08764 -402.420328) (xy 122.093455 -402.413196) (xy 122.099958 -402.395995)
			(xy 122.10034 -402.3868) (xy 122.10034 -401.893532) (xy 122.099905 -401.884348) (xy 122.093408 -401.867164)
			(xy 122.08764 -401.860004) (xy 122.065832 -401.834368) (xy 122.027884 -401.778779) (xy 121.996852 -401.719054)
			(xy 121.97318 -401.656047) (xy 121.957208 -401.590663) (xy 121.949166 -401.523838) (xy 121.949168 -401.456532)
			(xy 121.957214 -401.389708) (xy 121.973189 -401.324324) (xy 121.996864 -401.261319) (xy 122.0279 -401.201595)
			(xy 122.065851 -401.146008) (xy 122.08764 -401.120356) (xy 122.093443 -401.113215) (xy 122.099953 -401.096021)
			(xy 122.10034 -401.086828) (xy 122.10034 -400.92884) (xy 122.10075 -400.918715) (xy 122.108492 -400.900005)
			(xy 122.122812 -400.885688) (xy 122.141523 -400.877948) (xy 122.151648 -400.877532) (xy 122.868182 -400.877532)
			(xy 122.878307 -400.878041) (xy 122.897026 -400.885761) (xy 122.911383 -400.900041) (xy 122.919204 -400.918718)
			(xy 122.919744 -400.92884) (xy 122.919744 -401.086828) (xy 122.920153 -401.096015) (xy 122.926669 -401.113199)
			(xy 122.932444 -401.120356) (xy 122.954212 -401.146024) (xy 122.992163 -401.201608) (xy 123.023198 -401.261329)
			(xy 123.046873 -401.324332) (xy 123.062848 -401.389712) (xy 123.070894 -401.456533) (xy 123.070895 -401.523837)
			(xy 123.062853 -401.590658) (xy 123.046882 -401.65604) (xy 123.02321 -401.719043) (xy 123.020771 -401.723737)
			(xy 124.149301 -401.723737) (xy 124.149303 -401.65643) (xy 124.15735 -401.589605) (xy 124.173327 -401.524221)
			(xy 124.197004 -401.461215) (xy 124.228043 -401.401491) (xy 124.265997 -401.345906) (xy 124.287788 -401.320254)
			(xy 124.293585 -401.313109) (xy 124.3001 -401.295918) (xy 124.300488 -401.286726) (xy 124.300488 -400.793458)
			(xy 124.300101 -400.784268) (xy 124.293572 -400.767084) (xy 124.287788 -400.75993) (xy 124.266005 -400.734274)
			(xy 124.228052 -400.678689) (xy 124.197016 -400.618966) (xy 124.173341 -400.555962) (xy 124.157366 -400.49058)
			(xy 124.149321 -400.423757) (xy 124.14932 -400.356452) (xy 124.157365 -400.289629) (xy 124.173338 -400.224246)
			(xy 124.197013 -400.161242) (xy 124.228048 -400.101519) (xy 124.265999 -400.045933) (xy 124.287788 -400.020282)
			(xy 124.293573 -400.013129) (xy 124.300095 -399.995944) (xy 124.300488 -399.986754) (xy 124.300488 -399.828766)
			(xy 124.300837 -399.818586) (xy 124.308643 -399.799781) (xy 124.323052 -399.785395) (xy 124.341869 -399.777621)
			(xy 124.35205 -399.777204) (xy 125.06833 -399.777204) (xy 125.078486 -399.777708) (xy 125.097249 -399.785486)
			(xy 125.111612 -399.799848) (xy 125.119391 -399.818611) (xy 125.119892 -399.828766) (xy 125.119892 -399.986754)
			(xy 125.120326 -399.995939) (xy 125.126823 -400.013123) (xy 125.132592 -400.020282) (xy 125.154385 -400.04593)
			(xy 125.192331 -400.101518) (xy 125.223363 -400.161242) (xy 125.247034 -400.224247) (xy 125.263005 -400.289629)
			(xy 125.271049 -400.356452) (xy 125.271048 -400.423757) (xy 125.263004 -400.490579) (xy 125.247031 -400.555962)
			(xy 125.223359 -400.618966) (xy 125.192327 -400.67869) (xy 125.154379 -400.734277) (xy 125.132592 -400.75993)
			(xy 125.126799 -400.767078) (xy 125.120283 -400.784266) (xy 125.119892 -400.793458) (xy 125.119892 -401.286726)
			(xy 125.120291 -401.295914) (xy 125.126813 -401.313099) (xy 125.132592 -401.320254) (xy 125.154357 -401.345924)
			(xy 125.192305 -401.401509) (xy 125.223337 -401.46123) (xy 125.24701 -401.524232) (xy 125.262983 -401.589612)
			(xy 125.271029 -401.656432) (xy 125.271031 -401.723735) (xy 125.262989 -401.790555) (xy 125.24702 -401.855936)
			(xy 125.223351 -401.918939) (xy 125.192322 -401.978663) (xy 125.154377 -402.034249) (xy 125.132592 -402.059902)
			(xy 125.126811 -402.067058) (xy 125.120287 -402.08424) (xy 125.119892 -402.09343) (xy 125.119892 -402.251418)
			(xy 125.119382 -402.261573) (xy 125.111608 -402.280337) (xy 125.097247 -402.294701) (xy 125.078485 -402.30248)
			(xy 125.06833 -402.30298) (xy 124.35205 -402.30298) (xy 124.341884 -402.302496) (xy 124.323094 -402.29473)
			(xy 124.308708 -402.280363) (xy 124.300918 -402.261584) (xy 124.300488 -402.251418) (xy 124.300488 -402.09343)
			(xy 124.300066 -402.084244) (xy 124.293561 -402.067059) (xy 124.287788 -402.059902) (xy 124.265977 -402.034268)
			(xy 124.228026 -401.97868) (xy 124.196991 -401.918955) (xy 124.173317 -401.855948) (xy 124.157344 -401.790563)
			(xy 124.149301 -401.723737) (xy 123.020771 -401.723737) (xy 122.992178 -401.778766) (xy 122.954231 -401.834352)
			(xy 122.932444 -401.860004) (xy 122.926656 -401.867155) (xy 122.920138 -401.884341) (xy 122.919744 -401.893532)
			(xy 122.919744 -402.3868) (xy 122.920167 -402.395986) (xy 122.926673 -402.413169) (xy 122.932444 -402.420328)
			(xy 122.954185 -402.446019) (xy 122.992136 -402.501599) (xy 123.023173 -402.561317) (xy 123.046849 -402.624317)
			(xy 123.062826 -402.689695) (xy 123.070874 -402.756513) (xy 123.070878 -402.823815) (xy 123.07087 -402.823878)
			(xy 126.348914 -402.823878) (xy 126.348919 -402.75645) (xy 126.357 -402.689508) (xy 126.373042 -402.624016)
			(xy 126.396813 -402.560916) (xy 126.427971 -402.501119) (xy 126.466068 -402.445485) (xy 126.487936 -402.41982)
			(xy 126.493754 -402.41269) (xy 126.500255 -402.395488) (xy 126.500636 -402.386292) (xy 126.500636 -401.89404)
			(xy 126.500198 -401.884856) (xy 126.493703 -401.867672) (xy 126.487936 -401.860512) (xy 126.466051 -401.834864)
			(xy 126.427961 -401.779227) (xy 126.396809 -401.719429) (xy 126.373044 -401.65633) (xy 126.357009 -401.590839)
			(xy 126.348934 -401.523898) (xy 126.348936 -401.456472) (xy 126.357014 -401.389532) (xy 126.373053 -401.324041)
			(xy 126.396821 -401.260943) (xy 126.427976 -401.201147) (xy 126.46607 -401.145513) (xy 126.487936 -401.119848)
			(xy 126.493742 -401.112709) (xy 126.50025 -401.095514) (xy 126.500636 -401.08632) (xy 126.500636 -400.92884)
			(xy 126.50105 -400.918716) (xy 126.508791 -400.900006) (xy 126.523109 -400.885689) (xy 126.54182 -400.877949)
			(xy 126.551944 -400.877532) (xy 127.268224 -400.877532) (xy 127.278352 -400.877897) (xy 127.297062 -400.885659)
			(xy 127.311377 -400.899991) (xy 127.319116 -400.918711) (xy 127.319532 -400.92884) (xy 127.319532 -401.08632)
			(xy 127.319948 -401.095506) (xy 127.326459 -401.11269) (xy 127.332232 -401.119848) (xy 127.354075 -401.14553)
			(xy 127.392162 -401.201163) (xy 127.423312 -401.260957) (xy 127.447076 -401.324052) (xy 127.463112 -401.389538)
			(xy 127.471189 -401.456474) (xy 127.471191 -401.523896) (xy 127.463117 -401.590832) (xy 127.447085 -401.65632)
			(xy 127.423324 -401.719415) (xy 127.421073 -401.723737) (xy 128.549092 -401.723737) (xy 128.549094 -401.65643)
			(xy 128.557141 -401.589605) (xy 128.573117 -401.524221) (xy 128.596794 -401.461216) (xy 128.627832 -401.401492)
			(xy 128.665786 -401.345906) (xy 128.687576 -401.320254) (xy 128.693372 -401.313108) (xy 128.699888 -401.295918)
			(xy 128.700276 -401.286726) (xy 128.700276 -400.793458) (xy 128.699891 -400.784268) (xy 128.69336 -400.767084)
			(xy 128.687576 -400.75993) (xy 128.665793 -400.734273) (xy 128.627842 -400.678688) (xy 128.596806 -400.618966)
			(xy 128.573131 -400.555962) (xy 128.557157 -400.49058) (xy 128.549112 -400.423757) (xy 128.549111 -400.356452)
			(xy 128.557155 -400.289629) (xy 128.573129 -400.224247) (xy 128.596802 -400.161242) (xy 128.627837 -400.101519)
			(xy 128.665788 -400.045934) (xy 128.687576 -400.020282) (xy 128.69336 -400.013128) (xy 128.699883 -399.995944)
			(xy 128.700276 -399.986754) (xy 128.700276 -399.828766) (xy 128.700637 -399.818587) (xy 128.70844 -399.799785)
			(xy 128.722845 -399.7854) (xy 128.741659 -399.777623) (xy 128.751838 -399.777204) (xy 129.468118 -399.777204)
			(xy 129.478273 -399.777718) (xy 129.497036 -399.785492) (xy 129.511399 -399.799851) (xy 129.519179 -399.818611)
			(xy 129.51968 -399.828766) (xy 129.51968 -399.986754) (xy 129.520117 -399.995938) (xy 129.526612 -400.013123)
			(xy 129.53238 -400.020282) (xy 129.554173 -400.045929) (xy 129.592121 -400.101517) (xy 129.623152 -400.161241)
			(xy 129.646824 -400.224247) (xy 129.662796 -400.289629) (xy 129.670839 -400.356452) (xy 129.670839 -400.423757)
			(xy 129.662794 -400.49058) (xy 129.646821 -400.555962) (xy 129.623149 -400.618967) (xy 129.592116 -400.678691)
			(xy 129.554168 -400.734278) (xy 129.53238 -400.75993) (xy 129.526586 -400.767077) (xy 129.52007 -400.784266)
			(xy 129.51968 -400.793458) (xy 129.51968 -401.286726) (xy 129.520082 -401.295914) (xy 129.526602 -401.313098)
			(xy 129.53238 -401.320254) (xy 129.554146 -401.345924) (xy 129.592094 -401.401508) (xy 129.623127 -401.46123)
			(xy 129.6468 -401.524232) (xy 129.662774 -401.589612) (xy 129.67082 -401.656432) (xy 129.670822 -401.723735)
			(xy 129.66278 -401.790556) (xy 129.64681 -401.855937) (xy 129.623141 -401.91894) (xy 129.592111 -401.978663)
			(xy 129.554166 -402.03425) (xy 129.53238 -402.059902) (xy 129.526598 -402.067057) (xy 129.520075 -402.08424)
			(xy 129.51968 -402.09343) (xy 129.51968 -402.251418) (xy 129.519182 -402.261575) (xy 129.511405 -402.280341)
			(xy 129.497041 -402.294705) (xy 129.478275 -402.302482) (xy 129.468118 -402.30298) (xy 128.751838 -402.30298)
			(xy 128.741671 -402.302505) (xy 128.722881 -402.294736) (xy 128.708495 -402.280366) (xy 128.700706 -402.261584)
			(xy 128.700276 -402.251418) (xy 128.700276 -402.09343) (xy 128.699857 -402.084244) (xy 128.69335 -402.067059)
			(xy 128.687576 -402.059902) (xy 128.665766 -402.034268) (xy 128.627815 -401.97868) (xy 128.596781 -401.918954)
			(xy 128.573108 -401.855947) (xy 128.557135 -401.790562) (xy 128.549092 -401.723737) (xy 127.421073 -401.723737)
			(xy 127.392178 -401.779211) (xy 127.354094 -401.834846) (xy 127.332232 -401.860512) (xy 127.32644 -401.86766)
			(xy 127.319924 -401.884849) (xy 127.319532 -401.89404) (xy 127.319532 -402.386292) (xy 127.319961 -402.395477)
			(xy 127.326463 -402.412661) (xy 127.332232 -402.41982) (xy 127.354048 -402.445525) (xy 127.392136 -402.501154)
			(xy 127.423287 -402.560945) (xy 127.447052 -402.624037) (xy 127.46309 -402.689521) (xy 127.471169 -402.756454)
			(xy 127.471174 -402.823818) (xy 130.749234 -402.823818) (xy 130.749238 -402.75651) (xy 130.757287 -402.689684)
			(xy 130.773265 -402.624299) (xy 130.796942 -402.561293) (xy 130.82798 -402.501568) (xy 130.865934 -402.44598)
			(xy 130.887724 -402.420328) (xy 130.893536 -402.413194) (xy 130.900041 -402.395995) (xy 130.900424 -402.3868)
			(xy 130.900424 -401.893532) (xy 130.899993 -401.884347) (xy 130.893493 -401.867163) (xy 130.887724 -401.860004)
			(xy 130.865917 -401.834368) (xy 130.82797 -401.778779) (xy 130.796938 -401.719053) (xy 130.773267 -401.656046)
			(xy 130.757296 -401.590662) (xy 130.749254 -401.523838) (xy 130.749256 -401.456532) (xy 130.757301 -401.389708)
			(xy 130.773276 -401.324325) (xy 130.79695 -401.26132) (xy 130.827985 -401.201595) (xy 130.865935 -401.146008)
			(xy 130.887724 -401.120356) (xy 130.893525 -401.113214) (xy 130.900036 -401.096021) (xy 130.900424 -401.086828)
			(xy 130.900424 -400.92884) (xy 130.900855 -400.918686) (xy 130.908642 -400.899929) (xy 130.923036 -400.885604)
			(xy 130.94183 -400.877907) (xy 130.951986 -400.877532) (xy 131.668266 -400.877532) (xy 131.67839 -400.878054)
			(xy 131.697108 -400.88577) (xy 131.711465 -400.900045) (xy 131.719287 -400.918719) (xy 131.719828 -400.92884)
			(xy 131.719828 -401.086828) (xy 131.720218 -401.096017) (xy 131.726745 -401.113202) (xy 131.732528 -401.120356)
			(xy 131.754297 -401.146024) (xy 131.792249 -401.201607) (xy 131.823285 -401.261328) (xy 131.84696 -401.324331)
			(xy 131.862935 -401.389712) (xy 131.870981 -401.456533) (xy 131.870983 -401.523837) (xy 131.862941 -401.590659)
			(xy 131.846969 -401.65604) (xy 131.823297 -401.719044) (xy 131.792264 -401.778767) (xy 131.754315 -401.834352)
			(xy 131.732528 -401.860004) (xy 131.726738 -401.867154) (xy 131.720222 -401.884341) (xy 131.719828 -401.893532)
			(xy 131.719828 -402.3868) (xy 131.720232 -402.395988) (xy 131.726749 -402.413173) (xy 131.732528 -402.420328)
			(xy 131.75427 -402.446019) (xy 131.792222 -402.501599) (xy 131.823259 -402.561317) (xy 131.846936 -402.624316)
			(xy 131.862913 -402.689694) (xy 131.870962 -402.756513) (xy 131.870966 -402.823815) (xy 131.862926 -402.890635)
			(xy 131.846957 -402.956015) (xy 131.823289 -403.019017) (xy 131.792259 -403.078739) (xy 131.754314 -403.134324)
			(xy 131.732528 -403.159976) (xy 131.726708 -403.167104) (xy 131.720209 -403.184308) (xy 131.719828 -403.193504)
			(xy 131.719828 -403.351492) (xy 131.719372 -403.361642) (xy 131.711585 -403.380389) (xy 131.697199 -403.394712)
			(xy 131.678418 -403.402417) (xy 131.668266 -403.4028) (xy 130.951986 -403.4028) (xy 130.941863 -403.402286)
			(xy 130.92315 -403.394561) (xy 130.908795 -403.380284) (xy 130.90097 -403.361612) (xy 130.900424 -403.351492)
			(xy 130.900424 -403.193504) (xy 130.900007 -403.184318) (xy 130.893498 -403.167133) (xy 130.887724 -403.159976)
			(xy 130.86589 -403.134362) (xy 130.827943 -403.07877) (xy 130.796913 -403.019041) (xy 130.773243 -402.956032)
			(xy 130.757274 -402.890645) (xy 130.749234 -402.823818) (xy 127.471174 -402.823818) (xy 127.471174 -402.823874)
			(xy 127.463103 -402.890808) (xy 127.447074 -402.956294) (xy 127.423316 -403.019389) (xy 127.392173 -403.079184)
			(xy 127.354092 -403.134818) (xy 127.332232 -403.160484) (xy 127.326409 -403.16761) (xy 127.319912 -403.184816)
			(xy 127.319532 -403.194012) (xy 127.319532 -403.351492) (xy 127.319009 -403.361596) (xy 127.31128 -403.380268)
			(xy 127.296995 -403.394562) (xy 127.278328 -403.402303) (xy 127.268224 -403.4028) (xy 126.551944 -403.4028)
			(xy 126.541824 -403.402348) (xy 126.523122 -403.394614) (xy 126.508806 -403.380308) (xy 126.501059 -403.361611)
			(xy 126.500636 -403.351492) (xy 126.500636 -403.194012) (xy 126.500212 -403.184826) (xy 126.493707 -403.167642)
			(xy 126.487936 -403.160484) (xy 126.466024 -403.134858) (xy 126.427934 -403.079219) (xy 126.396783 -403.019418)
			(xy 126.37302 -402.956315) (xy 126.356987 -402.890821) (xy 126.348914 -402.823878) (xy 123.07087 -402.823878)
			(xy 123.062839 -402.890634) (xy 123.04687 -402.956014) (xy 123.023202 -403.019017) (xy 122.992173 -403.078739)
			(xy 122.954229 -403.134324) (xy 122.932444 -403.159976) (xy 122.926626 -403.167106) (xy 122.920126 -403.184308)
			(xy 122.919744 -403.193504) (xy 122.919744 -403.351492) (xy 122.919209 -403.361595) (xy 122.911483 -403.380264)
			(xy 122.897201 -403.394558) (xy 122.878538 -403.402301) (xy 122.868436 -403.4028) (xy 122.151902 -403.4028)
			(xy 122.14178 -403.402273) (xy 122.123067 -403.394553) (xy 122.108712 -403.38028) (xy 122.100886 -403.361611)
			(xy 122.10034 -403.351492) (xy 122.10034 -403.193504) (xy 122.099919 -403.184318) (xy 122.093412 -403.167134)
			(xy 122.08764 -403.159976) (xy 122.065805 -403.134363) (xy 122.027857 -403.078771) (xy 121.996826 -403.019042)
			(xy 121.973156 -402.956032) (xy 121.957186 -402.890645) (xy 121.949146 -402.823818) (xy 118.67111 -402.823818)
			(xy 118.67111 -402.823874) (xy 118.663038 -402.89081) (xy 118.647006 -402.956297) (xy 118.623245 -403.019392)
			(xy 118.592097 -403.079187) (xy 118.554011 -403.13482) (xy 118.532148 -403.160484) (xy 118.526327 -403.167612)
			(xy 118.519828 -403.184816) (xy 118.519448 -403.194012) (xy 118.519448 -403.351492) (xy 118.51891 -403.361594)
			(xy 118.511183 -403.380263) (xy 118.496903 -403.394557) (xy 118.478242 -403.4023) (xy 118.46814 -403.4028)
			(xy 117.75186 -403.4028) (xy 117.741749 -403.402348) (xy 117.72307 -403.394597) (xy 117.708776 -403.38029)
			(xy 117.701043 -403.361604) (xy 117.700552 -403.351492) (xy 117.700552 -403.194012) (xy 117.700125 -403.184827)
			(xy 117.693622 -403.167643) (xy 117.687852 -403.160484) (xy 117.665939 -403.134859) (xy 117.627848 -403.07922)
			(xy 117.596697 -403.019418) (xy 117.572933 -402.956316) (xy 117.556899 -402.890822) (xy 117.548826 -402.823878)
			(xy 87.871055 -402.823878) (xy 87.862984 -402.890809) (xy 87.846954 -402.956295) (xy 87.823196 -403.01939)
			(xy 87.792051 -403.079185) (xy 87.753969 -403.134819) (xy 87.732108 -403.160484) (xy 87.726294 -403.167617)
			(xy 87.71979 -403.184817) (xy 87.719408 -403.194012) (xy 87.719408 -403.351492) (xy 87.718978 -403.361613)
			(xy 87.711234 -403.380315) (xy 87.696922 -403.394629) (xy 87.678221 -403.402376) (xy 87.6681 -403.4028)
			(xy 86.95182 -403.4028) (xy 86.941699 -403.402368) (xy 86.922996 -403.394626) (xy 86.908681 -403.380315)
			(xy 86.900935 -403.361613) (xy 86.900512 -403.351492) (xy 86.900512 -403.194012) (xy 86.900093 -403.184826)
			(xy 86.893585 -403.167642) (xy 86.887812 -403.160484) (xy 86.8659 -403.134858) (xy 86.827812 -403.079218)
			(xy 86.796663 -403.019417) (xy 86.772901 -402.956315) (xy 86.756869 -402.890821) (xy 86.748796 -402.823878)
			(xy 83.470752 -402.823878) (xy 83.46272 -402.890635) (xy 83.446751 -402.956015) (xy 83.423082 -403.019018)
			(xy 83.392052 -403.07874) (xy 83.354106 -403.134324) (xy 83.33232 -403.159976) (xy 83.326511 -403.167113)
			(xy 83.320003 -403.18431) (xy 83.31962 -403.193504) (xy 83.31962 -403.351492) (xy 83.319172 -403.361643)
			(xy 83.311383 -403.380391) (xy 83.296995 -403.394714) (xy 83.278211 -403.402418) (xy 83.268058 -403.4028)
			(xy 82.551778 -403.4028) (xy 82.541655 -403.402293) (xy 82.522941 -403.394565) (xy 82.508586 -403.380286)
			(xy 82.500761 -403.361613) (xy 82.500216 -403.351492) (xy 82.500216 -403.193504) (xy 82.4998 -403.184318)
			(xy 82.49329 -403.167133) (xy 82.487516 -403.159976) (xy 82.465682 -403.134362) (xy 82.427736 -403.07877)
			(xy 82.396706 -403.019041) (xy 82.373037 -402.956031) (xy 82.357068 -402.890645) (xy 82.349028 -402.823818)
			(xy 79.070968 -402.823818) (xy 79.070968 -402.823874) (xy 79.062897 -402.890808) (xy 79.046867 -402.956294)
			(xy 79.023109 -403.019389) (xy 78.991966 -403.079184) (xy 78.953884 -403.134818) (xy 78.932024 -403.160484)
			(xy 78.926212 -403.167618) (xy 78.919706 -403.184817) (xy 78.919324 -403.194012) (xy 78.919324 -403.351492)
			(xy 78.918809 -403.361597) (xy 78.911078 -403.380271) (xy 78.896791 -403.394565) (xy 78.878121 -403.402304)
			(xy 78.868016 -403.4028) (xy 78.151736 -403.4028) (xy 78.141616 -403.402354) (xy 78.122913 -403.394618)
			(xy 78.108598 -403.38031) (xy 78.100851 -403.361612) (xy 78.100428 -403.351492) (xy 78.100428 -403.194012)
			(xy 78.100006 -403.184826) (xy 78.0935 -403.167642) (xy 78.087728 -403.160484) (xy 78.065816 -403.134858)
			(xy 78.027727 -403.079219) (xy 77.996577 -403.019417) (xy 77.972814 -402.956315) (xy 77.956781 -402.890821)
			(xy 77.948708 -402.823878) (xy 74.670664 -402.823878) (xy 74.662632 -402.890635) (xy 74.646664 -402.956014)
			(xy 74.622995 -403.019017) (xy 74.591966 -403.078739) (xy 74.554022 -403.134324) (xy 74.532236 -403.159976)
			(xy 74.526417 -403.167105) (xy 74.519917 -403.184308) (xy 74.519536 -403.193504) (xy 74.519536 -403.351492)
			(xy 74.519073 -403.361641) (xy 74.511286 -403.380386) (xy 74.496903 -403.394709) (xy 74.478125 -403.402415)
			(xy 74.467974 -403.4028) (xy 73.751694 -403.4028) (xy 73.741572 -403.402279) (xy 73.722858 -403.394557)
			(xy 73.708504 -403.380282) (xy 73.700678 -403.361611) (xy 73.700132 -403.351492) (xy 73.700132 -403.193504)
			(xy 73.699713 -403.184318) (xy 73.693205 -403.167134) (xy 73.687432 -403.159976) (xy 73.665597 -403.134363)
			(xy 73.62765 -403.07877) (xy 73.59662 -403.019041) (xy 73.57295 -402.956032) (xy 73.55698 -402.890645)
			(xy 73.54894 -402.823818) (xy 66.525648 -402.823818) (xy 66.525648 -405.623707) (xy 71.348811 -405.623707)
			(xy 71.348811 -405.556283) (xy 71.356888 -405.489345) (xy 71.372924 -405.423856) (xy 71.396688 -405.360759)
			(xy 71.427839 -405.300962) (xy 71.465928 -405.245327) (xy 71.487792 -405.219662) (xy 71.493586 -405.212515)
			(xy 71.500103 -405.195326) (xy 71.500492 -405.186134) (xy 71.500492 -404.693882) (xy 71.500092 -404.684694)
			(xy 71.493571 -404.667509) (xy 71.487792 -404.660354) (xy 71.46595 -404.634671) (xy 71.427861 -404.579039)
			(xy 71.39671 -404.519245) (xy 71.372945 -404.45615) (xy 71.356908 -404.390664) (xy 71.348831 -404.323727)
			(xy 71.348829 -404.256306) (xy 71.356902 -404.189369) (xy 71.372935 -404.123881) (xy 71.396696 -404.060785)
			(xy 71.427844 -404.00099) (xy 71.46593 -403.945355) (xy 71.487792 -403.91969) (xy 71.493574 -403.912535)
			(xy 71.500098 -403.895352) (xy 71.500492 -403.886162) (xy 71.500492 -403.728682) (xy 71.50101 -403.71856)
			(xy 71.508735 -403.699847) (xy 71.523011 -403.685493) (xy 71.541681 -403.677666) (xy 71.5518 -403.67712)
			(xy 72.26808 -403.67712) (xy 72.278235 -403.677538) (xy 72.296991 -403.685331) (xy 72.311316 -403.699729)
			(xy 72.319013 -403.718525) (xy 72.319388 -403.728682) (xy 72.319388 -403.886162) (xy 72.319819 -403.895347)
			(xy 72.326319 -403.912531) (xy 72.332088 -403.91969) (xy 72.353974 -403.945337) (xy 72.392063 -404.000974)
			(xy 72.423213 -404.060773) (xy 72.446977 -404.123872) (xy 72.463011 -404.189363) (xy 72.471085 -404.256304)
			(xy 72.471083 -404.323729) (xy 72.463005 -404.390669) (xy 72.446967 -404.45616) (xy 72.4232 -404.519258)
			(xy 72.392046 -404.579054) (xy 72.353954 -404.634689) (xy 72.332088 -404.660354) (xy 72.326285 -404.667494)
			(xy 72.319774 -404.684689) (xy 72.319388 -404.693882) (xy 72.319388 -405.186134) (xy 72.319784 -405.195323)
			(xy 72.326308 -405.212507) (xy 72.332088 -405.219662) (xy 72.353946 -405.245332) (xy 72.392036 -405.300965)
			(xy 72.423188 -405.360761) (xy 72.446953 -405.423857) (xy 72.462989 -405.489346) (xy 72.471066 -405.556284)
			(xy 72.471066 -405.623707) (xy 72.462991 -405.690645) (xy 72.446956 -405.756134) (xy 72.423191 -405.819231)
			(xy 72.392041 -405.879027) (xy 72.353952 -405.934661) (xy 72.332088 -405.960326) (xy 72.326297 -405.967475)
			(xy 72.319779 -405.984663) (xy 72.319388 -405.993854) (xy 72.319388 -406.151334) (xy 72.318902 -406.161459)
			(xy 72.311168 -406.180176) (xy 72.296883 -406.19453) (xy 72.278203 -406.202353) (xy 72.26808 -406.202896)
			(xy 71.5518 -406.202896) (xy 71.541645 -406.202478) (xy 71.522892 -406.194682) (xy 71.508569 -406.180284)
			(xy 71.50087 -406.161491) (xy 71.500492 -406.151334) (xy 71.500492 -405.993854) (xy 71.500058 -405.984669)
			(xy 71.493561 -405.967485) (xy 71.487792 -405.960326) (xy 71.465922 -405.934665) (xy 71.427834 -405.87903)
			(xy 71.396684 -405.819233) (xy 71.372921 -405.756136) (xy 71.356886 -405.690646) (xy 71.348811 -405.623707)
			(xy 66.525648 -405.623707) (xy 66.525648 -406.72373) (xy 73.548951 -406.72373) (xy 73.548954 -406.656422)
			(xy 73.557001 -406.589598) (xy 73.572978 -406.524214) (xy 73.596654 -406.461208) (xy 73.62769 -406.401483)
			(xy 73.665642 -406.345896) (xy 73.687432 -406.320244) (xy 73.693239 -406.313106) (xy 73.699747 -406.29591)
			(xy 73.700132 -406.286716) (xy 73.700132 -405.793448) (xy 73.699691 -405.784264) (xy 73.693198 -405.76708)
			(xy 73.687432 -405.75992) (xy 73.66564 -405.734271) (xy 73.627692 -405.678684) (xy 73.596659 -405.61896)
			(xy 73.572987 -405.555955) (xy 73.557015 -405.490572) (xy 73.548971 -405.42375) (xy 73.548971 -405.356444)
			(xy 73.557016 -405.289622) (xy 73.572989 -405.224239) (xy 73.596662 -405.161235) (xy 73.627695 -405.101511)
			(xy 73.665644 -405.045924) (xy 73.687432 -405.020272) (xy 73.693227 -405.013126) (xy 73.699742 -404.995936)
			(xy 73.700132 -404.986744) (xy 73.700132 -404.828756) (xy 73.700486 -404.818595) (xy 73.708302 -404.799836)
			(xy 73.72272 -404.785513) (xy 73.74153 -404.77782) (xy 73.751694 -404.777448) (xy 74.467974 -404.777448)
			(xy 74.4781 -404.777948) (xy 74.496822 -404.785669) (xy 74.51118 -404.799951) (xy 74.518998 -404.818633)
			(xy 74.519536 -404.828756) (xy 74.519536 -404.986744) (xy 74.519939 -404.995932) (xy 74.526459 -405.013115)
			(xy 74.532236 -405.020272) (xy 74.55402 -405.045927) (xy 74.591971 -405.101513) (xy 74.623006 -405.161235)
			(xy 74.64668 -405.22424) (xy 74.662654 -405.289622) (xy 74.670699 -405.356444) (xy 74.670699 -405.42375)
			(xy 74.662655 -405.490572) (xy 74.646682 -405.555955) (xy 74.623008 -405.618959) (xy 74.620571 -405.623649)
			(xy 75.749106 -405.623649) (xy 75.749107 -405.556342) (xy 75.757152 -405.489519) (xy 75.773127 -405.424136)
			(xy 75.796802 -405.361131) (xy 75.827839 -405.301407) (xy 75.865791 -405.245822) (xy 75.88758 -405.22017)
			(xy 75.893369 -405.21302) (xy 75.899889 -405.195833) (xy 75.90028 -405.186642) (xy 75.90028 -404.693374)
			(xy 75.899887 -404.684185) (xy 75.893362 -404.667001) (xy 75.88758 -404.659846) (xy 75.865813 -404.634177)
			(xy 75.827861 -404.578594) (xy 75.796824 -404.518873) (xy 75.773148 -404.45587) (xy 75.757173 -404.39049)
			(xy 75.749126 -404.323669) (xy 75.749124 -404.256365) (xy 75.757167 -404.189543) (xy 75.773138 -404.124161)
			(xy 75.796811 -404.061157) (xy 75.827844 -404.001435) (xy 75.865792 -403.94585) (xy 75.88758 -403.920198)
			(xy 75.893358 -403.913039) (xy 75.899884 -403.895859) (xy 75.90028 -403.88667) (xy 75.90028 -403.728682)
			(xy 75.90065 -403.718504) (xy 75.908449 -403.699701) (xy 75.922851 -403.685315) (xy 75.941664 -403.677538)
			(xy 75.951842 -403.67712) (xy 76.668122 -403.67712) (xy 76.678279 -403.677615) (xy 76.697045 -403.685393)
			(xy 76.711409 -403.699758) (xy 76.719186 -403.718525) (xy 76.719684 -403.728682) (xy 76.719684 -403.88667)
			(xy 76.720112 -403.895855) (xy 76.726614 -403.91304) (xy 76.732384 -403.920198) (xy 76.754193 -403.945833)
			(xy 76.792139 -404.001422) (xy 76.82317 -404.061148) (xy 76.846841 -404.124155) (xy 76.862812 -404.189539)
			(xy 76.870854 -404.256363) (xy 76.870852 -404.32367) (xy 76.862806 -404.390493) (xy 76.846831 -404.455877)
			(xy 76.823157 -404.518882) (xy 76.792122 -404.578606) (xy 76.754172 -404.634194) (xy 76.732384 -404.659846)
			(xy 76.726584 -404.666988) (xy 76.720072 -404.684181) (xy 76.719684 -404.693374) (xy 76.719684 -405.186642)
			(xy 76.720077 -405.195831) (xy 76.726603 -405.213015) (xy 76.732384 -405.22017) (xy 76.754165 -405.245827)
			(xy 76.792113 -405.301414) (xy 76.823145 -405.361137) (xy 76.846817 -405.42414) (xy 76.86279 -405.489522)
			(xy 76.870834 -405.556343) (xy 76.870835 -405.623648) (xy 76.862791 -405.690469) (xy 76.84682 -405.755851)
			(xy 76.823149 -405.818855) (xy 76.792117 -405.878579) (xy 76.754171 -405.934166) (xy 76.732384 -405.959818)
			(xy 76.726595 -405.966969) (xy 76.720077 -405.984155) (xy 76.719684 -405.993346) (xy 76.719684 -406.151334)
			(xy 76.719195 -406.161491) (xy 76.711414 -406.180257) (xy 76.697047 -406.19462) (xy 76.678279 -406.202397)
			(xy 76.668122 -406.202896) (xy 75.951842 -406.202896) (xy 75.941677 -406.202403) (xy 75.92289 -406.194638)
			(xy 75.908505 -406.180274) (xy 75.900712 -406.161498) (xy 75.90028 -406.151334) (xy 75.90028 -405.993346)
			(xy 75.899852 -405.984161) (xy 75.893351 -405.966976) (xy 75.88758 -405.959818) (xy 75.865785 -405.934171)
			(xy 75.827834 -405.878585) (xy 75.796799 -405.818861) (xy 75.773124 -405.755856) (xy 75.757151 -405.690472)
			(xy 75.749106 -405.623649) (xy 74.620571 -405.623649) (xy 74.591974 -405.678682) (xy 74.554024 -405.734268)
			(xy 74.532236 -405.75992) (xy 74.526441 -405.767066) (xy 74.519927 -405.784256) (xy 74.519536 -405.793448)
			(xy 74.519536 -406.286716) (xy 74.519953 -406.295902) (xy 74.526464 -406.313086) (xy 74.532236 -406.320244)
			(xy 74.553993 -406.345922) (xy 74.591944 -406.401504) (xy 74.62298 -406.461224) (xy 74.646656 -406.524225)
			(xy 74.662632 -406.589604) (xy 74.670679 -406.656424) (xy 74.670682 -406.723727) (xy 74.670675 -406.723789)
			(xy 77.94872 -406.723789) (xy 77.948723 -406.656363) (xy 77.956802 -406.589422) (xy 77.972842 -406.52393)
			(xy 77.996611 -406.460832) (xy 78.027767 -406.401035) (xy 78.065861 -406.345401) (xy 78.087728 -406.319736)
			(xy 78.093538 -406.3126) (xy 78.100044 -406.295402) (xy 78.100428 -406.286208) (xy 78.100428 -405.793956)
			(xy 78.100033 -405.784767) (xy 78.093508 -405.767584) (xy 78.087728 -405.760428) (xy 78.065859 -405.734766)
			(xy 78.027769 -405.679132) (xy 77.996617 -405.619336) (xy 77.972851 -405.556238) (xy 77.956815 -405.490748)
			(xy 77.948739 -405.423809) (xy 77.94874 -405.356385) (xy 77.956816 -405.289446) (xy 77.972853 -405.223956)
			(xy 77.996619 -405.160859) (xy 78.027772 -405.101063) (xy 78.065863 -405.045429) (xy 78.087728 -405.019764)
			(xy 78.093526 -405.01262) (xy 78.100039 -404.995428) (xy 78.100428 -404.986236) (xy 78.100428 -404.828756)
			(xy 78.10085 -404.818641) (xy 78.108607 -404.799956) (xy 78.122924 -404.785662) (xy 78.14162 -404.777934)
			(xy 78.151736 -404.777448) (xy 78.868016 -404.777448) (xy 78.878119 -404.777971) (xy 78.896788 -404.785704)
			(xy 78.91108 -404.799989) (xy 78.918823 -404.818653) (xy 78.919324 -404.828756) (xy 78.919324 -404.986236)
			(xy 78.919712 -404.995426) (xy 78.92624 -405.01261) (xy 78.932024 -405.019764) (xy 78.953883 -405.045433)
			(xy 78.99197 -405.101067) (xy 79.02312 -405.160863) (xy 79.046883 -405.22396) (xy 79.062918 -405.289448)
			(xy 79.070994 -405.356386) (xy 79.070995 -405.423808) (xy 79.062919 -405.490746) (xy 79.046885 -405.556235)
			(xy 79.023122 -405.619331) (xy 79.020843 -405.623707) (xy 80.148899 -405.623707) (xy 80.148899 -405.556284)
			(xy 80.156975 -405.489345) (xy 80.173011 -405.423856) (xy 80.196775 -405.360759) (xy 80.227925 -405.300963)
			(xy 80.266013 -405.245328) (xy 80.287876 -405.219662) (xy 80.293668 -405.212514) (xy 80.300186 -405.195326)
			(xy 80.300576 -405.186134) (xy 80.300576 -404.693882) (xy 80.30018 -404.684693) (xy 80.293657 -404.667509)
			(xy 80.287876 -404.660354) (xy 80.266034 -404.634671) (xy 80.227947 -404.579038) (xy 80.196796 -404.519244)
			(xy 80.173032 -404.45615) (xy 80.156996 -404.390663) (xy 80.148918 -404.323727) (xy 80.148917 -404.256306)
			(xy 80.15699 -404.189369) (xy 80.173022 -404.123882) (xy 80.196783 -404.060786) (xy 80.22793 -404.00099)
			(xy 80.266014 -403.945356) (xy 80.287876 -403.91969) (xy 80.293657 -403.912533) (xy 80.300182 -403.895352)
			(xy 80.300576 -403.886162) (xy 80.300576 -403.728682) (xy 80.301013 -403.71855) (xy 80.308753 -403.699821)
			(xy 80.323055 -403.685464) (xy 80.341754 -403.677652) (xy 80.351884 -403.67712) (xy 81.068164 -403.67712)
			(xy 81.078318 -403.677552) (xy 81.097074 -403.685339) (xy 81.111399 -403.699733) (xy 81.119096 -403.718526)
			(xy 81.119472 -403.728682) (xy 81.119472 -403.886162) (xy 81.119907 -403.895346) (xy 81.126404 -403.912531)
			(xy 81.132172 -403.91969) (xy 81.154059 -403.945337) (xy 81.192148 -404.000973) (xy 81.2233 -404.060772)
			(xy 81.247064 -404.123871) (xy 81.263099 -404.189363) (xy 81.271173 -404.256304) (xy 81.271171 -404.32373)
			(xy 81.263093 -404.39067) (xy 81.247054 -404.45616) (xy 81.223286 -404.519258) (xy 81.192131 -404.579055)
			(xy 81.154038 -404.634689) (xy 81.132172 -404.660354) (xy 81.126366 -404.667493) (xy 81.119858 -404.684688)
			(xy 81.119472 -404.693882) (xy 81.119472 -405.186134) (xy 81.119872 -405.195322) (xy 81.126393 -405.212506)
			(xy 81.132172 -405.219662) (xy 81.154031 -405.245332) (xy 81.192122 -405.300965) (xy 81.223274 -405.36076)
			(xy 81.24704 -405.423857) (xy 81.263077 -405.489345) (xy 81.271154 -405.556284) (xy 81.271154 -405.623707)
			(xy 81.263078 -405.690646) (xy 81.247043 -405.756135) (xy 81.223278 -405.819232) (xy 81.192126 -405.879027)
			(xy 81.154037 -405.934661) (xy 81.132172 -405.960326) (xy 81.126378 -405.967473) (xy 81.119862 -405.984662)
			(xy 81.119472 -405.993854) (xy 81.119472 -406.151334) (xy 81.119002 -406.161461) (xy 81.111265 -406.180181)
			(xy 81.096974 -406.194536) (xy 81.078289 -406.202356) (xy 81.068164 -406.202896) (xy 80.351884 -406.202896)
			(xy 80.341728 -406.202492) (xy 80.322975 -406.19469) (xy 80.308652 -406.180288) (xy 80.300953 -406.161492)
			(xy 80.300576 -406.151334) (xy 80.300576 -405.993854) (xy 80.300145 -405.984669) (xy 80.293646 -405.967484)
			(xy 80.287876 -405.960326) (xy 80.266007 -405.934665) (xy 80.22792 -405.879029) (xy 80.196771 -405.819232)
			(xy 80.173008 -405.756135) (xy 80.156974 -405.690646) (xy 80.148899 -405.623707) (xy 79.020843 -405.623707)
			(xy 78.991974 -405.679127) (xy 78.953887 -405.734762) (xy 78.932024 -405.760428) (xy 78.926236 -405.767579)
			(xy 78.919715 -405.784765) (xy 78.919324 -405.793956) (xy 78.919324 -406.286208) (xy 78.919725 -406.295396)
			(xy 78.926244 -406.312581) (xy 78.932024 -406.319736) (xy 78.953856 -406.345428) (xy 78.991944 -406.401059)
			(xy 79.023095 -406.460852) (xy 79.046859 -406.523945) (xy 79.062896 -406.589431) (xy 79.070974 -406.656366)
			(xy 79.070977 -406.72373) (xy 82.349039 -406.72373) (xy 82.349042 -406.656422) (xy 82.357089 -406.589598)
			(xy 82.373065 -406.524214) (xy 82.39674 -406.461209) (xy 82.427776 -406.401484) (xy 82.465727 -406.345896)
			(xy 82.487516 -406.320244) (xy 82.493321 -406.313105) (xy 82.49983 -406.29591) (xy 82.500216 -406.286716)
			(xy 82.500216 -405.793448) (xy 82.499779 -405.784264) (xy 82.493284 -405.767079) (xy 82.487516 -405.75992)
			(xy 82.465725 -405.734271) (xy 82.427778 -405.678683) (xy 82.396746 -405.618959) (xy 82.373074 -405.555954)
			(xy 82.357102 -405.490572) (xy 82.349059 -405.423749) (xy 82.349059 -405.356445) (xy 82.357103 -405.289622)
			(xy 82.373076 -405.22424) (xy 82.396748 -405.161235) (xy 82.427781 -405.101511) (xy 82.465729 -405.045924)
			(xy 82.487516 -405.020272) (xy 82.493309 -405.013124) (xy 82.499825 -404.995936) (xy 82.500216 -404.986744)
			(xy 82.500216 -404.828756) (xy 82.500586 -404.818597) (xy 82.508399 -404.799841) (xy 82.522811 -404.785518)
			(xy 82.541617 -404.777823) (xy 82.551778 -404.777448) (xy 83.268058 -404.777448) (xy 83.278183 -404.777961)
			(xy 83.296905 -404.785677) (xy 83.311263 -404.799955) (xy 83.319082 -404.818634) (xy 83.31962 -404.828756)
			(xy 83.31962 -404.986744) (xy 83.320004 -404.995934) (xy 83.326535 -405.013118) (xy 83.33232 -405.020272)
			(xy 83.354105 -405.045927) (xy 83.392057 -405.101512) (xy 83.423092 -405.161235) (xy 83.446767 -405.224239)
			(xy 83.462742 -405.289621) (xy 83.470787 -405.356444) (xy 83.470787 -405.42375) (xy 83.462743 -405.490573)
			(xy 83.446769 -405.555955) (xy 83.423095 -405.61896) (xy 83.420628 -405.623707) (xy 84.54869 -405.623707)
			(xy 84.54869 -405.556284) (xy 84.556766 -405.489346) (xy 84.572801 -405.423857) (xy 84.596564 -405.36076)
			(xy 84.627714 -405.300963) (xy 84.665801 -405.245328) (xy 84.687664 -405.219662) (xy 84.693467 -405.212522)
			(xy 84.699976 -405.195327) (xy 84.700364 -405.186134) (xy 84.700364 -404.693882) (xy 84.699948 -404.684696)
			(xy 84.693437 -404.667512) (xy 84.687664 -404.660354) (xy 84.665823 -404.63467) (xy 84.627736 -404.579038)
			(xy 84.596586 -404.519244) (xy 84.572822 -404.456149) (xy 84.556787 -404.390663) (xy 84.548709 -404.323727)
			(xy 84.548707 -404.256306) (xy 84.556781 -404.18937) (xy 84.572813 -404.123882) (xy 84.596573 -404.060787)
			(xy 84.627719 -404.000991) (xy 84.665803 -403.945356) (xy 84.687664 -403.91969) (xy 84.693455 -403.912541)
			(xy 84.699971 -403.895353) (xy 84.700364 -403.886162) (xy 84.700364 -403.728682) (xy 84.700812 -403.718551)
			(xy 84.70855 -403.699825) (xy 84.722849 -403.685468) (xy 84.741543 -403.677654) (xy 84.751672 -403.67712)
			(xy 85.467952 -403.67712) (xy 85.478105 -403.677561) (xy 85.496861 -403.685345) (xy 85.511186 -403.699736)
			(xy 85.518884 -403.718527) (xy 85.51926 -403.728682) (xy 85.51926 -403.886162) (xy 85.519698 -403.895346)
			(xy 85.526193 -403.91253) (xy 85.53196 -403.91969) (xy 85.553847 -403.945337) (xy 85.591938 -404.000973)
			(xy 85.62309 -404.060771) (xy 85.646854 -404.123871) (xy 85.66289 -404.189362) (xy 85.670964 -404.256303)
			(xy 85.670962 -404.32373) (xy 85.662884 -404.39067) (xy 85.646845 -404.456161) (xy 85.623076 -404.519259)
			(xy 85.591921 -404.579055) (xy 85.553827 -404.634689) (xy 85.53196 -404.660354) (xy 85.526153 -404.667492)
			(xy 85.519646 -404.684688) (xy 85.51926 -404.693882) (xy 85.51926 -405.186134) (xy 85.519663 -405.195322)
			(xy 85.526183 -405.212506) (xy 85.53196 -405.219662) (xy 85.553819 -405.245331) (xy 85.591911 -405.300964)
			(xy 85.623064 -405.36076) (xy 85.64683 -405.423856) (xy 85.662868 -405.489345) (xy 85.670945 -405.556284)
			(xy 85.670945 -405.623707) (xy 85.662869 -405.690646) (xy 85.646833 -405.756135) (xy 85.623068 -405.819232)
			(xy 85.591916 -405.879028) (xy 85.553825 -405.934661) (xy 85.53196 -405.960326) (xy 85.526165 -405.967472)
			(xy 85.51965 -405.984662) (xy 85.51926 -405.993854) (xy 85.51926 -406.151334) (xy 85.518801 -406.161463)
			(xy 85.511062 -406.180185) (xy 85.496768 -406.19454) (xy 85.478079 -406.202358) (xy 85.467952 -406.202896)
			(xy 84.751672 -406.202896) (xy 84.741516 -406.202501) (xy 84.722762 -406.194696) (xy 84.708439 -406.180291)
			(xy 84.700741 -406.161493) (xy 84.700364 -406.151334) (xy 84.700364 -405.993854) (xy 84.699914 -405.984671)
			(xy 84.693426 -405.967487) (xy 84.687664 -405.960326) (xy 84.665795 -405.934665) (xy 84.627709 -405.879029)
			(xy 84.596561 -405.819232) (xy 84.572799 -405.756135) (xy 84.556765 -405.690645) (xy 84.54869 -405.623707)
			(xy 83.420628 -405.623707) (xy 83.39206 -405.678683) (xy 83.354109 -405.734268) (xy 83.33232 -405.75992)
			(xy 83.326535 -405.767073) (xy 83.320013 -405.784258) (xy 83.31962 -405.793448) (xy 83.31962 -406.286716)
			(xy 83.320018 -406.295905) (xy 83.32654 -406.313089) (xy 83.33232 -406.320244) (xy 83.354077 -406.345921)
			(xy 83.39203 -406.401503) (xy 83.423067 -406.461223) (xy 83.446743 -406.524224) (xy 83.46272 -406.589604)
			(xy 83.470767 -406.656424) (xy 83.47077 -406.723728) (xy 83.470763 -406.723789) (xy 86.748808 -406.723789)
			(xy 86.748811 -406.656363) (xy 86.75689 -406.589422) (xy 86.772929 -406.523931) (xy 86.796697 -406.460833)
			(xy 86.827852 -406.401036) (xy 86.865946 -406.345401) (xy 86.887812 -406.319736) (xy 86.89362 -406.312599)
			(xy 86.900127 -406.295402) (xy 86.900512 -406.286208) (xy 86.900512 -405.793956) (xy 86.90012 -405.784767)
			(xy 86.893594 -405.767583) (xy 86.887812 -405.760428) (xy 86.865944 -405.734766) (xy 86.827854 -405.679131)
			(xy 86.796703 -405.619335) (xy 86.772939 -405.556238) (xy 86.756903 -405.490748) (xy 86.748827 -405.423809)
			(xy 86.748828 -405.356385) (xy 86.756904 -405.289446) (xy 86.77294 -405.223957) (xy 86.796706 -405.16086)
			(xy 86.827857 -405.101063) (xy 86.865947 -405.045429) (xy 86.887812 -405.019764) (xy 86.893608 -405.012618)
			(xy 86.900123 -404.995428) (xy 86.900512 -404.986236) (xy 86.900512 -404.828756) (xy 86.900949 -404.818643)
			(xy 86.908704 -404.799961) (xy 86.923015 -404.785668) (xy 86.941706 -404.777937) (xy 86.95182 -404.777448)
			(xy 87.6681 -404.777448) (xy 87.678202 -404.777984) (xy 87.696871 -404.785712) (xy 87.711163 -404.799993)
			(xy 87.718907 -404.818654) (xy 87.719408 -404.828756) (xy 87.719408 -404.986236) (xy 87.719799 -404.995425)
			(xy 87.726326 -405.01261) (xy 87.732108 -405.019764) (xy 87.753968 -405.045433) (xy 87.792056 -405.101067)
			(xy 87.823206 -405.160863) (xy 87.846971 -405.223959) (xy 87.863006 -405.289448) (xy 87.871082 -405.356385)
			(xy 87.871082 -405.423809) (xy 87.863007 -405.490746) (xy 87.846972 -405.556235) (xy 87.823209 -405.619332)
			(xy 87.792059 -405.679128) (xy 87.753971 -405.734763) (xy 87.732108 -405.760428) (xy 87.726318 -405.767578)
			(xy 87.719799 -405.784765) (xy 87.719408 -405.793956) (xy 87.719408 -406.286208) (xy 87.719813 -406.295396)
			(xy 87.72633 -406.31258) (xy 87.732108 -406.319736) (xy 87.75394 -406.345427) (xy 87.792029 -406.401058)
			(xy 87.823181 -406.460851) (xy 87.846947 -406.523944) (xy 87.862984 -406.58943) (xy 87.871062 -406.656365)
			(xy 87.871065 -406.723729) (xy 91.149127 -406.723729) (xy 91.14913 -406.656423) (xy 91.157177 -406.589598)
			(xy 91.173152 -406.524215) (xy 91.196827 -406.461209) (xy 91.227861 -406.401484) (xy 91.265812 -406.345897)
			(xy 91.2876 -406.320244) (xy 91.293403 -406.313103) (xy 91.299914 -406.295909) (xy 91.3003 -406.286716)
			(xy 91.3003 -405.793448) (xy 91.299867 -405.784263) (xy 91.293369 -405.767079) (xy 91.2876 -405.75992)
			(xy 91.26581 -405.734271) (xy 91.227863 -405.678683) (xy 91.196832 -405.618958) (xy 91.173162 -405.555954)
			(xy 91.15719 -405.490572) (xy 91.149147 -405.423749) (xy 91.149147 -405.356445) (xy 91.157191 -405.289622)
			(xy 91.173163 -405.224241) (xy 91.196835 -405.161236) (xy 91.227866 -405.101512) (xy 91.265813 -405.045925)
			(xy 91.2876 -405.020272) (xy 91.293391 -405.013123) (xy 91.299909 -404.995935) (xy 91.3003 -404.986744)
			(xy 91.3003 -404.828756) (xy 91.300686 -404.818599) (xy 91.308496 -404.799846) (xy 91.322903 -404.785524)
			(xy 91.341703 -404.777826) (xy 91.351862 -404.777448) (xy 92.068142 -404.777448) (xy 92.078272 -404.777892)
			(xy 92.096996 -404.785635) (xy 92.111351 -404.799934) (xy 92.119167 -404.818628) (xy 92.119704 -404.828756)
			(xy 92.119704 -404.986744) (xy 92.120092 -404.995934) (xy 92.126621 -405.013118) (xy 92.132404 -405.020272)
			(xy 92.154186 -405.045928) (xy 92.192133 -405.101515) (xy 92.223164 -405.161238) (xy 92.246835 -405.224242)
			(xy 92.262807 -405.289624) (xy 92.270851 -405.356445) (xy 92.270851 -405.423749) (xy 92.262808 -405.490571)
			(xy 92.246837 -405.555952) (xy 92.223166 -405.618956) (xy 92.220728 -405.623648) (xy 115.349248 -405.623648)
			(xy 115.349249 -405.556343) (xy 115.357293 -405.489521) (xy 115.373266 -405.424139) (xy 115.396938 -405.361134)
			(xy 115.42797 -405.30141) (xy 115.465917 -405.245823) (xy 115.487704 -405.22017) (xy 115.493496 -405.213022)
			(xy 115.500013 -405.195834) (xy 115.500404 -405.186642) (xy 115.500404 -404.693374) (xy 115.500006 -404.684186)
			(xy 115.493484 -404.667001) (xy 115.487704 -404.659846) (xy 115.465939 -404.634176) (xy 115.427992 -404.578591)
			(xy 115.396959 -404.51887) (xy 115.373287 -404.455868) (xy 115.357314 -404.390488) (xy 115.349268 -404.323668)
			(xy 115.349266 -404.256365) (xy 115.357308 -404.189545) (xy 115.373277 -404.124164) (xy 115.396946 -404.061161)
			(xy 115.427975 -404.001437) (xy 115.465919 -403.945851) (xy 115.487704 -403.920198) (xy 115.493484 -403.913041)
			(xy 115.500009 -403.89586) (xy 115.500404 -403.88667) (xy 115.500404 -403.728682) (xy 115.500918 -403.718527)
			(xy 115.508692 -403.699764) (xy 115.523051 -403.685401) (xy 115.541811 -403.677621) (xy 115.551966 -403.67712)
			(xy 116.268246 -403.67712) (xy 116.278404 -403.677595) (xy 116.297171 -403.685382) (xy 116.311534 -403.699752)
			(xy 116.31931 -403.718523) (xy 116.319808 -403.728682) (xy 116.319808 -403.88667) (xy 116.320231 -403.895856)
			(xy 116.326735 -403.91304) (xy 116.332508 -403.920198) (xy 116.354319 -403.945832) (xy 116.392271 -404.00142)
			(xy 116.423306 -404.061145) (xy 116.44698 -404.124152) (xy 116.462953 -404.189537) (xy 116.470996 -404.256363)
			(xy 116.470994 -404.32367) (xy 116.462947 -404.390495) (xy 116.44697 -404.455879) (xy 116.423292 -404.518885)
			(xy 116.392254 -404.578609) (xy 116.354299 -404.634195) (xy 116.332508 -404.659846) (xy 116.32671 -404.66699)
			(xy 116.320196 -404.684181) (xy 116.319808 -404.693374) (xy 116.319808 -405.186642) (xy 116.320196 -405.195832)
			(xy 116.326725 -405.213016) (xy 116.332508 -405.22017) (xy 116.354291 -405.245826) (xy 116.392244 -405.301411)
			(xy 116.42328 -405.361133) (xy 116.446956 -405.424137) (xy 116.462931 -405.48952) (xy 116.470976 -405.556343)
			(xy 116.470977 -405.623648) (xy 116.462932 -405.690471) (xy 116.446958 -405.755854) (xy 116.423284 -405.818858)
			(xy 116.392249 -405.878581) (xy 116.354297 -405.934167) (xy 116.332508 -405.959818) (xy 116.326722 -405.966971)
			(xy 116.320201 -405.984155) (xy 116.319808 -405.993346) (xy 116.319808 -406.151334) (xy 116.319296 -406.161488)
			(xy 116.311519 -406.180249) (xy 116.297159 -406.194612) (xy 116.2784 -406.202393) (xy 116.268246 -406.202896)
			(xy 115.551966 -406.202896) (xy 115.54181 -406.202395) (xy 115.523047 -406.194616) (xy 115.508684 -406.180253)
			(xy 115.500905 -406.16149) (xy 115.500404 -406.151334) (xy 115.500404 -405.993346) (xy 115.499971 -405.984161)
			(xy 115.493473 -405.966977) (xy 115.487704 -405.959818) (xy 115.465911 -405.93417) (xy 115.427965 -405.878582)
			(xy 115.396934 -405.818858) (xy 115.373263 -405.755853) (xy 115.357292 -405.69047) (xy 115.349248 -405.623648)
			(xy 92.220728 -405.623648) (xy 92.192136 -405.67868) (xy 92.15419 -405.734267) (xy 92.132404 -405.75992)
			(xy 92.126617 -405.767072) (xy 92.120096 -405.784257) (xy 92.119704 -405.793448) (xy 92.119704 -406.286716)
			(xy 92.120106 -406.295904) (xy 92.126625 -406.313088) (xy 92.132404 -406.320244) (xy 92.154159 -406.345923)
			(xy 92.192106 -406.401506) (xy 92.223138 -406.461227) (xy 92.246811 -406.524228) (xy 92.262785 -406.589606)
			(xy 92.270831 -406.656425) (xy 92.270834 -406.723727) (xy 92.270826 -406.72379) (xy 117.548838 -406.72379)
			(xy 117.548841 -406.656362) (xy 117.55692 -406.589421) (xy 117.572961 -406.523929) (xy 117.596731 -406.460831)
			(xy 117.627888 -406.401034) (xy 117.665984 -406.3454) (xy 117.687852 -406.319736) (xy 117.693665 -406.312602)
			(xy 117.700168 -406.295403) (xy 117.700552 -406.286208) (xy 117.700552 -405.793956) (xy 117.700151 -405.784768)
			(xy 117.69363 -405.767585) (xy 117.687852 -405.760428) (xy 117.665982 -405.734767) (xy 117.62789 -405.679133)
			(xy 117.596737 -405.619337) (xy 117.572971 -405.556239) (xy 117.556934 -405.490749) (xy 117.548857 -405.42381)
			(xy 117.548858 -405.356384) (xy 117.556935 -405.289445) (xy 117.572972 -405.223955) (xy 117.596739 -405.160858)
			(xy 117.627893 -405.101062) (xy 117.665986 -405.045428) (xy 117.687852 -405.019764) (xy 117.693653 -405.012622)
			(xy 117.700164 -404.995429) (xy 117.700552 -404.986236) (xy 117.700552 -404.828756) (xy 117.701048 -404.81865)
			(xy 117.708791 -404.79998) (xy 117.723084 -404.785689) (xy 117.741754 -404.777947) (xy 117.75186 -404.777448)
			(xy 118.46814 -404.777448) (xy 118.478245 -404.777951) (xy 118.496914 -404.785692) (xy 118.511206 -404.799983)
			(xy 118.518948 -404.818651) (xy 118.519448 -404.828756) (xy 118.519448 -404.986236) (xy 118.519853 -404.995424)
			(xy 118.526372 -405.012607) (xy 118.532148 -405.019764) (xy 118.55401 -405.045432) (xy 118.592102 -405.101065)
			(xy 118.623256 -405.16086) (xy 118.647023 -405.223957) (xy 118.66306 -405.289446) (xy 118.671137 -405.356385)
			(xy 118.671137 -405.423809) (xy 118.663061 -405.490748) (xy 118.647024 -405.556238) (xy 118.623258 -405.619335)
			(xy 118.62098 -405.623708) (xy 119.749017 -405.623708) (xy 119.749017 -405.556283) (xy 119.757094 -405.489345)
			(xy 119.77313 -405.423855) (xy 119.796895 -405.360758) (xy 119.828046 -405.300962) (xy 119.866136 -405.245327)
			(xy 119.888 -405.219662) (xy 119.893795 -405.212516) (xy 119.900311 -405.195326) (xy 119.9007 -405.186134)
			(xy 119.9007 -404.693882) (xy 119.900298 -404.684694) (xy 119.893779 -404.66751) (xy 119.888 -404.660354)
			(xy 119.866158 -404.634671) (xy 119.828068 -404.579039) (xy 119.796917 -404.519245) (xy 119.773151 -404.456151)
			(xy 119.757114 -404.390664) (xy 119.749037 -404.323727) (xy 119.749035 -404.256306) (xy 119.757108 -404.189369)
			(xy 119.773141 -404.123881) (xy 119.796903 -404.060785) (xy 119.828051 -404.000989) (xy 119.866137 -403.945355)
			(xy 119.888 -403.91969) (xy 119.893783 -403.912535) (xy 119.900306 -403.895352) (xy 119.9007 -403.886162)
			(xy 119.9007 -403.728682) (xy 119.90121 -403.718559) (xy 119.908937 -403.699845) (xy 119.923215 -403.685491)
			(xy 119.941888 -403.677665) (xy 119.952008 -403.67712) (xy 120.668288 -403.67712) (xy 120.678412 -403.677526)
			(xy 120.697119 -403.685274) (xy 120.711435 -403.699594) (xy 120.719177 -403.718304) (xy 120.719596 -403.728428)
			(xy 120.719596 -403.886162) (xy 120.720025 -403.895347) (xy 120.726526 -403.912532) (xy 120.732296 -403.91969)
			(xy 120.754182 -403.945337) (xy 120.79227 -404.000974) (xy 120.82342 -404.060773) (xy 120.847183 -404.123872)
			(xy 120.863217 -404.189363) (xy 120.871291 -404.256304) (xy 120.871289 -404.323729) (xy 120.863211 -404.390669)
			(xy 120.847173 -404.456159) (xy 120.823407 -404.519257) (xy 120.792253 -404.579054) (xy 120.754161 -404.634689)
			(xy 120.732296 -404.660354) (xy 120.726494 -404.667495) (xy 120.719983 -404.684689) (xy 120.719596 -404.693882)
			(xy 120.719596 -405.186134) (xy 120.719991 -405.195323) (xy 120.726515 -405.212507) (xy 120.732296 -405.219662)
			(xy 120.754154 -405.245332) (xy 120.792243 -405.300966) (xy 120.823395 -405.360761) (xy 120.847159 -405.423858)
			(xy 120.863195 -405.489346) (xy 120.871272 -405.556284) (xy 120.871272 -405.623707) (xy 120.863197 -405.690645)
			(xy 120.847162 -405.756134) (xy 120.823398 -405.81923) (xy 120.792248 -405.879026) (xy 120.75416 -405.934661)
			(xy 120.732296 -405.960326) (xy 120.726505 -405.967475) (xy 120.719987 -405.984663) (xy 120.719596 -405.993854)
			(xy 120.719596 -406.151334) (xy 120.719102 -406.161458) (xy 120.71137 -406.180174) (xy 120.697087 -406.194527)
			(xy 120.67841 -406.202352) (xy 120.668288 -406.202896) (xy 119.952008 -406.202896) (xy 119.941886 -406.202477)
			(xy 119.923181 -406.194731) (xy 119.908867 -406.180415) (xy 119.901122 -406.16171) (xy 119.9007 -406.151588)
			(xy 119.9007 -405.993854) (xy 119.900264 -405.98467) (xy 119.893768 -405.967485) (xy 119.888 -405.960326)
			(xy 119.86613 -405.934666) (xy 119.828042 -405.87903) (xy 119.796891 -405.819234) (xy 119.773127 -405.756136)
			(xy 119.757092 -405.690646) (xy 119.749017 -405.623708) (xy 118.62098 -405.623708) (xy 118.592105 -405.67913)
			(xy 118.554014 -405.734764) (xy 118.532148 -405.760428) (xy 118.526351 -405.767572) (xy 118.519838 -405.784764)
			(xy 118.519448 -405.793956) (xy 118.519448 -406.286208) (xy 118.519866 -406.295394) (xy 118.526375 -406.312578)
			(xy 118.532148 -406.319736) (xy 118.553982 -406.345426) (xy 118.592075 -406.401056) (xy 118.62323 -406.460848)
			(xy 118.646999 -406.523942) (xy 118.663038 -406.589429) (xy 118.671117 -406.656365) (xy 118.67112 -406.72373)
			(xy 121.949157 -406.72373) (xy 121.94916 -406.656422) (xy 121.957208 -406.589597) (xy 121.973184 -406.524213)
			(xy 121.99686 -406.461207) (xy 122.027897 -406.401483) (xy 122.06585 -406.345896) (xy 122.08764 -406.320244)
			(xy 122.093448 -406.313107) (xy 122.099955 -406.29591) (xy 122.10034 -406.286716) (xy 122.10034 -405.793448)
			(xy 122.099898 -405.784264) (xy 122.093405 -405.76708) (xy 122.08764 -405.75992) (xy 122.065848 -405.734271)
			(xy 122.027899 -405.678684) (xy 121.996866 -405.61896) (xy 121.973194 -405.555955) (xy 121.957221 -405.490573)
			(xy 121.949177 -405.42375) (xy 121.949177 -405.356444) (xy 121.957222 -405.289621) (xy 121.973195 -405.224239)
			(xy 121.996869 -405.161234) (xy 122.027902 -405.101511) (xy 122.065852 -405.045924) (xy 122.08764 -405.020272)
			(xy 122.093436 -405.013127) (xy 122.09995 -404.995936) (xy 122.10034 -404.986744) (xy 122.10034 -404.828756)
			(xy 122.100681 -404.818626) (xy 122.108451 -404.799913) (xy 122.122791 -404.785599) (xy 122.141517 -404.777863)
			(xy 122.151648 -404.777448) (xy 122.868182 -404.777448) (xy 122.878309 -404.777941) (xy 122.897031 -404.785665)
			(xy 122.911388 -404.799949) (xy 122.919207 -404.818632) (xy 122.919744 -404.828756) (xy 122.919744 -404.986744)
			(xy 122.920145 -404.995932) (xy 122.926666 -405.013116) (xy 122.932444 -405.020272) (xy 122.954228 -405.045927)
			(xy 122.992178 -405.101513) (xy 123.023213 -405.161236) (xy 123.046886 -405.22424) (xy 123.06286 -405.289622)
			(xy 123.070905 -405.356444) (xy 123.070905 -405.42375) (xy 123.062861 -405.490572) (xy 123.046888 -405.555954)
			(xy 123.023215 -405.618959) (xy 123.020778 -405.623649) (xy 124.149312 -405.623649) (xy 124.149313 -405.556342)
			(xy 124.157358 -405.489518) (xy 124.173333 -405.424135) (xy 124.197009 -405.36113) (xy 124.228046 -405.301407)
			(xy 124.265998 -405.245822) (xy 124.287788 -405.22017) (xy 124.293578 -405.21302) (xy 124.300097 -405.195833)
			(xy 124.300488 -405.186642) (xy 124.300488 -404.693374) (xy 124.300093 -404.684185) (xy 124.293569 -404.667001)
			(xy 124.287788 -404.659846) (xy 124.26602 -404.634177) (xy 124.228068 -404.578594) (xy 124.197031 -404.518873)
			(xy 124.173355 -404.455871) (xy 124.157379 -404.39049) (xy 124.149332 -404.323669) (xy 124.14933 -404.256364)
			(xy 124.157373 -404.189542) (xy 124.173345 -404.124161) (xy 124.197017 -404.061157) (xy 124.228051 -404.001435)
			(xy 124.266 -403.945849) (xy 124.287788 -403.920198) (xy 124.293567 -403.91304) (xy 124.300092 -403.895859)
			(xy 124.300488 -403.88667) (xy 124.300488 -403.728682) (xy 124.30085 -403.718503) (xy 124.308651 -403.699698)
			(xy 124.323056 -403.685313) (xy 124.34187 -403.677537) (xy 124.35205 -403.67712) (xy 125.06833 -403.67712)
			(xy 125.078487 -403.677608) (xy 125.097254 -403.685389) (xy 125.111617 -403.699756) (xy 125.119394 -403.718524)
			(xy 125.119892 -403.728682) (xy 125.119892 -403.88667) (xy 125.120318 -403.895855) (xy 125.126821 -403.91304)
			(xy 125.132592 -403.920198) (xy 125.1544 -403.945833) (xy 125.192347 -404.001422) (xy 125.223377 -404.061149)
			(xy 125.247047 -404.124155) (xy 125.263018 -404.189539) (xy 125.27106 -404.256363) (xy 125.271058 -404.32367)
			(xy 125.263012 -404.390493) (xy 125.247038 -404.455876) (xy 125.223364 -404.518882) (xy 125.19233 -404.578606)
			(xy 125.15438 -404.634193) (xy 125.132592 -404.659846) (xy 125.126792 -404.666989) (xy 125.12028 -404.684181)
			(xy 125.119892 -404.693374) (xy 125.119892 -405.186642) (xy 125.120284 -405.195831) (xy 125.12681 -405.213015)
			(xy 125.132592 -405.22017) (xy 125.154373 -405.245827) (xy 125.19232 -405.301414) (xy 125.223352 -405.361137)
			(xy 125.247023 -405.424141) (xy 125.262996 -405.489522) (xy 125.27104 -405.556343) (xy 125.271041 -405.623647)
			(xy 125.262998 -405.690469) (xy 125.247026 -405.755851) (xy 125.223355 -405.818855) (xy 125.192325 -405.878578)
			(xy 125.154378 -405.934165) (xy 125.132592 -405.959818) (xy 125.126804 -405.96697) (xy 125.120285 -405.984155)
			(xy 125.119892 -405.993346) (xy 125.119892 -406.151334) (xy 125.119395 -406.16149) (xy 125.111615 -406.180254)
			(xy 125.097251 -406.194617) (xy 125.078486 -406.202396) (xy 125.06833 -406.202896) (xy 124.35205 -406.202896)
			(xy 124.341886 -406.202396) (xy 124.323099 -406.194634) (xy 124.308713 -406.180272) (xy 124.30092 -406.161497)
			(xy 124.300488 -406.151334) (xy 124.300488 -405.993346) (xy 124.300059 -405.984161) (xy 124.293559 -405.966976)
			(xy 124.287788 -405.959818) (xy 124.265993 -405.934171) (xy 124.228041 -405.878585) (xy 124.197005 -405.818861)
			(xy 124.173331 -405.755856) (xy 124.157357 -405.690473) (xy 124.149312 -405.623649) (xy 123.020778 -405.623649)
			(xy 122.992181 -405.678682) (xy 122.954232 -405.734268) (xy 122.932444 -405.75992) (xy 122.92665 -405.767066)
			(xy 122.920135 -405.784256) (xy 122.919744 -405.793448) (xy 122.919744 -406.286716) (xy 122.920159 -406.295902)
			(xy 122.926671 -406.313086) (xy 122.932444 -406.320244) (xy 122.954201 -406.345922) (xy 122.992152 -406.401504)
			(xy 123.023187 -406.461224) (xy 123.046862 -406.524225) (xy 123.062838 -406.589605) (xy 123.070885 -406.656425)
			(xy 123.070888 -406.723727) (xy 123.070881 -406.723789) (xy 126.348926 -406.723789) (xy 126.348929 -406.656363)
			(xy 126.357008 -406.589421) (xy 126.373048 -406.52393) (xy 126.396818 -406.460832) (xy 126.427974 -406.401035)
			(xy 126.466069 -406.345401) (xy 126.487936 -406.319736) (xy 126.493747 -406.312601) (xy 126.500252 -406.295403)
			(xy 126.500636 -406.286208) (xy 126.500636 -405.793956) (xy 126.500239 -405.784768) (xy 126.493715 -405.767584)
			(xy 126.487936 -405.760428) (xy 126.466067 -405.734767) (xy 126.427976 -405.679132) (xy 126.396823 -405.619336)
			(xy 126.373058 -405.556239) (xy 126.357022 -405.490749) (xy 126.348945 -405.423809) (xy 126.348946 -405.356385)
			(xy 126.357023 -405.289445) (xy 126.37306 -405.223956) (xy 126.396826 -405.160859) (xy 126.427979 -405.101062)
			(xy 126.466071 -405.045429) (xy 126.487936 -405.019764) (xy 126.493735 -405.012621) (xy 126.500247 -404.995429)
			(xy 126.500636 -404.986236) (xy 126.500636 -404.828756) (xy 126.50105 -404.81864) (xy 126.508809 -404.799954)
			(xy 126.523128 -404.785659) (xy 126.541827 -404.777933) (xy 126.551944 -404.777448) (xy 127.268224 -404.777448)
			(xy 127.278328 -404.777964) (xy 127.296997 -404.7857) (xy 127.311289 -404.799986) (xy 127.319032 -404.818652)
			(xy 127.319532 -404.828756) (xy 127.319532 -404.986236) (xy 127.31994 -404.995423) (xy 127.326457 -405.012607)
			(xy 127.332232 -405.019764) (xy 127.354091 -405.045433) (xy 127.392178 -405.101068) (xy 127.423327 -405.160864)
			(xy 127.44709 -405.22396) (xy 127.463125 -405.289448) (xy 127.4712 -405.356386) (xy 127.471201 -405.423808)
			(xy 127.463126 -405.490746) (xy 127.447092 -405.556234) (xy 127.423329 -405.619331) (xy 127.42108 -405.623649)
			(xy 128.549103 -405.623649) (xy 128.549104 -405.556342) (xy 128.557149 -405.489519) (xy 128.573124 -405.424136)
			(xy 128.596799 -405.361131) (xy 128.627835 -405.301407) (xy 128.665787 -405.245822) (xy 128.687576 -405.22017)
			(xy 128.693365 -405.213019) (xy 128.699885 -405.195833) (xy 128.700276 -405.186642) (xy 128.700276 -404.693374)
			(xy 128.699884 -404.684185) (xy 128.693358 -404.667) (xy 128.687576 -404.659846) (xy 128.665809 -404.634177)
			(xy 128.627857 -404.578593) (xy 128.596821 -404.518873) (xy 128.573145 -404.45587) (xy 128.557169 -404.39049)
			(xy 128.549123 -404.323669) (xy 128.549121 -404.256365) (xy 128.557164 -404.189543) (xy 128.573135 -404.124161)
			(xy 128.596807 -404.061158) (xy 128.62784 -404.001435) (xy 128.665789 -403.94585) (xy 128.687576 -403.920198)
			(xy 128.693353 -403.913039) (xy 128.69988 -403.895859) (xy 128.700276 -403.88667) (xy 128.700276 -403.728682)
			(xy 128.70065 -403.718505) (xy 128.708448 -403.699702) (xy 128.722849 -403.685317) (xy 128.74166 -403.677539)
			(xy 128.751838 -403.67712) (xy 129.468118 -403.67712) (xy 129.478275 -403.677618) (xy 129.497041 -403.685395)
			(xy 129.511405 -403.699759) (xy 129.519182 -403.718525) (xy 129.51968 -403.728682) (xy 129.51968 -403.88667)
			(xy 129.520109 -403.895855) (xy 129.52661 -403.913039) (xy 129.53238 -403.920198) (xy 129.554189 -403.945833)
			(xy 129.592136 -404.001422) (xy 129.623167 -404.061148) (xy 129.646838 -404.124155) (xy 129.662809 -404.189539)
			(xy 129.670851 -404.256363) (xy 129.670849 -404.32367) (xy 129.662803 -404.390494) (xy 129.646828 -404.455877)
			(xy 129.623154 -404.518882) (xy 129.592119 -404.578606) (xy 129.554169 -404.634194) (xy 129.53238 -404.659846)
			(xy 129.526579 -404.666988) (xy 129.520068 -404.684181) (xy 129.51968 -404.693374) (xy 129.51968 -405.186642)
			(xy 129.520074 -405.195831) (xy 129.5266 -405.213015) (xy 129.53238 -405.22017) (xy 129.554161 -405.245827)
			(xy 129.592109 -405.301413) (xy 129.623142 -405.361136) (xy 129.646814 -405.42414) (xy 129.662787 -405.489522)
			(xy 129.670831 -405.556343) (xy 129.670832 -405.623648) (xy 129.662788 -405.690469) (xy 129.646817 -405.755851)
			(xy 129.623145 -405.818855) (xy 129.592114 -405.878579) (xy 129.554167 -405.934166) (xy 129.53238 -405.959818)
			(xy 129.526591 -405.966968) (xy 129.520072 -405.984155) (xy 129.51968 -405.993346) (xy 129.51968 -406.151334)
			(xy 129.519195 -406.161492) (xy 129.511413 -406.180258) (xy 129.497045 -406.194622) (xy 129.478276 -406.202398)
			(xy 129.468118 -406.202896) (xy 128.751838 -406.202896) (xy 128.741673 -406.202406) (xy 128.722886 -406.19464)
			(xy 128.708501 -406.180275) (xy 128.700708 -406.161498) (xy 128.700276 -406.151334) (xy 128.700276 -405.993346)
			(xy 128.699849 -405.984161) (xy 128.693347 -405.966976) (xy 128.687576 -405.959818) (xy 128.665781 -405.934171)
			(xy 128.62783 -405.878585) (xy 128.596795 -405.818861) (xy 128.573121 -405.755856) (xy 128.557148 -405.690472)
			(xy 128.549103 -405.623649) (xy 127.42108 -405.623649) (xy 127.392181 -405.679127) (xy 127.354095 -405.734762)
			(xy 127.332232 -405.760428) (xy 127.326433 -405.767571) (xy 127.319922 -405.784763) (xy 127.319532 -405.793956)
			(xy 127.319532 -406.286208) (xy 127.319954 -406.295394) (xy 127.326461 -406.312577) (xy 127.332232 -406.319736)
			(xy 127.354063 -406.345428) (xy 127.392151 -406.401059) (xy 127.423301 -406.460852) (xy 127.447066 -406.523945)
			(xy 127.463103 -406.589431) (xy 127.471181 -406.656366) (xy 127.471183 -406.72373) (xy 130.749245 -406.72373)
			(xy 130.749248 -406.656422) (xy 130.757295 -406.589598) (xy 130.773271 -406.524214) (xy 130.796947 -406.461208)
			(xy 130.827983 -406.401484) (xy 130.865935 -406.345896) (xy 130.887724 -406.320244) (xy 130.89353 -406.313105)
			(xy 130.900038 -406.29591) (xy 130.900424 -406.286716) (xy 130.900424 -405.793448) (xy 130.899985 -405.784264)
			(xy 130.893491 -405.76708) (xy 130.887724 -405.75992) (xy 130.865933 -405.734271) (xy 130.827985 -405.678684)
			(xy 130.796953 -405.61896) (xy 130.773281 -405.555955) (xy 130.757309 -405.490572) (xy 130.749265 -405.42375)
			(xy 130.749265 -405.356444) (xy 130.75731 -405.289622) (xy 130.773283 -405.22424) (xy 130.796955 -405.161235)
			(xy 130.827988 -405.101511) (xy 130.865936 -405.045924) (xy 130.887724 -405.020272) (xy 130.893518 -405.013125)
			(xy 130.900033 -404.995936) (xy 130.900424 -404.986744) (xy 130.900424 -404.828756) (xy 130.900786 -404.818596)
			(xy 130.908601 -404.799838) (xy 130.923016 -404.785515) (xy 130.941823 -404.777822) (xy 130.951986 -404.777448)
			(xy 131.668266 -404.777448) (xy 131.678391 -404.777955) (xy 131.697113 -404.785673) (xy 131.711471 -404.799953)
			(xy 131.71929 -404.818633) (xy 131.719828 -404.828756) (xy 131.719828 -404.986744) (xy 131.720211 -404.995934)
			(xy 131.726743 -405.013119) (xy 131.732528 -405.020272) (xy 131.754313 -405.045927) (xy 131.792264 -405.101512)
			(xy 131.823299 -405.161235) (xy 131.846974 -405.224239) (xy 131.862948 -405.289622) (xy 131.870993 -405.356444)
			(xy 131.870993 -405.42375) (xy 131.862949 -405.490573) (xy 131.846975 -405.555955) (xy 131.823302 -405.618959)
			(xy 131.792267 -405.678683) (xy 131.754316 -405.734268) (xy 131.732528 -405.75992) (xy 131.726732 -405.767065)
			(xy 131.720219 -405.784256) (xy 131.719828 -405.793448) (xy 131.719828 -406.286716) (xy 131.720224 -406.295905)
			(xy 131.726747 -406.313089) (xy 131.732528 -406.320244) (xy 131.754285 -406.345922) (xy 131.792237 -406.401504)
			(xy 131.823274 -406.461223) (xy 131.84695 -406.524225) (xy 131.862926 -406.589604) (xy 131.870973 -406.656424)
			(xy 131.870976 -406.723728) (xy 131.862934 -406.790548) (xy 131.846964 -406.855929) (xy 131.823293 -406.918933)
			(xy 131.792262 -406.978655) (xy 131.754315 -407.03424) (xy 131.732528 -407.059892) (xy 131.726744 -407.067045)
			(xy 131.720224 -407.08423) (xy 131.719828 -407.09342) (xy 131.719828 -407.251408) (xy 131.719385 -407.261559)
			(xy 131.711592 -407.280306) (xy 131.697203 -407.294628) (xy 131.678419 -407.302333) (xy 131.668266 -407.302716)
			(xy 130.951986 -407.302716) (xy 130.941853 -407.302283) (xy 130.923123 -407.294543) (xy 130.908766 -407.28024)
			(xy 130.900955 -407.261539) (xy 130.900424 -407.251408) (xy 130.900424 -407.09342) (xy 130.899999 -407.084235)
			(xy 130.893495 -407.06705) (xy 130.887724 -407.059892) (xy 130.865905 -407.034266) (xy 130.827958 -406.978675)
			(xy 130.796927 -406.918948) (xy 130.773257 -406.85594) (xy 130.757287 -406.790555) (xy 130.749245 -406.72373)
			(xy 127.471183 -406.72373) (xy 127.471183 -406.723786) (xy 127.463111 -406.790722) (xy 127.44708 -406.856209)
			(xy 127.423321 -406.919304) (xy 127.392176 -406.9791) (xy 127.354093 -407.034734) (xy 127.332232 -407.0604)
			(xy 127.326445 -407.067551) (xy 127.319926 -407.084737) (xy 127.319532 -407.093928) (xy 127.319532 -407.251408)
			(xy 127.319022 -407.261513) (xy 127.311288 -407.280185) (xy 127.296999 -407.294479) (xy 127.278329 -407.302219)
			(xy 127.268224 -407.302716) (xy 126.551944 -407.302716) (xy 126.541826 -407.302248) (xy 126.523127 -407.294518)
			(xy 126.508812 -407.280217) (xy 126.501062 -407.261525) (xy 126.500636 -407.251408) (xy 126.500636 -407.093928)
			(xy 126.500204 -407.084743) (xy 126.493705 -407.067559) (xy 126.487936 -407.0604) (xy 126.466039 -407.034761)
			(xy 126.427949 -406.979124) (xy 126.396798 -406.919324) (xy 126.373034 -406.856224) (xy 126.357 -406.790731)
			(xy 126.348926 -406.723789) (xy 123.070881 -406.723789) (xy 123.062847 -406.790548) (xy 123.046877 -406.855929)
			(xy 123.023207 -406.918932) (xy 122.992176 -406.978654) (xy 122.95423 -407.03424) (xy 122.932444 -407.059892)
			(xy 122.926661 -407.067047) (xy 122.92014 -407.08423) (xy 122.919744 -407.09342) (xy 122.919744 -407.251408)
			(xy 122.919222 -407.261512) (xy 122.91149 -407.280182) (xy 122.897205 -407.294475) (xy 122.878539 -407.302217)
			(xy 122.868436 -407.302716) (xy 122.151902 -407.302716) (xy 122.14177 -407.30227) (xy 122.123041 -407.294535)
			(xy 122.108683 -407.280236) (xy 122.100871 -407.261538) (xy 122.10034 -407.251408) (xy 122.10034 -407.09342)
			(xy 122.099911 -407.084235) (xy 122.09341 -407.067051) (xy 122.08764 -407.059892) (xy 122.065821 -407.034266)
			(xy 122.027873 -406.978676) (xy 121.996841 -406.918949) (xy 121.97317 -406.855941) (xy 121.957199 -406.790555)
			(xy 121.949157 -406.72373) (xy 118.67112 -406.72373) (xy 118.67112 -406.723787) (xy 118.663047 -406.790724)
			(xy 118.647013 -406.856212) (xy 118.62325 -406.919308) (xy 118.5921 -406.979103) (xy 118.554012 -407.034736)
			(xy 118.532148 -407.0604) (xy 118.526362 -407.067553) (xy 118.519843 -407.084738) (xy 118.519448 -407.093928)
			(xy 118.519448 -407.251408) (xy 118.518922 -407.261511) (xy 118.511191 -407.28018) (xy 118.496907 -407.294473)
			(xy 118.478243 -407.302216) (xy 118.46814 -407.302716) (xy 117.75186 -407.302716) (xy 117.741751 -407.302248)
			(xy 117.723075 -407.2945) (xy 117.708782 -407.280198) (xy 117.701046 -407.261518) (xy 117.700552 -407.251408)
			(xy 117.700552 -407.093928) (xy 117.700117 -407.084744) (xy 117.693619 -407.06756) (xy 117.687852 -407.0604)
			(xy 117.665955 -407.034762) (xy 117.627864 -406.979124) (xy 117.596711 -406.919325) (xy 117.572947 -406.856225)
			(xy 117.556912 -406.790732) (xy 117.548838 -406.72379) (xy 92.270826 -406.72379) (xy 92.262793 -406.790546)
			(xy 92.246825 -406.855926) (xy 92.223158 -406.918929) (xy 92.192131 -406.978652) (xy 92.154188 -407.034239)
			(xy 92.132404 -407.059892) (xy 92.126629 -407.067052) (xy 92.120101 -407.084231) (xy 92.119704 -407.09342)
			(xy 92.119704 -407.251408) (xy 92.119285 -407.261562) (xy 92.111487 -407.280314) (xy 92.09709 -407.294637)
			(xy 92.078298 -407.302337) (xy 92.068142 -407.302716) (xy 91.351862 -407.302716) (xy 91.341727 -407.302303)
			(xy 91.322997 -407.294555) (xy 91.308641 -407.280246) (xy 91.30083 -407.261541) (xy 91.3003 -407.251408)
			(xy 91.3003 -407.09342) (xy 91.29988 -407.084234) (xy 91.293373 -407.067049) (xy 91.2876 -407.059892)
			(xy 91.265782 -407.034265) (xy 91.227837 -406.978674) (xy 91.196807 -406.918947) (xy 91.173138 -406.855939)
			(xy 91.157168 -406.790554) (xy 91.149127 -406.723729) (xy 87.871065 -406.723729) (xy 87.871065 -406.723786)
			(xy 87.862993 -406.790722) (xy 87.846961 -406.85621) (xy 87.823201 -406.919305) (xy 87.792054 -406.9791)
			(xy 87.75397 -407.034735) (xy 87.732108 -407.0604) (xy 87.72633 -407.067558) (xy 87.719804 -407.084739)
			(xy 87.719408 -407.093928) (xy 87.719408 -407.251408) (xy 87.718921 -407.261516) (xy 87.711183 -407.280193)
			(xy 87.696886 -407.294487) (xy 87.678208 -407.302223) (xy 87.6681 -407.302716) (xy 86.95182 -407.302716)
			(xy 86.941701 -407.302268) (xy 86.923001 -407.29453) (xy 86.908686 -407.280223) (xy 86.900937 -407.261527)
			(xy 86.900512 -407.251408) (xy 86.900512 -407.093928) (xy 86.900086 -407.084743) (xy 86.893583 -407.067558)
			(xy 86.887812 -407.0604) (xy 86.865916 -407.034761) (xy 86.827828 -406.979123) (xy 86.796678 -406.919323)
			(xy 86.772915 -406.856223) (xy 86.756881 -406.790731) (xy 86.748808 -406.723789) (xy 83.470763 -406.723789)
			(xy 83.462728 -406.790549) (xy 83.446757 -406.85593) (xy 83.423086 -406.918933) (xy 83.392055 -406.978655)
			(xy 83.354107 -407.03424) (xy 83.33232 -407.059892) (xy 83.326547 -407.067054) (xy 83.320017 -407.084231)
			(xy 83.31962 -407.09342) (xy 83.31962 -407.251408) (xy 83.319185 -407.26156) (xy 83.311391 -407.280309)
			(xy 83.296998 -407.294631) (xy 83.278212 -407.302334) (xy 83.268058 -407.302716) (xy 82.551778 -407.302716)
			(xy 82.541644 -407.30229) (xy 82.522914 -407.294547) (xy 82.508557 -407.280242) (xy 82.500747 -407.26154)
			(xy 82.500216 -407.251408) (xy 82.500216 -407.09342) (xy 82.499792 -407.084234) (xy 82.493288 -407.06705)
			(xy 82.487516 -407.059892) (xy 82.465698 -407.034265) (xy 82.427751 -406.978675) (xy 82.396721 -406.918947)
			(xy 82.373051 -406.85594) (xy 82.35708 -406.790555) (xy 82.349039 -406.72373) (xy 79.070977 -406.72373)
			(xy 79.070977 -406.723786) (xy 79.062905 -406.790722) (xy 79.046874 -406.856209) (xy 79.023114 -406.919304)
			(xy 78.991969 -406.9791) (xy 78.953885 -407.034734) (xy 78.932024 -407.0604) (xy 78.926248 -407.06756)
			(xy 78.91972 -407.084739) (xy 78.919324 -407.093928) (xy 78.919324 -407.251408) (xy 78.918822 -407.261514)
			(xy 78.911086 -407.280188) (xy 78.896795 -407.294482) (xy 78.878122 -407.30222) (xy 78.868016 -407.302716)
			(xy 78.151736 -407.302716) (xy 78.141618 -407.302255) (xy 78.122918 -407.294521) (xy 78.108603 -407.280219)
			(xy 78.100854 -407.261526) (xy 78.100428 -407.251408) (xy 78.100428 -407.093928) (xy 78.099998 -407.084743)
			(xy 78.093497 -407.067559) (xy 78.087728 -407.0604) (xy 78.065832 -407.034761) (xy 78.027742 -406.979124)
			(xy 77.996591 -406.919324) (xy 77.972828 -406.856224) (xy 77.956793 -406.790731) (xy 77.94872 -406.723789)
			(xy 74.670675 -406.723789) (xy 74.662641 -406.790548) (xy 74.64667 -406.855929) (xy 74.623 -406.918932)
			(xy 74.591969 -406.978655) (xy 74.554022 -407.03424) (xy 74.532236 -407.059892) (xy 74.526453 -407.067046)
			(xy 74.519932 -407.08423) (xy 74.519536 -407.09342) (xy 74.519536 -407.251408) (xy 74.519085 -407.261558)
			(xy 74.511294 -407.280304) (xy 74.496907 -407.294625) (xy 74.478126 -407.302331) (xy 74.467974 -407.302716)
			(xy 73.751694 -407.302716) (xy 73.741562 -407.302277) (xy 73.722832 -407.294539) (xy 73.708474 -407.280238)
			(xy 73.700663 -407.261538) (xy 73.700132 -407.251408) (xy 73.700132 -407.09342) (xy 73.699705 -407.084235)
			(xy 73.693202 -407.067051) (xy 73.687432 -407.059892) (xy 73.665613 -407.034266) (xy 73.627666 -406.978675)
			(xy 73.596634 -406.918948) (xy 73.572963 -406.85594) (xy 73.556993 -406.790555) (xy 73.548951 -406.72373)
			(xy 66.525648 -406.72373) (xy 66.525648 -409.523886) (xy 71.34879 -409.523886) (xy 71.348793 -409.45646)
			(xy 71.356872 -409.389519) (xy 71.372911 -409.324028) (xy 71.396679 -409.26093) (xy 71.427834 -409.201133)
			(xy 71.465926 -409.145497) (xy 71.487792 -409.119832) (xy 71.493599 -409.112694) (xy 71.500108 -409.095498)
			(xy 71.500492 -409.086304) (xy 71.500492 -408.594052) (xy 71.500059 -408.584867) (xy 71.493561 -408.567682)
			(xy 71.487792 -408.560524) (xy 71.46592 -408.534865) (xy 71.427833 -408.479229) (xy 71.396683 -408.419432)
			(xy 71.372919 -408.356335) (xy 71.356885 -408.290845) (xy 71.348809 -408.223906) (xy 71.34881 -408.156482)
			(xy 71.356887 -408.089543) (xy 71.372923 -408.024054) (xy 71.396688 -407.960957) (xy 71.427839 -407.90116)
			(xy 71.465928 -407.845525) (xy 71.487792 -407.81986) (xy 71.493587 -407.812714) (xy 71.500103 -407.795524)
			(xy 71.500492 -407.786332) (xy 71.500492 -407.628852) (xy 71.500946 -407.618741) (xy 71.508698 -407.600063)
			(xy 71.523004 -407.585771) (xy 71.541689 -407.578036) (xy 71.5518 -407.577544) (xy 72.26808 -407.577544)
			(xy 72.278181 -407.5781) (xy 72.296848 -407.585821) (xy 72.311141 -407.600095) (xy 72.318887 -407.618752)
			(xy 72.319388 -407.628852) (xy 72.319388 -407.786332) (xy 72.319785 -407.795521) (xy 72.326308 -407.812705)
			(xy 72.332088 -407.81986) (xy 72.353945 -407.845532) (xy 72.392034 -407.901165) (xy 72.423186 -407.96096)
			(xy 72.446951 -408.024056) (xy 72.462988 -408.089545) (xy 72.471064 -408.156482) (xy 72.471065 -408.223906)
			(xy 72.46299 -408.290844) (xy 72.446955 -408.356332) (xy 72.423191 -408.419429) (xy 72.39204 -408.479225)
			(xy 72.353952 -408.534859) (xy 72.332088 -408.560524) (xy 72.326297 -408.567673) (xy 72.31978 -408.584861)
			(xy 72.319388 -408.594052) (xy 72.319388 -409.086304) (xy 72.319799 -409.095491) (xy 72.326313 -409.112675)
			(xy 72.332088 -409.119832) (xy 72.353917 -409.145526) (xy 72.392008 -409.201156) (xy 72.423161 -409.260948)
			(xy 72.446927 -409.324042) (xy 72.462966 -409.389527) (xy 72.471045 -409.456462) (xy 72.471048 -409.523884)
			(xy 72.462975 -409.59082) (xy 72.446943 -409.656307) (xy 72.423183 -409.719402) (xy 72.392035 -409.779197)
			(xy 72.35395 -409.834831) (xy 72.332088 -409.860496) (xy 72.326309 -409.867654) (xy 72.319784 -409.884835)
			(xy 72.319388 -409.894024) (xy 72.319388 -410.051504) (xy 72.318987 -410.061628) (xy 72.311235 -410.080334)
			(xy 72.296914 -410.094649) (xy 72.278204 -410.102392) (xy 72.26808 -410.102812) (xy 71.5518 -410.102812)
			(xy 71.541693 -410.102315) (xy 71.523017 -410.09458) (xy 71.508723 -410.080286) (xy 71.500986 -410.061611)
			(xy 71.500492 -410.051504) (xy 71.500492 -409.894024) (xy 71.500072 -409.884838) (xy 71.493565 -409.867653)
			(xy 71.487792 -409.860496) (xy 71.465893 -409.83486) (xy 71.427806 -409.779221) (xy 71.396657 -409.719421)
			(xy 71.372895 -409.65632) (xy 71.356863 -409.590827) (xy 71.34879 -409.523886) (xy 66.525648 -409.523886)
			(xy 66.525648 -410.623641) (xy 73.548963 -410.623641) (xy 73.548964 -410.556335) (xy 73.55701 -410.489511)
			(xy 73.572984 -410.424128) (xy 73.596658 -410.361123) (xy 73.627693 -410.301399) (xy 73.665643 -410.245812)
			(xy 73.687432 -410.22016) (xy 73.693232 -410.213017) (xy 73.699744 -410.195825) (xy 73.700132 -410.186632)
			(xy 73.700132 -409.693364) (xy 73.699732 -409.684176) (xy 73.69321 -409.666992) (xy 73.687432 -409.659836)
			(xy 73.665656 -409.634174) (xy 73.627707 -409.578589) (xy 73.596674 -409.518867) (xy 73.573001 -409.455863)
			(xy 73.557027 -409.390482) (xy 73.548982 -409.323661) (xy 73.548981 -409.256357) (xy 73.557024 -409.189535)
			(xy 73.572995 -409.124154) (xy 73.596667 -409.06115) (xy 73.627698 -409.001427) (xy 73.665645 -408.94584)
			(xy 73.687432 -408.920188) (xy 73.69322 -408.913037) (xy 73.699739 -408.895851) (xy 73.700132 -408.88666)
			(xy 73.700132 -408.728672) (xy 73.700499 -408.718512) (xy 73.70831 -408.699753) (xy 73.722724 -408.685429)
			(xy 73.741532 -408.677736) (xy 73.751694 -408.677364) (xy 74.467974 -408.677364) (xy 74.478102 -408.677848)
			(xy 74.496827 -408.685572) (xy 74.511185 -408.69986) (xy 74.519001 -408.718546) (xy 74.519536 -408.728672)
			(xy 74.519536 -408.88666) (xy 74.51998 -408.895843) (xy 74.526472 -408.913027) (xy 74.532236 -408.920188)
			(xy 74.554036 -408.94583) (xy 74.591986 -409.001418) (xy 74.62302 -409.061142) (xy 74.646694 -409.124148)
			(xy 74.662666 -409.189532) (xy 74.67071 -409.256356) (xy 74.670709 -409.323662) (xy 74.662663 -409.390486)
			(xy 74.646688 -409.455869) (xy 74.623013 -409.518874) (xy 74.620439 -409.523827) (xy 75.749085 -409.523827)
			(xy 75.749088 -409.456519) (xy 75.757137 -409.389693) (xy 75.773115 -409.324308) (xy 75.796793 -409.261302)
			(xy 75.827833 -409.201578) (xy 75.865789 -409.145992) (xy 75.88758 -409.12034) (xy 75.893382 -409.113199)
			(xy 75.899894 -409.096005) (xy 75.90028 -409.086812) (xy 75.90028 -408.593544) (xy 75.899853 -408.584358)
			(xy 75.893352 -408.567174) (xy 75.88758 -408.560016) (xy 75.865783 -408.534371) (xy 75.827832 -408.478784)
			(xy 75.796797 -408.41906) (xy 75.773123 -408.356055) (xy 75.757149 -408.290671) (xy 75.749105 -408.223847)
			(xy 75.749106 -408.156541) (xy 75.757151 -408.089717) (xy 75.773126 -408.024334) (xy 75.796802 -407.961329)
			(xy 75.827838 -407.901605) (xy 75.865791 -407.84602) (xy 75.88758 -407.820368) (xy 75.89337 -407.813218)
			(xy 75.899889 -407.796031) (xy 75.90028 -407.78684) (xy 75.90028 -407.628852) (xy 75.900682 -407.618697)
			(xy 75.90849 -407.599948) (xy 75.922892 -407.585627) (xy 75.941685 -407.577925) (xy 75.951842 -407.577544)
			(xy 76.668122 -407.577544) (xy 76.678251 -407.578008) (xy 76.696973 -407.585744) (xy 76.711329 -407.600037)
			(xy 76.719147 -407.618726) (xy 76.719684 -407.628852) (xy 76.719684 -407.78684) (xy 76.720078 -407.796029)
			(xy 76.726603 -407.813213) (xy 76.732384 -407.820368) (xy 76.754163 -407.846027) (xy 76.792111 -407.901613)
			(xy 76.823143 -407.961336) (xy 76.846815 -408.024339) (xy 76.862788 -408.08972) (xy 76.870833 -408.156542)
			(xy 76.870833 -408.223846) (xy 76.86279 -408.290668) (xy 76.846819 -408.356049) (xy 76.823148 -408.419053)
			(xy 76.792117 -408.478777) (xy 76.754171 -408.534364) (xy 76.732384 -408.560016) (xy 76.726596 -408.567167)
			(xy 76.720077 -408.584353) (xy 76.719684 -408.593544) (xy 76.719684 -409.086812) (xy 76.720092 -409.095999)
			(xy 76.726607 -409.113184) (xy 76.732384 -409.12034) (xy 76.754135 -409.146022) (xy 76.792084 -409.201605)
			(xy 76.823117 -409.261324) (xy 76.846791 -409.324325) (xy 76.862766 -409.389703) (xy 76.870812 -409.456522)
			(xy 76.870816 -409.523824) (xy 76.862775 -409.590644) (xy 76.846807 -409.656023) (xy 76.823139 -409.719026)
			(xy 76.792112 -409.778749) (xy 76.754169 -409.834335) (xy 76.732384 -409.859988) (xy 76.726566 -409.867118)
			(xy 76.720065 -409.88432) (xy 76.719684 -409.893516) (xy 76.719684 -410.051504) (xy 76.719281 -410.06166)
			(xy 76.711481 -410.080416) (xy 76.697079 -410.09474) (xy 76.678281 -410.102436) (xy 76.668122 -410.102812)
			(xy 75.951842 -410.102812) (xy 75.941724 -410.10224) (xy 75.923014 -410.094536) (xy 75.908658 -410.080276)
			(xy 75.900828 -410.061618) (xy 75.90028 -410.051504) (xy 75.90028 -409.893516) (xy 75.899867 -409.884329)
			(xy 75.893356 -409.867144) (xy 75.88758 -409.859988) (xy 75.865756 -409.834365) (xy 75.827805 -409.778776)
			(xy 75.796771 -409.719048) (xy 75.773099 -409.65604) (xy 75.757127 -409.590654) (xy 75.749085 -409.523827)
			(xy 74.620439 -409.523827) (xy 74.591977 -409.578598) (xy 74.554025 -409.634184) (xy 74.532236 -409.659836)
			(xy 74.526434 -409.666977) (xy 74.519924 -409.684171) (xy 74.519536 -409.693364) (xy 74.519536 -410.186632)
			(xy 74.519945 -410.195819) (xy 74.526461 -410.213002) (xy 74.532236 -410.22016) (xy 74.554009 -410.245825)
			(xy 74.59196 -410.301409) (xy 74.622995 -410.36113) (xy 74.64667 -410.424133) (xy 74.662644 -410.489514)
			(xy 74.67069 -410.556336) (xy 74.670692 -410.62364) (xy 74.670685 -410.623701) (xy 77.948731 -410.623701)
			(xy 77.948732 -410.556275) (xy 77.95681 -410.489335) (xy 77.972848 -410.423845) (xy 77.996615 -410.360747)
			(xy 78.02777 -410.300951) (xy 78.065862 -410.245317) (xy 78.087728 -410.219652) (xy 78.093531 -410.212512)
			(xy 78.100041 -410.195317) (xy 78.100428 -410.186124) (xy 78.100428 -409.693872) (xy 78.100025 -409.684684)
			(xy 78.093506 -409.6675) (xy 78.087728 -409.660344) (xy 78.065875 -409.63467) (xy 78.027784 -409.579037)
			(xy 77.996631 -409.519242) (xy 77.972865 -409.456147) (xy 77.956828 -409.390658) (xy 77.948751 -409.323721)
			(xy 77.94875 -409.256297) (xy 77.956825 -409.189359) (xy 77.97286 -409.123871) (xy 77.996624 -409.060774)
			(xy 78.027775 -409.000979) (xy 78.065864 -408.945345) (xy 78.087728 -408.91968) (xy 78.093519 -408.912531)
			(xy 78.100036 -408.895343) (xy 78.100428 -408.886152) (xy 78.100428 -408.728672) (xy 78.100794 -408.718544)
			(xy 78.108556 -408.699835) (xy 78.122888 -408.68552) (xy 78.141608 -408.677781) (xy 78.151736 -408.677364)
			(xy 78.868016 -408.677364) (xy 78.878121 -408.677871) (xy 78.896793 -408.685608) (xy 78.911086 -408.699897)
			(xy 78.918826 -408.718567) (xy 78.919324 -408.728672) (xy 78.919324 -408.886152) (xy 78.919752 -408.895337)
			(xy 78.926253 -408.912522) (xy 78.932024 -408.91968) (xy 78.953899 -408.945336) (xy 78.991986 -409.000972)
			(xy 79.023135 -409.06077) (xy 79.046897 -409.123868) (xy 79.062931 -409.189358) (xy 79.071005 -409.256297)
			(xy 79.071004 -409.323721) (xy 79.062928 -409.39066) (xy 79.046892 -409.456149) (xy 79.023127 -409.519246)
			(xy 79.02071 -409.523886) (xy 80.148878 -409.523886) (xy 80.148881 -409.45646) (xy 80.15696 -409.38952)
			(xy 80.172999 -409.324029) (xy 80.196766 -409.260931) (xy 80.227919 -409.201133) (xy 80.266011 -409.145498)
			(xy 80.287876 -409.119832) (xy 80.293681 -409.112693) (xy 80.300191 -409.095498) (xy 80.300576 -409.086304)
			(xy 80.300576 -408.594052) (xy 80.300146 -408.584867) (xy 80.293647 -408.567682) (xy 80.287876 -408.560524)
			(xy 80.266005 -408.534865) (xy 80.227918 -408.479229) (xy 80.196769 -408.419432) (xy 80.173006 -408.356334)
			(xy 80.156972 -408.290844) (xy 80.148897 -408.223906) (xy 80.148898 -408.156482) (xy 80.156974 -408.089544)
			(xy 80.17301 -408.024055) (xy 80.196774 -407.960957) (xy 80.227924 -407.901161) (xy 80.266012 -407.845526)
			(xy 80.287876 -407.81986) (xy 80.293669 -407.812712) (xy 80.300187 -407.795524) (xy 80.300576 -407.786332)
			(xy 80.300576 -407.628852) (xy 80.301045 -407.618743) (xy 80.308794 -407.600069) (xy 80.323095 -407.585776)
			(xy 80.341775 -407.578039) (xy 80.351884 -407.577544) (xy 81.068164 -407.577544) (xy 81.078264 -407.578113)
			(xy 81.09693 -407.585829) (xy 81.111224 -407.600099) (xy 81.11897 -407.618753) (xy 81.119472 -407.628852)
			(xy 81.119472 -407.786332) (xy 81.119873 -407.79552) (xy 81.126394 -407.812704) (xy 81.132172 -407.81986)
			(xy 81.154029 -407.845531) (xy 81.19212 -407.901164) (xy 81.223273 -407.960959) (xy 81.247038 -408.024056)
			(xy 81.263075 -408.089544) (xy 81.271152 -408.156482) (xy 81.271153 -408.223906) (xy 81.263077 -408.290844)
			(xy 81.247042 -408.356333) (xy 81.223277 -408.41943) (xy 81.192126 -408.479225) (xy 81.154036 -408.534859)
			(xy 81.132172 -408.560524) (xy 81.126379 -408.567672) (xy 81.119863 -408.58486) (xy 81.119472 -408.594052)
			(xy 81.119472 -409.086304) (xy 81.119886 -409.095491) (xy 81.126398 -409.112675) (xy 81.132172 -409.119832)
			(xy 81.154002 -409.145526) (xy 81.192093 -409.201156) (xy 81.223247 -409.260948) (xy 81.247014 -409.324041)
			(xy 81.263053 -409.389527) (xy 81.271132 -409.456462) (xy 81.271136 -409.523884) (xy 81.263063 -409.59082)
			(xy 81.247031 -409.656307) (xy 81.223269 -409.719403) (xy 81.192121 -409.779198) (xy 81.154035 -409.834831)
			(xy 81.132172 -409.860496) (xy 81.126391 -409.867652) (xy 81.119868 -409.884834) (xy 81.119472 -409.894024)
			(xy 81.119472 -410.051504) (xy 81.119086 -410.06163) (xy 81.111332 -410.080339) (xy 81.097006 -410.094654)
			(xy 81.078291 -410.102394) (xy 81.068164 -410.102812) (xy 80.351884 -410.102812) (xy 80.341776 -410.102328)
			(xy 80.3231 -410.094587) (xy 80.308806 -410.08029) (xy 80.30107 -410.061612) (xy 80.300576 -410.051504)
			(xy 80.300576 -409.894024) (xy 80.30016 -409.884837) (xy 80.293651 -409.867653) (xy 80.287876 -409.860496)
			(xy 80.265978 -409.83486) (xy 80.227891 -409.77922) (xy 80.196744 -409.71942) (xy 80.172983 -409.656319)
			(xy 80.15695 -409.590827) (xy 80.148878 -409.523886) (xy 79.02071 -409.523886) (xy 78.991976 -409.579043)
			(xy 78.953888 -409.634678) (xy 78.932024 -409.660344) (xy 78.926229 -409.667491) (xy 78.919713 -409.68468)
			(xy 78.919324 -409.693872) (xy 78.919324 -410.186124) (xy 78.919717 -410.195313) (xy 78.926242 -410.212497)
			(xy 78.932024 -410.219652) (xy 78.953871 -410.245331) (xy 78.991959 -410.300964) (xy 79.023109 -410.360758)
			(xy 79.046873 -410.423853) (xy 79.062909 -410.489341) (xy 79.070986 -410.556277) (xy 79.070987 -410.623641)
			(xy 82.349051 -410.623641) (xy 82.349052 -410.556335) (xy 82.357097 -410.489512) (xy 82.373071 -410.424129)
			(xy 82.396745 -410.361124) (xy 82.427779 -410.3014) (xy 82.465728 -410.245812) (xy 82.487516 -410.22016)
			(xy 82.493314 -410.213016) (xy 82.499827 -410.195824) (xy 82.500216 -410.186632) (xy 82.500216 -409.693364)
			(xy 82.49982 -409.684175) (xy 82.493296 -409.666991) (xy 82.487516 -409.659836) (xy 82.465741 -409.634174)
			(xy 82.427793 -409.578588) (xy 82.39676 -409.518866) (xy 82.373088 -409.455863) (xy 82.357115 -409.390482)
			(xy 82.34907 -409.323661) (xy 82.349069 -409.256357) (xy 82.357112 -409.189536) (xy 82.373083 -409.124155)
			(xy 82.396753 -409.061151) (xy 82.427784 -409.001427) (xy 82.46573 -408.94584) (xy 82.487516 -408.920188)
			(xy 82.493302 -408.913035) (xy 82.499822 -408.89585) (xy 82.500216 -408.88666) (xy 82.500216 -408.728672)
			(xy 82.500599 -408.718514) (xy 82.508407 -408.699758) (xy 82.522815 -408.685435) (xy 82.541618 -408.677739)
			(xy 82.551778 -408.677364) (xy 83.268058 -408.677364) (xy 83.278185 -408.677862) (xy 83.29691 -408.68558)
			(xy 83.311268 -408.699864) (xy 83.319085 -408.718548) (xy 83.31962 -408.728672) (xy 83.31962 -408.88666)
			(xy 83.320045 -408.895846) (xy 83.326548 -408.913031) (xy 83.33232 -408.920188) (xy 83.354121 -408.94583)
			(xy 83.392072 -409.001417) (xy 83.423107 -409.061141) (xy 83.446781 -409.124147) (xy 83.462754 -409.189531)
			(xy 83.470798 -409.256356) (xy 83.470797 -409.323662) (xy 83.462751 -409.390487) (xy 83.446775 -409.45587)
			(xy 83.423099 -409.518875) (xy 83.420495 -409.523886) (xy 84.548669 -409.523886) (xy 84.548672 -409.45646)
			(xy 84.556751 -409.38952) (xy 84.572789 -409.324029) (xy 84.596556 -409.260931) (xy 84.627709 -409.201134)
			(xy 84.665799 -409.145498) (xy 84.687664 -409.119832) (xy 84.69348 -409.112701) (xy 84.699981 -409.095499)
			(xy 84.700364 -409.086304) (xy 84.700364 -408.594052) (xy 84.699915 -408.584869) (xy 84.693427 -408.567685)
			(xy 84.687664 -408.560524) (xy 84.665793 -408.534865) (xy 84.627707 -408.479228) (xy 84.596559 -408.419431)
			(xy 84.572797 -408.356334) (xy 84.556763 -408.290844) (xy 84.548688 -408.223906) (xy 84.548689 -408.156482)
			(xy 84.556765 -408.089544) (xy 84.5728 -408.024055) (xy 84.596564 -407.960958) (xy 84.627714 -407.901161)
			(xy 84.665801 -407.845526) (xy 84.687664 -407.81986) (xy 84.693468 -407.81272) (xy 84.699976 -407.795525)
			(xy 84.700364 -407.786332) (xy 84.700364 -407.628852) (xy 84.700845 -407.618745) (xy 84.708592 -407.600072)
			(xy 84.722889 -407.585781) (xy 84.741564 -407.578041) (xy 84.751672 -407.577544) (xy 85.467952 -407.577544)
			(xy 85.478051 -407.578123) (xy 85.496717 -407.585835) (xy 85.511012 -407.600102) (xy 85.518758 -407.618754)
			(xy 85.51926 -407.628852) (xy 85.51926 -407.786332) (xy 85.519664 -407.79552) (xy 85.526183 -407.812703)
			(xy 85.53196 -407.81986) (xy 85.553818 -407.845531) (xy 85.591909 -407.901164) (xy 85.623062 -407.960959)
			(xy 85.646829 -408.024055) (xy 85.662866 -408.089544) (xy 85.670943 -408.156482) (xy 85.670944 -408.223906)
			(xy 85.662868 -408.290844) (xy 85.646832 -408.356333) (xy 85.623067 -408.41943) (xy 85.591915 -408.479226)
			(xy 85.553825 -408.534859) (xy 85.53196 -408.560524) (xy 85.526166 -408.567671) (xy 85.519651 -408.58486)
			(xy 85.51926 -408.594052) (xy 85.51926 -409.086304) (xy 85.519677 -409.09549) (xy 85.526187 -409.112674)
			(xy 85.53196 -409.119832) (xy 85.55379 -409.145526) (xy 85.591882 -409.201155) (xy 85.623037 -409.260947)
			(xy 85.646805 -409.32404) (xy 85.662844 -409.389526) (xy 85.670923 -409.456462) (xy 85.670927 -409.523884)
			(xy 85.662854 -409.59082) (xy 85.646821 -409.656308) (xy 85.623059 -409.719403) (xy 85.59191 -409.779198)
			(xy 85.553823 -409.834831) (xy 85.53196 -409.860496) (xy 85.526178 -409.867651) (xy 85.519655 -409.884834)
			(xy 85.51926 -409.894024) (xy 85.51926 -410.051504) (xy 85.518886 -410.061632) (xy 85.511129 -410.080343)
			(xy 85.496799 -410.094659) (xy 85.47808 -410.102396) (xy 85.467952 -410.102812) (xy 84.751672 -410.102812)
			(xy 84.741563 -410.102338) (xy 84.722886 -410.094594) (xy 84.708593 -410.080293) (xy 84.700857 -410.061613)
			(xy 84.700364 -410.051504) (xy 84.700364 -409.894024) (xy 84.699928 -409.88484) (xy 84.693431 -409.867656)
			(xy 84.687664 -409.860496) (xy 84.665766 -409.834859) (xy 84.627681 -409.77922) (xy 84.596534 -409.719419)
			(xy 84.572773 -409.656319) (xy 84.556741 -409.590827) (xy 84.548669 -409.523886) (xy 83.420495 -409.523886)
			(xy 83.392063 -409.578599) (xy 83.35411 -409.634184) (xy 83.33232 -409.659836) (xy 83.326528 -409.666985)
			(xy 83.32001 -409.684172) (xy 83.31962 -409.693364) (xy 83.31962 -410.186632) (xy 83.32001 -410.195821)
			(xy 83.326537 -410.213006) (xy 83.33232 -410.22016) (xy 83.354093 -410.245825) (xy 83.392045 -410.301408)
			(xy 83.423081 -410.36113) (xy 83.446757 -410.424133) (xy 83.462732 -410.489514) (xy 83.470778 -410.556336)
			(xy 83.47078 -410.62364) (xy 83.470773 -410.623701) (xy 86.748819 -410.623701) (xy 86.74882 -410.556275)
			(xy 86.756898 -410.489336) (xy 86.772936 -410.423846) (xy 86.796702 -410.360748) (xy 86.827855 -410.300952)
			(xy 86.865947 -410.245317) (xy 86.887812 -410.219652) (xy 86.893613 -410.21251) (xy 86.900125 -410.195317)
			(xy 86.900512 -410.186124) (xy 86.900512 -409.693872) (xy 86.900113 -409.684684) (xy 86.893591 -409.6675)
			(xy 86.887812 -409.660344) (xy 86.865959 -409.634669) (xy 86.82787 -409.579036) (xy 86.796718 -409.519242)
			(xy 86.772952 -409.456146) (xy 86.756916 -409.390658) (xy 86.748839 -409.32372) (xy 86.748837 -409.256298)
			(xy 86.756912 -409.18936) (xy 86.772947 -409.123871) (xy 86.79671 -409.060775) (xy 86.82786 -409.000979)
			(xy 86.865948 -408.945345) (xy 86.887812 -408.91968) (xy 86.893601 -408.912529) (xy 86.90012 -408.895343)
			(xy 86.900512 -408.886152) (xy 86.900512 -408.728672) (xy 86.900962 -408.71856) (xy 86.908711 -408.699879)
			(xy 86.923019 -408.685585) (xy 86.941708 -408.677853) (xy 86.95182 -408.677364) (xy 87.6681 -408.677364)
			(xy 87.678204 -408.677884) (xy 87.696876 -408.685615) (xy 87.711169 -408.699901) (xy 87.71891 -408.718568)
			(xy 87.719408 -408.728672) (xy 87.719408 -408.886152) (xy 87.719839 -408.895337) (xy 87.726338 -408.912522)
			(xy 87.732108 -408.91968) (xy 87.753983 -408.945336) (xy 87.792071 -409.000972) (xy 87.823221 -409.060769)
			(xy 87.846984 -409.123867) (xy 87.863019 -409.189358) (xy 87.871093 -409.256297) (xy 87.871092 -409.323721)
			(xy 87.863015 -409.39066) (xy 87.846979 -409.45615) (xy 87.823214 -409.519247) (xy 87.792062 -409.579044)
			(xy 87.753972 -409.634679) (xy 87.732108 -409.660344) (xy 87.726311 -409.667489) (xy 87.719796 -409.68468)
			(xy 87.719408 -409.693872) (xy 87.719408 -410.186124) (xy 87.719805 -410.195313) (xy 87.726328 -410.212497)
			(xy 87.732108 -410.219652) (xy 87.753956 -410.24533) (xy 87.792045 -410.300963) (xy 87.823196 -410.360758)
			(xy 87.84696 -410.423853) (xy 87.862997 -410.48934) (xy 87.871074 -410.556277) (xy 87.871075 -410.623641)
			(xy 91.149138 -410.623641) (xy 91.14914 -410.556335) (xy 91.157185 -410.489512) (xy 91.173158 -410.42413)
			(xy 91.196831 -410.361125) (xy 91.227864 -410.3014) (xy 91.265813 -410.245813) (xy 91.2876 -410.22016)
			(xy 91.293396 -410.213014) (xy 91.299911 -410.195824) (xy 91.3003 -410.186632) (xy 91.3003 -409.693364)
			(xy 91.299907 -409.684175) (xy 91.293382 -409.666991) (xy 91.2876 -409.659836) (xy 91.265825 -409.634174)
			(xy 91.227879 -409.578588) (xy 91.196847 -409.518865) (xy 91.173175 -409.455862) (xy 91.157203 -409.390482)
			(xy 91.149158 -409.323661) (xy 91.149157 -409.256357) (xy 91.157199 -409.189536) (xy 91.17317 -409.124155)
			(xy 91.19684 -409.061151) (xy 91.227869 -409.001428) (xy 91.265814 -408.945841) (xy 91.2876 -408.920188)
			(xy 91.293384 -408.913034) (xy 91.299906 -408.89585) (xy 91.3003 -408.88666) (xy 91.3003 -408.728672)
			(xy 91.300699 -408.718516) (xy 91.308503 -408.699763) (xy 91.322907 -408.685441) (xy 91.341704 -408.677742)
			(xy 91.351862 -408.677364) (xy 92.068142 -408.677364) (xy 92.078274 -408.677793) (xy 92.097001 -408.685539)
			(xy 92.111357 -408.699843) (xy 92.11917 -408.718542) (xy 92.119704 -408.728672) (xy 92.119704 -408.88666)
			(xy 92.120132 -408.895845) (xy 92.126633 -408.91303) (xy 92.132404 -408.920188) (xy 92.154202 -408.945831)
			(xy 92.192148 -409.00142) (xy 92.223178 -409.061145) (xy 92.246848 -409.124151) (xy 92.262819 -409.189534)
			(xy 92.270862 -409.256356) (xy 92.270861 -409.323662) (xy 92.262816 -409.390484) (xy 92.246843 -409.455867)
			(xy 92.223171 -409.518871) (xy 92.220596 -409.523827) (xy 115.349227 -409.523827) (xy 115.349231 -409.456519)
			(xy 115.357278 -409.389695) (xy 115.373254 -409.324311) (xy 115.396929 -409.261305) (xy 115.427964 -409.20158)
			(xy 115.465915 -409.145993) (xy 115.487704 -409.12034) (xy 115.493509 -409.113201) (xy 115.500019 -409.096006)
			(xy 115.500404 -409.086812) (xy 115.500404 -408.593544) (xy 115.499972 -408.584359) (xy 115.493473 -408.567175)
			(xy 115.487704 -408.560016) (xy 115.465909 -408.53437) (xy 115.427963 -408.478782) (xy 115.396932 -408.419057)
			(xy 115.373261 -408.356052) (xy 115.35729 -408.290669) (xy 115.349247 -408.223846) (xy 115.349248 -408.156541)
			(xy 115.357292 -408.089719) (xy 115.373265 -408.024337) (xy 115.396937 -407.961332) (xy 115.427969 -407.901608)
			(xy 115.465917 -407.846021) (xy 115.487704 -407.820368) (xy 115.493497 -407.81322) (xy 115.500014 -407.796032)
			(xy 115.500404 -407.78684) (xy 115.500404 -407.628852) (xy 115.500846 -407.61874) (xy 115.5086 -407.60006)
			(xy 115.52291 -407.585767) (xy 115.541599 -407.578034) (xy 115.551712 -407.577544) (xy 116.268246 -407.577544)
			(xy 116.278376 -407.577989) (xy 116.297099 -407.585733) (xy 116.311454 -407.600031) (xy 116.319271 -407.618724)
			(xy 116.319808 -407.628852) (xy 116.319808 -407.78684) (xy 116.320197 -407.79603) (xy 116.326725 -407.813214)
			(xy 116.332508 -407.820368) (xy 116.354289 -407.846026) (xy 116.392242 -407.90161) (xy 116.423279 -407.961333)
			(xy 116.446954 -408.024336) (xy 116.462929 -408.089718) (xy 116.470975 -408.156541) (xy 116.470976 -408.223847)
			(xy 116.462931 -408.29067) (xy 116.446958 -408.356052) (xy 116.423283 -408.419056) (xy 116.392248 -408.478779)
			(xy 116.354297 -408.534365) (xy 116.332508 -408.560016) (xy 116.326723 -408.56717) (xy 116.320201 -408.584354)
			(xy 116.319808 -408.593544) (xy 116.319808 -409.086812) (xy 116.320211 -409.096) (xy 116.326729 -409.113184)
			(xy 116.332508 -409.12034) (xy 116.354262 -409.146021) (xy 116.392215 -409.201602) (xy 116.423253 -409.261321)
			(xy 116.44693 -409.324322) (xy 116.462907 -409.389701) (xy 116.470955 -409.456521) (xy 116.470958 -409.523825)
			(xy 116.462917 -409.590646) (xy 116.446946 -409.656026) (xy 116.423275 -409.71903) (xy 116.392243 -409.778752)
			(xy 116.354295 -409.834337) (xy 116.332508 -409.859988) (xy 116.326692 -409.86712) (xy 116.320189 -409.884321)
			(xy 116.319808 -409.893516) (xy 116.319808 -410.051504) (xy 116.319318 -410.061612) (xy 116.311581 -410.080289)
			(xy 116.297285 -410.094583) (xy 116.278608 -410.102319) (xy 116.2685 -410.102812) (xy 115.551966 -410.102812)
			(xy 115.541844 -410.102303) (xy 115.523131 -410.094574) (xy 115.508778 -410.080295) (xy 115.500951 -410.061624)
			(xy 115.500404 -410.051504) (xy 115.500404 -409.893516) (xy 115.499985 -409.88433) (xy 115.493477 -409.867145)
			(xy 115.487704 -409.859988) (xy 115.465882 -409.834364) (xy 115.427937 -409.778773) (xy 115.396907 -409.719045)
			(xy 115.373238 -409.656037) (xy 115.357268 -409.590652) (xy 115.349227 -409.523827) (xy 92.220596 -409.523827)
			(xy 92.192139 -409.578596) (xy 92.154191 -409.634183) (xy 92.132404 -409.659836) (xy 92.12661 -409.666983)
			(xy 92.120094 -409.684172) (xy 92.119704 -409.693364) (xy 92.119704 -410.186632) (xy 92.120098 -410.195821)
			(xy 92.126623 -410.213005) (xy 92.132404 -410.22016) (xy 92.154175 -410.245826) (xy 92.192121 -410.301411)
			(xy 92.223153 -410.361133) (xy 92.246825 -410.424136) (xy 92.262797 -410.489516) (xy 92.270842 -410.556336)
			(xy 92.270844 -410.623639) (xy 92.270837 -410.623701) (xy 117.548849 -410.623701) (xy 117.54885 -410.556275)
			(xy 117.556929 -410.489335) (xy 117.572967 -410.423844) (xy 117.596736 -410.360746) (xy 117.627891 -410.30095)
			(xy 117.665985 -410.245316) (xy 117.687852 -410.219652) (xy 117.693658 -410.212514) (xy 117.700166 -410.195318)
			(xy 117.700552 -410.186124) (xy 117.700552 -409.693872) (xy 117.700144 -409.684685) (xy 117.693627 -409.667501)
			(xy 117.687852 -409.660344) (xy 117.665998 -409.63467) (xy 117.627906 -409.579038) (xy 117.596751 -409.519243)
			(xy 117.572984 -409.456148) (xy 117.556946 -409.390659) (xy 117.548869 -409.323721) (xy 117.548868 -409.256297)
			(xy 117.556943 -409.189359) (xy 117.572979 -409.12387) (xy 117.596744 -409.060773) (xy 117.627896 -409.000978)
			(xy 117.665987 -408.945344) (xy 117.687852 -408.91968) (xy 117.693646 -408.912533) (xy 117.700161 -408.895344)
			(xy 117.700552 -408.886152) (xy 117.700552 -408.728672) (xy 117.701061 -408.718567) (xy 117.708799 -408.699898)
			(xy 117.723088 -408.685606) (xy 117.741756 -408.677863) (xy 117.75186 -408.677364) (xy 118.46814 -408.677364)
			(xy 118.478247 -408.677852) (xy 118.496919 -408.685596) (xy 118.511211 -408.699891) (xy 118.518951 -408.718565)
			(xy 118.519448 -408.728672) (xy 118.519448 -408.886152) (xy 118.519893 -408.895335) (xy 118.526384 -408.912519)
			(xy 118.532148 -408.91968) (xy 118.554026 -408.945335) (xy 118.592117 -409.000969) (xy 118.62327 -409.060767)
			(xy 118.647036 -409.123865) (xy 118.663072 -409.189356) (xy 118.671148 -409.256296) (xy 118.671147 -409.323722)
			(xy 118.663069 -409.390662) (xy 118.647031 -409.456152) (xy 118.623263 -409.51925) (xy 118.620848 -409.523886)
			(xy 119.748996 -409.523886) (xy 119.748999 -409.45646) (xy 119.757078 -409.389519) (xy 119.773118 -409.324028)
			(xy 119.796886 -409.26093) (xy 119.828041 -409.201132) (xy 119.866134 -409.145497) (xy 119.888 -409.119832)
			(xy 119.893808 -409.112695) (xy 119.900316 -409.095498) (xy 119.9007 -409.086304) (xy 119.9007 -408.594052)
			(xy 119.900265 -408.584867) (xy 119.893769 -408.567683) (xy 119.888 -408.560524) (xy 119.866128 -408.534865)
			(xy 119.82804 -408.47923) (xy 119.796889 -408.419433) (xy 119.773126 -408.356335) (xy 119.757091 -408.290845)
			(xy 119.749015 -408.223906) (xy 119.749016 -408.156482) (xy 119.757093 -408.089543) (xy 119.773129 -408.024054)
			(xy 119.796894 -407.960956) (xy 119.828046 -407.90116) (xy 119.866136 -407.845525) (xy 119.888 -407.81986)
			(xy 119.893796 -407.812714) (xy 119.900311 -407.795524) (xy 119.9007 -407.786332) (xy 119.9007 -407.628852)
			(xy 119.901146 -407.61874) (xy 119.908899 -407.600061) (xy 119.923208 -407.585768) (xy 119.941896 -407.578035)
			(xy 119.952008 -407.577544) (xy 120.668288 -407.577544) (xy 120.678389 -407.578094) (xy 120.697056 -407.585817)
			(xy 120.71135 -407.600093) (xy 120.719095 -407.618752) (xy 120.719596 -407.628852) (xy 120.719596 -407.786332)
			(xy 120.719991 -407.795521) (xy 120.726515 -407.812705) (xy 120.732296 -407.81986) (xy 120.754152 -407.845532)
			(xy 120.792241 -407.901165) (xy 120.823393 -407.96096) (xy 120.847158 -408.024056) (xy 120.863194 -408.089545)
			(xy 120.87127 -408.156482) (xy 120.871271 -408.223906) (xy 120.863196 -408.290843) (xy 120.847161 -408.356332)
			(xy 120.823398 -408.419429) (xy 120.792248 -408.479225) (xy 120.75416 -408.534859) (xy 120.732296 -408.560524)
			(xy 120.726506 -408.567674) (xy 120.719988 -408.584861) (xy 120.719596 -408.594052) (xy 120.719596 -409.086304)
			(xy 120.720005 -409.095491) (xy 120.72652 -409.112675) (xy 120.732296 -409.119832) (xy 120.754125 -409.145526)
			(xy 120.792215 -409.201157) (xy 120.823367 -409.260949) (xy 120.847134 -409.324042) (xy 120.863172 -409.389527)
			(xy 120.871251 -409.456463) (xy 120.871254 -409.523883) (xy 120.863181 -409.590819) (xy 120.84715 -409.656306)
			(xy 120.823389 -409.719402) (xy 120.792243 -409.779197) (xy 120.754158 -409.834831) (xy 120.732296 -409.860496)
			(xy 120.726518 -409.867654) (xy 120.719992 -409.884835) (xy 120.719596 -409.894024) (xy 120.719596 -410.051504)
			(xy 120.719187 -410.061627) (xy 120.711437 -410.080332) (xy 120.697118 -410.094646) (xy 120.678411 -410.10239)
			(xy 120.668288 -410.102812) (xy 119.952008 -410.102812) (xy 119.941888 -410.102378) (xy 119.923186 -410.094634)
			(xy 119.908872 -410.080324) (xy 119.901125 -410.061624) (xy 119.9007 -410.051504) (xy 119.9007 -409.894024)
			(xy 119.900278 -409.884838) (xy 119.893773 -409.867654) (xy 119.888 -409.860496) (xy 119.866101 -409.83486)
			(xy 119.828013 -409.779221) (xy 119.796864 -409.719421) (xy 119.773102 -409.65632) (xy 119.757069 -409.590828)
			(xy 119.748996 -409.523886) (xy 118.620848 -409.523886) (xy 118.592108 -409.579046) (xy 118.554015 -409.63468)
			(xy 118.532148 -409.660344) (xy 118.526344 -409.667484) (xy 118.519835 -409.684679) (xy 118.519448 -409.693872)
			(xy 118.519448 -410.186124) (xy 118.519858 -410.195311) (xy 118.526373 -410.212495) (xy 118.532148 -410.219652)
			(xy 118.553998 -410.245329) (xy 118.592091 -410.300961) (xy 118.623245 -410.360755) (xy 118.647012 -410.42385)
			(xy 118.663051 -410.489338) (xy 118.671128 -410.556276) (xy 118.67113 -410.623641) (xy 121.949169 -410.623641)
			(xy 121.94917 -410.556335) (xy 121.957216 -410.489511) (xy 121.97319 -410.424128) (xy 121.996865 -410.361123)
			(xy 122.0279 -410.301399) (xy 122.065851 -410.245812) (xy 122.08764 -410.22016) (xy 122.093441 -410.213018)
			(xy 122.099952 -410.195825) (xy 122.10034 -410.186632) (xy 122.10034 -409.693364) (xy 122.099938 -409.684176)
			(xy 122.093418 -409.666992) (xy 122.08764 -409.659836) (xy 122.065864 -409.634174) (xy 122.027915 -409.578589)
			(xy 121.996881 -409.518867) (xy 121.973208 -409.455864) (xy 121.957234 -409.390483) (xy 121.949189 -409.323661)
			(xy 121.949188 -409.256357) (xy 121.957231 -409.189535) (xy 121.973202 -409.124154) (xy 121.996874 -409.06115)
			(xy 122.027906 -409.001427) (xy 122.065853 -408.94584) (xy 122.08764 -408.920188) (xy 122.093429 -408.913038)
			(xy 122.099947 -408.895851) (xy 122.10034 -408.88666) (xy 122.10034 -408.728672) (xy 122.100694 -408.718543)
			(xy 122.108459 -408.699831) (xy 122.122795 -408.685516) (xy 122.141518 -408.677779) (xy 122.151648 -408.677364)
			(xy 122.868182 -408.677364) (xy 122.878311 -408.677842) (xy 122.897036 -408.685568) (xy 122.911394 -408.699858)
			(xy 122.919209 -408.718546) (xy 122.919744 -408.728672) (xy 122.919744 -408.88666) (xy 122.920186 -408.895844)
			(xy 122.926679 -408.913028) (xy 122.932444 -408.920188) (xy 122.954244 -408.94583) (xy 122.992193 -409.001418)
			(xy 123.023227 -409.061143) (xy 123.0469 -409.124148) (xy 123.062873 -409.189532) (xy 123.070916 -409.256356)
			(xy 123.070915 -409.323662) (xy 123.062869 -409.390486) (xy 123.046895 -409.455869) (xy 123.02322 -409.518874)
			(xy 123.020646 -409.523827) (xy 124.149291 -409.523827) (xy 124.149295 -409.456519) (xy 124.157343 -409.389693)
			(xy 124.173321 -409.324308) (xy 124.197 -409.261302) (xy 124.22804 -409.201577) (xy 124.265997 -409.145992)
			(xy 124.287788 -409.12034) (xy 124.293591 -409.113199) (xy 124.300102 -409.096005) (xy 124.300488 -409.086812)
			(xy 124.300488 -408.593544) (xy 124.300059 -408.584359) (xy 124.293559 -408.567174) (xy 124.287788 -408.560016)
			(xy 124.265991 -408.534371) (xy 124.228039 -408.478785) (xy 124.197004 -408.419061) (xy 124.173329 -408.356055)
			(xy 124.157355 -408.290671) (xy 124.149311 -408.223847) (xy 124.149312 -408.156541) (xy 124.157357 -408.089717)
			(xy 124.173333 -408.024333) (xy 124.197008 -407.961328) (xy 124.228045 -407.901605) (xy 124.265998 -407.84602)
			(xy 124.287788 -407.820368) (xy 124.293579 -407.813219) (xy 124.300097 -407.796031) (xy 124.300488 -407.78684)
			(xy 124.300488 -407.628852) (xy 124.300946 -407.618742) (xy 124.308697 -407.600065) (xy 124.323002 -407.585772)
			(xy 124.341685 -407.578037) (xy 124.351796 -407.577544) (xy 125.06833 -407.577544) (xy 125.078459 -407.578002)
			(xy 125.097182 -407.58574) (xy 125.111537 -407.600035) (xy 125.119355 -407.618725) (xy 125.119892 -407.628852)
			(xy 125.119892 -407.78684) (xy 125.120285 -407.796029) (xy 125.126811 -407.813213) (xy 125.132592 -407.820368)
			(xy 125.154371 -407.846027) (xy 125.192318 -407.901613) (xy 125.22335 -407.961336) (xy 125.247022 -408.02434)
			(xy 125.262994 -408.089721) (xy 125.271039 -408.156542) (xy 125.271039 -408.223846) (xy 125.262997 -408.290667)
			(xy 125.247025 -408.356049) (xy 125.223355 -408.419053) (xy 125.192324 -408.478776) (xy 125.154378 -408.534363)
			(xy 125.132592 -408.560016) (xy 125.126805 -408.567168) (xy 125.120285 -408.584353) (xy 125.119892 -408.593544)
			(xy 125.119892 -409.086812) (xy 125.120298 -409.096) (xy 125.126815 -409.113184) (xy 125.132592 -409.12034)
			(xy 125.154343 -409.146022) (xy 125.192291 -409.201605) (xy 125.223324 -409.261324) (xy 125.246998 -409.324325)
			(xy 125.262972 -409.389703) (xy 125.271019 -409.456522) (xy 125.271022 -409.523824) (xy 125.262982 -409.590643)
			(xy 125.247014 -409.656023) (xy 125.223347 -409.719026) (xy 125.192319 -409.778749) (xy 125.154377 -409.834336)
			(xy 125.132592 -409.859988) (xy 125.126775 -409.867118) (xy 125.120273 -409.88432) (xy 125.119892 -409.893516)
			(xy 125.119892 -410.051504) (xy 125.119487 -410.061628) (xy 125.111736 -410.080333) (xy 125.097416 -410.094647)
			(xy 125.078708 -410.102391) (xy 125.068584 -410.102812) (xy 124.35205 -410.102812) (xy 124.341933 -410.102234)
			(xy 124.323223 -410.094532) (xy 124.308867 -410.080274) (xy 124.301036 -410.061618) (xy 124.300488 -410.051504)
			(xy 124.300488 -409.893516) (xy 124.300073 -409.884329) (xy 124.293563 -409.867145) (xy 124.287788 -409.859988)
			(xy 124.265963 -409.834366) (xy 124.228013 -409.778776) (xy 124.196978 -409.719049) (xy 124.173305 -409.65604)
			(xy 124.157333 -409.590654) (xy 124.149291 -409.523827) (xy 123.020646 -409.523827) (xy 122.992184 -409.578598)
			(xy 122.954233 -409.634184) (xy 122.932444 -409.659836) (xy 122.926643 -409.666978) (xy 122.920132 -409.684171)
			(xy 122.919744 -409.693364) (xy 122.919744 -410.186632) (xy 122.920151 -410.195819) (xy 122.926668 -410.213003)
			(xy 122.932444 -410.22016) (xy 122.954216 -410.245825) (xy 122.992167 -410.301409) (xy 123.023202 -410.361131)
			(xy 123.046876 -410.424134) (xy 123.062851 -410.489514) (xy 123.070896 -410.556336) (xy 123.070898 -410.62364)
			(xy 123.070891 -410.623701) (xy 126.348937 -410.623701) (xy 126.348938 -410.556275) (xy 126.357016 -410.489335)
			(xy 126.373055 -410.423845) (xy 126.396822 -410.360747) (xy 126.427977 -410.300951) (xy 126.46607 -410.245317)
			(xy 126.487936 -410.219652) (xy 126.49374 -410.212512) (xy 126.500249 -410.195317) (xy 126.500636 -410.186124)
			(xy 126.500636 -409.693872) (xy 126.500231 -409.684684) (xy 126.493713 -409.667501) (xy 126.487936 -409.660344)
			(xy 126.466083 -409.63467) (xy 126.427991 -409.579037) (xy 126.396838 -409.519243) (xy 126.373071 -409.456147)
			(xy 126.357034 -409.390659) (xy 126.348957 -409.323721) (xy 126.348956 -409.256297) (xy 126.357031 -409.189359)
			(xy 126.373066 -409.12387) (xy 126.396831 -409.060774) (xy 126.427982 -409.000978) (xy 126.466071 -408.945345)
			(xy 126.487936 -408.91968) (xy 126.493728 -408.912532) (xy 126.500245 -408.895343) (xy 126.500636 -408.886152)
			(xy 126.500636 -408.728672) (xy 126.500994 -408.718543) (xy 126.508758 -408.699832) (xy 126.523093 -408.685517)
			(xy 126.541815 -408.67778) (xy 126.551944 -408.677364) (xy 127.268224 -408.677364) (xy 127.27833 -408.677864)
			(xy 127.297002 -408.685603) (xy 127.311294 -408.699895) (xy 127.319035 -408.718566) (xy 127.319532 -408.728672)
			(xy 127.319532 -408.886152) (xy 127.31998 -408.895335) (xy 127.326469 -408.912519) (xy 127.332232 -408.91968)
			(xy 127.354107 -408.945336) (xy 127.392193 -409.000973) (xy 127.423341 -409.06077) (xy 127.447103 -409.123868)
			(xy 127.463137 -409.189358) (xy 127.471211 -409.256297) (xy 127.47121 -409.323721) (xy 127.463134 -409.39066)
			(xy 127.447098 -409.456149) (xy 127.423334 -409.519246) (xy 127.420948 -409.523827) (xy 128.549082 -409.523827)
			(xy 128.549085 -409.456519) (xy 128.557133 -409.389693) (xy 128.573111 -409.324308) (xy 128.59679 -409.261302)
			(xy 128.627829 -409.201578) (xy 128.665785 -409.145991) (xy 128.687576 -409.12034) (xy 128.693378 -409.113198)
			(xy 128.69989 -409.096005) (xy 128.700276 -409.086812) (xy 128.700276 -408.593544) (xy 128.69985 -408.584358)
			(xy 128.693348 -408.567174) (xy 128.687576 -408.560016) (xy 128.665779 -408.534371) (xy 128.627828 -408.478784)
			(xy 128.596793 -408.41906) (xy 128.573119 -408.356055) (xy 128.557146 -408.290671) (xy 128.549102 -408.223847)
			(xy 128.549103 -408.156541) (xy 128.557148 -408.089717) (xy 128.573123 -408.024334) (xy 128.596798 -407.961329)
			(xy 128.627835 -407.901605) (xy 128.665787 -407.84602) (xy 128.687576 -407.820368) (xy 128.693366 -407.813218)
			(xy 128.699885 -407.796031) (xy 128.700276 -407.78684) (xy 128.700276 -407.628852) (xy 128.700745 -407.618743)
			(xy 128.708494 -407.600069) (xy 128.722795 -407.585776) (xy 128.741475 -407.578039) (xy 128.751584 -407.577544)
			(xy 129.468118 -407.577544) (xy 129.478246 -407.578012) (xy 129.496969 -407.585746) (xy 129.511325 -407.600038)
			(xy 129.519143 -407.618726) (xy 129.51968 -407.628852) (xy 129.51968 -407.78684) (xy 129.520075 -407.796029)
			(xy 129.5266 -407.813213) (xy 129.53238 -407.820368) (xy 129.554159 -407.846027) (xy 129.592107 -407.901613)
			(xy 129.62314 -407.961336) (xy 129.646812 -408.024339) (xy 129.662785 -408.08972) (xy 129.67083 -408.156542)
			(xy 129.67083 -408.223846) (xy 129.662787 -408.290668) (xy 129.646816 -408.356049) (xy 129.623145 -408.419053)
			(xy 129.592113 -408.478777) (xy 129.554167 -408.534364) (xy 129.53238 -408.560016) (xy 129.526592 -408.567167)
			(xy 129.520073 -408.584353) (xy 129.51968 -408.593544) (xy 129.51968 -409.086812) (xy 129.520089 -409.095999)
			(xy 129.526604 -409.113183) (xy 129.53238 -409.12034) (xy 129.554131 -409.146022) (xy 129.59208 -409.201604)
			(xy 129.623114 -409.261324) (xy 129.646788 -409.324325) (xy 129.662763 -409.389703) (xy 129.670809 -409.456522)
			(xy 129.670813 -409.523824) (xy 129.662772 -409.590644) (xy 129.646804 -409.656024) (xy 129.623136 -409.719026)
			(xy 129.592108 -409.778749) (xy 129.554165 -409.834335) (xy 129.53238 -409.859988) (xy 129.526561 -409.867117)
			(xy 129.52006 -409.88432) (xy 129.51968 -409.893516) (xy 129.51968 -410.051504) (xy 129.519287 -410.061629)
			(xy 129.511534 -410.080337) (xy 129.49721 -410.094651) (xy 129.478497 -410.102393) (xy 129.468372 -410.102812)
			(xy 128.751838 -410.102812) (xy 128.74172 -410.102244) (xy 128.72301 -410.094538) (xy 128.708654 -410.080277)
			(xy 128.700824 -410.061618) (xy 128.700276 -410.051504) (xy 128.700276 -409.893516) (xy 128.699864 -409.884329)
			(xy 128.693352 -409.867144) (xy 128.687576 -409.859988) (xy 128.665751 -409.834366) (xy 128.627801 -409.778776)
			(xy 128.596768 -409.719048) (xy 128.573095 -409.65604) (xy 128.557124 -409.590654) (xy 128.549082 -409.523827)
			(xy 127.420948 -409.523827) (xy 127.392184 -409.579043) (xy 127.354096 -409.634678) (xy 127.332232 -409.660344)
			(xy 127.326426 -409.667482) (xy 127.319919 -409.684678) (xy 127.319532 -409.693872) (xy 127.319532 -410.186124)
			(xy 127.319946 -410.19531) (xy 127.326459 -410.212494) (xy 127.332232 -410.219652) (xy 127.354079 -410.245331)
			(xy 127.392166 -410.300964) (xy 127.423316 -410.360759) (xy 127.44708 -410.423854) (xy 127.463115 -410.489341)
			(xy 127.471192 -410.556277) (xy 127.471193 -410.623641) (xy 130.749257 -410.623641) (xy 130.749258 -410.556335)
			(xy 130.757303 -410.489512) (xy 130.773278 -410.424129) (xy 130.796952 -410.361123) (xy 130.827986 -410.301399)
			(xy 130.865936 -410.245812) (xy 130.887724 -410.22016) (xy 130.893523 -410.213017) (xy 130.900035 -410.195825)
			(xy 130.900424 -410.186632) (xy 130.900424 -409.693364) (xy 130.900026 -409.684176) (xy 130.893503 -409.666992)
			(xy 130.887724 -409.659836) (xy 130.865948 -409.634174) (xy 130.828 -409.578589) (xy 130.796967 -409.518866)
			(xy 130.773294 -409.455863) (xy 130.757321 -409.390482) (xy 130.749276 -409.323661) (xy 130.749275 -409.256357)
			(xy 130.757318 -409.189536) (xy 130.773289 -409.124154) (xy 130.79696 -409.06115) (xy 130.827991 -409.001427)
			(xy 130.865937 -408.94584) (xy 130.887724 -408.920188) (xy 130.893511 -408.913036) (xy 130.900031 -408.895851)
			(xy 130.900424 -408.88666) (xy 130.900424 -408.728672) (xy 130.900799 -408.718513) (xy 130.908608 -408.699755)
			(xy 130.92302 -408.685432) (xy 130.941825 -408.677738) (xy 130.951986 -408.677364) (xy 131.668266 -408.677364)
			(xy 131.678393 -408.677855) (xy 131.697118 -408.685576) (xy 131.711477 -408.699862) (xy 131.719293 -408.718547)
			(xy 131.719828 -408.728672) (xy 131.719828 -408.88666) (xy 131.720251 -408.895846) (xy 131.726755 -408.913031)
			(xy 131.732528 -408.920188) (xy 131.754328 -408.94583) (xy 131.792279 -409.001417) (xy 131.823314 -409.061142)
			(xy 131.846987 -409.124148) (xy 131.86296 -409.189532) (xy 131.871004 -409.256356) (xy 131.871003 -409.323662)
			(xy 131.862957 -409.390486) (xy 131.846982 -409.45587) (xy 131.823306 -409.518875) (xy 131.79227 -409.578598)
			(xy 131.754317 -409.634184) (xy 131.732528 -409.659836) (xy 131.726725 -409.666976) (xy 131.720216 -409.684171)
			(xy 131.719828 -409.693364) (xy 131.719828 -410.186632) (xy 131.720217 -410.195822) (xy 131.726745 -410.213006)
			(xy 131.732528 -410.22016) (xy 131.754301 -410.245825) (xy 131.792252 -410.301409) (xy 131.823288 -410.36113)
			(xy 131.846963 -410.424133) (xy 131.862938 -410.489514) (xy 131.870984 -410.556336) (xy 131.870986 -410.62364)
			(xy 131.862943 -410.690462) (xy 131.84697 -410.755844) (xy 131.823298 -410.818848) (xy 131.792265 -410.878571)
			(xy 131.754316 -410.934156) (xy 131.732528 -410.959808) (xy 131.726737 -410.966957) (xy 131.720221 -410.984145)
			(xy 131.719828 -410.993336) (xy 131.719828 -411.151324) (xy 131.719399 -411.161476) (xy 131.7116 -411.180224)
			(xy 131.697207 -411.194545) (xy 131.67842 -411.202249) (xy 131.668266 -411.202632) (xy 130.951986 -411.202632)
			(xy 130.941855 -411.202184) (xy 130.923128 -411.194446) (xy 130.908772 -411.180148) (xy 130.900958 -411.161453)
			(xy 130.900424 -411.151324) (xy 130.900424 -410.993336) (xy 130.899991 -410.984151) (xy 130.893493 -410.966967)
			(xy 130.887724 -410.959808) (xy 130.865921 -410.934169) (xy 130.827974 -410.87858) (xy 130.796942 -410.818855)
			(xy 130.773271 -410.755848) (xy 130.757299 -410.690465) (xy 130.749257 -410.623641) (xy 127.471193 -410.623641)
			(xy 127.471193 -410.623699) (xy 127.463119 -410.690635) (xy 127.447087 -410.756123) (xy 127.423326 -410.819219)
			(xy 127.392179 -410.879015) (xy 127.354094 -410.93465) (xy 127.332232 -410.960316) (xy 127.326438 -410.967463)
			(xy 127.319924 -410.984652) (xy 127.319532 -410.993844) (xy 127.319532 -411.151324) (xy 127.319035 -411.16143)
			(xy 127.311296 -411.180103) (xy 127.297003 -411.194396) (xy 127.27833 -411.202135) (xy 127.268224 -411.202632)
			(xy 126.551944 -411.202632) (xy 126.541828 -411.202149) (xy 126.523132 -411.194421) (xy 126.508817 -411.180125)
			(xy 126.501065 -411.161439) (xy 126.500636 -411.151324) (xy 126.500636 -410.993844) (xy 126.500196 -410.98466)
			(xy 126.493702 -410.967476) (xy 126.487936 -410.960316) (xy 126.466055 -410.934664) (xy 126.427964 -410.879029)
			(xy 126.396812 -410.819231) (xy 126.373048 -410.756132) (xy 126.357012 -410.690641) (xy 126.348937 -410.623701)
			(xy 123.070891 -410.623701) (xy 123.062855 -410.690462) (xy 123.046883 -410.755843) (xy 123.023211 -410.818847)
			(xy 122.992179 -410.87857) (xy 122.954231 -410.934156) (xy 122.932444 -410.959808) (xy 122.926655 -410.966958)
			(xy 122.920137 -410.984145) (xy 122.919744 -410.993336) (xy 122.919744 -411.151324) (xy 122.919236 -411.161429)
			(xy 122.911498 -411.180099) (xy 122.897209 -411.194392) (xy 122.878541 -411.202133) (xy 122.868436 -411.202632)
			(xy 122.151902 -411.202632) (xy 122.141772 -411.202171) (xy 122.123046 -411.194439) (xy 122.108688 -411.180144)
			(xy 122.100874 -411.161452) (xy 122.10034 -411.151324) (xy 122.10034 -410.993336) (xy 122.099903 -410.984152)
			(xy 122.093407 -410.966968) (xy 122.08764 -410.959808) (xy 122.065836 -410.934169) (xy 122.027888 -410.878581)
			(xy 121.996855 -410.818855) (xy 121.973183 -410.755849) (xy 121.957211 -410.690465) (xy 121.949169 -410.623641)
			(xy 118.67113 -410.623641) (xy 118.67113 -410.6237) (xy 118.663055 -410.690638) (xy 118.647019 -410.756127)
			(xy 118.623255 -410.819223) (xy 118.592103 -410.879018) (xy 118.554013 -410.934652) (xy 118.532148 -410.960316)
			(xy 118.526356 -410.967464) (xy 118.51984 -410.984653) (xy 118.519448 -410.993844) (xy 118.519448 -411.151324)
			(xy 118.518936 -411.161428) (xy 118.511199 -411.180098) (xy 118.496911 -411.19439) (xy 118.478244 -411.202133)
			(xy 118.46814 -411.202632) (xy 117.75186 -411.202632) (xy 117.741753 -411.202148) (xy 117.72308 -411.194404)
			(xy 117.708787 -411.180107) (xy 117.701048 -411.161431) (xy 117.700552 -411.151324) (xy 117.700552 -410.993844)
			(xy 117.700109 -410.984661) (xy 117.693617 -410.967477) (xy 117.687852 -410.960316) (xy 117.66597 -410.934665)
			(xy 117.627879 -410.879029) (xy 117.596726 -410.819232) (xy 117.57296 -410.756133) (xy 117.556924 -410.690642)
			(xy 117.548849 -410.623701) (xy 92.270837 -410.623701) (xy 92.262802 -410.69046) (xy 92.246832 -410.755841)
			(xy 92.223163 -410.818845) (xy 92.192134 -410.878568) (xy 92.154189 -410.934155) (xy 92.132404 -410.959808)
			(xy 92.126622 -410.966964) (xy 92.120098 -410.984146) (xy 92.119704 -410.993336) (xy 92.119704 -411.151324)
			(xy 92.119298 -411.161479) (xy 92.111495 -411.180231) (xy 92.097094 -411.194554) (xy 92.078299 -411.202253)
			(xy 92.068142 -411.202632) (xy 91.351862 -411.202632) (xy 91.341729 -411.202204) (xy 91.323002 -411.194458)
			(xy 91.308646 -411.180154) (xy 91.300833 -411.161455) (xy 91.3003 -411.151324) (xy 91.3003 -410.993336)
			(xy 91.299873 -410.984151) (xy 91.293371 -410.966966) (xy 91.2876 -410.959808) (xy 91.265798 -410.934168)
			(xy 91.227852 -410.878579) (xy 91.196822 -410.818853) (xy 91.173151 -410.755847) (xy 91.157181 -410.690464)
			(xy 91.149138 -410.623641) (xy 87.871075 -410.623641) (xy 87.871075 -410.623699) (xy 87.863001 -410.690636)
			(xy 87.846967 -410.756124) (xy 87.823205 -410.81922) (xy 87.792057 -410.879016) (xy 87.753971 -410.934651)
			(xy 87.732108 -410.960316) (xy 87.726323 -410.96747) (xy 87.719801 -410.984654) (xy 87.719408 -410.993844)
			(xy 87.719408 -411.151324) (xy 87.718935 -411.161433) (xy 87.711191 -411.180111) (xy 87.69689 -411.194404)
			(xy 87.67821 -411.20214) (xy 87.6681 -411.202632) (xy 86.95182 -411.202632) (xy 86.941716 -411.202099)
			(xy 86.923045 -411.194374) (xy 86.90875 -411.180092) (xy 86.901009 -411.161427) (xy 86.900512 -411.151324)
			(xy 86.900512 -410.993844) (xy 86.900078 -410.984659) (xy 86.893581 -410.967475) (xy 86.887812 -410.960316)
			(xy 86.865932 -410.934664) (xy 86.827843 -410.879028) (xy 86.796692 -410.81923) (xy 86.772928 -410.756131)
			(xy 86.756894 -410.69064) (xy 86.748819 -410.623701) (xy 83.470773 -410.623701) (xy 83.462736 -410.690462)
			(xy 83.446764 -410.755844) (xy 83.423091 -410.818848) (xy 83.392058 -410.878571) (xy 83.354108 -410.934156)
			(xy 83.33232 -410.959808) (xy 83.32654 -410.966965) (xy 83.320015 -410.984146) (xy 83.31962 -410.993336)
			(xy 83.31962 -411.151324) (xy 83.319199 -411.161477) (xy 83.311399 -411.180226) (xy 83.297003 -411.194548)
			(xy 83.278213 -411.202251) (xy 83.268058 -411.202632) (xy 82.551778 -411.202632) (xy 82.541646 -411.202191)
			(xy 82.522919 -411.194451) (xy 82.508563 -411.18015) (xy 82.500749 -411.161454) (xy 82.500216 -411.151324)
			(xy 82.500216 -410.993336) (xy 82.499785 -410.984151) (xy 82.493285 -410.966967) (xy 82.487516 -410.959808)
			(xy 82.465713 -410.934169) (xy 82.427766 -410.87858) (xy 82.396735 -410.818854) (xy 82.373064 -410.755848)
			(xy 82.357093 -410.690465) (xy 82.349051 -410.623641) (xy 79.070987 -410.623641) (xy 79.070987 -410.623699)
			(xy 79.062913 -410.690636) (xy 79.04688 -410.756124) (xy 79.023119 -410.81922) (xy 78.991971 -410.879016)
			(xy 78.953886 -410.93465) (xy 78.932024 -410.960316) (xy 78.926241 -410.967471) (xy 78.919717 -410.984654)
			(xy 78.919324 -410.993844) (xy 78.919324 -411.151324) (xy 78.918835 -411.161431) (xy 78.911094 -411.180106)
			(xy 78.896799 -411.194399) (xy 78.878123 -411.202137) (xy 78.868016 -411.202632) (xy 78.151736 -411.202632)
			(xy 78.14162 -411.202155) (xy 78.122923 -411.194425) (xy 78.108609 -411.180127) (xy 78.100857 -411.16144)
			(xy 78.100428 -411.151324) (xy 78.100428 -410.993844) (xy 78.09999 -410.98466) (xy 78.093495 -410.967476)
			(xy 78.087728 -410.960316) (xy 78.065847 -410.934664) (xy 78.027757 -410.879028) (xy 77.996606 -410.819231)
			(xy 77.972841 -410.756132) (xy 77.956806 -410.690641) (xy 77.948731 -410.623701) (xy 74.670685 -410.623701)
			(xy 74.662649 -410.690462) (xy 74.646677 -410.755844) (xy 74.623005 -410.818848) (xy 74.591972 -410.87857)
			(xy 74.554023 -410.934156) (xy 74.532236 -410.959808) (xy 74.526446 -410.966957) (xy 74.519929 -410.984145)
			(xy 74.519536 -410.993336) (xy 74.519536 -411.151324) (xy 74.519099 -411.161475) (xy 74.511302 -411.180221)
			(xy 74.496911 -411.194542) (xy 74.478127 -411.202248) (xy 74.467974 -411.202632) (xy 73.751694 -411.202632)
			(xy 73.741563 -411.202177) (xy 73.722837 -411.194442) (xy 73.70848 -411.180146) (xy 73.700666 -411.161452)
			(xy 73.700132 -411.151324) (xy 73.700132 -410.993336) (xy 73.699697 -410.984152) (xy 73.6932 -410.966967)
			(xy 73.687432 -410.959808) (xy 73.665629 -410.934169) (xy 73.627681 -410.87858) (xy 73.596649 -410.818855)
			(xy 73.572977 -410.755849) (xy 73.557005 -410.690465) (xy 73.548963 -410.623641) (xy 66.525648 -410.623641)
			(xy 66.525648 -417.289488) (xy 66.525648 -417.371276) (xy 141.02334 -417.371276) (xy 141.02334 -394.305282)
			(xy 141.023796 -394.293166) (xy 141.031289 -394.270122) (xy 141.045535 -394.25052) (xy 141.06514 -394.23628)
			(xy 141.088186 -394.228793) (xy 141.100302 -394.22832) (xy 154.426158 -394.22832) (xy 154.57678 -394.378688)
			(xy 154.57678 -397.823825) (xy 159.349135 -397.823825) (xy 159.349138 -397.756518) (xy 159.357186 -397.689693)
			(xy 159.373162 -397.624309) (xy 159.396838 -397.561303) (xy 159.427875 -397.501578) (xy 159.465827 -397.44599)
			(xy 159.487616 -397.420338) (xy 159.493423 -397.4132) (xy 159.499931 -397.396004) (xy 159.500316 -397.38681)
			(xy 159.500316 -396.893542) (xy 159.499882 -396.884357) (xy 159.493384 -396.867173) (xy 159.487616 -396.860014)
			(xy 159.465819 -396.83437) (xy 159.427872 -396.778782) (xy 159.396841 -396.719057) (xy 159.373169 -396.656051)
			(xy 159.357198 -396.590668) (xy 159.349155 -396.523845) (xy 159.349156 -396.45654) (xy 159.3572 -396.389717)
			(xy 159.373174 -396.324334) (xy 159.396847 -396.26133) (xy 159.42788 -396.201606) (xy 159.465828 -396.146018)
			(xy 159.487616 -396.120366) (xy 159.493411 -396.11322) (xy 159.499926 -396.09603) (xy 159.500316 -396.086838)
			(xy 159.500316 -395.92885) (xy 159.500804 -395.918684) (xy 159.508569 -395.899895) (xy 159.522934 -395.885509)
			(xy 159.541713 -395.877718) (xy 159.551878 -395.877288) (xy 160.268158 -395.877288) (xy 160.278333 -395.877699)
			(xy 160.297136 -395.88548) (xy 160.311525 -395.89987) (xy 160.319302 -395.918675) (xy 160.31972 -395.92885)
			(xy 160.31972 -396.086838) (xy 160.320108 -396.096028) (xy 160.326637 -396.113212) (xy 160.33242 -396.120366)
			(xy 160.354199 -396.146026) (xy 160.392151 -396.20161) (xy 160.423187 -396.261332) (xy 160.446862 -396.324336)
			(xy 160.462837 -396.389718) (xy 160.470882 -396.45654) (xy 160.470883 -396.523845) (xy 160.46284 -396.590668)
			(xy 160.446866 -396.65605) (xy 160.423193 -396.719054) (xy 160.392159 -396.778777) (xy 160.354208 -396.834362)
			(xy 160.33242 -396.860014) (xy 160.326637 -396.867169) (xy 160.320114 -396.884352) (xy 160.31972 -396.893542)
			(xy 160.31972 -397.38681) (xy 160.320121 -397.395998) (xy 160.326641 -397.413183) (xy 160.33242 -397.420338)
			(xy 160.354172 -397.44602) (xy 160.392124 -397.501601) (xy 160.420549 -397.556296) (xy 161.5488 -397.556296)
			(xy 161.556874 -397.489359) (xy 161.572908 -397.423871) (xy 161.596669 -397.360775) (xy 161.627817 -397.300979)
			(xy 161.665902 -397.245344) (xy 161.687764 -397.219678) (xy 161.69356 -397.212533) (xy 161.700073 -397.195342)
			(xy 161.700464 -397.18615) (xy 161.700464 -397.028924) (xy 161.701004 -397.018821) (xy 161.708727 -397.00015)
			(xy 161.723007 -396.985856) (xy 161.74167 -396.978114) (xy 161.751772 -396.977616) (xy 162.468052 -396.977616)
			(xy 162.478173 -396.978056) (xy 162.496879 -396.985791) (xy 162.511195 -397.000101) (xy 162.51894 -397.018803)
			(xy 162.51936 -397.028924) (xy 162.51936 -397.18615) (xy 162.519803 -397.195333) (xy 162.526295 -397.212518)
			(xy 162.53206 -397.219678) (xy 162.553935 -397.245334) (xy 162.592026 -397.300969) (xy 162.623179 -397.360766)
			(xy 162.646944 -397.423864) (xy 162.66298 -397.489355) (xy 162.671056 -397.556295) (xy 162.671055 -397.62372)
			(xy 162.662977 -397.69066) (xy 162.64694 -397.75615) (xy 162.623173 -397.819247) (xy 162.620757 -397.823885)
			(xy 163.748903 -397.823885) (xy 163.748907 -397.756458) (xy 163.756987 -397.689517) (xy 163.773027 -397.624026)
			(xy 163.796796 -397.560927) (xy 163.827951 -397.50113) (xy 163.866045 -397.445495) (xy 163.887912 -397.41983)
			(xy 163.893722 -397.412694) (xy 163.900228 -397.395497) (xy 163.900612 -397.386302) (xy 163.900612 -396.89405)
			(xy 163.900175 -396.884866) (xy 163.89368 -396.867681) (xy 163.887912 -396.860522) (xy 163.866038 -396.834865)
			(xy 163.827949 -396.77923) (xy 163.796798 -396.719432) (xy 163.773034 -396.656334) (xy 163.756998 -396.590844)
			(xy 163.748923 -396.523905) (xy 163.748924 -396.45648) (xy 163.757001 -396.389541) (xy 163.773038 -396.324051)
			(xy 163.796804 -396.260954) (xy 163.827956 -396.201157) (xy 163.866047 -396.145523) (xy 163.887912 -396.119858)
			(xy 163.89371 -396.112714) (xy 163.900224 -396.095523) (xy 163.900612 -396.08633) (xy 163.900612 -395.92885)
			(xy 163.901167 -395.91873) (xy 163.908873 -395.900015) (xy 163.923138 -395.885658) (xy 163.941803 -395.877832)
			(xy 163.95192 -395.877288) (xy 164.6682 -395.877288) (xy 164.678353 -395.877721) (xy 164.697103 -395.885515)
			(xy 164.711426 -395.899908) (xy 164.719127 -395.918695) (xy 164.719508 -395.92885) (xy 164.719508 -396.08633)
			(xy 164.719902 -396.095519) (xy 164.726426 -396.112703) (xy 164.732208 -396.119858) (xy 164.754062 -396.145531)
			(xy 164.79215 -396.201165) (xy 164.823301 -396.26096) (xy 164.847065 -396.324056) (xy 164.863101 -396.389544)
			(xy 164.871178 -396.456481) (xy 164.871179 -396.523904) (xy 164.863104 -396.590841) (xy 164.84707 -396.65633)
			(xy 164.823307 -396.719426) (xy 164.792158 -396.779222) (xy 164.754071 -396.834857) (xy 164.732208 -396.860522)
			(xy 164.726421 -396.867674) (xy 164.7199 -396.884859) (xy 164.719508 -396.89405) (xy 164.719508 -397.386302)
			(xy 164.719915 -397.395489) (xy 164.726431 -397.412674) (xy 164.732208 -397.41983) (xy 164.754034 -397.445526)
			(xy 164.792124 -397.501156) (xy 164.823276 -397.560948) (xy 164.846898 -397.62366) (xy 165.949096 -397.62366)
			(xy 165.949096 -397.556355) (xy 165.957139 -397.489533) (xy 165.973111 -397.424151) (xy 165.996783 -397.361147)
			(xy 166.027816 -397.301424) (xy 166.065765 -397.245838) (xy 166.087552 -397.220186) (xy 166.093343 -397.213037)
			(xy 166.09986 -397.195849) (xy 166.100252 -397.186658) (xy 166.100252 -397.028924) (xy 166.10074 -397.018777)
			(xy 166.108519 -397.000035) (xy 166.122895 -396.985712) (xy 166.141666 -396.978003) (xy 166.151814 -396.977616)
			(xy 166.868094 -396.977616) (xy 166.878217 -396.978131) (xy 166.896934 -396.985852) (xy 166.911289 -397.000129)
			(xy 166.919113 -397.018803) (xy 166.919656 -397.028924) (xy 166.919656 -397.186658) (xy 166.920096 -397.195842)
			(xy 166.92659 -397.213026) (xy 166.932356 -397.220186) (xy 166.954154 -397.24583) (xy 166.992103 -397.301417)
			(xy 167.023136 -397.361142) (xy 167.046808 -397.424148) (xy 167.062781 -397.489531) (xy 167.070824 -397.556355)
			(xy 167.070823 -397.62366) (xy 167.062778 -397.690484) (xy 167.046804 -397.755867) (xy 167.02313 -397.818872)
			(xy 167.020556 -397.823825) (xy 168.149223 -397.823825) (xy 168.149226 -397.756518) (xy 168.157274 -397.689693)
			(xy 168.17325 -397.624309) (xy 168.196925 -397.561304) (xy 168.22796 -397.501579) (xy 168.265911 -397.445991)
			(xy 168.2877 -397.420338) (xy 168.293505 -397.413199) (xy 168.300015 -397.396004) (xy 168.3004 -397.38681)
			(xy 168.3004 -396.893542) (xy 168.29997 -396.884357) (xy 168.29347 -396.867172) (xy 168.2877 -396.860014)
			(xy 168.265904 -396.834369) (xy 168.227958 -396.778781) (xy 168.196927 -396.719056) (xy 168.173256 -396.656051)
			(xy 168.157285 -396.590668) (xy 168.149243 -396.523845) (xy 168.149244 -396.45654) (xy 168.157288 -396.389717)
			(xy 168.173261 -396.324335) (xy 168.196933 -396.26133) (xy 168.227965 -396.201606) (xy 168.265913 -396.146019)
			(xy 168.2877 -396.120366) (xy 168.293494 -396.113219) (xy 168.30001 -396.09603) (xy 168.3004 -396.086838)
			(xy 168.3004 -395.92885) (xy 168.300904 -395.918686) (xy 168.308665 -395.8999) (xy 168.323026 -395.885515)
			(xy 168.341799 -395.877721) (xy 168.351962 -395.877288) (xy 169.068242 -395.877288) (xy 169.078423 -395.877631)
			(xy 169.097228 -395.885439) (xy 169.111613 -395.89985) (xy 169.119388 -395.918669) (xy 169.119804 -395.92885)
			(xy 169.119804 -396.086838) (xy 169.120195 -396.096027) (xy 169.126722 -396.113212) (xy 169.132504 -396.120366)
			(xy 169.154281 -396.146027) (xy 169.192227 -396.201613) (xy 169.223258 -396.261336) (xy 169.24693 -396.324339)
			(xy 169.262902 -396.38972) (xy 169.270946 -396.456541) (xy 169.270947 -396.523844) (xy 169.262905 -396.590665)
			(xy 169.246934 -396.656047) (xy 169.223264 -396.71905) (xy 169.192235 -396.778774) (xy 169.15429 -396.834361)
			(xy 169.132504 -396.860014) (xy 169.126719 -396.867168) (xy 169.120197 -396.884352) (xy 169.119804 -396.893542)
			(xy 169.119804 -397.38681) (xy 169.120209 -397.395998) (xy 169.126726 -397.413182) (xy 169.132504 -397.420338)
			(xy 169.154253 -397.446021) (xy 169.1922 -397.501604) (xy 169.22062 -397.556296) (xy 170.348863 -397.556296)
			(xy 170.356939 -397.489357) (xy 170.372975 -397.423868) (xy 170.39674 -397.360771) (xy 170.427892 -397.300976)
			(xy 170.465983 -397.245342) (xy 170.487848 -397.219678) (xy 170.493642 -397.212531) (xy 170.500157 -397.195342)
			(xy 170.500548 -397.18615) (xy 170.500548 -397.028924) (xy 170.501103 -397.018823) (xy 170.508823 -397.000155)
			(xy 170.523098 -396.985862) (xy 170.541756 -396.978117) (xy 170.551856 -396.977616) (xy 171.268136 -396.977616)
			(xy 171.278249 -396.978056) (xy 171.296931 -396.985808) (xy 171.311225 -397.000119) (xy 171.318956 -397.01881)
			(xy 171.319444 -397.028924) (xy 171.319444 -397.18615) (xy 171.319891 -397.195333) (xy 171.326381 -397.212517)
			(xy 171.332144 -397.219678) (xy 171.35402 -397.245334) (xy 171.392112 -397.300969) (xy 171.423265 -397.360766)
			(xy 171.447031 -397.423864) (xy 171.463068 -397.489355) (xy 171.471144 -397.556295) (xy 171.471143 -397.62372)
			(xy 171.463065 -397.69066) (xy 171.447027 -397.756151) (xy 171.423259 -397.819248) (xy 171.420874 -397.823826)
			(xy 172.54899 -397.823826) (xy 172.548993 -397.756517) (xy 172.557042 -397.689691) (xy 172.57302 -397.624306)
			(xy 172.5967 -397.5613) (xy 172.62774 -397.501575) (xy 172.665697 -397.44599) (xy 172.687488 -397.420338)
			(xy 172.693292 -397.413198) (xy 172.699803 -397.396004) (xy 172.700188 -397.38681) (xy 172.700188 -396.893542)
			(xy 172.69976 -396.884357) (xy 172.693259 -396.867172) (xy 172.687488 -396.860014) (xy 172.665689 -396.834371)
			(xy 172.627737 -396.778784) (xy 172.596702 -396.71906) (xy 172.573027 -396.656054) (xy 172.557054 -396.59067)
			(xy 172.54901 -396.523846) (xy 172.54901 -396.456539) (xy 172.557056 -396.389715) (xy 172.573032 -396.324332)
			(xy 172.596708 -396.261327) (xy 172.627745 -396.201603) (xy 172.665698 -396.146018) (xy 172.687488 -396.120366)
			(xy 172.69328 -396.113218) (xy 172.699798 -396.09603) (xy 172.700188 -396.086838) (xy 172.700188 -395.92885)
			(xy 172.700606 -395.918675) (xy 172.708384 -395.899872) (xy 172.722772 -395.885484) (xy 172.741575 -395.877706)
			(xy 172.75175 -395.877288) (xy 173.46803 -395.877288) (xy 173.47821 -395.87764) (xy 173.497015 -395.885445)
			(xy 173.5114 -395.899852) (xy 173.519175 -395.91867) (xy 173.519592 -395.92885) (xy 173.519592 -396.086838)
			(xy 173.519986 -396.096027) (xy 173.526511 -396.113211) (xy 173.532292 -396.120366) (xy 173.554069 -396.146027)
			(xy 173.592016 -396.201613) (xy 173.623048 -396.261335) (xy 173.64672 -396.324339) (xy 173.662693 -396.389719)
			(xy 173.670737 -396.456541) (xy 173.670738 -396.523844) (xy 173.662695 -396.590666) (xy 173.646725 -396.656047)
			(xy 173.623054 -396.719051) (xy 173.592024 -396.778774) (xy 173.554078 -396.834361) (xy 173.532292 -396.860014)
			(xy 173.526506 -396.867167) (xy 173.519985 -396.884351) (xy 173.519592 -396.893542) (xy 173.519592 -397.38681)
			(xy 173.519999 -397.395998) (xy 173.526515 -397.413182) (xy 173.532292 -397.420338) (xy 173.554041 -397.446021)
			(xy 173.591989 -397.501604) (xy 173.620441 -397.556355) (xy 174.749183 -397.556355) (xy 174.757226 -397.489534)
			(xy 174.773198 -397.424152) (xy 174.796869 -397.361148) (xy 174.827901 -397.301424) (xy 174.865849 -397.245838)
			(xy 174.887636 -397.220186) (xy 174.893426 -397.213036) (xy 174.899944 -397.195849) (xy 174.900336 -397.186658)
			(xy 174.900336 -397.028924) (xy 174.900742 -397.018767) (xy 174.908536 -397.000008) (xy 174.922939 -396.985682)
			(xy 174.941739 -396.977988) (xy 174.951898 -396.977616) (xy 175.668178 -396.977616) (xy 175.6783 -396.978144)
			(xy 175.697017 -396.98586) (xy 175.711373 -397.000133) (xy 175.719197 -397.018805) (xy 175.71974 -397.028924)
			(xy 175.71974 -397.186658) (xy 175.720184 -397.195841) (xy 175.726675 -397.213025) (xy 175.73244 -397.220186)
			(xy 175.754238 -397.24583) (xy 175.792188 -397.301417) (xy 175.823222 -397.361142) (xy 175.846895 -397.424147)
			(xy 175.862868 -397.489531) (xy 175.870912 -397.556354) (xy 175.870911 -397.623661) (xy 175.862865 -397.690484)
			(xy 175.846891 -397.755867) (xy 175.823216 -397.818872) (xy 175.79218 -397.878596) (xy 175.754229 -397.934182)
			(xy 175.73244 -397.959834) (xy 175.726639 -397.966976) (xy 175.720129 -397.984169) (xy 175.71974 -397.993362)
			(xy 175.71974 -398.486884) (xy 175.720171 -398.496069) (xy 175.726672 -398.513253) (xy 175.73244 -398.520412)
			(xy 175.754264 -398.546035) (xy 175.792213 -398.601625) (xy 175.823246 -398.661352) (xy 175.846918 -398.724361)
			(xy 175.862889 -398.789747) (xy 175.87093 -398.856573) (xy 175.870927 -398.923881) (xy 175.862879 -398.990707)
			(xy 175.846902 -399.056091) (xy 175.823224 -399.119097) (xy 175.792185 -399.178822) (xy 175.754231 -399.234408)
			(xy 175.73244 -399.26006) (xy 175.726628 -399.267194) (xy 175.720124 -399.284393) (xy 175.71974 -399.293588)
			(xy 175.71974 -399.451576) (xy 175.71926 -399.461724) (xy 175.71148 -399.480468) (xy 175.697101 -399.494791)
			(xy 175.678327 -399.502498) (xy 175.668178 -399.502884) (xy 174.951898 -399.502884) (xy 174.941774 -399.502376)
			(xy 174.923058 -399.494652) (xy 174.908702 -399.480372) (xy 174.900879 -399.461697) (xy 174.900336 -399.451576)
			(xy 174.900336 -399.293588) (xy 174.899924 -399.284401) (xy 174.893411 -399.267217) (xy 174.887636 -399.26006)
			(xy 174.865884 -399.234379) (xy 174.827934 -399.178796) (xy 174.7969 -399.119077) (xy 174.773225 -399.056076)
			(xy 174.75725 -398.990697) (xy 174.749203 -398.923878) (xy 174.749199 -398.856576) (xy 174.75724 -398.789756)
			(xy 174.773209 -398.724376) (xy 174.796878 -398.661373) (xy 174.827906 -398.60165) (xy 174.865851 -398.546064)
			(xy 174.887636 -398.520412) (xy 174.893457 -398.513284) (xy 174.899956 -398.49608) (xy 174.900336 -398.486884)
			(xy 174.900336 -397.993362) (xy 174.899936 -397.984174) (xy 174.893414 -397.96699) (xy 174.887636 -397.959834)
			(xy 174.865858 -397.934174) (xy 174.827909 -397.878588) (xy 174.796876 -397.818866) (xy 174.773202 -397.755863)
			(xy 174.757229 -397.690481) (xy 174.749184 -397.62366) (xy 174.749183 -397.556355) (xy 173.620441 -397.556355)
			(xy 173.623023 -397.561324) (xy 173.646696 -397.624324) (xy 173.662671 -397.689702) (xy 173.670718 -397.756521)
			(xy 173.670721 -397.823822) (xy 173.662681 -397.890642) (xy 173.646713 -397.956021) (xy 173.623046 -398.019024)
			(xy 173.592019 -398.078747) (xy 173.554077 -398.134334) (xy 173.532292 -398.159986) (xy 173.526475 -398.167117)
			(xy 173.519973 -398.184318) (xy 173.519592 -398.193514) (xy 173.519592 -398.351502) (xy 173.519069 -398.361656)
			(xy 173.511299 -398.38042) (xy 173.496943 -398.394784) (xy 173.478184 -398.402563) (xy 173.46803 -398.403064)
			(xy 172.75175 -398.403064) (xy 172.741582 -398.402595) (xy 172.722789 -398.394827) (xy 172.708402 -398.380455)
			(xy 172.700615 -398.36167) (xy 172.700188 -398.351502) (xy 172.700188 -398.193514) (xy 172.699774 -398.184327)
			(xy 172.693263 -398.167143) (xy 172.687488 -398.159986) (xy 172.665661 -398.134365) (xy 172.627711 -398.078775)
			(xy 172.596676 -398.019048) (xy 172.573004 -397.956039) (xy 172.557032 -397.890653) (xy 172.54899 -397.823826)
			(xy 171.420874 -397.823826) (xy 171.392104 -397.879044) (xy 171.354011 -397.934678) (xy 171.332144 -397.960342)
			(xy 171.32634 -397.967482) (xy 171.319831 -397.984677) (xy 171.319444 -397.99387) (xy 171.319444 -398.486376)
			(xy 171.319878 -398.49556) (xy 171.326376 -398.512744) (xy 171.332144 -398.519904) (xy 171.354045 -398.545539)
			(xy 171.392137 -398.601177) (xy 171.423289 -398.660976) (xy 171.447054 -398.724077) (xy 171.463088 -398.789571)
			(xy 171.471162 -398.856513) (xy 171.471159 -398.923941) (xy 171.463078 -398.990883) (xy 171.447037 -399.056374)
			(xy 171.423267 -399.119473) (xy 171.392109 -399.17927) (xy 171.354012 -399.234904) (xy 171.332144 -399.260568)
			(xy 171.326329 -399.2677) (xy 171.319827 -399.284901) (xy 171.319444 -399.294096) (xy 171.319444 -399.451576)
			(xy 171.318896 -399.461678) (xy 171.311175 -399.480347) (xy 171.296897 -399.494641) (xy 171.278237 -399.502385)
			(xy 171.268136 -399.502884) (xy 170.551856 -399.502884) (xy 170.541742 -399.50245) (xy 170.52306 -399.494695)
			(xy 170.508766 -399.480383) (xy 170.501036 -399.46169) (xy 170.500548 -399.451576) (xy 170.500548 -399.294096)
			(xy 170.500129 -399.28491) (xy 170.49362 -399.267726) (xy 170.487848 -399.260568) (xy 170.466018 -399.234874)
			(xy 170.427925 -399.179245) (xy 170.39677 -399.119453) (xy 170.373001 -399.05636) (xy 170.356962 -398.990874)
			(xy 170.348883 -398.923938) (xy 170.348879 -398.856516) (xy 170.356952 -398.789579) (xy 170.372985 -398.724092)
			(xy 170.396748 -398.660996) (xy 170.427897 -398.601201) (xy 170.465984 -398.545568) (xy 170.487848 -398.519904)
			(xy 170.493631 -398.51275) (xy 170.500153 -398.495566) (xy 170.500548 -398.486376) (xy 170.500548 -397.99387)
			(xy 170.500141 -397.984683) (xy 170.493624 -397.967499) (xy 170.487848 -397.960342) (xy 170.465992 -397.934669)
			(xy 170.4279 -397.879037) (xy 170.396746 -397.819242) (xy 170.372979 -397.756146) (xy 170.356942 -397.690658)
			(xy 170.348864 -397.623719) (xy 170.348863 -397.556296) (xy 169.22062 -397.556296) (xy 169.223233 -397.561324)
			(xy 169.246906 -397.624324) (xy 169.26288 -397.689702) (xy 169.270927 -397.756521) (xy 169.27093 -397.823822)
			(xy 169.26289 -397.890641) (xy 169.246923 -397.956021) (xy 169.223256 -398.019024) (xy 169.19223 -398.078746)
			(xy 169.154288 -398.134333) (xy 169.132504 -398.159986) (xy 169.126689 -398.167118) (xy 169.120185 -398.184319)
			(xy 169.119804 -398.193514) (xy 169.119804 -398.351502) (xy 169.119269 -398.361655) (xy 169.111502 -398.380416)
			(xy 169.097149 -398.394779) (xy 169.078394 -398.402561) (xy 169.068242 -398.403064) (xy 168.351962 -398.403064)
			(xy 168.341802 -398.402598) (xy 168.323032 -398.394811) (xy 168.308669 -398.380437) (xy 168.300895 -398.361662)
			(xy 168.3004 -398.351502) (xy 168.3004 -398.193514) (xy 168.299983 -398.184328) (xy 168.293474 -398.167143)
			(xy 168.2877 -398.159986) (xy 168.265876 -398.134364) (xy 168.227931 -398.078772) (xy 168.196902 -398.019044)
			(xy 168.173233 -397.956036) (xy 168.157263 -397.89065) (xy 168.149223 -397.823825) (xy 167.020556 -397.823825)
			(xy 166.992095 -397.878596) (xy 166.954145 -397.934182) (xy 166.932356 -397.959834) (xy 166.926557 -397.966977)
			(xy 166.920045 -397.984169) (xy 166.919656 -397.993362) (xy 166.919656 -398.486884) (xy 166.920084 -398.496069)
			(xy 166.926586 -398.513253) (xy 166.932356 -398.520412) (xy 166.954179 -398.546035) (xy 166.992127 -398.601625)
			(xy 167.023159 -398.661353) (xy 167.04683 -398.724361) (xy 167.062801 -398.789747) (xy 167.070842 -398.856573)
			(xy 167.070839 -398.923881) (xy 167.062791 -398.990706) (xy 167.046814 -399.05609) (xy 167.023137 -399.119097)
			(xy 166.9921 -399.178821) (xy 166.954146 -399.234408) (xy 166.932356 -399.26006) (xy 166.926546 -399.267195)
			(xy 166.92004 -399.284394) (xy 166.919656 -399.293588) (xy 166.919656 -399.451576) (xy 166.91916 -399.461722)
			(xy 166.911383 -399.480463) (xy 166.89701 -399.494785) (xy 166.878241 -399.502496) (xy 166.868094 -399.502884)
			(xy 166.151814 -399.502884) (xy 166.141691 -399.502363) (xy 166.122975 -399.494644) (xy 166.108619 -399.480369)
			(xy 166.100795 -399.461696) (xy 166.100252 -399.451576) (xy 166.100252 -399.293588) (xy 166.099836 -399.284402)
			(xy 166.093325 -399.267218) (xy 166.087552 -399.26006) (xy 166.065799 -399.234379) (xy 166.027849 -399.178797)
			(xy 165.996813 -399.119077) (xy 165.973138 -399.056077) (xy 165.957162 -398.990698) (xy 165.949115 -398.923878)
			(xy 165.949111 -398.856576) (xy 165.957152 -398.789755) (xy 165.973122 -398.724375) (xy 165.996791 -398.661372)
			(xy 166.027821 -398.60165) (xy 166.065766 -398.546064) (xy 166.087552 -398.520412) (xy 166.093375 -398.513286)
			(xy 166.099872 -398.49608) (xy 166.100252 -398.486884) (xy 166.100252 -397.993362) (xy 166.099848 -397.984174)
			(xy 166.093329 -397.966991) (xy 166.087552 -397.959834) (xy 166.065774 -397.934174) (xy 166.027824 -397.878589)
			(xy 165.99679 -397.818866) (xy 165.973116 -397.755863) (xy 165.957142 -397.690482) (xy 165.949096 -397.62366)
			(xy 164.846898 -397.62366) (xy 164.847042 -397.624041) (xy 164.863079 -397.689526) (xy 164.871158 -397.756461)
			(xy 164.871162 -397.823882) (xy 164.86309 -397.890817) (xy 164.847058 -397.956304) (xy 164.823299 -398.019399)
			(xy 164.792153 -398.079195) (xy 164.754069 -398.134829) (xy 164.732208 -398.160494) (xy 164.726432 -398.167654)
			(xy 164.719905 -398.184833) (xy 164.719508 -398.194022) (xy 164.719508 -398.351502) (xy 164.718976 -398.361623)
			(xy 164.711257 -398.380335) (xy 164.696985 -398.394689) (xy 164.678318 -398.402517) (xy 164.6682 -398.403064)
			(xy 163.95192 -398.403064) (xy 163.941763 -398.402661) (xy 163.923004 -398.394866) (xy 163.908678 -398.380462)
			(xy 163.900984 -398.361662) (xy 163.900612 -398.351502) (xy 163.900612 -398.194022) (xy 163.900188 -398.184836)
			(xy 163.893684 -398.167652) (xy 163.887912 -398.160494) (xy 163.86601 -398.13486) (xy 163.827922 -398.079221)
			(xy 163.796772 -398.019421) (xy 163.77301 -397.95632) (xy 163.756976 -397.890827) (xy 163.748903 -397.823885)
			(xy 162.620757 -397.823885) (xy 162.592019 -397.879044) (xy 162.553926 -397.934677) (xy 162.53206 -397.960342)
			(xy 162.526258 -397.967483) (xy 162.519748 -397.984677) (xy 162.51936 -397.99387) (xy 162.51936 -398.486376)
			(xy 162.51979 -398.495561) (xy 162.526291 -398.512745) (xy 162.53206 -398.519904) (xy 162.553961 -398.545539)
			(xy 162.592051 -398.601177) (xy 162.623202 -398.660977) (xy 162.646966 -398.724078) (xy 162.663 -398.789571)
			(xy 162.671074 -398.856513) (xy 162.671071 -398.923941) (xy 162.662991 -398.990882) (xy 162.64695 -399.056374)
			(xy 162.62318 -399.119472) (xy 162.592023 -399.179269) (xy 162.553928 -399.234903) (xy 162.53206 -399.260568)
			(xy 162.526247 -399.267701) (xy 162.519743 -399.284901) (xy 162.51936 -399.294096) (xy 162.51936 -399.451576)
			(xy 162.518964 -399.461702) (xy 162.511216 -399.480413) (xy 162.496893 -399.494729) (xy 162.478178 -399.502468)
			(xy 162.468052 -399.502884) (xy 161.751772 -399.502884) (xy 161.741659 -399.502438) (xy 161.722978 -399.494688)
			(xy 161.708683 -399.480379) (xy 161.700952 -399.461689) (xy 161.700464 -399.451576) (xy 161.700464 -399.294096)
			(xy 161.700041 -399.28491) (xy 161.693535 -399.267727) (xy 161.687764 -399.260568) (xy 161.665937 -399.234873)
			(xy 161.627849 -399.179242) (xy 161.596699 -399.119449) (xy 161.572934 -399.056357) (xy 161.556897 -398.990871)
			(xy 161.548819 -398.923937) (xy 161.548816 -398.856517) (xy 161.556888 -398.789582) (xy 161.572918 -398.724095)
			(xy 161.596677 -398.661) (xy 161.627821 -398.601205) (xy 161.665903 -398.54557) (xy 161.687764 -398.519904)
			(xy 161.693549 -398.512751) (xy 161.700069 -398.495566) (xy 161.700464 -398.486376) (xy 161.700464 -397.99387)
			(xy 161.700054 -397.984683) (xy 161.693538 -397.9675) (xy 161.687764 -397.960342) (xy 161.665911 -397.934668)
			(xy 161.627824 -397.879034) (xy 161.596675 -397.819239) (xy 161.572912 -397.756143) (xy 161.556877 -397.690655)
			(xy 161.548801 -397.623719) (xy 161.5488 -397.556296) (xy 160.420549 -397.556296) (xy 160.423161 -397.561321)
			(xy 160.446838 -397.624321) (xy 160.462815 -397.6897) (xy 160.470863 -397.75652) (xy 160.470866 -397.823823)
			(xy 160.462825 -397.890644) (xy 160.446855 -397.956024) (xy 160.423185 -398.019027) (xy 160.392154 -398.078749)
			(xy 160.354207 -398.134334) (xy 160.33242 -398.159986) (xy 160.326607 -398.16712) (xy 160.320101 -398.184319)
			(xy 160.31972 -398.193514) (xy 160.31972 -398.351502) (xy 160.319337 -398.361679) (xy 160.311543 -398.380482)
			(xy 160.297145 -398.394868) (xy 160.278335 -398.402645) (xy 160.268158 -398.403064) (xy 159.551878 -398.403064)
			(xy 159.541719 -398.402585) (xy 159.52295 -398.394804) (xy 159.508585 -398.380433) (xy 159.500811 -398.361661)
			(xy 159.500316 -398.351502) (xy 159.500316 -398.193514) (xy 159.499895 -398.184328) (xy 159.493388 -398.167144)
			(xy 159.487616 -398.159986) (xy 159.465792 -398.134364) (xy 159.427845 -398.078773) (xy 159.396815 -398.019045)
			(xy 159.373145 -397.956036) (xy 159.357176 -397.890651) (xy 159.349135 -397.823825) (xy 154.57678 -397.823825)
			(xy 154.57678 -401.723737) (xy 159.349146 -401.723737) (xy 159.349148 -401.65643) (xy 159.357194 -401.589607)
			(xy 159.373169 -401.524223) (xy 159.396843 -401.461218) (xy 159.427878 -401.401494) (xy 159.465828 -401.345906)
			(xy 159.487616 -401.320254) (xy 159.493416 -401.313112) (xy 159.499928 -401.295919) (xy 159.500316 -401.286726)
			(xy 159.500316 -400.793458) (xy 159.499923 -400.784269) (xy 159.493397 -400.767085) (xy 159.487616 -400.75993)
			(xy 159.465835 -400.734273) (xy 159.427887 -400.678686) (xy 159.396855 -400.618963) (xy 159.373183 -400.55596)
			(xy 159.35721 -400.490578) (xy 159.349166 -400.423757) (xy 159.349165 -400.356452) (xy 159.357209 -400.289631)
			(xy 159.37318 -400.224249) (xy 159.396851 -400.161245) (xy 159.427883 -400.101521) (xy 159.465829 -400.045934)
			(xy 159.487616 -400.020282) (xy 159.493405 -400.013131) (xy 159.499923 -399.995945) (xy 159.500316 -399.986754)
			(xy 159.500316 -399.828766) (xy 159.500805 -399.818609) (xy 159.508586 -399.799843) (xy 159.522953 -399.78548)
			(xy 159.541721 -399.777703) (xy 159.551878 -399.777204) (xy 160.268158 -399.777204) (xy 160.278323 -399.777697)
			(xy 160.29711 -399.785462) (xy 160.311495 -399.799826) (xy 160.319288 -399.818602) (xy 160.31972 -399.828766)
			(xy 160.31972 -399.986754) (xy 160.320148 -399.995939) (xy 160.326649 -400.013124) (xy 160.33242 -400.020282)
			(xy 160.354215 -400.045929) (xy 160.392166 -400.101515) (xy 160.423201 -400.161239) (xy 160.446876 -400.224244)
			(xy 160.462849 -400.289628) (xy 160.470894 -400.356451) (xy 160.470893 -400.423758) (xy 160.462848 -400.490581)
			(xy 160.446873 -400.555964) (xy 160.423198 -400.618969) (xy 160.392161 -400.678693) (xy 160.354209 -400.734278)
			(xy 160.33242 -400.75993) (xy 160.326631 -400.76708) (xy 160.320111 -400.784267) (xy 160.31972 -400.793458)
			(xy 160.31972 -401.286726) (xy 160.320113 -401.295915) (xy 160.326638 -401.313099) (xy 160.33242 -401.320254)
			(xy 160.354187 -401.345923) (xy 160.392139 -401.401506) (xy 160.423176 -401.461227) (xy 160.446852 -401.52423)
			(xy 160.462827 -401.58961) (xy 160.470874 -401.656431) (xy 160.470876 -401.723735) (xy 160.462833 -401.790557)
			(xy 160.446862 -401.855939) (xy 160.423189 -401.918943) (xy 160.392156 -401.978665) (xy 160.354208 -402.03425)
			(xy 160.33242 -402.059902) (xy 160.326642 -402.067061) (xy 160.320116 -402.084241) (xy 160.31972 -402.09343)
			(xy 160.31972 -402.251418) (xy 160.31935 -402.261596) (xy 160.311551 -402.280399) (xy 160.297149 -402.294785)
			(xy 160.278336 -402.302562) (xy 160.268158 -402.30298) (xy 159.551878 -402.30298) (xy 159.541721 -402.302485)
			(xy 159.522955 -402.294707) (xy 159.508591 -402.280342) (xy 159.500814 -402.261575) (xy 159.500316 -402.251418)
			(xy 159.500316 -402.09343) (xy 159.499888 -402.084245) (xy 159.493386 -402.06706) (xy 159.487616 -402.059902)
			(xy 159.465807 -402.034267) (xy 159.427861 -401.978678) (xy 159.39683 -401.918952) (xy 159.373159 -401.855945)
			(xy 159.357188 -401.790561) (xy 159.349146 -401.723737) (xy 154.57678 -401.723737) (xy 154.57678 -402.823877)
			(xy 161.54876 -402.823877) (xy 161.548765 -402.756451) (xy 161.556845 -402.68951) (xy 161.572884 -402.624018)
			(xy 161.596652 -402.56092) (xy 161.627806 -402.501122) (xy 161.665898 -402.445486) (xy 161.687764 -402.41982)
			(xy 161.693585 -402.412692) (xy 161.700083 -402.395488) (xy 161.700464 -402.386292) (xy 161.700464 -401.89404)
			(xy 161.70002 -401.884857) (xy 161.693528 -401.867673) (xy 161.687764 -401.860512) (xy 161.665882 -401.834862)
			(xy 161.627796 -401.779225) (xy 161.596648 -401.719426) (xy 161.572887 -401.656327) (xy 161.556854 -401.590837)
			(xy 161.54878 -401.523897) (xy 161.548782 -401.456473) (xy 161.556859 -401.389534) (xy 161.572896 -401.324044)
			(xy 161.59666 -401.260946) (xy 161.627811 -401.201149) (xy 161.6659 -401.145514) (xy 161.687764 -401.119848)
			(xy 161.693573 -401.112712) (xy 161.700078 -401.095514) (xy 161.700464 -401.08632) (xy 161.700464 -400.92884)
			(xy 161.700948 -400.918725) (xy 161.708676 -400.900029) (xy 161.722972 -400.885714) (xy 161.741657 -400.877961)
			(xy 161.751772 -400.877532) (xy 162.468052 -400.877532) (xy 162.478175 -400.877956) (xy 162.496884 -400.885694)
			(xy 162.511201 -400.900009) (xy 162.518942 -400.918717) (xy 162.51936 -400.92884) (xy 162.51936 -401.08632)
			(xy 162.519769 -401.095507) (xy 162.526285 -401.112691) (xy 162.53206 -401.119848) (xy 162.553906 -401.145529)
			(xy 162.591998 -401.20116) (xy 162.623151 -401.260954) (xy 162.646919 -401.324049) (xy 162.662957 -401.389536)
			(xy 162.671035 -401.456474) (xy 162.671037 -401.523896) (xy 162.662962 -401.590834) (xy 162.646927 -401.656323)
			(xy 162.623164 -401.719419) (xy 162.620884 -401.723796) (xy 163.748915 -401.723796) (xy 163.748917 -401.656371)
			(xy 163.756995 -401.589431) (xy 163.773033 -401.52394) (xy 163.7968 -401.460842) (xy 163.827954 -401.401046)
			(xy 163.866046 -401.345411) (xy 163.887912 -401.319746) (xy 163.893715 -401.312606) (xy 163.900226 -401.295411)
			(xy 163.900612 -401.286218) (xy 163.900612 -400.793966) (xy 163.900216 -400.784777) (xy 163.893692 -400.767593)
			(xy 163.887912 -400.760438) (xy 163.866054 -400.734768) (xy 163.827964 -400.679135) (xy 163.796812 -400.619339)
			(xy 163.773047 -400.556243) (xy 163.757011 -400.490754) (xy 163.748934 -400.423816) (xy 163.748934 -400.356393)
			(xy 163.757009 -400.289455) (xy 163.773044 -400.223966) (xy 163.796809 -400.160869) (xy 163.827959 -400.101073)
			(xy 163.866048 -400.045439) (xy 163.887912 -400.019774) (xy 163.893703 -400.012625) (xy 163.900221 -399.995437)
			(xy 163.900612 -399.986246) (xy 163.900612 -399.828766) (xy 163.901098 -399.818641) (xy 163.908832 -399.799924)
			(xy 163.923117 -399.78557) (xy 163.941797 -399.777747) (xy 163.95192 -399.777204) (xy 164.6682 -399.777204)
			(xy 164.678355 -399.777622) (xy 164.697108 -399.785418) (xy 164.711431 -399.799816) (xy 164.71913 -399.818609)
			(xy 164.719508 -399.828766) (xy 164.719508 -399.986246) (xy 164.719942 -399.995431) (xy 164.726439 -400.012615)
			(xy 164.732208 -400.019774) (xy 164.754078 -400.045435) (xy 164.792166 -400.10107) (xy 164.823316 -400.160867)
			(xy 164.847079 -400.223964) (xy 164.863114 -400.289454) (xy 164.871189 -400.356393) (xy 164.871189 -400.423817)
			(xy 164.863112 -400.490755) (xy 164.847076 -400.556244) (xy 164.823312 -400.619341) (xy 164.792161 -400.679138)
			(xy 164.754072 -400.734773) (xy 164.732208 -400.760438) (xy 164.726414 -400.767585) (xy 164.719897 -400.784774)
			(xy 164.719508 -400.793966) (xy 164.719508 -401.286218) (xy 164.719908 -401.295406) (xy 164.726429 -401.312591)
			(xy 164.732208 -401.319746) (xy 164.75405 -401.345429) (xy 164.792139 -401.401061) (xy 164.82329 -401.460855)
			(xy 164.847055 -401.52395) (xy 164.863092 -401.589436) (xy 164.871169 -401.656373) (xy 164.871171 -401.723794)
			(xy 164.863098 -401.790731) (xy 164.847065 -401.856219) (xy 164.823304 -401.919315) (xy 164.792156 -401.97911)
			(xy 164.75407 -402.034745) (xy 164.732208 -402.06041) (xy 164.726426 -402.067565) (xy 164.719902 -402.084748)
			(xy 164.719508 -402.093938) (xy 164.719508 -402.251418) (xy 164.71899 -402.26154) (xy 164.711265 -402.280253)
			(xy 164.696989 -402.294607) (xy 164.678319 -402.302434) (xy 164.6682 -402.30298) (xy 163.95192 -402.30298)
			(xy 163.941765 -402.302562) (xy 163.923009 -402.294769) (xy 163.908684 -402.280371) (xy 163.900987 -402.261575)
			(xy 163.900612 -402.251418) (xy 163.900612 -402.093938) (xy 163.900181 -402.084753) (xy 163.893681 -402.067569)
			(xy 163.887912 -402.06041) (xy 163.866026 -402.034763) (xy 163.827937 -401.979126) (xy 163.796787 -401.919327)
			(xy 163.773023 -401.856228) (xy 163.756989 -401.790737) (xy 163.748915 -401.723796) (xy 162.620884 -401.723796)
			(xy 162.592013 -401.779214) (xy 162.553924 -401.834847) (xy 162.53206 -401.860512) (xy 162.526271 -401.867662)
			(xy 162.519753 -401.884849) (xy 162.51936 -401.89404) (xy 162.51936 -402.386292) (xy 162.519783 -402.395478)
			(xy 162.526289 -402.412662) (xy 162.53206 -402.41982) (xy 162.553878 -402.445523) (xy 162.591971 -402.501152)
			(xy 162.623126 -402.560942) (xy 162.646895 -402.624034) (xy 162.662935 -402.689519) (xy 162.671015 -402.756454)
			(xy 162.671019 -402.823818) (xy 165.949055 -402.823818) (xy 165.94906 -402.756509) (xy 165.957109 -402.689683)
			(xy 165.973087 -402.624298) (xy 165.996766 -402.561292) (xy 166.027805 -402.501567) (xy 166.065761 -402.44598)
			(xy 166.087552 -402.420328) (xy 166.093368 -402.413197) (xy 166.09987 -402.395995) (xy 166.100252 -402.3868)
			(xy 166.100252 -401.893532) (xy 166.099815 -401.884348) (xy 166.093319 -401.867164) (xy 166.087552 -401.860004)
			(xy 166.065744 -401.834368) (xy 166.027795 -401.77878) (xy 165.996762 -401.719054) (xy 165.97309 -401.656047)
			(xy 165.957118 -401.590663) (xy 165.949075 -401.523838) (xy 165.949077 -401.456532) (xy 165.957123 -401.389707)
			(xy 165.973098 -401.324324) (xy 165.996774 -401.261318) (xy 166.02781 -401.201594) (xy 166.065762 -401.146008)
			(xy 166.087552 -401.120356) (xy 166.093356 -401.113216) (xy 166.099865 -401.096021) (xy 166.100252 -401.086828)
			(xy 166.100252 -400.92884) (xy 166.100754 -400.918694) (xy 166.108527 -400.899952) (xy 166.122899 -400.885629)
			(xy 166.141667 -400.87792) (xy 166.151814 -400.877532) (xy 166.868094 -400.877532) (xy 166.878219 -400.878031)
			(xy 166.896939 -400.885756) (xy 166.911295 -400.900038) (xy 166.919116 -400.918717) (xy 166.919656 -400.92884)
			(xy 166.919656 -401.086828) (xy 166.920063 -401.096015) (xy 166.92658 -401.113199) (xy 166.932356 -401.120356)
			(xy 166.954124 -401.146024) (xy 166.992074 -401.201608) (xy 167.023108 -401.26133) (xy 167.046782 -401.324332)
			(xy 167.062757 -401.389712) (xy 167.070803 -401.456533) (xy 167.070804 -401.523837) (xy 167.062762 -401.590658)
			(xy 167.046791 -401.656039) (xy 167.02312 -401.719043) (xy 167.020682 -401.723736) (xy 168.149234 -401.723736)
			(xy 168.149236 -401.65643) (xy 168.157282 -401.589607) (xy 168.173256 -401.524224) (xy 168.19693 -401.461219)
			(xy 168.227963 -401.401494) (xy 168.265912 -401.345907) (xy 168.2877 -401.320254) (xy 168.293499 -401.31311)
			(xy 168.300012 -401.295919) (xy 168.3004 -401.286726) (xy 168.3004 -400.793458) (xy 168.30001 -400.784269)
			(xy 168.293482 -400.767084) (xy 168.2877 -400.75993) (xy 168.265919 -400.734272) (xy 168.227973 -400.678686)
			(xy 168.196942 -400.618963) (xy 168.17327 -400.555959) (xy 168.157298 -400.490578) (xy 168.149254 -400.423756)
			(xy 168.149253 -400.356453) (xy 168.157296 -400.289631) (xy 168.173267 -400.22425) (xy 168.196938 -400.161246)
			(xy 168.227968 -400.101522) (xy 168.265914 -400.045935) (xy 168.2877 -400.020282) (xy 168.293487 -400.01313)
			(xy 168.300007 -399.995945) (xy 168.3004 -399.986754) (xy 168.3004 -399.828766) (xy 168.300905 -399.818611)
			(xy 168.308683 -399.799848) (xy 168.323045 -399.785485) (xy 168.341807 -399.777705) (xy 168.351962 -399.777204)
			(xy 169.068242 -399.777204) (xy 169.078398 -399.777698) (xy 169.097162 -399.78548) (xy 169.111524 -399.799845)
			(xy 169.119303 -399.81861) (xy 169.119804 -399.828766) (xy 169.119804 -399.986754) (xy 169.120235 -399.995939)
			(xy 169.126734 -400.013124) (xy 169.132504 -400.020282) (xy 169.154296 -400.04593) (xy 169.192242 -400.101518)
			(xy 169.223273 -400.161243) (xy 169.246943 -400.224248) (xy 169.262915 -400.28963) (xy 169.270958 -400.356452)
			(xy 169.270957 -400.423757) (xy 169.262913 -400.490579) (xy 169.246941 -400.555961) (xy 169.223269 -400.618966)
			(xy 169.192237 -400.67869) (xy 169.154291 -400.734277) (xy 169.132504 -400.75993) (xy 169.126713 -400.767079)
			(xy 169.120195 -400.784267) (xy 169.119804 -400.793458) (xy 169.119804 -401.286726) (xy 169.1202 -401.295915)
			(xy 169.126723 -401.313099) (xy 169.132504 -401.320254) (xy 169.154269 -401.345925) (xy 169.192215 -401.401509)
			(xy 169.223247 -401.461231) (xy 169.246919 -401.524233) (xy 169.262893 -401.589612) (xy 169.270938 -401.656432)
			(xy 169.27094 -401.723735) (xy 169.262899 -401.790555) (xy 169.246929 -401.855936) (xy 169.223261 -401.918939)
			(xy 169.192232 -401.978662) (xy 169.154289 -402.034249) (xy 169.132504 -402.059902) (xy 169.126725 -402.067059)
			(xy 169.1202 -402.084241) (xy 169.119804 -402.09343) (xy 169.119804 -402.251418) (xy 169.119283 -402.261572)
			(xy 169.11151 -402.280333) (xy 169.097154 -402.294697) (xy 169.078396 -402.302478) (xy 169.068242 -402.30298)
			(xy 168.351962 -402.30298) (xy 168.341804 -402.302498) (xy 168.323037 -402.294715) (xy 168.308674 -402.280346)
			(xy 168.300898 -402.261576) (xy 168.3004 -402.251418) (xy 168.3004 -402.09343) (xy 168.299975 -402.084244)
			(xy 168.293472 -402.06706) (xy 168.2877 -402.059902) (xy 168.265892 -402.034267) (xy 168.227946 -401.978677)
			(xy 168.196916 -401.918951) (xy 168.173246 -401.855944) (xy 168.157276 -401.79056) (xy 168.149234 -401.723736)
			(xy 167.020682 -401.723736) (xy 166.992089 -401.778766) (xy 166.954142 -401.834352) (xy 166.932356 -401.860004)
			(xy 166.92657 -401.867156) (xy 166.92005 -401.884342) (xy 166.919656 -401.893532) (xy 166.919656 -402.3868)
			(xy 166.920076 -402.395986) (xy 166.926584 -402.41317) (xy 166.932356 -402.420328) (xy 166.954097 -402.446019)
			(xy 166.992047 -402.5016) (xy 167.023083 -402.561318) (xy 167.046758 -402.624317) (xy 167.062735 -402.689695)
			(xy 167.070783 -402.756513) (xy 167.070787 -402.823815) (xy 167.070779 -402.823878) (xy 170.348823 -402.823878)
			(xy 170.348828 -402.75645) (xy 170.356909 -402.689507) (xy 170.372951 -402.624015) (xy 170.396723 -402.560916)
			(xy 170.427882 -402.501119) (xy 170.465979 -402.445484) (xy 170.487848 -402.41982) (xy 170.493667 -402.412691)
			(xy 170.500167 -402.395488) (xy 170.500548 -402.386292) (xy 170.500548 -401.89404) (xy 170.500108 -401.884856)
			(xy 170.493614 -401.867672) (xy 170.487848 -401.860512) (xy 170.465963 -401.834864) (xy 170.427871 -401.779228)
			(xy 170.396719 -401.71943) (xy 170.372954 -401.656331) (xy 170.356918 -401.590839) (xy 170.348843 -401.523898)
			(xy 170.348845 -401.456472) (xy 170.356924 -401.389531) (xy 170.372963 -401.324041) (xy 170.396731 -401.260943)
			(xy 170.427887 -401.201146) (xy 170.465981 -401.145512) (xy 170.487848 -401.119848) (xy 170.493655 -401.112711)
			(xy 170.500162 -401.095514) (xy 170.500548 -401.08632) (xy 170.500548 -400.92884) (xy 170.501117 -400.91874)
			(xy 170.508832 -400.900073) (xy 170.523102 -400.885779) (xy 170.541757 -400.878033) (xy 170.551856 -400.877532)
			(xy 171.268136 -400.877532) (xy 171.278265 -400.877887) (xy 171.296975 -400.885653) (xy 171.311289 -400.899989)
			(xy 171.319028 -400.918711) (xy 171.319444 -400.92884) (xy 171.319444 -401.08632) (xy 171.319857 -401.095507)
			(xy 171.32637 -401.11269) (xy 171.332144 -401.119848) (xy 171.35399 -401.145528) (xy 171.392083 -401.20116)
			(xy 171.423238 -401.260953) (xy 171.447006 -401.324048) (xy 171.463044 -401.389536) (xy 171.471123 -401.456473)
			(xy 171.471124 -401.523897) (xy 171.46305 -401.590834) (xy 171.447015 -401.656323) (xy 171.42325 -401.719419)
			(xy 171.421001 -401.723737) (xy 172.549001 -401.723737) (xy 172.549003 -401.65643) (xy 172.55705 -401.589605)
			(xy 172.573027 -401.524221) (xy 172.596704 -401.461215) (xy 172.627743 -401.401491) (xy 172.665697 -401.345906)
			(xy 172.687488 -401.320254) (xy 172.693285 -401.313109) (xy 172.6998 -401.295918) (xy 172.700188 -401.286726)
			(xy 172.700188 -400.793458) (xy 172.699801 -400.784268) (xy 172.693272 -400.767084) (xy 172.687488 -400.75993)
			(xy 172.665705 -400.734274) (xy 172.627752 -400.678689) (xy 172.596716 -400.618966) (xy 172.573041 -400.555962)
			(xy 172.557066 -400.49058) (xy 172.549021 -400.423757) (xy 172.54902 -400.356452) (xy 172.557065 -400.289629)
			(xy 172.573038 -400.224246) (xy 172.596713 -400.161242) (xy 172.627748 -400.101519) (xy 172.665699 -400.045933)
			(xy 172.687488 -400.020282) (xy 172.693273 -400.013129) (xy 172.699795 -399.995944) (xy 172.700188 -399.986754)
			(xy 172.700188 -399.828766) (xy 172.700537 -399.818586) (xy 172.708343 -399.799781) (xy 172.722752 -399.785395)
			(xy 172.741569 -399.777621) (xy 172.75175 -399.777204) (xy 173.46803 -399.777204) (xy 173.478186 -399.777708)
			(xy 173.496949 -399.785486) (xy 173.511312 -399.799848) (xy 173.519091 -399.818611) (xy 173.519592 -399.828766)
			(xy 173.519592 -399.986754) (xy 173.520026 -399.995939) (xy 173.526523 -400.013123) (xy 173.532292 -400.020282)
			(xy 173.554085 -400.04593) (xy 173.592031 -400.101518) (xy 173.623063 -400.161242) (xy 173.646734 -400.224247)
			(xy 173.662705 -400.289629) (xy 173.670749 -400.356452) (xy 173.670748 -400.423757) (xy 173.662704 -400.490579)
			(xy 173.646731 -400.555962) (xy 173.623059 -400.618966) (xy 173.592027 -400.67869) (xy 173.554079 -400.734277)
			(xy 173.532292 -400.75993) (xy 173.526499 -400.767078) (xy 173.519983 -400.784266) (xy 173.519592 -400.793458)
			(xy 173.519592 -401.286726) (xy 173.519991 -401.295914) (xy 173.526513 -401.313099) (xy 173.532292 -401.320254)
			(xy 173.554057 -401.345924) (xy 173.592005 -401.401509) (xy 173.623037 -401.46123) (xy 173.64671 -401.524232)
			(xy 173.662683 -401.589612) (xy 173.670729 -401.656432) (xy 173.670731 -401.723735) (xy 173.662689 -401.790555)
			(xy 173.64672 -401.855936) (xy 173.623051 -401.918939) (xy 173.592022 -401.978663) (xy 173.554077 -402.034249)
			(xy 173.532292 -402.059902) (xy 173.526511 -402.067058) (xy 173.519987 -402.08424) (xy 173.519592 -402.09343)
			(xy 173.519592 -402.251418) (xy 173.519082 -402.261573) (xy 173.511308 -402.280337) (xy 173.496947 -402.294701)
			(xy 173.478185 -402.30248) (xy 173.46803 -402.30298) (xy 172.75175 -402.30298) (xy 172.741584 -402.302496)
			(xy 172.722794 -402.29473) (xy 172.708408 -402.280363) (xy 172.700618 -402.261584) (xy 172.700188 -402.251418)
			(xy 172.700188 -402.09343) (xy 172.699766 -402.084244) (xy 172.693261 -402.067059) (xy 172.687488 -402.059902)
			(xy 172.665677 -402.034268) (xy 172.627726 -401.97868) (xy 172.596691 -401.918955) (xy 172.573017 -401.855948)
			(xy 172.557044 -401.790563) (xy 172.549001 -401.723737) (xy 171.421001 -401.723737) (xy 171.392099 -401.779215)
			(xy 171.354009 -401.834848) (xy 171.332144 -401.860512) (xy 171.326353 -401.867661) (xy 171.319836 -401.884849)
			(xy 171.319444 -401.89404) (xy 171.319444 -402.386292) (xy 171.31987 -402.395477) (xy 171.326374 -402.412661)
			(xy 171.332144 -402.41982) (xy 171.353963 -402.445523) (xy 171.392057 -402.501151) (xy 171.423213 -402.560941)
			(xy 171.446982 -402.624033) (xy 171.463022 -402.689518) (xy 171.471103 -402.756453) (xy 171.471107 -402.823818)
			(xy 174.749143 -402.823818) (xy 174.749147 -402.75651) (xy 174.757196 -402.689684) (xy 174.773174 -402.624299)
			(xy 174.796852 -402.561292) (xy 174.827891 -402.501567) (xy 174.865845 -402.44598) (xy 174.887636 -402.420328)
			(xy 174.89345 -402.413195) (xy 174.899953 -402.395995) (xy 174.900336 -402.3868) (xy 174.900336 -401.893532)
			(xy 174.899902 -401.884348) (xy 174.893404 -401.867163) (xy 174.887636 -401.860004) (xy 174.865829 -401.834368)
			(xy 174.827881 -401.778779) (xy 174.796848 -401.719053) (xy 174.773177 -401.656047) (xy 174.757205 -401.590663)
			(xy 174.749163 -401.523838) (xy 174.749165 -401.456532) (xy 174.757211 -401.389708) (xy 174.773186 -401.324324)
			(xy 174.796861 -401.261319) (xy 174.827896 -401.201595) (xy 174.865847 -401.146008) (xy 174.887636 -401.120356)
			(xy 174.893438 -401.113215) (xy 174.899949 -401.096021) (xy 174.900336 -401.086828) (xy 174.900336 -400.92884)
			(xy 174.900755 -400.918684) (xy 174.908544 -400.899926) (xy 174.922943 -400.8856) (xy 174.94174 -400.877905)
			(xy 174.951898 -400.877532) (xy 175.668178 -400.877532) (xy 175.678302 -400.878044) (xy 175.697022 -400.885763)
			(xy 175.711378 -400.900042) (xy 175.7192 -400.918718) (xy 175.71974 -400.92884) (xy 175.71974 -401.086828)
			(xy 175.72015 -401.096015) (xy 175.726665 -401.113198) (xy 175.73244 -401.120356) (xy 175.754209 -401.146024)
			(xy 175.792159 -401.201608) (xy 175.823195 -401.261329) (xy 175.846869 -401.324331) (xy 175.862844 -401.389712)
			(xy 175.870891 -401.456533) (xy 175.870892 -401.523837) (xy 175.86285 -401.590658) (xy 175.846878 -401.65604)
			(xy 175.823207 -401.719044) (xy 175.792175 -401.778766) (xy 175.754227 -401.834352) (xy 175.73244 -401.860004)
			(xy 175.726652 -401.867155) (xy 175.720134 -401.884341) (xy 175.71974 -401.893532) (xy 175.71974 -402.3868)
			(xy 175.720164 -402.395985) (xy 175.726669 -402.413169) (xy 175.73244 -402.420328) (xy 175.754181 -402.446019)
			(xy 175.792133 -402.501599) (xy 175.823169 -402.561317) (xy 175.846846 -402.624317) (xy 175.862823 -402.689694)
			(xy 175.870871 -402.756513) (xy 175.870875 -402.823815) (xy 175.862835 -402.890634) (xy 175.846867 -402.956014)
			(xy 175.823199 -403.019017) (xy 175.79217 -403.078739) (xy 175.754225 -403.134324) (xy 175.73244 -403.159976)
			(xy 175.726621 -403.167105) (xy 175.720122 -403.184308) (xy 175.71974 -403.193504) (xy 175.71974 -403.351492)
			(xy 175.719273 -403.361641) (xy 175.711487 -403.380385) (xy 175.697105 -403.394707) (xy 175.678328 -403.402415)
			(xy 175.668178 -403.4028) (xy 174.951898 -403.4028) (xy 174.941776 -403.402276) (xy 174.923063 -403.394555)
			(xy 174.908708 -403.380281) (xy 174.900882 -403.361611) (xy 174.900336 -403.351492) (xy 174.900336 -403.193504)
			(xy 174.899916 -403.184318) (xy 174.893408 -403.167134) (xy 174.887636 -403.159976) (xy 174.865801 -403.134363)
			(xy 174.827854 -403.078771) (xy 174.796823 -403.019042) (xy 174.773153 -402.956032) (xy 174.757183 -402.890645)
			(xy 174.749143 -402.823818) (xy 171.471107 -402.823818) (xy 171.471107 -402.823874) (xy 171.463035 -402.89081)
			(xy 171.447003 -402.956298) (xy 171.423242 -403.019393) (xy 171.392094 -403.079187) (xy 171.354007 -403.13482)
			(xy 171.332144 -403.160484) (xy 171.326322 -403.167611) (xy 171.319824 -403.184816) (xy 171.319444 -403.194012)
			(xy 171.319444 -403.351492) (xy 171.318909 -403.361595) (xy 171.311183 -403.380264) (xy 171.296901 -403.394558)
			(xy 171.278238 -403.402301) (xy 171.268136 -403.4028) (xy 170.551856 -403.4028) (xy 170.541744 -403.402351)
			(xy 170.523065 -403.394599) (xy 170.508772 -403.380291) (xy 170.501039 -403.361604) (xy 170.500548 -403.351492)
			(xy 170.500548 -403.194012) (xy 170.500121 -403.184827) (xy 170.493618 -403.167643) (xy 170.487848 -403.160484)
			(xy 170.465935 -403.134858) (xy 170.427845 -403.079219) (xy 170.396693 -403.019418) (xy 170.37293 -402.956316)
			(xy 170.356896 -402.890822) (xy 170.348823 -402.823878) (xy 167.070779 -402.823878) (xy 167.062748 -402.890634)
			(xy 167.04678 -402.956014) (xy 167.023112 -403.019016) (xy 166.992084 -403.078738) (xy 166.954141 -403.134324)
			(xy 166.932356 -403.159976) (xy 166.926539 -403.167107) (xy 166.920038 -403.184308) (xy 166.919656 -403.193504)
			(xy 166.919656 -403.351492) (xy 166.919173 -403.361639) (xy 166.911391 -403.38038) (xy 166.897014 -403.394702)
			(xy 166.878242 -403.402412) (xy 166.868094 -403.4028) (xy 166.151814 -403.4028) (xy 166.141693 -403.402263)
			(xy 166.12298 -403.394547) (xy 166.108624 -403.380277) (xy 166.100798 -403.36161) (xy 166.100252 -403.351492)
			(xy 166.100252 -403.193504) (xy 166.099828 -403.184318) (xy 166.093323 -403.167135) (xy 166.087552 -403.159976)
			(xy 166.065717 -403.134363) (xy 166.027768 -403.078771) (xy 165.996736 -403.019042) (xy 165.973066 -402.956033)
			(xy 165.957096 -402.890646) (xy 165.949055 -402.823818) (xy 162.671019 -402.823818) (xy 162.671019 -402.823874)
			(xy 162.662948 -402.89081) (xy 162.646916 -402.956297) (xy 162.623155 -403.019392) (xy 162.592008 -403.079187)
			(xy 162.553923 -403.13482) (xy 162.53206 -403.160484) (xy 162.52624 -403.167613) (xy 162.51974 -403.184816)
			(xy 162.51936 -403.194012) (xy 162.51936 -403.351492) (xy 162.518976 -403.361619) (xy 162.511224 -403.38033)
			(xy 162.496896 -403.394646) (xy 162.478179 -403.402384) (xy 162.468052 -403.4028) (xy 161.751772 -403.4028)
			(xy 161.741661 -403.402338) (xy 161.722983 -403.394591) (xy 161.708689 -403.380287) (xy 161.700955 -403.361603)
			(xy 161.700464 -403.351492) (xy 161.700464 -403.194012) (xy 161.700034 -403.184827) (xy 161.693532 -403.167643)
			(xy 161.687764 -403.160484) (xy 161.665854 -403.134857) (xy 161.627769 -403.079216) (xy 161.596623 -403.019414)
			(xy 161.572863 -402.956313) (xy 161.556832 -402.890819) (xy 161.54876 -402.823877) (xy 154.57678 -402.823877)
			(xy 154.57678 -405.623648) (xy 159.349158 -405.623648) (xy 159.349158 -405.556343) (xy 159.357202 -405.48952)
			(xy 159.373175 -405.424138) (xy 159.396848 -405.361133) (xy 159.427881 -405.301409) (xy 159.465829 -405.245822)
			(xy 159.487616 -405.22017) (xy 159.49341 -405.213023) (xy 159.499926 -405.195834) (xy 159.500316 -405.186642)
			(xy 159.500316 -404.693374) (xy 159.499915 -404.684186) (xy 159.493395 -404.667002) (xy 159.487616 -404.659846)
			(xy 159.465851 -404.634176) (xy 159.427903 -404.578591) (xy 159.39687 -404.51887) (xy 159.373197 -404.455868)
			(xy 159.357223 -404.390488) (xy 159.349177 -404.323668) (xy 159.349175 -404.256365) (xy 159.357217 -404.189544)
			(xy 159.373187 -404.124164) (xy 159.396856 -404.06116) (xy 159.427886 -404.001437) (xy 159.46583 -403.94585)
			(xy 159.487616 -403.920198) (xy 159.493398 -403.913042) (xy 159.499921 -403.89586) (xy 159.500316 -403.88667)
			(xy 159.500316 -403.728682) (xy 159.500818 -403.718526) (xy 159.508594 -403.69976) (xy 159.522957 -403.685396)
			(xy 159.541722 -403.677619) (xy 159.551878 -403.67712) (xy 160.268158 -403.67712) (xy 160.278325 -403.677598)
			(xy 160.297115 -403.685366) (xy 160.311501 -403.699735) (xy 160.31929 -403.718516) (xy 160.31972 -403.728682)
			(xy 160.31972 -403.88667) (xy 160.32014 -403.895856) (xy 160.326646 -403.913041) (xy 160.33242 -403.920198)
			(xy 160.354231 -403.945832) (xy 160.392181 -404.00142) (xy 160.423216 -404.061146) (xy 160.446889 -404.124153)
			(xy 160.462862 -404.189538) (xy 160.470905 -404.256363) (xy 160.470903 -404.32367) (xy 160.462856 -404.390495)
			(xy 160.446879 -404.455879) (xy 160.423202 -404.518885) (xy 160.392164 -404.578608) (xy 160.35421 -404.634194)
			(xy 160.33242 -404.659846) (xy 160.326624 -404.666992) (xy 160.320108 -404.684182) (xy 160.31972 -404.693374)
			(xy 160.31972 -405.186642) (xy 160.320105 -405.195832) (xy 160.326636 -405.213016) (xy 160.33242 -405.22017)
			(xy 160.354203 -405.245826) (xy 160.392155 -405.301411) (xy 160.42319 -405.361134) (xy 160.446865 -405.424138)
			(xy 160.46284 -405.48952) (xy 160.470885 -405.556343) (xy 160.470886 -405.623648) (xy 160.462842 -405.690471)
			(xy 160.446868 -405.755853) (xy 160.423194 -405.818858) (xy 160.392159 -405.878581) (xy 160.354209 -405.934166)
			(xy 160.33242 -405.959818) (xy 160.326636 -405.966972) (xy 160.320113 -405.984156) (xy 160.31972 -405.993346)
			(xy 160.31972 -406.151334) (xy 160.319363 -406.161513) (xy 160.311559 -406.180317) (xy 160.297153 -406.194702)
			(xy 160.278338 -406.202478) (xy 160.268158 -406.202896) (xy 159.551878 -406.202896) (xy 159.541723 -406.202386)
			(xy 159.52296 -406.19461) (xy 159.508596 -406.18025) (xy 159.500817 -406.161489) (xy 159.500316 -406.151334)
			(xy 159.500316 -405.993346) (xy 159.49988 -405.984162) (xy 159.493384 -405.966977) (xy 159.487616 -405.959818)
			(xy 159.465823 -405.93417) (xy 159.427876 -405.878583) (xy 159.396844 -405.818858) (xy 159.373173 -405.755853)
			(xy 159.357201 -405.690471) (xy 159.349158 -405.623648) (xy 154.57678 -405.623648) (xy 154.57678 -406.723789)
			(xy 161.548771 -406.723789) (xy 161.548774 -406.656363) (xy 161.556853 -406.589423) (xy 161.572891 -406.523933)
			(xy 161.596657 -406.460835) (xy 161.627809 -406.401038) (xy 161.665899 -406.345402) (xy 161.687764 -406.319736)
			(xy 161.693578 -406.312604) (xy 161.70008 -406.295403) (xy 161.700464 -406.286208) (xy 161.700464 -405.793956)
			(xy 161.700061 -405.784768) (xy 161.693541 -405.767585) (xy 161.687764 -405.760428) (xy 161.665897 -405.734765)
			(xy 161.627811 -405.67913) (xy 161.596663 -405.619333) (xy 161.5729 -405.556236) (xy 161.556866 -405.490747)
			(xy 161.548791 -405.423809) (xy 161.548792 -405.356385) (xy 161.556867 -405.289447) (xy 161.572902 -405.223959)
			(xy 161.596665 -405.160862) (xy 161.627814 -405.101065) (xy 161.665901 -405.04543) (xy 161.687764 -405.019764)
			(xy 161.693566 -405.012623) (xy 161.700076 -404.995429) (xy 161.700464 -404.986236) (xy 161.700464 -404.828756)
			(xy 161.700948 -404.818649) (xy 161.708694 -404.799977) (xy 161.72299 -404.785685) (xy 161.741665 -404.777945)
			(xy 161.751772 -404.777448) (xy 162.468052 -404.777448) (xy 162.478165 -404.777954) (xy 162.496858 -404.785677)
			(xy 162.511172 -404.799965) (xy 162.518928 -404.818644) (xy 162.51936 -404.828756) (xy 162.51936 -404.986236)
			(xy 162.519762 -404.995424) (xy 162.526282 -405.012608) (xy 162.53206 -405.019764) (xy 162.553921 -405.045432)
			(xy 162.592013 -405.101065) (xy 162.623166 -405.16086) (xy 162.646932 -405.223957) (xy 162.662969 -405.289446)
			(xy 162.671046 -405.356385) (xy 162.671046 -405.423809) (xy 162.66297 -405.490748) (xy 162.646934 -405.556237)
			(xy 162.623168 -405.619334) (xy 162.620889 -405.623708) (xy 163.748926 -405.623708) (xy 163.748926 -405.556283)
			(xy 163.757003 -405.489344) (xy 163.77304 -405.423855) (xy 163.796805 -405.360758) (xy 163.827957 -405.300961)
			(xy 163.866047 -405.245327) (xy 163.887912 -405.219662) (xy 163.893709 -405.212517) (xy 163.900223 -405.195326)
			(xy 163.900612 -405.186134) (xy 163.900612 -404.693882) (xy 163.900208 -404.684694) (xy 163.89369 -404.66751)
			(xy 163.887912 -404.660354) (xy 163.866069 -404.634671) (xy 163.827979 -404.579039) (xy 163.796827 -404.519246)
			(xy 163.773061 -404.456151) (xy 163.757023 -404.390664) (xy 163.748946 -404.323728) (xy 163.748944 -404.256305)
			(xy 163.757018 -404.189368) (xy 163.773051 -404.12388) (xy 163.796813 -404.060784) (xy 163.827962 -404.000989)
			(xy 163.866049 -403.945355) (xy 163.887912 -403.91969) (xy 163.893697 -403.912536) (xy 163.900218 -403.895352)
			(xy 163.900612 -403.886162) (xy 163.900612 -403.728682) (xy 163.901111 -403.718558) (xy 163.908839 -403.699841)
			(xy 163.923121 -403.685486) (xy 163.941798 -403.677663) (xy 163.95192 -403.67712) (xy 164.6682 -403.67712)
			(xy 164.678357 -403.677522) (xy 164.697113 -403.685321) (xy 164.711437 -403.699724) (xy 164.719133 -403.718523)
			(xy 164.719508 -403.728682) (xy 164.719508 -403.886162) (xy 164.719935 -403.895347) (xy 164.726437 -403.912532)
			(xy 164.732208 -403.91969) (xy 164.754093 -403.945338) (xy 164.792181 -404.000975) (xy 164.82333 -404.060774)
			(xy 164.847093 -404.123873) (xy 164.863126 -404.189364) (xy 164.8712 -404.256304) (xy 164.871198 -404.323729)
			(xy 164.86312 -404.390669) (xy 164.847083 -404.456159) (xy 164.823317 -404.519257) (xy 164.792164 -404.579054)
			(xy 164.754073 -404.634689) (xy 164.732208 -404.660354) (xy 164.726407 -404.667496) (xy 164.719895 -404.684689)
			(xy 164.719508 -404.693882) (xy 164.719508 -405.186134) (xy 164.7199 -405.195323) (xy 164.726426 -405.212508)
			(xy 164.732208 -405.219662) (xy 164.754066 -405.245332) (xy 164.792154 -405.300966) (xy 164.823305 -405.360762)
			(xy 164.847069 -405.423858) (xy 164.863104 -405.489346) (xy 164.871181 -405.556284) (xy 164.871181 -405.623707)
			(xy 164.863106 -405.690645) (xy 164.847072 -405.756133) (xy 164.823308 -405.81923) (xy 164.792159 -405.879026)
			(xy 164.754071 -405.934661) (xy 164.732208 -405.960326) (xy 164.726419 -405.967477) (xy 164.719899 -405.984663)
			(xy 164.719508 -405.993854) (xy 164.719508 -406.151334) (xy 164.719003 -406.161457) (xy 164.711273 -406.18017)
			(xy 164.696993 -406.194523) (xy 164.67832 -406.20235) (xy 164.6682 -406.202896) (xy 163.95192 -406.202896)
			(xy 163.941767 -406.202462) (xy 163.923014 -406.194672) (xy 163.90869 -406.180279) (xy 163.90099 -406.161489)
			(xy 163.900612 -406.151334) (xy 163.900612 -405.993854) (xy 163.900173 -405.98467) (xy 163.893679 -405.967485)
			(xy 163.887912 -405.960326) (xy 163.866042 -405.934666) (xy 163.827952 -405.879031) (xy 163.796801 -405.819234)
			(xy 163.773037 -405.756137) (xy 163.757001 -405.690647) (xy 163.748926 -405.623708) (xy 162.620889 -405.623708)
			(xy 162.592016 -405.67913) (xy 162.553925 -405.734763) (xy 162.53206 -405.760428) (xy 162.526264 -405.767573)
			(xy 162.51975 -405.784764) (xy 162.51936 -405.793956) (xy 162.51936 -406.286208) (xy 162.519775 -406.295394)
			(xy 162.526286 -406.312578) (xy 162.53206 -406.319736) (xy 162.553894 -406.345426) (xy 162.591986 -406.401056)
			(xy 162.623141 -406.460849) (xy 162.646908 -406.523942) (xy 162.662947 -406.589429) (xy 162.671026 -406.656365)
			(xy 162.671029 -406.72373) (xy 165.949066 -406.72373) (xy 165.949069 -406.656422) (xy 165.957117 -406.589597)
			(xy 165.973094 -406.524213) (xy 165.996771 -406.461207) (xy 166.027808 -406.401483) (xy 166.065762 -406.345896)
			(xy 166.087552 -406.320244) (xy 166.093361 -406.313108) (xy 166.099867 -406.29591) (xy 166.100252 -406.286716)
			(xy 166.100252 -405.793448) (xy 166.099807 -405.784265) (xy 166.093316 -405.767081) (xy 166.087552 -405.75992)
			(xy 166.06576 -405.734271) (xy 166.027811 -405.678685) (xy 165.996777 -405.618961) (xy 165.973104 -405.555956)
			(xy 165.957131 -405.490573) (xy 165.949087 -405.42375) (xy 165.949087 -405.356444) (xy 165.957132 -405.289621)
			(xy 165.973105 -405.224239) (xy 165.996779 -405.161234) (xy 166.027814 -405.10151) (xy 166.065764 -405.045924)
			(xy 166.087552 -405.020272) (xy 166.093349 -405.013128) (xy 166.099862 -404.995936) (xy 166.100252 -404.986744)
			(xy 166.100252 -404.828756) (xy 166.100685 -404.818605) (xy 166.108486 -404.799861) (xy 166.122878 -404.785541)
			(xy 166.141661 -404.777834) (xy 166.151814 -404.777448) (xy 166.868094 -404.777448) (xy 166.878221 -404.777932)
			(xy 166.896944 -404.785659) (xy 166.911301 -404.799946) (xy 166.919119 -404.818631) (xy 166.919656 -404.828756)
			(xy 166.919656 -404.986744) (xy 166.920055 -404.995932) (xy 166.926578 -405.013116) (xy 166.932356 -405.020272)
			(xy 166.95414 -405.045927) (xy 166.992089 -405.101513) (xy 167.023123 -405.161236) (xy 167.046796 -405.22424)
			(xy 167.062769 -405.289622) (xy 167.070814 -405.356445) (xy 167.070814 -405.423749) (xy 167.06277 -405.490572)
			(xy 167.046798 -405.555954) (xy 167.023125 -405.618958) (xy 167.020688 -405.623648) (xy 168.149245 -405.623648)
			(xy 168.149246 -405.556343) (xy 168.15729 -405.489521) (xy 168.173263 -405.424139) (xy 168.196934 -405.361134)
			(xy 168.227966 -405.30141) (xy 168.265913 -405.245823) (xy 168.2877 -405.22017) (xy 168.293492 -405.213021)
			(xy 168.300009 -405.195834) (xy 168.3004 -405.186642) (xy 168.3004 -404.693374) (xy 168.300003 -404.684185)
			(xy 168.29348 -404.667001) (xy 168.2877 -404.659846) (xy 168.265935 -404.634176) (xy 168.227988 -404.578591)
			(xy 168.196956 -404.518869) (xy 168.173284 -404.455867) (xy 168.15731 -404.390488) (xy 168.149265 -404.323668)
			(xy 168.149263 -404.256365) (xy 168.157305 -404.189545) (xy 168.173274 -404.124164) (xy 168.196943 -404.061161)
			(xy 168.227971 -404.001438) (xy 168.265915 -403.945851) (xy 168.2877 -403.920198) (xy 168.29348 -403.913041)
			(xy 168.300005 -403.89586) (xy 168.3004 -403.88667) (xy 168.3004 -403.728682) (xy 168.300917 -403.718528)
			(xy 168.308691 -403.699765) (xy 168.323049 -403.685402) (xy 168.341808 -403.677621) (xy 168.351962 -403.67712)
			(xy 169.068242 -403.67712) (xy 169.0784 -403.677599) (xy 169.097167 -403.685383) (xy 169.11153 -403.699753)
			(xy 169.119306 -403.718524) (xy 169.119804 -403.728682) (xy 169.119804 -403.88667) (xy 169.120228 -403.895856)
			(xy 169.126732 -403.91304) (xy 169.132504 -403.920198) (xy 169.154312 -403.945833) (xy 169.192257 -404.001423)
			(xy 169.223287 -404.061149) (xy 169.246957 -404.124156) (xy 169.262927 -404.18954) (xy 169.270969 -404.256364)
			(xy 169.270967 -404.32367) (xy 169.262921 -404.390493) (xy 169.246947 -404.455876) (xy 169.223274 -404.518881)
			(xy 169.19224 -404.578606) (xy 169.154292 -404.634193) (xy 169.132504 -404.659846) (xy 169.126706 -404.66699)
			(xy 169.120192 -404.684181) (xy 169.119804 -404.693374) (xy 169.119804 -405.186642) (xy 169.120193 -405.195832)
			(xy 169.126721 -405.213016) (xy 169.132504 -405.22017) (xy 169.154284 -405.245828) (xy 169.192231 -405.301414)
			(xy 169.223262 -405.361137) (xy 169.246933 -405.424141) (xy 169.262905 -405.489522) (xy 169.270949 -405.556344)
			(xy 169.27095 -405.623647) (xy 169.262907 -405.690469) (xy 169.246936 -405.75585) (xy 169.223266 -405.818854)
			(xy 169.192235 -405.878578) (xy 169.15429 -405.934165) (xy 169.132504 -405.959818) (xy 169.126718 -405.966971)
			(xy 169.120197 -405.984155) (xy 169.119804 -405.993346) (xy 169.119804 -406.151334) (xy 169.119296 -406.161489)
			(xy 169.111518 -406.180251) (xy 169.097157 -406.194613) (xy 169.078397 -406.202394) (xy 169.068242 -406.202896)
			(xy 168.351962 -406.202896) (xy 168.341806 -406.202399) (xy 168.323042 -406.194618) (xy 168.30868 -406.180254)
			(xy 168.300901 -406.16149) (xy 168.3004 -406.151334) (xy 168.3004 -405.993346) (xy 168.299968 -405.984161)
			(xy 168.293469 -405.966977) (xy 168.2877 -405.959818) (xy 168.265908 -405.93417) (xy 168.227961 -405.878582)
			(xy 168.196931 -405.818858) (xy 168.17326 -405.755853) (xy 168.157289 -405.69047) (xy 168.149245 -405.623648)
			(xy 167.020688 -405.623648) (xy 166.992092 -405.678681) (xy 166.954143 -405.734268) (xy 166.932356 -405.75992)
			(xy 166.926563 -405.767067) (xy 166.920047 -405.784256) (xy 166.919656 -405.793448) (xy 166.919656 -406.286716)
			(xy 166.920068 -406.295903) (xy 166.926582 -406.313087) (xy 166.932356 -406.320244) (xy 166.954112 -406.345922)
			(xy 166.992062 -406.401505) (xy 167.023097 -406.461225) (xy 167.046772 -406.524226) (xy 167.062747 -406.589605)
			(xy 167.070794 -406.656425) (xy 167.070797 -406.723727) (xy 167.070789 -406.72379) (xy 170.348835 -406.72379)
			(xy 170.348838 -406.656362) (xy 170.356917 -406.589421) (xy 170.372958 -406.52393) (xy 170.396728 -406.460831)
			(xy 170.427885 -406.401034) (xy 170.46598 -406.3454) (xy 170.487848 -406.319736) (xy 170.49366 -406.312602)
			(xy 170.500164 -406.295403) (xy 170.500548 -406.286208) (xy 170.500548 -405.793956) (xy 170.500148 -405.784768)
			(xy 170.493626 -405.767584) (xy 170.487848 -405.760428) (xy 170.465978 -405.734767) (xy 170.427887 -405.679133)
			(xy 170.396733 -405.619337) (xy 170.372967 -405.556239) (xy 170.356931 -405.490749) (xy 170.348854 -405.423809)
			(xy 170.348855 -405.356385) (xy 170.356932 -405.289445) (xy 170.372969 -405.223955) (xy 170.396736 -405.160858)
			(xy 170.42789 -405.101062) (xy 170.465982 -405.045428) (xy 170.487848 -405.019764) (xy 170.493648 -405.012622)
			(xy 170.500159 -404.995429) (xy 170.500548 -404.986236) (xy 170.500548 -404.828756) (xy 170.501048 -404.818651)
			(xy 170.50879 -404.799982) (xy 170.523082 -404.78569) (xy 170.541751 -404.777948) (xy 170.551856 -404.777448)
			(xy 171.268136 -404.777448) (xy 171.278241 -404.777954) (xy 171.29691 -404.785694) (xy 171.311201 -404.799984)
			(xy 171.318944 -404.818651) (xy 171.319444 -404.828756) (xy 171.319444 -404.986236) (xy 171.31985 -404.995423)
			(xy 171.326368 -405.012607) (xy 171.332144 -405.019764) (xy 171.354006 -405.045432) (xy 171.392099 -405.101064)
			(xy 171.423253 -405.16086) (xy 171.447019 -405.223956) (xy 171.463057 -405.289446) (xy 171.471134 -405.356385)
			(xy 171.471134 -405.423809) (xy 171.463058 -405.490748) (xy 171.447021 -405.556238) (xy 171.423255 -405.619335)
			(xy 171.421007 -405.623649) (xy 172.549012 -405.623649) (xy 172.549013 -405.556342) (xy 172.557058 -405.489518)
			(xy 172.573033 -405.424135) (xy 172.596709 -405.36113) (xy 172.627746 -405.301407) (xy 172.665698 -405.245822)
			(xy 172.687488 -405.22017) (xy 172.693278 -405.21302) (xy 172.699797 -405.195833) (xy 172.700188 -405.186642)
			(xy 172.700188 -404.693374) (xy 172.699793 -404.684185) (xy 172.693269 -404.667001) (xy 172.687488 -404.659846)
			(xy 172.66572 -404.634177) (xy 172.627768 -404.578594) (xy 172.596731 -404.518873) (xy 172.573055 -404.455871)
			(xy 172.557079 -404.39049) (xy 172.549032 -404.323669) (xy 172.54903 -404.256364) (xy 172.557073 -404.189542)
			(xy 172.573045 -404.124161) (xy 172.596717 -404.061157) (xy 172.627751 -404.001435) (xy 172.6657 -403.945849)
			(xy 172.687488 -403.920198) (xy 172.693267 -403.91304) (xy 172.699792 -403.895859) (xy 172.700188 -403.88667)
			(xy 172.700188 -403.728682) (xy 172.70055 -403.718503) (xy 172.708351 -403.699698) (xy 172.722756 -403.685313)
			(xy 172.74157 -403.677537) (xy 172.75175 -403.67712) (xy 173.46803 -403.67712) (xy 173.478187 -403.677608)
			(xy 173.496954 -403.685389) (xy 173.511317 -403.699756) (xy 173.519094 -403.718524) (xy 173.519592 -403.728682)
			(xy 173.519592 -403.88667) (xy 173.520018 -403.895855) (xy 173.526521 -403.91304) (xy 173.532292 -403.920198)
			(xy 173.5541 -403.945833) (xy 173.592047 -404.001422) (xy 173.623077 -404.061149) (xy 173.646747 -404.124155)
			(xy 173.662718 -404.189539) (xy 173.67076 -404.256363) (xy 173.670758 -404.32367) (xy 173.662712 -404.390493)
			(xy 173.646738 -404.455876) (xy 173.623064 -404.518882) (xy 173.59203 -404.578606) (xy 173.55408 -404.634193)
			(xy 173.532292 -404.659846) (xy 173.526492 -404.666989) (xy 173.51998 -404.684181) (xy 173.519592 -404.693374)
			(xy 173.519592 -405.186642) (xy 173.519984 -405.195831) (xy 173.52651 -405.213015) (xy 173.532292 -405.22017)
			(xy 173.554073 -405.245827) (xy 173.59202 -405.301414) (xy 173.623052 -405.361137) (xy 173.646723 -405.424141)
			(xy 173.662696 -405.489522) (xy 173.67074 -405.556343) (xy 173.670741 -405.623647) (xy 173.662698 -405.690469)
			(xy 173.646726 -405.755851) (xy 173.623055 -405.818855) (xy 173.592025 -405.878578) (xy 173.554078 -405.934165)
			(xy 173.532292 -405.959818) (xy 173.526504 -405.96697) (xy 173.519985 -405.984155) (xy 173.519592 -405.993346)
			(xy 173.519592 -406.151334) (xy 173.519095 -406.16149) (xy 173.511315 -406.180254) (xy 173.496951 -406.194617)
			(xy 173.478186 -406.202396) (xy 173.46803 -406.202896) (xy 172.75175 -406.202896) (xy 172.741586 -406.202396)
			(xy 172.722799 -406.194634) (xy 172.708413 -406.180272) (xy 172.70062 -406.161497) (xy 172.700188 -406.151334)
			(xy 172.700188 -405.993346) (xy 172.699759 -405.984161) (xy 172.693259 -405.966976) (xy 172.687488 -405.959818)
			(xy 172.665693 -405.934171) (xy 172.627741 -405.878585) (xy 172.596705 -405.818861) (xy 172.573031 -405.755856)
			(xy 172.557057 -405.690473) (xy 172.549012 -405.623649) (xy 171.421007 -405.623649) (xy 171.392102 -405.67913)
			(xy 171.35401 -405.734764) (xy 171.332144 -405.760428) (xy 171.326346 -405.767572) (xy 171.319834 -405.784764)
			(xy 171.319444 -405.793956) (xy 171.319444 -406.286208) (xy 171.319863 -406.295394) (xy 171.326372 -406.312578)
			(xy 171.332144 -406.319736) (xy 171.353978 -406.345426) (xy 171.392072 -406.401056) (xy 171.423227 -406.460848)
			(xy 171.446996 -406.523942) (xy 171.463035 -406.589428) (xy 171.471114 -406.656365) (xy 171.471117 -406.72373)
			(xy 174.749154 -406.72373) (xy 174.749157 -406.656422) (xy 174.757205 -406.589597) (xy 174.773181 -406.524213)
			(xy 174.796857 -406.461208) (xy 174.827894 -406.401483) (xy 174.865846 -406.345896) (xy 174.887636 -406.320244)
			(xy 174.893443 -406.313107) (xy 174.899951 -406.29591) (xy 174.900336 -406.286716) (xy 174.900336 -405.793448)
			(xy 174.899895 -405.784264) (xy 174.893402 -405.76708) (xy 174.887636 -405.75992) (xy 174.865844 -405.734271)
			(xy 174.827896 -405.678684) (xy 174.796863 -405.61896) (xy 174.77319 -405.555955) (xy 174.757218 -405.490573)
			(xy 174.749174 -405.42375) (xy 174.749174 -405.356444) (xy 174.757219 -405.289621) (xy 174.773192 -405.224239)
			(xy 174.796865 -405.161234) (xy 174.827899 -405.101511) (xy 174.865848 -405.045924) (xy 174.887636 -405.020272)
			(xy 174.893432 -405.013126) (xy 174.899946 -404.995936) (xy 174.900336 -404.986744) (xy 174.900336 -404.828756)
			(xy 174.900686 -404.818594) (xy 174.908503 -404.799834) (xy 174.922922 -404.785511) (xy 174.941734 -404.77782)
			(xy 174.951898 -404.777448) (xy 175.668178 -404.777448) (xy 175.678304 -404.777945) (xy 175.697027 -404.785667)
			(xy 175.711384 -404.79995) (xy 175.719202 -404.818632) (xy 175.71974 -404.828756) (xy 175.71974 -404.986744)
			(xy 175.720142 -404.995932) (xy 175.726663 -405.013115) (xy 175.73244 -405.020272) (xy 175.754224 -405.045927)
			(xy 175.792175 -405.101513) (xy 175.823209 -405.161236) (xy 175.846883 -405.22424) (xy 175.862857 -405.289622)
			(xy 175.870902 -405.356444) (xy 175.870902 -405.42375) (xy 175.862858 -405.490572) (xy 175.846885 -405.555954)
			(xy 175.823212 -405.618959) (xy 175.792178 -405.678682) (xy 175.754228 -405.734268) (xy 175.73244 -405.75992)
			(xy 175.726645 -405.767066) (xy 175.720131 -405.784256) (xy 175.71974 -405.793448) (xy 175.71974 -406.286716)
			(xy 175.720156 -406.295902) (xy 175.726667 -406.313086) (xy 175.73244 -406.320244) (xy 175.754197 -406.345922)
			(xy 175.792148 -406.401504) (xy 175.823184 -406.461224) (xy 175.846859 -406.524225) (xy 175.862835 -406.589604)
			(xy 175.870882 -406.656424) (xy 175.870885 -406.723727) (xy 175.862844 -406.790548) (xy 175.846873 -406.855929)
			(xy 175.823203 -406.918932) (xy 175.792173 -406.978655) (xy 175.754226 -407.03424) (xy 175.73244 -407.059892)
			(xy 175.726657 -407.067046) (xy 175.720136 -407.08423) (xy 175.71974 -407.09342) (xy 175.71974 -407.251408)
			(xy 175.719286 -407.261558) (xy 175.711495 -407.280302) (xy 175.697109 -407.294624) (xy 175.678329 -407.302331)
			(xy 175.668178 -407.302716) (xy 174.951898 -407.302716) (xy 174.941766 -407.302274) (xy 174.923036 -407.294537)
			(xy 174.908679 -407.280237) (xy 174.900867 -407.261538) (xy 174.900336 -407.251408) (xy 174.900336 -407.09342)
			(xy 174.899908 -407.084235) (xy 174.893406 -407.067051) (xy 174.887636 -407.059892) (xy 174.865817 -407.034266)
			(xy 174.827869 -406.978676) (xy 174.796837 -406.918948) (xy 174.773167 -406.85594) (xy 174.757196 -406.790555)
			(xy 174.749154 -406.72373) (xy 171.471117 -406.72373) (xy 171.471117 -406.723787) (xy 171.463044 -406.790724)
			(xy 171.44701 -406.856212) (xy 171.423247 -406.919308) (xy 171.392097 -406.979103) (xy 171.354008 -407.034736)
			(xy 171.332144 -407.0604) (xy 171.326358 -407.067552) (xy 171.319839 -407.084738) (xy 171.319444 -407.093928)
			(xy 171.319444 -407.251408) (xy 171.318922 -407.261512) (xy 171.31119 -407.280182) (xy 171.296905 -407.294475)
			(xy 171.278239 -407.302217) (xy 171.268136 -407.302716) (xy 170.551856 -407.302716) (xy 170.541746 -407.302251)
			(xy 170.52307 -407.294502) (xy 170.508778 -407.280199) (xy 170.501042 -407.261518) (xy 170.500548 -407.251408)
			(xy 170.500548 -407.093928) (xy 170.500114 -407.084744) (xy 170.493616 -407.067559) (xy 170.487848 -407.0604)
			(xy 170.465951 -407.034762) (xy 170.42786 -406.979124) (xy 170.396708 -406.919325) (xy 170.372944 -406.856224)
			(xy 170.356909 -406.790732) (xy 170.348835 -406.72379) (xy 167.070789 -406.72379) (xy 167.062756 -406.790548)
			(xy 167.046786 -406.855928) (xy 167.023117 -406.918931) (xy 166.992087 -406.978654) (xy 166.954142 -407.03424)
			(xy 166.932356 -407.059892) (xy 166.926575 -407.067048) (xy 166.920052 -407.08423) (xy 166.919656 -407.09342)
			(xy 166.919656 -407.251408) (xy 166.919186 -407.261556) (xy 166.911398 -407.280297) (xy 166.897017 -407.294618)
			(xy 166.878243 -407.302328) (xy 166.868094 -407.302716) (xy 166.151814 -407.302716) (xy 166.141683 -407.302261)
			(xy 166.122954 -407.294529) (xy 166.108595 -407.280233) (xy 166.100783 -407.261537) (xy 166.100252 -407.251408)
			(xy 166.100252 -407.09342) (xy 166.099821 -407.084235) (xy 166.093321 -407.067051) (xy 166.087552 -407.059892)
			(xy 166.065732 -407.034266) (xy 166.027784 -406.978676) (xy 165.996751 -406.918949) (xy 165.973079 -406.855941)
			(xy 165.957108 -406.790556) (xy 165.949066 -406.72373) (xy 162.671029 -406.72373) (xy 162.671029 -406.723787)
			(xy 162.662956 -406.790724) (xy 162.646923 -406.856212) (xy 162.62316 -406.919307) (xy 162.592011 -406.979102)
			(xy 162.553923 -407.034735) (xy 162.53206 -407.0604) (xy 162.526276 -407.067554) (xy 162.519755 -407.084738)
			(xy 162.51936 -407.093928) (xy 162.51936 -407.251408) (xy 162.518989 -407.261536) (xy 162.511231 -407.280247)
			(xy 162.4969 -407.294563) (xy 162.47818 -407.3023) (xy 162.468052 -407.302716) (xy 161.751772 -407.302716)
			(xy 161.741663 -407.302238) (xy 161.722988 -407.294494) (xy 161.708694 -407.280196) (xy 161.700958 -407.261517)
			(xy 161.700464 -407.251408) (xy 161.700464 -407.093928) (xy 161.700026 -407.084744) (xy 161.69353 -407.06756)
			(xy 161.687764 -407.0604) (xy 161.66587 -407.03476) (xy 161.627784 -406.979121) (xy 161.596637 -406.919321)
			(xy 161.572876 -406.856221) (xy 161.556844 -406.790729) (xy 161.548771 -406.723789) (xy 154.57678 -406.723789)
			(xy 154.57678 -409.523827) (xy 159.349136 -409.523827) (xy 159.34914 -409.456519) (xy 159.357187 -409.389695)
			(xy 159.373163 -409.324311) (xy 159.396839 -409.261305) (xy 159.427875 -409.20158) (xy 159.465827 -409.145992)
			(xy 159.487616 -409.12034) (xy 159.493422 -409.113202) (xy 159.499931 -409.096006) (xy 159.500316 -409.086812)
			(xy 159.500316 -408.593544) (xy 159.499881 -408.58436) (xy 159.493384 -408.567175) (xy 159.487616 -408.560016)
			(xy 159.465821 -408.53437) (xy 159.427874 -408.478782) (xy 159.396842 -408.419058) (xy 159.373171 -408.356052)
			(xy 159.357199 -408.29067) (xy 159.349156 -408.223847) (xy 159.349157 -408.156541) (xy 159.357201 -408.089719)
			(xy 159.373175 -408.024336) (xy 159.396847 -407.961331) (xy 159.42788 -407.901607) (xy 159.465828 -407.84602)
			(xy 159.487616 -407.820368) (xy 159.49341 -407.813221) (xy 159.499926 -407.796032) (xy 159.500316 -407.78684)
			(xy 159.500316 -407.628852) (xy 159.500683 -407.618693) (xy 159.508497 -407.599936) (xy 159.522911 -407.585614)
			(xy 159.541716 -407.577919) (xy 159.551878 -407.577544) (xy 160.268158 -407.577544) (xy 160.278283 -407.578061)
			(xy 160.297003 -407.585776) (xy 160.311361 -407.600053) (xy 160.319181 -407.61873) (xy 160.31972 -407.628852)
			(xy 160.31972 -407.78684) (xy 160.320107 -407.79603) (xy 160.326636 -407.813214) (xy 160.33242 -407.820368)
			(xy 160.354201 -407.846026) (xy 160.392153 -407.901611) (xy 160.423189 -407.961333) (xy 160.446864 -408.024337)
			(xy 160.462838 -408.089719) (xy 160.470884 -408.156541) (xy 160.470885 -408.223847) (xy 160.462841 -408.290669)
			(xy 160.446867 -408.356052) (xy 160.423194 -408.419056) (xy 160.392159 -408.478779) (xy 160.354208 -408.534364)
			(xy 160.33242 -408.560016) (xy 160.326636 -408.567171) (xy 160.320113 -408.584354) (xy 160.31972 -408.593544)
			(xy 160.31972 -409.086812) (xy 160.32012 -409.096) (xy 160.32664 -409.113185) (xy 160.33242 -409.12034)
			(xy 160.354174 -409.146021) (xy 160.392126 -409.201602) (xy 160.423163 -409.261321) (xy 160.44684 -409.324322)
			(xy 160.462817 -409.389701) (xy 160.470864 -409.456521) (xy 160.470867 -409.523824) (xy 160.462826 -409.590645)
			(xy 160.446856 -409.656026) (xy 160.423185 -409.719029) (xy 160.392154 -409.778751) (xy 160.354207 -409.834336)
			(xy 160.33242 -409.859988) (xy 160.326606 -409.867121) (xy 160.320101 -409.884321) (xy 160.31972 -409.893516)
			(xy 160.31972 -410.051504) (xy 160.319282 -410.061656) (xy 160.311489 -410.080404) (xy 160.297098 -410.094727)
			(xy 160.278312 -410.10243) (xy 160.268158 -410.102812) (xy 159.551878 -410.102812) (xy 159.541756 -410.102293)
			(xy 159.523044 -410.094568) (xy 159.508691 -410.080292) (xy 159.500863 -410.061623) (xy 159.500316 -410.051504)
			(xy 159.500316 -409.893516) (xy 159.499894 -409.88433) (xy 159.493388 -409.867146) (xy 159.487616 -409.859988)
			(xy 159.465794 -409.834365) (xy 159.427847 -409.778774) (xy 159.396817 -409.719046) (xy 159.373147 -409.656038)
			(xy 159.357177 -409.590652) (xy 159.349136 -409.523827) (xy 154.57678 -409.523827) (xy 154.57678 -410.6237)
			(xy 161.548783 -410.6237) (xy 161.548784 -410.556276) (xy 161.556861 -410.489337) (xy 161.572897 -410.423848)
			(xy 161.596662 -410.36075) (xy 161.627812 -410.300953) (xy 161.6659 -410.245318) (xy 161.687764 -410.219652)
			(xy 161.693571 -410.212515) (xy 161.700078 -410.195318) (xy 161.700464 -410.186124) (xy 161.700464 -409.693872)
			(xy 161.700053 -409.684685) (xy 161.693538 -409.667502) (xy 161.687764 -409.660344) (xy 161.665913 -409.634668)
			(xy 161.627826 -409.579035) (xy 161.596677 -409.519239) (xy 161.572914 -409.456144) (xy 161.556879 -409.390657)
			(xy 161.548802 -409.32372) (xy 161.548801 -409.256298) (xy 161.556875 -409.189361) (xy 161.572909 -409.123873)
			(xy 161.59667 -409.060777) (xy 161.627817 -409.000981) (xy 161.665902 -408.945346) (xy 161.687764 -408.91968)
			(xy 161.693559 -408.912534) (xy 161.700073 -408.895344) (xy 161.700464 -408.886152) (xy 161.700464 -408.728672)
			(xy 161.700961 -408.718566) (xy 161.708701 -408.699894) (xy 161.722994 -408.685601) (xy 161.741666 -408.677861)
			(xy 161.751772 -408.677364) (xy 162.468052 -408.677364) (xy 162.478167 -408.677854) (xy 162.496863 -408.68558)
			(xy 162.511177 -408.699874) (xy 162.518931 -408.718558) (xy 162.51936 -408.728672) (xy 162.51936 -408.886152)
			(xy 162.519802 -408.895336) (xy 162.526295 -408.91252) (xy 162.53206 -408.91968) (xy 162.553937 -408.945335)
			(xy 162.592028 -409.00097) (xy 162.623181 -409.060767) (xy 162.646946 -409.123866) (xy 162.662982 -409.189356)
			(xy 162.671057 -409.256296) (xy 162.671056 -409.323722) (xy 162.662978 -409.390662) (xy 162.64694 -409.456152)
			(xy 162.623173 -409.519249) (xy 162.620757 -409.523886) (xy 163.748905 -409.523886) (xy 163.748908 -409.45646)
			(xy 163.756988 -409.389519) (xy 163.773027 -409.324027) (xy 163.796796 -409.260929) (xy 163.827952 -409.201132)
			(xy 163.866045 -409.145497) (xy 163.887912 -409.119832) (xy 163.893721 -409.112696) (xy 163.900228 -409.095498)
			(xy 163.900612 -409.086304) (xy 163.900612 -408.594052) (xy 163.900174 -408.584868) (xy 163.893679 -408.567683)
			(xy 163.887912 -408.560524) (xy 163.86604 -408.534865) (xy 163.82795 -408.47923) (xy 163.796799 -408.419433)
			(xy 163.773035 -408.356335) (xy 163.757 -408.290845) (xy 163.748925 -408.223906) (xy 163.748925 -408.156482)
			(xy 163.757002 -408.089543) (xy 163.773039 -408.024053) (xy 163.796804 -407.960956) (xy 163.827957 -407.901159)
			(xy 163.866047 -407.845525) (xy 163.887912 -407.81986) (xy 163.893709 -407.812715) (xy 163.900223 -407.795524)
			(xy 163.900612 -407.786332) (xy 163.900612 -407.628852) (xy 163.901046 -407.618739) (xy 163.908802 -407.600057)
			(xy 163.923114 -407.585764) (xy 163.941806 -407.578033) (xy 163.95192 -407.577544) (xy 164.6682 -407.577544)
			(xy 164.678302 -407.578084) (xy 164.696969 -407.585811) (xy 164.711262 -407.60009) (xy 164.719007 -407.618751)
			(xy 164.719508 -407.628852) (xy 164.719508 -407.786332) (xy 164.719901 -407.795521) (xy 164.726426 -407.812705)
			(xy 164.732208 -407.81986) (xy 164.754064 -407.845532) (xy 164.792152 -407.901166) (xy 164.823303 -407.960961)
			(xy 164.847067 -408.024057) (xy 164.863103 -408.089545) (xy 164.871179 -408.156483) (xy 164.87118 -408.223905)
			(xy 164.863105 -408.290843) (xy 164.847071 -408.356332) (xy 164.823308 -408.419428) (xy 164.792158 -408.479224)
			(xy 164.754071 -408.534859) (xy 164.732208 -408.560524) (xy 164.72642 -408.567675) (xy 164.7199 -408.584861)
			(xy 164.719508 -408.594052) (xy 164.719508 -409.086304) (xy 164.719915 -409.095492) (xy 164.726431 -409.112676)
			(xy 164.732208 -409.119832) (xy 164.754036 -409.145527) (xy 164.792126 -409.201157) (xy 164.823277 -409.260949)
			(xy 164.847043 -409.324042) (xy 164.863081 -409.389528) (xy 164.87116 -409.456463) (xy 164.871163 -409.523883)
			(xy 164.863091 -409.590819) (xy 164.847059 -409.656306) (xy 164.8233 -409.719401) (xy 164.792153 -409.779196)
			(xy 164.75407 -409.834831) (xy 164.732208 -409.860496) (xy 164.726432 -409.867656) (xy 164.719905 -409.884835)
			(xy 164.719508 -409.894024) (xy 164.719508 -410.051504) (xy 164.719018 -410.061612) (xy 164.711281 -410.080289)
			(xy 164.696985 -410.094583) (xy 164.678308 -410.102319) (xy 164.6682 -410.102812) (xy 163.95192 -410.102812)
			(xy 163.9418 -410.102368) (xy 163.923099 -410.094629) (xy 163.908785 -410.080321) (xy 163.901037 -410.061624)
			(xy 163.900612 -410.051504) (xy 163.900612 -409.894024) (xy 163.900188 -409.884838) (xy 163.893683 -409.867654)
			(xy 163.887912 -409.860496) (xy 163.866012 -409.83486) (xy 163.827924 -409.779222) (xy 163.796774 -409.719422)
			(xy 163.773011 -409.656321) (xy 163.756978 -409.590828) (xy 163.748905 -409.523886) (xy 162.620757 -409.523886)
			(xy 162.592019 -409.579046) (xy 162.553926 -409.634679) (xy 162.53206 -409.660344) (xy 162.526257 -409.667485)
			(xy 162.519747 -409.684679) (xy 162.51936 -409.693872) (xy 162.51936 -410.186124) (xy 162.519768 -410.195311)
			(xy 162.526284 -410.212495) (xy 162.53206 -410.219652) (xy 162.55391 -410.24533) (xy 162.592001 -410.300961)
			(xy 162.623155 -410.360755) (xy 162.646922 -410.423851) (xy 162.66296 -410.489339) (xy 162.671038 -410.556276)
			(xy 162.671039 -410.623641) (xy 165.949078 -410.623641) (xy 165.949079 -410.556335) (xy 165.957125 -410.489511)
			(xy 165.9731 -410.424127) (xy 165.996775 -410.361122) (xy 166.027811 -410.301398) (xy 166.065763 -410.245812)
			(xy 166.087552 -410.22016) (xy 166.093354 -410.213019) (xy 166.099864 -410.195825) (xy 166.100252 -410.186632)
			(xy 166.100252 -409.693364) (xy 166.099847 -409.684176) (xy 166.093328 -409.666993) (xy 166.087552 -409.659836)
			(xy 166.065776 -409.634174) (xy 166.027826 -409.578589) (xy 165.996791 -409.518867) (xy 165.973117 -409.455864)
			(xy 165.957143 -409.390483) (xy 165.949098 -409.323661) (xy 165.949097 -409.256357) (xy 165.95714 -409.189535)
			(xy 165.973112 -409.124153) (xy 165.996784 -409.061149) (xy 166.027817 -409.001426) (xy 166.065765 -408.94584)
			(xy 166.087552 -408.920188) (xy 166.093343 -408.913039) (xy 166.099859 -408.895851) (xy 166.100252 -408.88666)
			(xy 166.100252 -408.728672) (xy 166.100698 -408.718522) (xy 166.108493 -408.699778) (xy 166.122882 -408.685458)
			(xy 166.141662 -408.67775) (xy 166.151814 -408.677364) (xy 166.868094 -408.677364) (xy 166.878223 -408.677832)
			(xy 166.896949 -408.685562) (xy 166.911306 -408.699855) (xy 166.919121 -408.718545) (xy 166.919656 -408.728672)
			(xy 166.919656 -408.88666) (xy 166.920095 -408.895844) (xy 166.92659 -408.913028) (xy 166.932356 -408.920188)
			(xy 166.954156 -408.94583) (xy 166.992105 -409.001418) (xy 167.023138 -409.061143) (xy 167.04681 -409.124149)
			(xy 167.062782 -409.189532) (xy 167.070826 -409.256356) (xy 167.070824 -409.323662) (xy 167.062779 -409.390486)
			(xy 167.046805 -409.455869) (xy 167.02313 -409.518874) (xy 167.020557 -409.523826) (xy 168.149224 -409.523826)
			(xy 168.149228 -409.456519) (xy 168.157275 -409.389695) (xy 168.17325 -409.324311) (xy 168.196925 -409.261305)
			(xy 168.227961 -409.201581) (xy 168.265911 -409.145993) (xy 168.2877 -409.12034) (xy 168.293505 -409.1132)
			(xy 168.300014 -409.096006) (xy 168.3004 -409.086812) (xy 168.3004 -408.593544) (xy 168.299969 -408.584359)
			(xy 168.29347 -408.567174) (xy 168.2877 -408.560016) (xy 168.265906 -408.53437) (xy 168.22796 -408.478782)
			(xy 168.196929 -408.419057) (xy 168.173258 -408.356052) (xy 168.157287 -408.290669) (xy 168.149244 -408.223846)
			(xy 168.149245 -408.156542) (xy 168.157289 -408.089719) (xy 168.173262 -408.024337) (xy 168.196934 -407.961332)
			(xy 168.227966 -407.901608) (xy 168.265913 -407.846021) (xy 168.2877 -407.820368) (xy 168.293493 -407.81322)
			(xy 168.30001 -407.796032) (xy 168.3004 -407.78684) (xy 168.3004 -407.628852) (xy 168.300782 -407.618695)
			(xy 168.308594 -407.599941) (xy 168.323002 -407.58562) (xy 168.341802 -407.577922) (xy 168.351962 -407.577544)
			(xy 169.068242 -407.577544) (xy 169.078372 -407.577992) (xy 169.097095 -407.585735) (xy 169.11145 -407.600032)
			(xy 169.119267 -407.618724) (xy 169.119804 -407.628852) (xy 169.119804 -407.78684) (xy 169.120194 -407.796029)
			(xy 169.126721 -407.813214) (xy 169.132504 -407.820368) (xy 169.154283 -407.846027) (xy 169.192229 -407.901614)
			(xy 169.22326 -407.961337) (xy 169.246931 -408.02434) (xy 169.262904 -408.089721) (xy 169.270948 -408.156542)
			(xy 169.270948 -408.223846) (xy 169.262906 -408.290667) (xy 169.246935 -408.356048) (xy 169.223265 -408.419052)
			(xy 169.192235 -408.478776) (xy 169.15429 -408.534363) (xy 169.132504 -408.560016) (xy 169.126719 -408.567169)
			(xy 169.120197 -408.584354) (xy 169.119804 -408.593544) (xy 169.119804 -409.086812) (xy 169.120208 -409.096)
			(xy 169.126726 -409.113184) (xy 169.132504 -409.12034) (xy 169.154255 -409.146022) (xy 169.192202 -409.201605)
			(xy 169.223235 -409.261325) (xy 169.246908 -409.324325) (xy 169.262882 -409.389704) (xy 169.270928 -409.456522)
			(xy 169.270931 -409.523824) (xy 169.262891 -409.590643) (xy 169.246924 -409.656023) (xy 169.223257 -409.719026)
			(xy 169.19223 -409.778748) (xy 169.154288 -409.834335) (xy 169.132504 -409.859988) (xy 169.126688 -409.86712)
			(xy 169.120185 -409.88432) (xy 169.119804 -409.893516) (xy 169.119804 -410.051504) (xy 169.119382 -410.061658)
			(xy 169.111586 -410.08041) (xy 169.097189 -410.094733) (xy 169.078398 -410.102433) (xy 169.068242 -410.102812)
			(xy 168.351962 -410.102812) (xy 168.341839 -410.102306) (xy 168.323127 -410.094575) (xy 168.308774 -410.080296)
			(xy 168.300947 -410.061624) (xy 168.3004 -410.051504) (xy 168.3004 -409.893516) (xy 168.299982 -409.88433)
			(xy 168.293474 -409.867145) (xy 168.2877 -409.859988) (xy 168.265878 -409.834364) (xy 168.227933 -409.778773)
			(xy 168.196903 -409.719045) (xy 168.173234 -409.656037) (xy 168.157265 -409.590652) (xy 168.149224 -409.523826)
			(xy 167.020557 -409.523826) (xy 166.992095 -409.578598) (xy 166.954145 -409.634184) (xy 166.932356 -409.659836)
			(xy 166.926556 -409.666979) (xy 166.920045 -409.684171) (xy 166.919656 -409.693364) (xy 166.919656 -410.186632)
			(xy 166.920061 -410.19582) (xy 166.926579 -410.213003) (xy 166.932356 -410.22016) (xy 166.954128 -410.245825)
			(xy 166.992078 -410.30141) (xy 167.023112 -410.361131) (xy 167.046786 -410.424134) (xy 167.06276 -410.489515)
			(xy 167.070805 -410.556336) (xy 167.070807 -410.62364) (xy 167.0708 -410.623701) (xy 170.348846 -410.623701)
			(xy 170.348847 -410.556275) (xy 170.356926 -410.489335) (xy 170.372964 -410.423844) (xy 170.396732 -410.360747)
			(xy 170.427888 -410.30095) (xy 170.465981 -410.245316) (xy 170.487848 -410.219652) (xy 170.493653 -410.212513)
			(xy 170.500162 -410.195318) (xy 170.500548 -410.186124) (xy 170.500548 -409.693872) (xy 170.50014 -409.684685)
			(xy 170.493624 -409.667501) (xy 170.487848 -409.660344) (xy 170.465994 -409.63467) (xy 170.427902 -409.579038)
			(xy 170.396748 -409.519243) (xy 170.372981 -409.456147) (xy 170.356943 -409.390659) (xy 170.348866 -409.323721)
			(xy 170.348865 -409.256297) (xy 170.35694 -409.189359) (xy 170.372976 -409.12387) (xy 170.396741 -409.060773)
			(xy 170.427893 -409.000978) (xy 170.465983 -408.945344) (xy 170.487848 -408.91968) (xy 170.493642 -408.912533)
			(xy 170.500157 -408.895344) (xy 170.500548 -408.886152) (xy 170.500548 -408.728672) (xy 170.501061 -408.718568)
			(xy 170.508798 -408.699899) (xy 170.523086 -408.685607) (xy 170.541752 -408.677864) (xy 170.551856 -408.677364)
			(xy 171.268136 -408.677364) (xy 171.278243 -408.677855) (xy 171.296915 -408.685598) (xy 171.311207 -408.699892)
			(xy 171.318947 -408.718565) (xy 171.319444 -408.728672) (xy 171.319444 -408.886152) (xy 171.31989 -408.895335)
			(xy 171.32638 -408.912519) (xy 171.332144 -408.91968) (xy 171.354022 -408.945335) (xy 171.392114 -409.000969)
			(xy 171.423267 -409.060766) (xy 171.447033 -409.123865) (xy 171.463069 -409.189356) (xy 171.471145 -409.256296)
			(xy 171.471144 -409.323722) (xy 171.463066 -409.390662) (xy 171.447028 -409.456152) (xy 171.42326 -409.51925)
			(xy 171.420875 -409.523827) (xy 172.548991 -409.523827) (xy 172.548995 -409.456519) (xy 172.557043 -409.389693)
			(xy 172.573021 -409.324308) (xy 172.5967 -409.261302) (xy 172.62774 -409.201577) (xy 172.665697 -409.145992)
			(xy 172.687488 -409.12034) (xy 172.693291 -409.113199) (xy 172.699802 -409.096005) (xy 172.700188 -409.086812)
			(xy 172.700188 -408.593544) (xy 172.699759 -408.584359) (xy 172.693259 -408.567174) (xy 172.687488 -408.560016)
			(xy 172.665691 -408.534371) (xy 172.627739 -408.478785) (xy 172.596704 -408.419061) (xy 172.573029 -408.356055)
			(xy 172.557055 -408.290671) (xy 172.549011 -408.223847) (xy 172.549012 -408.156541) (xy 172.557057 -408.089717)
			(xy 172.573033 -408.024333) (xy 172.596708 -407.961328) (xy 172.627745 -407.901605) (xy 172.665698 -407.84602)
			(xy 172.687488 -407.820368) (xy 172.693279 -407.813219) (xy 172.699797 -407.796031) (xy 172.700188 -407.78684)
			(xy 172.700188 -407.628852) (xy 172.700582 -407.618696) (xy 172.708391 -407.599945) (xy 172.722796 -407.585624)
			(xy 172.741592 -407.577924) (xy 172.75175 -407.577544) (xy 173.46803 -407.577544) (xy 173.478159 -407.578002)
			(xy 173.496882 -407.58574) (xy 173.511237 -407.600035) (xy 173.519055 -407.618725) (xy 173.519592 -407.628852)
			(xy 173.519592 -407.78684) (xy 173.519985 -407.796029) (xy 173.526511 -407.813213) (xy 173.532292 -407.820368)
			(xy 173.554071 -407.846027) (xy 173.592018 -407.901613) (xy 173.62305 -407.961336) (xy 173.646722 -408.02434)
			(xy 173.662694 -408.089721) (xy 173.670739 -408.156542) (xy 173.670739 -408.223846) (xy 173.662697 -408.290667)
			(xy 173.646725 -408.356049) (xy 173.623055 -408.419053) (xy 173.592024 -408.478776) (xy 173.554078 -408.534363)
			(xy 173.532292 -408.560016) (xy 173.526505 -408.567168) (xy 173.519985 -408.584353) (xy 173.519592 -408.593544)
			(xy 173.519592 -409.086812) (xy 173.519998 -409.096) (xy 173.526515 -409.113184) (xy 173.532292 -409.12034)
			(xy 173.554043 -409.146022) (xy 173.591991 -409.201605) (xy 173.623024 -409.261324) (xy 173.646698 -409.324325)
			(xy 173.662672 -409.389703) (xy 173.670719 -409.456522) (xy 173.670722 -409.523824) (xy 173.662682 -409.590643)
			(xy 173.646714 -409.656023) (xy 173.623047 -409.719026) (xy 173.592019 -409.778749) (xy 173.554077 -409.834336)
			(xy 173.532292 -409.859988) (xy 173.526475 -409.867118) (xy 173.519973 -409.88432) (xy 173.519592 -409.893516)
			(xy 173.519592 -410.051504) (xy 173.519181 -410.061659) (xy 173.511383 -410.080413) (xy 173.496983 -410.094737)
			(xy 173.478187 -410.102435) (xy 173.46803 -410.102812) (xy 172.75175 -410.102812) (xy 172.741633 -410.102234)
			(xy 172.722923 -410.094532) (xy 172.708567 -410.080274) (xy 172.700736 -410.061618) (xy 172.700188 -410.051504)
			(xy 172.700188 -409.893516) (xy 172.699773 -409.884329) (xy 172.693263 -409.867145) (xy 172.687488 -409.859988)
			(xy 172.665663 -409.834366) (xy 172.627713 -409.778776) (xy 172.596678 -409.719049) (xy 172.573005 -409.65604)
			(xy 172.557033 -409.590654) (xy 172.548991 -409.523827) (xy 171.420875 -409.523827) (xy 171.392104 -409.579046)
			(xy 171.354011 -409.63468) (xy 171.332144 -409.660344) (xy 171.326339 -409.667483) (xy 171.319831 -409.684679)
			(xy 171.319444 -409.693872) (xy 171.319444 -410.186124) (xy 171.319855 -410.195311) (xy 171.32637 -410.212494)
			(xy 171.332144 -410.219652) (xy 171.353994 -410.245329) (xy 171.392087 -410.300961) (xy 171.423242 -410.360755)
			(xy 171.447009 -410.42385) (xy 171.463047 -410.489338) (xy 171.471125 -410.556276) (xy 171.471127 -410.623641)
			(xy 174.749166 -410.623641) (xy 174.749167 -410.556335) (xy 174.757213 -410.489511) (xy 174.773187 -410.424128)
			(xy 174.796862 -410.361123) (xy 174.827897 -410.301399) (xy 174.865847 -410.245812) (xy 174.887636 -410.22016)
			(xy 174.893437 -410.213018) (xy 174.899948 -410.195825) (xy 174.900336 -410.186632) (xy 174.900336 -409.693364)
			(xy 174.899935 -409.684176) (xy 174.893414 -409.666992) (xy 174.887636 -409.659836) (xy 174.86586 -409.634174)
			(xy 174.827911 -409.578589) (xy 174.796878 -409.518867) (xy 174.773205 -409.455863) (xy 174.757231 -409.390482)
			(xy 174.749186 -409.323661) (xy 174.749185 -409.256357) (xy 174.757228 -409.189535) (xy 174.773199 -409.124154)
			(xy 174.79687 -409.06115) (xy 174.827902 -409.001427) (xy 174.865849 -408.94584) (xy 174.887636 -408.920188)
			(xy 174.893425 -408.913037) (xy 174.899943 -408.895851) (xy 174.900336 -408.88666) (xy 174.900336 -408.728672)
			(xy 174.900699 -408.718512) (xy 174.908511 -408.699752) (xy 174.922926 -408.685428) (xy 174.941735 -408.677736)
			(xy 174.951898 -408.677364) (xy 175.668178 -408.677364) (xy 175.678306 -408.677845) (xy 175.697032 -408.68557)
			(xy 175.711389 -408.699859) (xy 175.719205 -408.718546) (xy 175.71974 -408.728672) (xy 175.71974 -408.88666)
			(xy 175.720183 -408.895843) (xy 175.726675 -408.913028) (xy 175.73244 -408.920188) (xy 175.75424 -408.94583)
			(xy 175.79219 -409.001418) (xy 175.823224 -409.061142) (xy 175.846897 -409.124148) (xy 175.862869 -409.189532)
			(xy 175.870913 -409.256356) (xy 175.870912 -409.323662) (xy 175.862866 -409.390486) (xy 175.846891 -409.455869)
			(xy 175.823216 -409.518874) (xy 175.792181 -409.578598) (xy 175.754229 -409.634184) (xy 175.73244 -409.659836)
			(xy 175.726638 -409.666977) (xy 175.720128 -409.684171) (xy 175.71974 -409.693364) (xy 175.71974 -410.186632)
			(xy 175.720148 -410.195819) (xy 175.726665 -410.213003) (xy 175.73244 -410.22016) (xy 175.754213 -410.245825)
			(xy 175.792163 -410.301409) (xy 175.823198 -410.361131) (xy 175.846873 -410.424134) (xy 175.862848 -410.489514)
			(xy 175.870893 -410.556336) (xy 175.870895 -410.62364) (xy 175.862852 -410.690462) (xy 175.84688 -410.755843)
			(xy 175.823208 -410.818847) (xy 175.792176 -410.87857) (xy 175.754227 -410.934156) (xy 175.73244 -410.959808)
			(xy 175.72665 -410.966958) (xy 175.720133 -410.984145) (xy 175.71974 -410.993336) (xy 175.71974 -411.151324)
			(xy 175.719299 -411.161475) (xy 175.711503 -411.18022) (xy 175.697113 -411.194541) (xy 175.678331 -411.202247)
			(xy 175.668178 -411.202632) (xy 174.951898 -411.202632) (xy 174.941768 -411.202174) (xy 174.923041 -411.194441)
			(xy 174.908684 -411.180145) (xy 174.90087 -411.161452) (xy 174.900336 -411.151324) (xy 174.900336 -410.993336)
			(xy 174.8999 -410.984152) (xy 174.893403 -410.966968) (xy 174.887636 -410.959808) (xy 174.865833 -410.934169)
			(xy 174.827884 -410.87858) (xy 174.796852 -410.818855) (xy 174.77318 -410.755849) (xy 174.757208 -410.690465)
			(xy 174.749166 -410.623641) (xy 171.471127 -410.623641) (xy 171.471127 -410.6237) (xy 171.463052 -410.690638)
			(xy 171.447016 -410.756127) (xy 171.423251 -410.819223) (xy 171.392099 -410.879019) (xy 171.354009 -410.934652)
			(xy 171.332144 -410.960316) (xy 171.326351 -410.967464) (xy 171.319836 -410.984653) (xy 171.319444 -410.993844)
			(xy 171.319444 -411.151324) (xy 171.318936 -411.161429) (xy 171.311198 -411.180099) (xy 171.296909 -411.194392)
			(xy 171.278241 -411.202133) (xy 171.268136 -411.202632) (xy 170.551856 -411.202632) (xy 170.541748 -411.202152)
			(xy 170.523075 -411.194405) (xy 170.508783 -411.180108) (xy 170.501044 -411.161432) (xy 170.500548 -411.151324)
			(xy 170.500548 -410.993844) (xy 170.500106 -410.98466) (xy 170.493613 -410.967476) (xy 170.487848 -410.960316)
			(xy 170.465967 -410.934665) (xy 170.427875 -410.879029) (xy 170.396723 -410.819232) (xy 170.372957 -410.756133)
			(xy 170.356921 -410.690641) (xy 170.348846 -410.623701) (xy 167.0708 -410.623701) (xy 167.062764 -410.690461)
			(xy 167.046793 -410.755843) (xy 167.023122 -410.818847) (xy 166.99209 -410.87857) (xy 166.954143 -410.934156)
			(xy 166.932356 -410.959808) (xy 166.926568 -410.966959) (xy 166.920049 -410.984145) (xy 166.919656 -410.993336)
			(xy 166.919656 -411.151324) (xy 166.919199 -411.161473) (xy 166.911406 -411.180215) (xy 166.897021 -411.194535)
			(xy 166.878245 -411.202244) (xy 166.868094 -411.202632) (xy 166.151814 -411.202632) (xy 166.141685 -411.202161)
			(xy 166.122959 -411.194433) (xy 166.108601 -411.180141) (xy 166.100786 -411.161451) (xy 166.100252 -411.151324)
			(xy 166.100252 -410.993336) (xy 166.099813 -410.984152) (xy 166.093318 -410.966968) (xy 166.087552 -410.959808)
			(xy 166.065748 -410.934169) (xy 166.027799 -410.878581) (xy 165.996765 -410.818856) (xy 165.973093 -410.75585)
			(xy 165.957121 -410.690466) (xy 165.949078 -410.623641) (xy 162.671039 -410.623641) (xy 162.671039 -410.6237)
			(xy 162.662964 -410.690637) (xy 162.646929 -410.756126) (xy 162.623165 -410.819223) (xy 162.592014 -410.879018)
			(xy 162.553924 -410.934651) (xy 162.53206 -410.960316) (xy 162.526269 -410.967465) (xy 162.519752 -410.984653)
			(xy 162.51936 -410.993844) (xy 162.51936 -411.151324) (xy 162.519003 -411.161453) (xy 162.511239 -411.180165)
			(xy 162.496904 -411.19448) (xy 162.478182 -411.202217) (xy 162.468052 -411.202632) (xy 161.751772 -411.202632)
			(xy 161.741665 -411.202139) (xy 161.722993 -411.194398) (xy 161.7087 -411.180104) (xy 161.700961 -411.161431)
			(xy 161.700464 -411.151324) (xy 161.700464 -410.993844) (xy 161.700019 -410.984661) (xy 161.693528 -410.967477)
			(xy 161.687764 -410.960316) (xy 161.665886 -410.934663) (xy 161.6278 -410.879026) (xy 161.596652 -410.819228)
			(xy 161.57289 -410.756129) (xy 161.556857 -410.690639) (xy 161.548783 -410.6237) (xy 154.57678 -410.6237)
			(xy 154.57678 -417.371276) (xy 154.576371 -417.383441) (xy 154.568857 -417.406581) (xy 154.554556 -417.426265)
			(xy 154.53487 -417.440562) (xy 154.511729 -417.448073) (xy 154.499564 -417.448492) (xy 141.100302 -417.448492)
			(xy 141.088157 -417.448035) (xy 141.06506 -417.440516) (xy 141.045426 -417.426216) (xy 141.031183 -417.406541)
			(xy 141.02373 -417.383422) (xy 141.02334 -417.371276) (xy 66.525648 -417.371276) (xy 66.525648 -417.533836)
			(xy 66.525172 -417.545883) (xy 66.517735 -417.568802) (xy 66.503597 -417.588313) (xy 66.484133 -417.602517)
			(xy 66.46124 -417.610031) (xy 66.449194 -417.610544) (xy 53.151024 -417.610544) (xy 53.138954 -417.610016)
			(xy 53.115994 -417.602564) (xy 53.09646 -417.588383) (xy 53.082263 -417.56886) (xy 53.074793 -417.545905)
			(xy 53.074316 -417.533836) (xy 53.074316 -417.289488) (xy 53.073808 -417.289488) (xy 0.681656 -417.289488)
			(xy 0.736245 -417.384039) (xy 0.79912 -417.476259) (xy 0.86871 -417.563523) (xy 0.944627 -417.645342)
			(xy 1.026446 -417.721259) (xy 1.113709 -417.790849) (xy 1.205929 -417.853724) (xy 1.302589 -417.909531)
			(xy 1.40315 -417.957958) (xy 1.507049 -417.998736) (xy 1.613704 -418.031635) (xy 1.72252 -418.056471)
			(xy 1.832887 -418.073107) (xy 1.944189 -418.081448) (xy 1.999996 -418.081968)
		)
		(stroke
			(width 0)
			(type solid)
		)
		(fill yes)
		(layer "In4.Cu")
		(net "GND")
	)
	(gr_circle
		(center 36.849812 -316.799722)
		(end 37.103812 -316.799722)
		(stroke
			(width 0.1016)
			(type default)
		)
		(fill no)
		(layer "In4.Cu")
	)
	(gr_circle
		(center 36.849812 -314.899802)
		(end 37.103812 -314.899802)
		(stroke
			(width 0.1016)
			(type default)
		)
		(fill no)
		(layer "In4.Cu")
	)
	(gr_circle
		(center 36.849812 -312.049922)
		(end 37.103812 -312.049922)
		(stroke
			(width 0.1016)
			(type default)
		)
		(fill no)
		(layer "In4.Cu")
	)
	(gr_circle
		(center 36.849812 -310.149748)
		(end 37.103812 -310.149748)
		(stroke
			(width 0.1016)
			(type default)
		)
		(fill no)
		(layer "In4.Cu")
	)
	(gr_circle
		(center 36.849812 -308.249828)
		(end 37.103812 -308.249828)
		(stroke
			(width 0.1016)
			(type default)
		)
		(fill no)
		(layer "In4.Cu")
	)
	(gr_circle
		(center 36.849812 -306.349908)
		(end 37.103812 -306.349908)
		(stroke
			(width 0.1016)
			(type default)
		)
		(fill no)
		(layer "In4.Cu")
	)
	(gr_circle
		(center 36.849812 -304.449734)
		(end 37.103812 -304.449734)
		(stroke
			(width 0.1016)
			(type default)
		)
		(fill no)
		(layer "In4.Cu")
	)
	(gr_circle
		(center 36.849812 -302.549814)
		(end 37.103812 -302.549814)
		(stroke
			(width 0.1016)
			(type default)
		)
		(fill no)
		(layer "In4.Cu")
	)
	(gr_circle
		(center 37.799772 -316.799722)
		(end 38.053772 -316.799722)
		(stroke
			(width 0.1016)
			(type default)
		)
		(fill no)
		(layer "In4.Cu")
	)
	(gr_circle
		(center 37.799772 -314.899802)
		(end 38.053772 -314.899802)
		(stroke
			(width 0.1016)
			(type default)
		)
		(fill no)
		(layer "In4.Cu")
	)
	(gr_circle
		(center 37.799772 -312.049922)
		(end 38.053772 -312.049922)
		(stroke
			(width 0.1016)
			(type default)
		)
		(fill no)
		(layer "In4.Cu")
	)
	(gr_circle
		(center 37.799772 -310.149748)
		(end 38.053772 -310.149748)
		(stroke
			(width 0.1016)
			(type default)
		)
		(fill no)
		(layer "In4.Cu")
	)
	(gr_circle
		(center 37.799772 -308.249828)
		(end 38.053772 -308.249828)
		(stroke
			(width 0.1016)
			(type default)
		)
		(fill no)
		(layer "In4.Cu")
	)
	(gr_circle
		(center 37.799772 -306.349908)
		(end 38.053772 -306.349908)
		(stroke
			(width 0.1016)
			(type default)
		)
		(fill no)
		(layer "In4.Cu")
	)
	(gr_circle
		(center 37.799772 -304.449734)
		(end 38.053772 -304.449734)
		(stroke
			(width 0.1016)
			(type default)
		)
		(fill no)
		(layer "In4.Cu")
	)
	(gr_circle
		(center 37.799772 -302.549814)
		(end 38.053772 -302.549814)
		(stroke
			(width 0.1016)
			(type default)
		)
		(fill no)
		(layer "In4.Cu")
	)
	(gr_circle
		(center 38.749986 -318.699896)
		(end 39.003986 -318.699896)
		(stroke
			(width 0.1016)
			(type default)
		)
		(fill no)
		(layer "In4.Cu")
	)
	(gr_circle
		(center 38.749986 -317.749936)
		(end 39.003986 -317.749936)
		(stroke
			(width 0.1016)
			(type default)
		)
		(fill no)
		(layer "In4.Cu")
	)
	(gr_circle
		(center 38.749986 -313.949842)
		(end 39.003986 -313.949842)
		(stroke
			(width 0.1016)
			(type default)
		)
		(fill no)
		(layer "In4.Cu")
	)
	(gr_circle
		(center 38.749986 -312.999882)
		(end 39.003986 -312.999882)
		(stroke
			(width 0.1016)
			(type default)
		)
		(fill no)
		(layer "In4.Cu")
	)
	(gr_circle
		(center 38.749986 -309.199788)
		(end 39.003986 -309.199788)
		(stroke
			(width 0.1016)
			(type default)
		)
		(fill no)
		(layer "In4.Cu")
	)
	(gr_circle
		(center 38.749986 -307.299868)
		(end 39.003986 -307.299868)
		(stroke
			(width 0.1016)
			(type default)
		)
		(fill no)
		(layer "In4.Cu")
	)
	(gr_circle
		(center 38.749986 -305.399948)
		(end 39.003986 -305.399948)
		(stroke
			(width 0.1016)
			(type default)
		)
		(fill no)
		(layer "In4.Cu")
	)
	(gr_circle
		(center 38.749986 -303.499774)
		(end 39.003986 -303.499774)
		(stroke
			(width 0.1016)
			(type default)
		)
		(fill no)
		(layer "In4.Cu")
	)
	(gr_circle
		(center 38.749986 -301.599854)
		(end 39.003986 -301.599854)
		(stroke
			(width 0.1016)
			(type default)
		)
		(fill no)
		(layer "In4.Cu")
	)
	(gr_circle
		(center 39.699946 -316.799722)
		(end 39.953946 -316.799722)
		(stroke
			(width 0.1016)
			(type default)
		)
		(fill no)
		(layer "In4.Cu")
	)
	(gr_circle
		(center 39.699946 -315.849762)
		(end 39.953946 -315.849762)
		(stroke
			(width 0.1016)
			(type default)
		)
		(fill no)
		(layer "In4.Cu")
	)
	(gr_circle
		(center 39.699946 -312.049922)
		(end 39.953946 -312.049922)
		(stroke
			(width 0.1016)
			(type default)
		)
		(fill no)
		(layer "In4.Cu")
	)
	(gr_circle
		(center 39.699946 -311.099962)
		(end 39.953946 -311.099962)
		(stroke
			(width 0.1016)
			(type default)
		)
		(fill no)
		(layer "In4.Cu")
	)
	(gr_circle
		(center 39.699946 -309.199788)
		(end 39.953946 -309.199788)
		(stroke
			(width 0.1016)
			(type default)
		)
		(fill no)
		(layer "In4.Cu")
	)
	(gr_circle
		(center 39.699946 -307.299868)
		(end 39.953946 -307.299868)
		(stroke
			(width 0.1016)
			(type default)
		)
		(fill no)
		(layer "In4.Cu")
	)
	(gr_circle
		(center 39.699946 -305.399948)
		(end 39.953946 -305.399948)
		(stroke
			(width 0.1016)
			(type default)
		)
		(fill no)
		(layer "In4.Cu")
	)
	(gr_circle
		(center 39.699946 -303.499774)
		(end 39.953946 -303.499774)
		(stroke
			(width 0.1016)
			(type default)
		)
		(fill no)
		(layer "In4.Cu")
	)
	(gr_circle
		(center 39.699946 -301.599854)
		(end 39.953946 -301.599854)
		(stroke
			(width 0.1016)
			(type default)
		)
		(fill no)
		(layer "In4.Cu")
	)
	(gr_circle
		(center 40.649906 -318.699896)
		(end 40.903906 -318.699896)
		(stroke
			(width 0.1016)
			(type default)
		)
		(fill no)
		(layer "In4.Cu")
	)
	(gr_circle
		(center 40.649906 -317.749936)
		(end 40.903906 -317.749936)
		(stroke
			(width 0.1016)
			(type default)
		)
		(fill no)
		(layer "In4.Cu")
	)
	(gr_circle
		(center 40.649906 -313.949842)
		(end 40.903906 -313.949842)
		(stroke
			(width 0.1016)
			(type default)
		)
		(fill no)
		(layer "In4.Cu")
	)
	(gr_circle
		(center 40.649906 -312.999882)
		(end 40.903906 -312.999882)
		(stroke
			(width 0.1016)
			(type default)
		)
		(fill no)
		(layer "In4.Cu")
	)
	(gr_circle
		(center 41.599866 -316.799722)
		(end 41.853866 -316.799722)
		(stroke
			(width 0.1016)
			(type default)
		)
		(fill no)
		(layer "In4.Cu")
	)
	(gr_circle
		(center 41.599866 -315.849762)
		(end 41.853866 -315.849762)
		(stroke
			(width 0.1016)
			(type default)
		)
		(fill no)
		(layer "In4.Cu")
	)
	(gr_circle
		(center 41.599866 -312.049922)
		(end 41.853866 -312.049922)
		(stroke
			(width 0.1016)
			(type default)
		)
		(fill no)
		(layer "In4.Cu")
	)
	(gr_circle
		(center 41.599866 -311.099962)
		(end 41.853866 -311.099962)
		(stroke
			(width 0.1016)
			(type default)
		)
		(fill no)
		(layer "In4.Cu")
	)
	(gr_circle
		(center 41.599866 -309.199788)
		(end 41.853866 -309.199788)
		(stroke
			(width 0.1016)
			(type default)
		)
		(fill no)
		(layer "In4.Cu")
	)
	(gr_circle
		(center 41.599866 -307.299868)
		(end 41.853866 -307.299868)
		(stroke
			(width 0.1016)
			(type default)
		)
		(fill no)
		(layer "In4.Cu")
	)
	(gr_circle
		(center 41.599866 -305.399948)
		(end 41.853866 -305.399948)
		(stroke
			(width 0.1016)
			(type default)
		)
		(fill no)
		(layer "In4.Cu")
	)
	(gr_circle
		(center 41.599866 -303.499774)
		(end 41.853866 -303.499774)
		(stroke
			(width 0.1016)
			(type default)
		)
		(fill no)
		(layer "In4.Cu")
	)
	(gr_circle
		(center 41.599866 -301.599854)
		(end 41.853866 -301.599854)
		(stroke
			(width 0.1016)
			(type default)
		)
		(fill no)
		(layer "In4.Cu")
	)
	(gr_circle
		(center 42.549826 -318.699896)
		(end 42.803826 -318.699896)
		(stroke
			(width 0.1016)
			(type default)
		)
		(fill no)
		(layer "In4.Cu")
	)
	(gr_circle
		(center 42.549826 -317.749936)
		(end 42.803826 -317.749936)
		(stroke
			(width 0.1016)
			(type default)
		)
		(fill no)
		(layer "In4.Cu")
	)
	(gr_circle
		(center 42.549826 -313.949842)
		(end 42.803826 -313.949842)
		(stroke
			(width 0.1016)
			(type default)
		)
		(fill no)
		(layer "In4.Cu")
	)
	(gr_circle
		(center 42.549826 -312.999882)
		(end 42.803826 -312.999882)
		(stroke
			(width 0.1016)
			(type default)
		)
		(fill no)
		(layer "In4.Cu")
	)
	(gr_circle
		(center 42.549826 -309.199788)
		(end 42.803826 -309.199788)
		(stroke
			(width 0.1016)
			(type default)
		)
		(fill no)
		(layer "In4.Cu")
	)
	(gr_circle
		(center 42.549826 -307.299868)
		(end 42.803826 -307.299868)
		(stroke
			(width 0.1016)
			(type default)
		)
		(fill no)
		(layer "In4.Cu")
	)
	(gr_circle
		(center 42.549826 -305.399948)
		(end 42.803826 -305.399948)
		(stroke
			(width 0.1016)
			(type default)
		)
		(fill no)
		(layer "In4.Cu")
	)
	(gr_circle
		(center 42.549826 -303.499774)
		(end 42.803826 -303.499774)
		(stroke
			(width 0.1016)
			(type default)
		)
		(fill no)
		(layer "In4.Cu")
	)
	(gr_circle
		(center 42.549826 -301.599854)
		(end 42.803826 -301.599854)
		(stroke
			(width 0.1016)
			(type default)
		)
		(fill no)
		(layer "In4.Cu")
	)
	(gr_circle
		(center 43.499786 -316.799722)
		(end 43.753786 -316.799722)
		(stroke
			(width 0.1016)
			(type default)
		)
		(fill no)
		(layer "In4.Cu")
	)
	(gr_circle
		(center 43.499786 -315.849762)
		(end 43.753786 -315.849762)
		(stroke
			(width 0.1016)
			(type default)
		)
		(fill no)
		(layer "In4.Cu")
	)
	(gr_circle
		(center 43.499786 -312.049922)
		(end 43.753786 -312.049922)
		(stroke
			(width 0.1016)
			(type default)
		)
		(fill no)
		(layer "In4.Cu")
	)
	(gr_circle
		(center 43.499786 -311.099962)
		(end 43.753786 -311.099962)
		(stroke
			(width 0.1016)
			(type default)
		)
		(fill no)
		(layer "In4.Cu")
	)
	(gr_circle
		(center 43.499786 -308.249828)
		(end 43.753786 -308.249828)
		(stroke
			(width 0.1016)
			(type default)
		)
		(fill no)
		(layer "In4.Cu")
	)
	(gr_circle
		(center 43.499786 -306.349908)
		(end 43.753786 -306.349908)
		(stroke
			(width 0.1016)
			(type default)
		)
		(fill no)
		(layer "In4.Cu")
	)
	(gr_circle
		(center 43.499786 -304.449734)
		(end 43.753786 -304.449734)
		(stroke
			(width 0.1016)
			(type default)
		)
		(fill no)
		(layer "In4.Cu")
	)
	(gr_circle
		(center 43.499786 -302.549814)
		(end 43.753786 -302.549814)
		(stroke
			(width 0.1016)
			(type default)
		)
		(fill no)
		(layer "In4.Cu")
	)
	(gr_circle
		(center 44.449746 -318.699896)
		(end 44.703746 -318.699896)
		(stroke
			(width 0.1016)
			(type default)
		)
		(fill no)
		(layer "In4.Cu")
	)
	(gr_circle
		(center 44.449746 -317.749936)
		(end 44.703746 -317.749936)
		(stroke
			(width 0.1016)
			(type default)
		)
		(fill no)
		(layer "In4.Cu")
	)
	(gr_circle
		(center 44.449746 -313.949842)
		(end 44.703746 -313.949842)
		(stroke
			(width 0.1016)
			(type default)
		)
		(fill no)
		(layer "In4.Cu")
	)
	(gr_circle
		(center 44.449746 -312.999882)
		(end 44.703746 -312.999882)
		(stroke
			(width 0.1016)
			(type default)
		)
		(fill no)
		(layer "In4.Cu")
	)
	(gr_circle
		(center 44.449746 -308.249828)
		(end 44.703746 -308.249828)
		(stroke
			(width 0.1016)
			(type default)
		)
		(fill no)
		(layer "In4.Cu")
	)
	(gr_circle
		(center 44.449746 -306.349908)
		(end 44.703746 -306.349908)
		(stroke
			(width 0.1016)
			(type default)
		)
		(fill no)
		(layer "In4.Cu")
	)
	(gr_circle
		(center 44.449746 -304.449734)
		(end 44.703746 -304.449734)
		(stroke
			(width 0.1016)
			(type default)
		)
		(fill no)
		(layer "In4.Cu")
	)
	(gr_circle
		(center 44.449746 -302.549814)
		(end 44.703746 -302.549814)
		(stroke
			(width 0.1016)
			(type default)
		)
		(fill no)
		(layer "In4.Cu")
	)
	(gr_circle
		(center 44.449746 -278.799798)
		(end 44.703746 -278.799798)
		(stroke
			(width 0.1016)
			(type default)
		)
		(fill no)
		(layer "In4.Cu")
	)
	(gr_circle
		(center 44.449746 -277.849838)
		(end 44.703746 -277.849838)
		(stroke
			(width 0.1016)
			(type default)
		)
		(fill no)
		(layer "In4.Cu")
	)
	(gr_circle
		(center 44.449746 -274.049744)
		(end 44.703746 -274.049744)
		(stroke
			(width 0.1016)
			(type default)
		)
		(fill no)
		(layer "In4.Cu")
	)
	(gr_circle
		(center 44.449746 -273.099784)
		(end 44.703746 -273.099784)
		(stroke
			(width 0.1016)
			(type default)
		)
		(fill no)
		(layer "In4.Cu")
	)
	(gr_circle
		(center 45.39996 -316.799722)
		(end 45.65396 -316.799722)
		(stroke
			(width 0.1016)
			(type default)
		)
		(fill no)
		(layer "In4.Cu")
	)
	(gr_circle
		(center 45.39996 -315.849762)
		(end 45.65396 -315.849762)
		(stroke
			(width 0.1016)
			(type default)
		)
		(fill no)
		(layer "In4.Cu")
	)
	(gr_circle
		(center 45.39996 -312.049922)
		(end 45.65396 -312.049922)
		(stroke
			(width 0.1016)
			(type default)
		)
		(fill no)
		(layer "In4.Cu")
	)
	(gr_circle
		(center 45.39996 -311.099962)
		(end 45.65396 -311.099962)
		(stroke
			(width 0.1016)
			(type default)
		)
		(fill no)
		(layer "In4.Cu")
	)
	(gr_circle
		(center 45.39996 -280.699464)
		(end 45.65396 -280.699464)
		(stroke
			(width 0.1016)
			(type default)
		)
		(fill no)
		(layer "In4.Cu")
	)
	(gr_circle
		(center 45.39996 -279.749504)
		(end 45.65396 -279.749504)
		(stroke
			(width 0.1016)
			(type default)
		)
		(fill no)
		(layer "In4.Cu")
	)
	(gr_circle
		(center 45.39996 -275.949918)
		(end 45.65396 -275.949918)
		(stroke
			(width 0.1016)
			(type default)
		)
		(fill no)
		(layer "In4.Cu")
	)
	(gr_circle
		(center 45.39996 -274.999958)
		(end 45.65396 -274.999958)
		(stroke
			(width 0.1016)
			(type default)
		)
		(fill no)
		(layer "In4.Cu")
	)
	(gr_circle
		(center 46.34992 -318.699896)
		(end 46.60392 -318.699896)
		(stroke
			(width 0.1016)
			(type default)
		)
		(fill no)
		(layer "In4.Cu")
	)
	(gr_circle
		(center 46.34992 -317.749936)
		(end 46.60392 -317.749936)
		(stroke
			(width 0.1016)
			(type default)
		)
		(fill no)
		(layer "In4.Cu")
	)
	(gr_circle
		(center 46.34992 -313.949842)
		(end 46.60392 -313.949842)
		(stroke
			(width 0.1016)
			(type default)
		)
		(fill no)
		(layer "In4.Cu")
	)
	(gr_circle
		(center 46.34992 -312.999882)
		(end 46.60392 -312.999882)
		(stroke
			(width 0.1016)
			(type default)
		)
		(fill no)
		(layer "In4.Cu")
	)
	(gr_circle
		(center 46.34992 -278.799798)
		(end 46.60392 -278.799798)
		(stroke
			(width 0.1016)
			(type default)
		)
		(fill no)
		(layer "In4.Cu")
	)
	(gr_circle
		(center 46.34992 -277.849838)
		(end 46.60392 -277.849838)
		(stroke
			(width 0.1016)
			(type default)
		)
		(fill no)
		(layer "In4.Cu")
	)
	(gr_circle
		(center 46.34992 -274.049744)
		(end 46.60392 -274.049744)
		(stroke
			(width 0.1016)
			(type default)
		)
		(fill no)
		(layer "In4.Cu")
	)
	(gr_circle
		(center 46.34992 -273.099784)
		(end 46.60392 -273.099784)
		(stroke
			(width 0.1016)
			(type default)
		)
		(fill no)
		(layer "In4.Cu")
	)
	(gr_circle
		(center 47.29988 -316.799722)
		(end 47.55388 -316.799722)
		(stroke
			(width 0.1016)
			(type default)
		)
		(fill no)
		(layer "In4.Cu")
	)
	(gr_circle
		(center 47.29988 -315.849762)
		(end 47.55388 -315.849762)
		(stroke
			(width 0.1016)
			(type default)
		)
		(fill no)
		(layer "In4.Cu")
	)
	(gr_circle
		(center 47.29988 -312.049922)
		(end 47.55388 -312.049922)
		(stroke
			(width 0.1016)
			(type default)
		)
		(fill no)
		(layer "In4.Cu")
	)
	(gr_circle
		(center 47.29988 -311.099962)
		(end 47.55388 -311.099962)
		(stroke
			(width 0.1016)
			(type default)
		)
		(fill no)
		(layer "In4.Cu")
	)
	(gr_circle
		(center 47.29988 -280.699464)
		(end 47.55388 -280.699464)
		(stroke
			(width 0.1016)
			(type default)
		)
		(fill no)
		(layer "In4.Cu")
	)
	(gr_circle
		(center 47.29988 -279.749504)
		(end 47.55388 -279.749504)
		(stroke
			(width 0.1016)
			(type default)
		)
		(fill no)
		(layer "In4.Cu")
	)
	(gr_circle
		(center 47.29988 -275.949918)
		(end 47.55388 -275.949918)
		(stroke
			(width 0.1016)
			(type default)
		)
		(fill no)
		(layer "In4.Cu")
	)
	(gr_circle
		(center 47.29988 -274.999958)
		(end 47.55388 -274.999958)
		(stroke
			(width 0.1016)
			(type default)
		)
		(fill no)
		(layer "In4.Cu")
	)
	(gr_circle
		(center 48.24984 -318.699896)
		(end 48.50384 -318.699896)
		(stroke
			(width 0.1016)
			(type default)
		)
		(fill no)
		(layer "In4.Cu")
	)
	(gr_circle
		(center 48.24984 -317.749936)
		(end 48.50384 -317.749936)
		(stroke
			(width 0.1016)
			(type default)
		)
		(fill no)
		(layer "In4.Cu")
	)
	(gr_circle
		(center 48.24984 -313.949842)
		(end 48.50384 -313.949842)
		(stroke
			(width 0.1016)
			(type default)
		)
		(fill no)
		(layer "In4.Cu")
	)
	(gr_circle
		(center 48.24984 -312.999882)
		(end 48.50384 -312.999882)
		(stroke
			(width 0.1016)
			(type default)
		)
		(fill no)
		(layer "In4.Cu")
	)
	(gr_circle
		(center 48.24984 -278.799798)
		(end 48.50384 -278.799798)
		(stroke
			(width 0.1016)
			(type default)
		)
		(fill no)
		(layer "In4.Cu")
	)
	(gr_circle
		(center 48.24984 -277.849838)
		(end 48.50384 -277.849838)
		(stroke
			(width 0.1016)
			(type default)
		)
		(fill no)
		(layer "In4.Cu")
	)
	(gr_circle
		(center 48.24984 -274.049744)
		(end 48.50384 -274.049744)
		(stroke
			(width 0.1016)
			(type default)
		)
		(fill no)
		(layer "In4.Cu")
	)
	(gr_circle
		(center 48.24984 -273.099784)
		(end 48.50384 -273.099784)
		(stroke
			(width 0.1016)
			(type default)
		)
		(fill no)
		(layer "In4.Cu")
	)
	(gr_circle
		(center 49.1998 -316.799722)
		(end 49.4538 -316.799722)
		(stroke
			(width 0.1016)
			(type default)
		)
		(fill no)
		(layer "In4.Cu")
	)
	(gr_circle
		(center 49.1998 -315.849762)
		(end 49.4538 -315.849762)
		(stroke
			(width 0.1016)
			(type default)
		)
		(fill no)
		(layer "In4.Cu")
	)
	(gr_circle
		(center 49.1998 -312.049922)
		(end 49.4538 -312.049922)
		(stroke
			(width 0.1016)
			(type default)
		)
		(fill no)
		(layer "In4.Cu")
	)
	(gr_circle
		(center 49.1998 -311.099962)
		(end 49.4538 -311.099962)
		(stroke
			(width 0.1016)
			(type default)
		)
		(fill no)
		(layer "In4.Cu")
	)
	(gr_circle
		(center 49.1998 -280.699464)
		(end 49.4538 -280.699464)
		(stroke
			(width 0.1016)
			(type default)
		)
		(fill no)
		(layer "In4.Cu")
	)
	(gr_circle
		(center 49.1998 -279.749504)
		(end 49.4538 -279.749504)
		(stroke
			(width 0.1016)
			(type default)
		)
		(fill no)
		(layer "In4.Cu")
	)
	(gr_circle
		(center 49.1998 -275.949918)
		(end 49.4538 -275.949918)
		(stroke
			(width 0.1016)
			(type default)
		)
		(fill no)
		(layer "In4.Cu")
	)
	(gr_circle
		(center 49.1998 -274.999958)
		(end 49.4538 -274.999958)
		(stroke
			(width 0.1016)
			(type default)
		)
		(fill no)
		(layer "In4.Cu")
	)
	(gr_circle
		(center 50.14976 -318.699896)
		(end 50.40376 -318.699896)
		(stroke
			(width 0.1016)
			(type default)
		)
		(fill no)
		(layer "In4.Cu")
	)
	(gr_circle
		(center 50.14976 -317.749936)
		(end 50.40376 -317.749936)
		(stroke
			(width 0.1016)
			(type default)
		)
		(fill no)
		(layer "In4.Cu")
	)
	(gr_circle
		(center 50.14976 -313.949842)
		(end 50.40376 -313.949842)
		(stroke
			(width 0.1016)
			(type default)
		)
		(fill no)
		(layer "In4.Cu")
	)
	(gr_circle
		(center 50.14976 -312.999882)
		(end 50.40376 -312.999882)
		(stroke
			(width 0.1016)
			(type default)
		)
		(fill no)
		(layer "In4.Cu")
	)
	(gr_circle
		(center 50.14976 -278.799798)
		(end 50.40376 -278.799798)
		(stroke
			(width 0.1016)
			(type default)
		)
		(fill no)
		(layer "In4.Cu")
	)
	(gr_circle
		(center 50.14976 -277.849838)
		(end 50.40376 -277.849838)
		(stroke
			(width 0.1016)
			(type default)
		)
		(fill no)
		(layer "In4.Cu")
	)
	(gr_circle
		(center 50.14976 -274.049744)
		(end 50.40376 -274.049744)
		(stroke
			(width 0.1016)
			(type default)
		)
		(fill no)
		(layer "In4.Cu")
	)
	(gr_circle
		(center 50.14976 -273.099784)
		(end 50.40376 -273.099784)
		(stroke
			(width 0.1016)
			(type default)
		)
		(fill no)
		(layer "In4.Cu")
	)
	(gr_circle
		(center 51.099974 -316.799722)
		(end 51.353974 -316.799722)
		(stroke
			(width 0.1016)
			(type default)
		)
		(fill no)
		(layer "In4.Cu")
	)
	(gr_circle
		(center 51.099974 -315.849762)
		(end 51.353974 -315.849762)
		(stroke
			(width 0.1016)
			(type default)
		)
		(fill no)
		(layer "In4.Cu")
	)
	(gr_circle
		(center 51.099974 -312.049922)
		(end 51.353974 -312.049922)
		(stroke
			(width 0.1016)
			(type default)
		)
		(fill no)
		(layer "In4.Cu")
	)
	(gr_circle
		(center 51.099974 -311.099962)
		(end 51.353974 -311.099962)
		(stroke
			(width 0.1016)
			(type default)
		)
		(fill no)
		(layer "In4.Cu")
	)
	(gr_circle
		(center 51.099974 -280.699464)
		(end 51.353974 -280.699464)
		(stroke
			(width 0.1016)
			(type default)
		)
		(fill no)
		(layer "In4.Cu")
	)
	(gr_circle
		(center 51.099974 -279.749504)
		(end 51.353974 -279.749504)
		(stroke
			(width 0.1016)
			(type default)
		)
		(fill no)
		(layer "In4.Cu")
	)
	(gr_circle
		(center 51.099974 -275.949918)
		(end 51.353974 -275.949918)
		(stroke
			(width 0.1016)
			(type default)
		)
		(fill no)
		(layer "In4.Cu")
	)
	(gr_circle
		(center 51.099974 -274.999958)
		(end 51.353974 -274.999958)
		(stroke
			(width 0.1016)
			(type default)
		)
		(fill no)
		(layer "In4.Cu")
	)
	(gr_circle
		(center 52.049934 -318.699896)
		(end 52.303934 -318.699896)
		(stroke
			(width 0.1016)
			(type default)
		)
		(fill no)
		(layer "In4.Cu")
	)
	(gr_circle
		(center 52.049934 -317.749936)
		(end 52.303934 -317.749936)
		(stroke
			(width 0.1016)
			(type default)
		)
		(fill no)
		(layer "In4.Cu")
	)
	(gr_circle
		(center 52.049934 -313.949842)
		(end 52.303934 -313.949842)
		(stroke
			(width 0.1016)
			(type default)
		)
		(fill no)
		(layer "In4.Cu")
	)
	(gr_circle
		(center 52.049934 -312.999882)
		(end 52.303934 -312.999882)
		(stroke
			(width 0.1016)
			(type default)
		)
		(fill no)
		(layer "In4.Cu")
	)
	(gr_circle
		(center 52.049934 -278.799798)
		(end 52.303934 -278.799798)
		(stroke
			(width 0.1016)
			(type default)
		)
		(fill no)
		(layer "In4.Cu")
	)
	(gr_circle
		(center 52.049934 -277.849838)
		(end 52.303934 -277.849838)
		(stroke
			(width 0.1016)
			(type default)
		)
		(fill no)
		(layer "In4.Cu")
	)
	(gr_circle
		(center 52.049934 -274.049744)
		(end 52.303934 -274.049744)
		(stroke
			(width 0.1016)
			(type default)
		)
		(fill no)
		(layer "In4.Cu")
	)
	(gr_circle
		(center 52.049934 -273.099784)
		(end 52.303934 -273.099784)
		(stroke
			(width 0.1016)
			(type default)
		)
		(fill no)
		(layer "In4.Cu")
	)
	(gr_circle
		(center 52.999894 -316.799722)
		(end 53.253894 -316.799722)
		(stroke
			(width 0.1016)
			(type default)
		)
		(fill no)
		(layer "In4.Cu")
	)
	(gr_circle
		(center 52.999894 -315.849762)
		(end 53.253894 -315.849762)
		(stroke
			(width 0.1016)
			(type default)
		)
		(fill no)
		(layer "In4.Cu")
	)
	(gr_circle
		(center 52.999894 -312.049922)
		(end 53.253894 -312.049922)
		(stroke
			(width 0.1016)
			(type default)
		)
		(fill no)
		(layer "In4.Cu")
	)
	(gr_circle
		(center 52.999894 -311.099962)
		(end 53.253894 -311.099962)
		(stroke
			(width 0.1016)
			(type default)
		)
		(fill no)
		(layer "In4.Cu")
	)
	(gr_circle
		(center 52.999894 -280.699464)
		(end 53.253894 -280.699464)
		(stroke
			(width 0.1016)
			(type default)
		)
		(fill no)
		(layer "In4.Cu")
	)
	(gr_circle
		(center 52.999894 -279.749504)
		(end 53.253894 -279.749504)
		(stroke
			(width 0.1016)
			(type default)
		)
		(fill no)
		(layer "In4.Cu")
	)
	(gr_circle
		(center 52.999894 -275.949918)
		(end 53.253894 -275.949918)
		(stroke
			(width 0.1016)
			(type default)
		)
		(fill no)
		(layer "In4.Cu")
	)
	(gr_circle
		(center 52.999894 -274.999958)
		(end 53.253894 -274.999958)
		(stroke
			(width 0.1016)
			(type default)
		)
		(fill no)
		(layer "In4.Cu")
	)
	(gr_circle
		(center 53.949854 -318.699896)
		(end 54.203854 -318.699896)
		(stroke
			(width 0.1016)
			(type default)
		)
		(fill no)
		(layer "In4.Cu")
	)
	(gr_circle
		(center 53.949854 -317.749936)
		(end 54.203854 -317.749936)
		(stroke
			(width 0.1016)
			(type default)
		)
		(fill no)
		(layer "In4.Cu")
	)
	(gr_circle
		(center 53.949854 -313.949842)
		(end 54.203854 -313.949842)
		(stroke
			(width 0.1016)
			(type default)
		)
		(fill no)
		(layer "In4.Cu")
	)
	(gr_circle
		(center 53.949854 -312.999882)
		(end 54.203854 -312.999882)
		(stroke
			(width 0.1016)
			(type default)
		)
		(fill no)
		(layer "In4.Cu")
	)
	(gr_circle
		(center 53.949854 -278.799798)
		(end 54.203854 -278.799798)
		(stroke
			(width 0.1016)
			(type default)
		)
		(fill no)
		(layer "In4.Cu")
	)
	(gr_circle
		(center 53.949854 -277.849838)
		(end 54.203854 -277.849838)
		(stroke
			(width 0.1016)
			(type default)
		)
		(fill no)
		(layer "In4.Cu")
	)
	(gr_circle
		(center 53.949854 -274.049744)
		(end 54.203854 -274.049744)
		(stroke
			(width 0.1016)
			(type default)
		)
		(fill no)
		(layer "In4.Cu")
	)
	(gr_circle
		(center 53.949854 -273.099784)
		(end 54.203854 -273.099784)
		(stroke
			(width 0.1016)
			(type default)
		)
		(fill no)
		(layer "In4.Cu")
	)
	(gr_circle
		(center 54.899814 -316.799722)
		(end 55.153814 -316.799722)
		(stroke
			(width 0.1016)
			(type default)
		)
		(fill no)
		(layer "In4.Cu")
	)
	(gr_circle
		(center 54.899814 -315.849762)
		(end 55.153814 -315.849762)
		(stroke
			(width 0.1016)
			(type default)
		)
		(fill no)
		(layer "In4.Cu")
	)
	(gr_circle
		(center 54.899814 -312.049922)
		(end 55.153814 -312.049922)
		(stroke
			(width 0.1016)
			(type default)
		)
		(fill no)
		(layer "In4.Cu")
	)
	(gr_circle
		(center 54.899814 -311.099962)
		(end 55.153814 -311.099962)
		(stroke
			(width 0.1016)
			(type default)
		)
		(fill no)
		(layer "In4.Cu")
	)
	(gr_circle
		(center 54.899814 -280.699464)
		(end 55.153814 -280.699464)
		(stroke
			(width 0.1016)
			(type default)
		)
		(fill no)
		(layer "In4.Cu")
	)
	(gr_circle
		(center 54.899814 -279.749504)
		(end 55.153814 -279.749504)
		(stroke
			(width 0.1016)
			(type default)
		)
		(fill no)
		(layer "In4.Cu")
	)
	(gr_circle
		(center 54.899814 -275.949918)
		(end 55.153814 -275.949918)
		(stroke
			(width 0.1016)
			(type default)
		)
		(fill no)
		(layer "In4.Cu")
	)
	(gr_circle
		(center 54.899814 -274.999958)
		(end 55.153814 -274.999958)
		(stroke
			(width 0.1016)
			(type default)
		)
		(fill no)
		(layer "In4.Cu")
	)
	(gr_circle
		(center 55.849774 -318.699896)
		(end 56.103774 -318.699896)
		(stroke
			(width 0.1016)
			(type default)
		)
		(fill no)
		(layer "In4.Cu")
	)
	(gr_circle
		(center 55.849774 -317.749936)
		(end 56.103774 -317.749936)
		(stroke
			(width 0.1016)
			(type default)
		)
		(fill no)
		(layer "In4.Cu")
	)
	(gr_circle
		(center 55.849774 -313.949842)
		(end 56.103774 -313.949842)
		(stroke
			(width 0.1016)
			(type default)
		)
		(fill no)
		(layer "In4.Cu")
	)
	(gr_circle
		(center 55.849774 -312.999882)
		(end 56.103774 -312.999882)
		(stroke
			(width 0.1016)
			(type default)
		)
		(fill no)
		(layer "In4.Cu")
	)
	(gr_circle
		(center 55.849774 -278.799798)
		(end 56.103774 -278.799798)
		(stroke
			(width 0.1016)
			(type default)
		)
		(fill no)
		(layer "In4.Cu")
	)
	(gr_circle
		(center 55.849774 -277.849838)
		(end 56.103774 -277.849838)
		(stroke
			(width 0.1016)
			(type default)
		)
		(fill no)
		(layer "In4.Cu")
	)
	(gr_circle
		(center 55.849774 -274.049744)
		(end 56.103774 -274.049744)
		(stroke
			(width 0.1016)
			(type default)
		)
		(fill no)
		(layer "In4.Cu")
	)
	(gr_circle
		(center 55.849774 -273.099784)
		(end 56.103774 -273.099784)
		(stroke
			(width 0.1016)
			(type default)
		)
		(fill no)
		(layer "In4.Cu")
	)
	(gr_circle
		(center 56.799734 -280.699464)
		(end 57.053734 -280.699464)
		(stroke
			(width 0.1016)
			(type default)
		)
		(fill no)
		(layer "In4.Cu")
	)
	(gr_circle
		(center 56.799734 -279.749504)
		(end 57.053734 -279.749504)
		(stroke
			(width 0.1016)
			(type default)
		)
		(fill no)
		(layer "In4.Cu")
	)
	(gr_circle
		(center 56.799988 -316.799722)
		(end 57.053988 -316.799722)
		(stroke
			(width 0.1016)
			(type default)
		)
		(fill no)
		(layer "In4.Cu")
	)
	(gr_circle
		(center 56.799988 -315.849762)
		(end 57.053988 -315.849762)
		(stroke
			(width 0.1016)
			(type default)
		)
		(fill no)
		(layer "In4.Cu")
	)
	(gr_circle
		(center 56.799988 -312.049922)
		(end 57.053988 -312.049922)
		(stroke
			(width 0.1016)
			(type default)
		)
		(fill no)
		(layer "In4.Cu")
	)
	(gr_circle
		(center 56.799988 -311.099962)
		(end 57.053988 -311.099962)
		(stroke
			(width 0.1016)
			(type default)
		)
		(fill no)
		(layer "In4.Cu")
	)
	(gr_circle
		(center 56.799988 -275.949918)
		(end 57.053988 -275.949918)
		(stroke
			(width 0.1016)
			(type default)
		)
		(fill no)
		(layer "In4.Cu")
	)
	(gr_circle
		(center 56.799988 -274.999958)
		(end 57.053988 -274.999958)
		(stroke
			(width 0.1016)
			(type default)
		)
		(fill no)
		(layer "In4.Cu")
	)
	(gr_circle
		(center 57.749948 -318.699896)
		(end 58.003948 -318.699896)
		(stroke
			(width 0.1016)
			(type default)
		)
		(fill no)
		(layer "In4.Cu")
	)
	(gr_circle
		(center 57.749948 -317.749936)
		(end 58.003948 -317.749936)
		(stroke
			(width 0.1016)
			(type default)
		)
		(fill no)
		(layer "In4.Cu")
	)
	(gr_circle
		(center 57.749948 -313.949842)
		(end 58.003948 -313.949842)
		(stroke
			(width 0.1016)
			(type default)
		)
		(fill no)
		(layer "In4.Cu")
	)
	(gr_circle
		(center 57.749948 -312.999882)
		(end 58.003948 -312.999882)
		(stroke
			(width 0.1016)
			(type default)
		)
		(fill no)
		(layer "In4.Cu")
	)
	(gr_circle
		(center 57.749948 -278.799798)
		(end 58.003948 -278.799798)
		(stroke
			(width 0.1016)
			(type default)
		)
		(fill no)
		(layer "In4.Cu")
	)
	(gr_circle
		(center 57.749948 -277.849838)
		(end 58.003948 -277.849838)
		(stroke
			(width 0.1016)
			(type default)
		)
		(fill no)
		(layer "In4.Cu")
	)
	(gr_circle
		(center 57.749948 -274.049744)
		(end 58.003948 -274.049744)
		(stroke
			(width 0.1016)
			(type default)
		)
		(fill no)
		(layer "In4.Cu")
	)
	(gr_circle
		(center 57.749948 -273.099784)
		(end 58.003948 -273.099784)
		(stroke
			(width 0.1016)
			(type default)
		)
		(fill no)
		(layer "In4.Cu")
	)
	(gr_circle
		(center 58.699908 -316.799722)
		(end 58.953908 -316.799722)
		(stroke
			(width 0.1016)
			(type default)
		)
		(fill no)
		(layer "In4.Cu")
	)
	(gr_circle
		(center 58.699908 -315.849762)
		(end 58.953908 -315.849762)
		(stroke
			(width 0.1016)
			(type default)
		)
		(fill no)
		(layer "In4.Cu")
	)
	(gr_circle
		(center 58.699908 -312.049922)
		(end 58.953908 -312.049922)
		(stroke
			(width 0.1016)
			(type default)
		)
		(fill no)
		(layer "In4.Cu")
	)
	(gr_circle
		(center 58.699908 -311.099962)
		(end 58.953908 -311.099962)
		(stroke
			(width 0.1016)
			(type default)
		)
		(fill no)
		(layer "In4.Cu")
	)
	(gr_circle
		(center 58.699908 -280.699464)
		(end 58.953908 -280.699464)
		(stroke
			(width 0.1016)
			(type default)
		)
		(fill no)
		(layer "In4.Cu")
	)
	(gr_circle
		(center 58.699908 -279.749504)
		(end 58.953908 -279.749504)
		(stroke
			(width 0.1016)
			(type default)
		)
		(fill no)
		(layer "In4.Cu")
	)
	(gr_circle
		(center 58.699908 -275.949918)
		(end 58.953908 -275.949918)
		(stroke
			(width 0.1016)
			(type default)
		)
		(fill no)
		(layer "In4.Cu")
	)
	(gr_circle
		(center 58.699908 -274.999958)
		(end 58.953908 -274.999958)
		(stroke
			(width 0.1016)
			(type default)
		)
		(fill no)
		(layer "In4.Cu")
	)
	(gr_circle
		(center 59.649614 -278.799798)
		(end 59.903614 -278.799798)
		(stroke
			(width 0.1016)
			(type default)
		)
		(fill no)
		(layer "In4.Cu")
	)
	(gr_circle
		(center 59.649614 -277.849838)
		(end 59.903614 -277.849838)
		(stroke
			(width 0.1016)
			(type default)
		)
		(fill no)
		(layer "In4.Cu")
	)
	(gr_circle
		(center 59.649614 -274.04949)
		(end 59.903614 -274.04949)
		(stroke
			(width 0.1016)
			(type default)
		)
		(fill no)
		(layer "In4.Cu")
	)
	(gr_circle
		(center 59.649614 -273.09953)
		(end 59.903614 -273.09953)
		(stroke
			(width 0.1016)
			(type default)
		)
		(fill no)
		(layer "In4.Cu")
	)
	(gr_circle
		(center 59.649868 -318.699896)
		(end 59.903868 -318.699896)
		(stroke
			(width 0.1016)
			(type default)
		)
		(fill no)
		(layer "In4.Cu")
	)
	(gr_circle
		(center 59.649868 -317.749936)
		(end 59.903868 -317.749936)
		(stroke
			(width 0.1016)
			(type default)
		)
		(fill no)
		(layer "In4.Cu")
	)
	(gr_circle
		(center 59.649868 -313.949842)
		(end 59.903868 -313.949842)
		(stroke
			(width 0.1016)
			(type default)
		)
		(fill no)
		(layer "In4.Cu")
	)
	(gr_circle
		(center 59.649868 -312.999882)
		(end 59.903868 -312.999882)
		(stroke
			(width 0.1016)
			(type default)
		)
		(fill no)
		(layer "In4.Cu")
	)
	(gr_circle
		(center 60.599574 -275.949664)
		(end 60.853574 -275.949664)
		(stroke
			(width 0.1016)
			(type default)
		)
		(fill no)
		(layer "In4.Cu")
	)
	(gr_circle
		(center 60.599574 -274.999704)
		(end 60.853574 -274.999704)
		(stroke
			(width 0.1016)
			(type default)
		)
		(fill no)
		(layer "In4.Cu")
	)
	(gr_circle
		(center 60.599828 -316.799722)
		(end 60.853828 -316.799722)
		(stroke
			(width 0.1016)
			(type default)
		)
		(fill no)
		(layer "In4.Cu")
	)
	(gr_circle
		(center 60.599828 -315.849762)
		(end 60.853828 -315.849762)
		(stroke
			(width 0.1016)
			(type default)
		)
		(fill no)
		(layer "In4.Cu")
	)
	(gr_circle
		(center 60.599828 -312.049922)
		(end 60.853828 -312.049922)
		(stroke
			(width 0.1016)
			(type default)
		)
		(fill no)
		(layer "In4.Cu")
	)
	(gr_circle
		(center 60.599828 -311.099962)
		(end 60.853828 -311.099962)
		(stroke
			(width 0.1016)
			(type default)
		)
		(fill no)
		(layer "In4.Cu")
	)
	(gr_circle
		(center 60.599828 -280.699464)
		(end 60.853828 -280.699464)
		(stroke
			(width 0.1016)
			(type default)
		)
		(fill no)
		(layer "In4.Cu")
	)
	(gr_circle
		(center 60.599828 -279.749504)
		(end 60.853828 -279.749504)
		(stroke
			(width 0.1016)
			(type default)
		)
		(fill no)
		(layer "In4.Cu")
	)
	(gr_circle
		(center 61.549534 -278.799798)
		(end 61.803534 -278.799798)
		(stroke
			(width 0.1016)
			(type default)
		)
		(fill no)
		(layer "In4.Cu")
	)
	(gr_circle
		(center 61.549534 -277.849838)
		(end 61.803534 -277.849838)
		(stroke
			(width 0.1016)
			(type default)
		)
		(fill no)
		(layer "In4.Cu")
	)
	(gr_circle
		(center 61.549534 -274.049744)
		(end 61.803534 -274.049744)
		(stroke
			(width 0.1016)
			(type default)
		)
		(fill no)
		(layer "In4.Cu")
	)
	(gr_circle
		(center 61.549534 -273.099784)
		(end 61.803534 -273.099784)
		(stroke
			(width 0.1016)
			(type default)
		)
		(fill no)
		(layer "In4.Cu")
	)
	(gr_circle
		(center 61.549788 -318.699896)
		(end 61.803788 -318.699896)
		(stroke
			(width 0.1016)
			(type default)
		)
		(fill no)
		(layer "In4.Cu")
	)
	(gr_circle
		(center 61.549788 -317.749936)
		(end 61.803788 -317.749936)
		(stroke
			(width 0.1016)
			(type default)
		)
		(fill no)
		(layer "In4.Cu")
	)
	(gr_circle
		(center 61.549788 -313.949842)
		(end 61.803788 -313.949842)
		(stroke
			(width 0.1016)
			(type default)
		)
		(fill no)
		(layer "In4.Cu")
	)
	(gr_circle
		(center 61.549788 -312.999882)
		(end 61.803788 -312.999882)
		(stroke
			(width 0.1016)
			(type default)
		)
		(fill no)
		(layer "In4.Cu")
	)
	(gr_circle
		(center 62.499494 -275.949918)
		(end 62.753494 -275.949918)
		(stroke
			(width 0.1016)
			(type default)
		)
		(fill no)
		(layer "In4.Cu")
	)
	(gr_circle
		(center 62.499494 -274.999958)
		(end 62.753494 -274.999958)
		(stroke
			(width 0.1016)
			(type default)
		)
		(fill no)
		(layer "In4.Cu")
	)
	(gr_circle
		(center 62.499748 -316.799722)
		(end 62.753748 -316.799722)
		(stroke
			(width 0.1016)
			(type default)
		)
		(fill no)
		(layer "In4.Cu")
	)
	(gr_circle
		(center 62.499748 -315.849762)
		(end 62.753748 -315.849762)
		(stroke
			(width 0.1016)
			(type default)
		)
		(fill no)
		(layer "In4.Cu")
	)
	(gr_circle
		(center 62.499748 -312.049922)
		(end 62.753748 -312.049922)
		(stroke
			(width 0.1016)
			(type default)
		)
		(fill no)
		(layer "In4.Cu")
	)
	(gr_circle
		(center 62.499748 -311.099962)
		(end 62.753748 -311.099962)
		(stroke
			(width 0.1016)
			(type default)
		)
		(fill no)
		(layer "In4.Cu")
	)
	(gr_circle
		(center 62.499748 -280.699464)
		(end 62.753748 -280.699464)
		(stroke
			(width 0.1016)
			(type default)
		)
		(fill no)
		(layer "In4.Cu")
	)
	(gr_circle
		(center 62.499748 -279.749504)
		(end 62.753748 -279.749504)
		(stroke
			(width 0.1016)
			(type default)
		)
		(fill no)
		(layer "In4.Cu")
	)
	(gr_circle
		(center 63.449708 -278.799798)
		(end 63.703708 -278.799798)
		(stroke
			(width 0.1016)
			(type default)
		)
		(fill no)
		(layer "In4.Cu")
	)
	(gr_circle
		(center 63.449708 -277.849838)
		(end 63.703708 -277.849838)
		(stroke
			(width 0.1016)
			(type default)
		)
		(fill no)
		(layer "In4.Cu")
	)
	(gr_circle
		(center 63.449708 -274.049744)
		(end 63.703708 -274.049744)
		(stroke
			(width 0.1016)
			(type default)
		)
		(fill no)
		(layer "In4.Cu")
	)
	(gr_circle
		(center 63.449708 -273.099784)
		(end 63.703708 -273.099784)
		(stroke
			(width 0.1016)
			(type default)
		)
		(fill no)
		(layer "In4.Cu")
	)
	(gr_circle
		(center 63.449962 -318.699896)
		(end 63.703962 -318.699896)
		(stroke
			(width 0.1016)
			(type default)
		)
		(fill no)
		(layer "In4.Cu")
	)
	(gr_circle
		(center 63.449962 -317.749936)
		(end 63.703962 -317.749936)
		(stroke
			(width 0.1016)
			(type default)
		)
		(fill no)
		(layer "In4.Cu")
	)
	(gr_circle
		(center 63.449962 -313.949842)
		(end 63.703962 -313.949842)
		(stroke
			(width 0.1016)
			(type default)
		)
		(fill no)
		(layer "In4.Cu")
	)
	(gr_circle
		(center 63.449962 -312.999882)
		(end 63.703962 -312.999882)
		(stroke
			(width 0.1016)
			(type default)
		)
		(fill no)
		(layer "In4.Cu")
	)
	(gr_circle
		(center 64.399668 -275.949664)
		(end 64.653668 -275.949664)
		(stroke
			(width 0.1016)
			(type default)
		)
		(fill no)
		(layer "In4.Cu")
	)
	(gr_circle
		(center 64.399668 -274.999704)
		(end 64.653668 -274.999704)
		(stroke
			(width 0.1016)
			(type default)
		)
		(fill no)
		(layer "In4.Cu")
	)
	(gr_circle
		(center 64.399922 -316.799722)
		(end 64.653922 -316.799722)
		(stroke
			(width 0.1016)
			(type default)
		)
		(fill no)
		(layer "In4.Cu")
	)
	(gr_circle
		(center 64.399922 -315.849762)
		(end 64.653922 -315.849762)
		(stroke
			(width 0.1016)
			(type default)
		)
		(fill no)
		(layer "In4.Cu")
	)
	(gr_circle
		(center 64.399922 -312.049922)
		(end 64.653922 -312.049922)
		(stroke
			(width 0.1016)
			(type default)
		)
		(fill no)
		(layer "In4.Cu")
	)
	(gr_circle
		(center 64.399922 -311.099962)
		(end 64.653922 -311.099962)
		(stroke
			(width 0.1016)
			(type default)
		)
		(fill no)
		(layer "In4.Cu")
	)
	(gr_circle
		(center 64.399922 -280.699464)
		(end 64.653922 -280.699464)
		(stroke
			(width 0.1016)
			(type default)
		)
		(fill no)
		(layer "In4.Cu")
	)
	(gr_circle
		(center 64.399922 -279.749504)
		(end 64.653922 -279.749504)
		(stroke
			(width 0.1016)
			(type default)
		)
		(fill no)
		(layer "In4.Cu")
	)
	(gr_circle
		(center 65.349628 -278.799798)
		(end 65.603628 -278.799798)
		(stroke
			(width 0.1016)
			(type default)
		)
		(fill no)
		(layer "In4.Cu")
	)
	(gr_circle
		(center 65.349628 -277.849838)
		(end 65.603628 -277.849838)
		(stroke
			(width 0.1016)
			(type default)
		)
		(fill no)
		(layer "In4.Cu")
	)
	(gr_circle
		(center 65.349628 -274.049744)
		(end 65.603628 -274.049744)
		(stroke
			(width 0.1016)
			(type default)
		)
		(fill no)
		(layer "In4.Cu")
	)
	(gr_circle
		(center 65.349628 -273.099784)
		(end 65.603628 -273.099784)
		(stroke
			(width 0.1016)
			(type default)
		)
		(fill no)
		(layer "In4.Cu")
	)
	(gr_circle
		(center 65.349882 -318.699896)
		(end 65.603882 -318.699896)
		(stroke
			(width 0.1016)
			(type default)
		)
		(fill no)
		(layer "In4.Cu")
	)
	(gr_circle
		(center 65.349882 -317.749936)
		(end 65.603882 -317.749936)
		(stroke
			(width 0.1016)
			(type default)
		)
		(fill no)
		(layer "In4.Cu")
	)
	(gr_circle
		(center 65.349882 -313.949842)
		(end 65.603882 -313.949842)
		(stroke
			(width 0.1016)
			(type default)
		)
		(fill no)
		(layer "In4.Cu")
	)
	(gr_circle
		(center 65.349882 -312.999882)
		(end 65.603882 -312.999882)
		(stroke
			(width 0.1016)
			(type default)
		)
		(fill no)
		(layer "In4.Cu")
	)
	(gr_circle
		(center 66.299588 -275.949918)
		(end 66.553588 -275.949918)
		(stroke
			(width 0.1016)
			(type default)
		)
		(fill no)
		(layer "In4.Cu")
	)
	(gr_circle
		(center 66.299588 -274.999958)
		(end 66.553588 -274.999958)
		(stroke
			(width 0.1016)
			(type default)
		)
		(fill no)
		(layer "In4.Cu")
	)
	(gr_circle
		(center 66.299842 -316.799722)
		(end 66.553842 -316.799722)
		(stroke
			(width 0.1016)
			(type default)
		)
		(fill no)
		(layer "In4.Cu")
	)
	(gr_circle
		(center 66.299842 -315.849762)
		(end 66.553842 -315.849762)
		(stroke
			(width 0.1016)
			(type default)
		)
		(fill no)
		(layer "In4.Cu")
	)
	(gr_circle
		(center 66.299842 -312.049922)
		(end 66.553842 -312.049922)
		(stroke
			(width 0.1016)
			(type default)
		)
		(fill no)
		(layer "In4.Cu")
	)
	(gr_circle
		(center 66.299842 -311.099962)
		(end 66.553842 -311.099962)
		(stroke
			(width 0.1016)
			(type default)
		)
		(fill no)
		(layer "In4.Cu")
	)
	(gr_circle
		(center 66.299842 -280.699464)
		(end 66.553842 -280.699464)
		(stroke
			(width 0.1016)
			(type default)
		)
		(fill no)
		(layer "In4.Cu")
	)
	(gr_circle
		(center 66.299842 -279.749504)
		(end 66.553842 -279.749504)
		(stroke
			(width 0.1016)
			(type default)
		)
		(fill no)
		(layer "In4.Cu")
	)
	(gr_circle
		(center 67.249548 -278.799798)
		(end 67.503548 -278.799798)
		(stroke
			(width 0.1016)
			(type default)
		)
		(fill no)
		(layer "In4.Cu")
	)
	(gr_circle
		(center 67.249548 -277.849838)
		(end 67.503548 -277.849838)
		(stroke
			(width 0.1016)
			(type default)
		)
		(fill no)
		(layer "In4.Cu")
	)
	(gr_circle
		(center 67.249548 -274.049744)
		(end 67.503548 -274.049744)
		(stroke
			(width 0.1016)
			(type default)
		)
		(fill no)
		(layer "In4.Cu")
	)
	(gr_circle
		(center 67.249548 -273.099784)
		(end 67.503548 -273.099784)
		(stroke
			(width 0.1016)
			(type default)
		)
		(fill no)
		(layer "In4.Cu")
	)
	(gr_circle
		(center 67.249802 -318.699896)
		(end 67.503802 -318.699896)
		(stroke
			(width 0.1016)
			(type default)
		)
		(fill no)
		(layer "In4.Cu")
	)
	(gr_circle
		(center 67.249802 -317.749936)
		(end 67.503802 -317.749936)
		(stroke
			(width 0.1016)
			(type default)
		)
		(fill no)
		(layer "In4.Cu")
	)
	(gr_circle
		(center 67.249802 -313.949842)
		(end 67.503802 -313.949842)
		(stroke
			(width 0.1016)
			(type default)
		)
		(fill no)
		(layer "In4.Cu")
	)
	(gr_circle
		(center 67.249802 -312.999882)
		(end 67.503802 -312.999882)
		(stroke
			(width 0.1016)
			(type default)
		)
		(fill no)
		(layer "In4.Cu")
	)
	(gr_circle
		(center 68.199508 -275.949664)
		(end 68.453508 -275.949664)
		(stroke
			(width 0.1016)
			(type default)
		)
		(fill no)
		(layer "In4.Cu")
	)
	(gr_circle
		(center 68.199508 -274.999704)
		(end 68.453508 -274.999704)
		(stroke
			(width 0.1016)
			(type default)
		)
		(fill no)
		(layer "In4.Cu")
	)
	(gr_circle
		(center 68.199762 -316.799722)
		(end 68.453762 -316.799722)
		(stroke
			(width 0.1016)
			(type default)
		)
		(fill no)
		(layer "In4.Cu")
	)
	(gr_circle
		(center 68.199762 -315.849762)
		(end 68.453762 -315.849762)
		(stroke
			(width 0.1016)
			(type default)
		)
		(fill no)
		(layer "In4.Cu")
	)
	(gr_circle
		(center 68.199762 -312.049922)
		(end 68.453762 -312.049922)
		(stroke
			(width 0.1016)
			(type default)
		)
		(fill no)
		(layer "In4.Cu")
	)
	(gr_circle
		(center 68.199762 -311.099962)
		(end 68.453762 -311.099962)
		(stroke
			(width 0.1016)
			(type default)
		)
		(fill no)
		(layer "In4.Cu")
	)
	(gr_circle
		(center 68.199762 -280.699464)
		(end 68.453762 -280.699464)
		(stroke
			(width 0.1016)
			(type default)
		)
		(fill no)
		(layer "In4.Cu")
	)
	(gr_circle
		(center 68.199762 -279.749504)
		(end 68.453762 -279.749504)
		(stroke
			(width 0.1016)
			(type default)
		)
		(fill no)
		(layer "In4.Cu")
	)
	(gr_circle
		(center 69.149722 -278.799798)
		(end 69.403722 -278.799798)
		(stroke
			(width 0.1016)
			(type default)
		)
		(fill no)
		(layer "In4.Cu")
	)
	(gr_circle
		(center 69.149722 -277.849838)
		(end 69.403722 -277.849838)
		(stroke
			(width 0.1016)
			(type default)
		)
		(fill no)
		(layer "In4.Cu")
	)
	(gr_circle
		(center 69.149722 -274.049744)
		(end 69.403722 -274.049744)
		(stroke
			(width 0.1016)
			(type default)
		)
		(fill no)
		(layer "In4.Cu")
	)
	(gr_circle
		(center 69.149722 -273.099784)
		(end 69.403722 -273.099784)
		(stroke
			(width 0.1016)
			(type default)
		)
		(fill no)
		(layer "In4.Cu")
	)
	(gr_circle
		(center 69.149976 -318.699896)
		(end 69.403976 -318.699896)
		(stroke
			(width 0.1016)
			(type default)
		)
		(fill no)
		(layer "In4.Cu")
	)
	(gr_circle
		(center 69.149976 -317.749936)
		(end 69.403976 -317.749936)
		(stroke
			(width 0.1016)
			(type default)
		)
		(fill no)
		(layer "In4.Cu")
	)
	(gr_circle
		(center 69.149976 -313.949842)
		(end 69.403976 -313.949842)
		(stroke
			(width 0.1016)
			(type default)
		)
		(fill no)
		(layer "In4.Cu")
	)
	(gr_circle
		(center 69.149976 -312.999882)
		(end 69.403976 -312.999882)
		(stroke
			(width 0.1016)
			(type default)
		)
		(fill no)
		(layer "In4.Cu")
	)
	(gr_circle
		(center 70.099428 -275.949918)
		(end 70.353428 -275.949918)
		(stroke
			(width 0.1016)
			(type default)
		)
		(fill no)
		(layer "In4.Cu")
	)
	(gr_circle
		(center 70.099428 -274.999958)
		(end 70.353428 -274.999958)
		(stroke
			(width 0.1016)
			(type default)
		)
		(fill no)
		(layer "In4.Cu")
	)
	(gr_circle
		(center 70.099936 -316.799722)
		(end 70.353936 -316.799722)
		(stroke
			(width 0.1016)
			(type default)
		)
		(fill no)
		(layer "In4.Cu")
	)
	(gr_circle
		(center 70.099936 -315.849762)
		(end 70.353936 -315.849762)
		(stroke
			(width 0.1016)
			(type default)
		)
		(fill no)
		(layer "In4.Cu")
	)
	(gr_circle
		(center 70.099936 -312.049922)
		(end 70.353936 -312.049922)
		(stroke
			(width 0.1016)
			(type default)
		)
		(fill no)
		(layer "In4.Cu")
	)
	(gr_circle
		(center 70.099936 -311.099962)
		(end 70.353936 -311.099962)
		(stroke
			(width 0.1016)
			(type default)
		)
		(fill no)
		(layer "In4.Cu")
	)
	(gr_circle
		(center 70.099936 -280.699464)
		(end 70.353936 -280.699464)
		(stroke
			(width 0.1016)
			(type default)
		)
		(fill no)
		(layer "In4.Cu")
	)
	(gr_circle
		(center 70.099936 -279.749504)
		(end 70.353936 -279.749504)
		(stroke
			(width 0.1016)
			(type default)
		)
		(fill no)
		(layer "In4.Cu")
	)
	(gr_circle
		(center 71.049642 -278.799798)
		(end 71.303642 -278.799798)
		(stroke
			(width 0.1016)
			(type default)
		)
		(fill no)
		(layer "In4.Cu")
	)
	(gr_circle
		(center 71.049642 -277.849838)
		(end 71.303642 -277.849838)
		(stroke
			(width 0.1016)
			(type default)
		)
		(fill no)
		(layer "In4.Cu")
	)
	(gr_circle
		(center 71.049642 -274.049744)
		(end 71.303642 -274.049744)
		(stroke
			(width 0.1016)
			(type default)
		)
		(fill no)
		(layer "In4.Cu")
	)
	(gr_circle
		(center 71.049642 -273.099784)
		(end 71.303642 -273.099784)
		(stroke
			(width 0.1016)
			(type default)
		)
		(fill no)
		(layer "In4.Cu")
	)
	(gr_circle
		(center 71.049896 -318.699896)
		(end 71.303896 -318.699896)
		(stroke
			(width 0.1016)
			(type default)
		)
		(fill no)
		(layer "In4.Cu")
	)
	(gr_circle
		(center 71.049896 -317.749936)
		(end 71.303896 -317.749936)
		(stroke
			(width 0.1016)
			(type default)
		)
		(fill no)
		(layer "In4.Cu")
	)
	(gr_circle
		(center 71.049896 -313.949842)
		(end 71.303896 -313.949842)
		(stroke
			(width 0.1016)
			(type default)
		)
		(fill no)
		(layer "In4.Cu")
	)
	(gr_circle
		(center 71.049896 -312.999882)
		(end 71.303896 -312.999882)
		(stroke
			(width 0.1016)
			(type default)
		)
		(fill no)
		(layer "In4.Cu")
	)
	(gr_circle
		(center 71.999602 -275.949664)
		(end 72.253602 -275.949664)
		(stroke
			(width 0.1016)
			(type default)
		)
		(fill no)
		(layer "In4.Cu")
	)
	(gr_circle
		(center 71.999602 -274.999704)
		(end 72.253602 -274.999704)
		(stroke
			(width 0.1016)
			(type default)
		)
		(fill no)
		(layer "In4.Cu")
	)
	(gr_circle
		(center 71.999856 -316.799722)
		(end 72.253856 -316.799722)
		(stroke
			(width 0.1016)
			(type default)
		)
		(fill no)
		(layer "In4.Cu")
	)
	(gr_circle
		(center 71.999856 -315.849762)
		(end 72.253856 -315.849762)
		(stroke
			(width 0.1016)
			(type default)
		)
		(fill no)
		(layer "In4.Cu")
	)
	(gr_circle
		(center 71.999856 -312.049922)
		(end 72.253856 -312.049922)
		(stroke
			(width 0.1016)
			(type default)
		)
		(fill no)
		(layer "In4.Cu")
	)
	(gr_circle
		(center 71.999856 -311.099962)
		(end 72.253856 -311.099962)
		(stroke
			(width 0.1016)
			(type default)
		)
		(fill no)
		(layer "In4.Cu")
	)
	(gr_circle
		(center 71.999856 -280.699464)
		(end 72.253856 -280.699464)
		(stroke
			(width 0.1016)
			(type default)
		)
		(fill no)
		(layer "In4.Cu")
	)
	(gr_circle
		(center 71.999856 -279.749504)
		(end 72.253856 -279.749504)
		(stroke
			(width 0.1016)
			(type default)
		)
		(fill no)
		(layer "In4.Cu")
	)
	(gr_circle
		(center 72.949562 -278.799798)
		(end 73.203562 -278.799798)
		(stroke
			(width 0.1016)
			(type default)
		)
		(fill no)
		(layer "In4.Cu")
	)
	(gr_circle
		(center 72.949562 -277.849838)
		(end 73.203562 -277.849838)
		(stroke
			(width 0.1016)
			(type default)
		)
		(fill no)
		(layer "In4.Cu")
	)
	(gr_circle
		(center 72.949562 -274.049744)
		(end 73.203562 -274.049744)
		(stroke
			(width 0.1016)
			(type default)
		)
		(fill no)
		(layer "In4.Cu")
	)
	(gr_circle
		(center 72.949562 -273.099784)
		(end 73.203562 -273.099784)
		(stroke
			(width 0.1016)
			(type default)
		)
		(fill no)
		(layer "In4.Cu")
	)
	(gr_circle
		(center 72.949816 -318.699896)
		(end 73.203816 -318.699896)
		(stroke
			(width 0.1016)
			(type default)
		)
		(fill no)
		(layer "In4.Cu")
	)
	(gr_circle
		(center 72.949816 -317.749936)
		(end 73.203816 -317.749936)
		(stroke
			(width 0.1016)
			(type default)
		)
		(fill no)
		(layer "In4.Cu")
	)
	(gr_circle
		(center 72.949816 -313.949842)
		(end 73.203816 -313.949842)
		(stroke
			(width 0.1016)
			(type default)
		)
		(fill no)
		(layer "In4.Cu")
	)
	(gr_circle
		(center 72.949816 -312.999882)
		(end 73.203816 -312.999882)
		(stroke
			(width 0.1016)
			(type default)
		)
		(fill no)
		(layer "In4.Cu")
	)
	(gr_circle
		(center 73.899522 -275.949918)
		(end 74.153522 -275.949918)
		(stroke
			(width 0.1016)
			(type default)
		)
		(fill no)
		(layer "In4.Cu")
	)
	(gr_circle
		(center 73.899522 -274.999958)
		(end 74.153522 -274.999958)
		(stroke
			(width 0.1016)
			(type default)
		)
		(fill no)
		(layer "In4.Cu")
	)
	(gr_circle
		(center 73.899776 -316.799722)
		(end 74.153776 -316.799722)
		(stroke
			(width 0.1016)
			(type default)
		)
		(fill no)
		(layer "In4.Cu")
	)
	(gr_circle
		(center 73.899776 -315.849762)
		(end 74.153776 -315.849762)
		(stroke
			(width 0.1016)
			(type default)
		)
		(fill no)
		(layer "In4.Cu")
	)
	(gr_circle
		(center 73.899776 -312.049922)
		(end 74.153776 -312.049922)
		(stroke
			(width 0.1016)
			(type default)
		)
		(fill no)
		(layer "In4.Cu")
	)
	(gr_circle
		(center 73.899776 -311.099962)
		(end 74.153776 -311.099962)
		(stroke
			(width 0.1016)
			(type default)
		)
		(fill no)
		(layer "In4.Cu")
	)
	(gr_circle
		(center 73.899776 -280.699464)
		(end 74.153776 -280.699464)
		(stroke
			(width 0.1016)
			(type default)
		)
		(fill no)
		(layer "In4.Cu")
	)
	(gr_circle
		(center 73.899776 -279.749504)
		(end 74.153776 -279.749504)
		(stroke
			(width 0.1016)
			(type default)
		)
		(fill no)
		(layer "In4.Cu")
	)
	(gr_circle
		(center 74.849736 -278.799798)
		(end 75.103736 -278.799798)
		(stroke
			(width 0.1016)
			(type default)
		)
		(fill no)
		(layer "In4.Cu")
	)
	(gr_circle
		(center 74.849736 -277.849838)
		(end 75.103736 -277.849838)
		(stroke
			(width 0.1016)
			(type default)
		)
		(fill no)
		(layer "In4.Cu")
	)
	(gr_circle
		(center 74.849736 -274.049744)
		(end 75.103736 -274.049744)
		(stroke
			(width 0.1016)
			(type default)
		)
		(fill no)
		(layer "In4.Cu")
	)
	(gr_circle
		(center 74.849736 -273.099784)
		(end 75.103736 -273.099784)
		(stroke
			(width 0.1016)
			(type default)
		)
		(fill no)
		(layer "In4.Cu")
	)
	(gr_circle
		(center 74.84999 -318.699896)
		(end 75.10399 -318.699896)
		(stroke
			(width 0.1016)
			(type default)
		)
		(fill no)
		(layer "In4.Cu")
	)
	(gr_circle
		(center 74.84999 -317.749936)
		(end 75.10399 -317.749936)
		(stroke
			(width 0.1016)
			(type default)
		)
		(fill no)
		(layer "In4.Cu")
	)
	(gr_circle
		(center 74.84999 -313.949842)
		(end 75.10399 -313.949842)
		(stroke
			(width 0.1016)
			(type default)
		)
		(fill no)
		(layer "In4.Cu")
	)
	(gr_circle
		(center 74.84999 -312.999882)
		(end 75.10399 -312.999882)
		(stroke
			(width 0.1016)
			(type default)
		)
		(fill no)
		(layer "In4.Cu")
	)
	(gr_circle
		(center 74.84999 -308.249828)
		(end 75.10399 -308.249828)
		(stroke
			(width 0.1016)
			(type default)
		)
		(fill no)
		(layer "In4.Cu")
	)
	(gr_circle
		(center 74.84999 -306.349908)
		(end 75.10399 -306.349908)
		(stroke
			(width 0.1016)
			(type default)
		)
		(fill no)
		(layer "In4.Cu")
	)
	(gr_circle
		(center 74.84999 -304.449734)
		(end 75.10399 -304.449734)
		(stroke
			(width 0.1016)
			(type default)
		)
		(fill no)
		(layer "In4.Cu")
	)
	(gr_circle
		(center 74.84999 -287.349946)
		(end 75.10399 -287.349946)
		(stroke
			(width 0.1016)
			(type default)
		)
		(fill no)
		(layer "In4.Cu")
	)
	(gr_circle
		(center 74.84999 -285.449772)
		(end 75.10399 -285.449772)
		(stroke
			(width 0.1016)
			(type default)
		)
		(fill no)
		(layer "In4.Cu")
	)
	(gr_circle
		(center 74.84999 -283.549852)
		(end 75.10399 -283.549852)
		(stroke
			(width 0.1016)
			(type default)
		)
		(fill no)
		(layer "In4.Cu")
	)
	(gr_circle
		(center 75.799696 -275.949664)
		(end 76.053696 -275.949664)
		(stroke
			(width 0.1016)
			(type default)
		)
		(fill no)
		(layer "In4.Cu")
	)
	(gr_circle
		(center 75.799696 -274.999704)
		(end 76.053696 -274.999704)
		(stroke
			(width 0.1016)
			(type default)
		)
		(fill no)
		(layer "In4.Cu")
	)
	(gr_circle
		(center 75.79995 -316.799722)
		(end 76.05395 -316.799722)
		(stroke
			(width 0.1016)
			(type default)
		)
		(fill no)
		(layer "In4.Cu")
	)
	(gr_circle
		(center 75.79995 -315.849762)
		(end 76.05395 -315.849762)
		(stroke
			(width 0.1016)
			(type default)
		)
		(fill no)
		(layer "In4.Cu")
	)
	(gr_circle
		(center 75.79995 -312.049922)
		(end 76.05395 -312.049922)
		(stroke
			(width 0.1016)
			(type default)
		)
		(fill no)
		(layer "In4.Cu")
	)
	(gr_circle
		(center 75.79995 -311.099962)
		(end 76.05395 -311.099962)
		(stroke
			(width 0.1016)
			(type default)
		)
		(fill no)
		(layer "In4.Cu")
	)
	(gr_circle
		(center 75.79995 -308.249828)
		(end 76.05395 -308.249828)
		(stroke
			(width 0.1016)
			(type default)
		)
		(fill no)
		(layer "In4.Cu")
	)
	(gr_circle
		(center 75.79995 -306.349908)
		(end 76.05395 -306.349908)
		(stroke
			(width 0.1016)
			(type default)
		)
		(fill no)
		(layer "In4.Cu")
	)
	(gr_circle
		(center 75.79995 -304.449734)
		(end 76.05395 -304.449734)
		(stroke
			(width 0.1016)
			(type default)
		)
		(fill no)
		(layer "In4.Cu")
	)
	(gr_circle
		(center 75.79995 -287.349946)
		(end 76.05395 -287.349946)
		(stroke
			(width 0.1016)
			(type default)
		)
		(fill no)
		(layer "In4.Cu")
	)
	(gr_circle
		(center 75.79995 -285.449772)
		(end 76.05395 -285.449772)
		(stroke
			(width 0.1016)
			(type default)
		)
		(fill no)
		(layer "In4.Cu")
	)
	(gr_circle
		(center 75.79995 -283.549852)
		(end 76.05395 -283.549852)
		(stroke
			(width 0.1016)
			(type default)
		)
		(fill no)
		(layer "In4.Cu")
	)
	(gr_circle
		(center 75.79995 -280.699464)
		(end 76.05395 -280.699464)
		(stroke
			(width 0.1016)
			(type default)
		)
		(fill no)
		(layer "In4.Cu")
	)
	(gr_circle
		(center 75.79995 -279.749504)
		(end 76.05395 -279.749504)
		(stroke
			(width 0.1016)
			(type default)
		)
		(fill no)
		(layer "In4.Cu")
	)
	(gr_circle
		(center 76.749656 -278.799798)
		(end 77.003656 -278.799798)
		(stroke
			(width 0.1016)
			(type default)
		)
		(fill no)
		(layer "In4.Cu")
	)
	(gr_circle
		(center 76.749656 -277.849838)
		(end 77.003656 -277.849838)
		(stroke
			(width 0.1016)
			(type default)
		)
		(fill no)
		(layer "In4.Cu")
	)
	(gr_circle
		(center 76.749656 -274.049744)
		(end 77.003656 -274.049744)
		(stroke
			(width 0.1016)
			(type default)
		)
		(fill no)
		(layer "In4.Cu")
	)
	(gr_circle
		(center 76.749656 -273.099784)
		(end 77.003656 -273.099784)
		(stroke
			(width 0.1016)
			(type default)
		)
		(fill no)
		(layer "In4.Cu")
	)
	(gr_circle
		(center 76.74991 -318.699896)
		(end 77.00391 -318.699896)
		(stroke
			(width 0.1016)
			(type default)
		)
		(fill no)
		(layer "In4.Cu")
	)
	(gr_circle
		(center 76.74991 -317.749936)
		(end 77.00391 -317.749936)
		(stroke
			(width 0.1016)
			(type default)
		)
		(fill no)
		(layer "In4.Cu")
	)
	(gr_circle
		(center 76.74991 -313.949842)
		(end 77.00391 -313.949842)
		(stroke
			(width 0.1016)
			(type default)
		)
		(fill no)
		(layer "In4.Cu")
	)
	(gr_circle
		(center 76.74991 -312.999882)
		(end 77.00391 -312.999882)
		(stroke
			(width 0.1016)
			(type default)
		)
		(fill no)
		(layer "In4.Cu")
	)
	(gr_circle
		(center 76.74991 -309.199788)
		(end 77.00391 -309.199788)
		(stroke
			(width 0.1016)
			(type default)
		)
		(fill no)
		(layer "In4.Cu")
	)
	(gr_circle
		(center 76.74991 -307.299868)
		(end 77.00391 -307.299868)
		(stroke
			(width 0.1016)
			(type default)
		)
		(fill no)
		(layer "In4.Cu")
	)
	(gr_circle
		(center 76.74991 -305.399948)
		(end 77.00391 -305.399948)
		(stroke
			(width 0.1016)
			(type default)
		)
		(fill no)
		(layer "In4.Cu")
	)
	(gr_circle
		(center 76.74991 -288.299906)
		(end 77.00391 -288.299906)
		(stroke
			(width 0.1016)
			(type default)
		)
		(fill no)
		(layer "In4.Cu")
	)
	(gr_circle
		(center 76.74991 -286.399986)
		(end 77.00391 -286.399986)
		(stroke
			(width 0.1016)
			(type default)
		)
		(fill no)
		(layer "In4.Cu")
	)
	(gr_circle
		(center 76.74991 -284.499812)
		(end 77.00391 -284.499812)
		(stroke
			(width 0.1016)
			(type default)
		)
		(fill no)
		(layer "In4.Cu")
	)
	(gr_circle
		(center 76.74991 -282.599892)
		(end 77.00391 -282.599892)
		(stroke
			(width 0.1016)
			(type default)
		)
		(fill no)
		(layer "In4.Cu")
	)
	(gr_circle
		(center 77.699616 -275.949918)
		(end 77.953616 -275.949918)
		(stroke
			(width 0.1016)
			(type default)
		)
		(fill no)
		(layer "In4.Cu")
	)
	(gr_circle
		(center 77.699616 -274.999958)
		(end 77.953616 -274.999958)
		(stroke
			(width 0.1016)
			(type default)
		)
		(fill no)
		(layer "In4.Cu")
	)
	(gr_circle
		(center 77.69987 -316.799722)
		(end 77.95387 -316.799722)
		(stroke
			(width 0.1016)
			(type default)
		)
		(fill no)
		(layer "In4.Cu")
	)
	(gr_circle
		(center 77.69987 -315.849762)
		(end 77.95387 -315.849762)
		(stroke
			(width 0.1016)
			(type default)
		)
		(fill no)
		(layer "In4.Cu")
	)
	(gr_circle
		(center 77.69987 -312.049922)
		(end 77.95387 -312.049922)
		(stroke
			(width 0.1016)
			(type default)
		)
		(fill no)
		(layer "In4.Cu")
	)
	(gr_circle
		(center 77.69987 -311.099962)
		(end 77.95387 -311.099962)
		(stroke
			(width 0.1016)
			(type default)
		)
		(fill no)
		(layer "In4.Cu")
	)
	(gr_circle
		(center 77.69987 -309.199788)
		(end 77.95387 -309.199788)
		(stroke
			(width 0.1016)
			(type default)
		)
		(fill no)
		(layer "In4.Cu")
	)
	(gr_circle
		(center 77.69987 -307.299868)
		(end 77.95387 -307.299868)
		(stroke
			(width 0.1016)
			(type default)
		)
		(fill no)
		(layer "In4.Cu")
	)
	(gr_circle
		(center 77.69987 -305.399948)
		(end 77.95387 -305.399948)
		(stroke
			(width 0.1016)
			(type default)
		)
		(fill no)
		(layer "In4.Cu")
	)
	(gr_circle
		(center 77.69987 -288.299906)
		(end 77.95387 -288.299906)
		(stroke
			(width 0.1016)
			(type default)
		)
		(fill no)
		(layer "In4.Cu")
	)
	(gr_circle
		(center 77.69987 -286.399986)
		(end 77.95387 -286.399986)
		(stroke
			(width 0.1016)
			(type default)
		)
		(fill no)
		(layer "In4.Cu")
	)
	(gr_circle
		(center 77.69987 -284.499812)
		(end 77.95387 -284.499812)
		(stroke
			(width 0.1016)
			(type default)
		)
		(fill no)
		(layer "In4.Cu")
	)
	(gr_circle
		(center 77.69987 -282.599892)
		(end 77.95387 -282.599892)
		(stroke
			(width 0.1016)
			(type default)
		)
		(fill no)
		(layer "In4.Cu")
	)
	(gr_circle
		(center 77.69987 -280.699464)
		(end 77.95387 -280.699464)
		(stroke
			(width 0.1016)
			(type default)
		)
		(fill no)
		(layer "In4.Cu")
	)
	(gr_circle
		(center 77.69987 -279.749504)
		(end 77.95387 -279.749504)
		(stroke
			(width 0.1016)
			(type default)
		)
		(fill no)
		(layer "In4.Cu")
	)
	(gr_circle
		(center 78.649576 -278.799798)
		(end 78.903576 -278.799798)
		(stroke
			(width 0.1016)
			(type default)
		)
		(fill no)
		(layer "In4.Cu")
	)
	(gr_circle
		(center 78.649576 -277.849838)
		(end 78.903576 -277.849838)
		(stroke
			(width 0.1016)
			(type default)
		)
		(fill no)
		(layer "In4.Cu")
	)
	(gr_circle
		(center 78.649576 -274.049744)
		(end 78.903576 -274.049744)
		(stroke
			(width 0.1016)
			(type default)
		)
		(fill no)
		(layer "In4.Cu")
	)
	(gr_circle
		(center 78.649576 -273.099784)
		(end 78.903576 -273.099784)
		(stroke
			(width 0.1016)
			(type default)
		)
		(fill no)
		(layer "In4.Cu")
	)
	(gr_circle
		(center 78.64983 -318.699896)
		(end 78.90383 -318.699896)
		(stroke
			(width 0.1016)
			(type default)
		)
		(fill no)
		(layer "In4.Cu")
	)
	(gr_circle
		(center 78.64983 -317.749936)
		(end 78.90383 -317.749936)
		(stroke
			(width 0.1016)
			(type default)
		)
		(fill no)
		(layer "In4.Cu")
	)
	(gr_circle
		(center 78.64983 -313.949842)
		(end 78.90383 -313.949842)
		(stroke
			(width 0.1016)
			(type default)
		)
		(fill no)
		(layer "In4.Cu")
	)
	(gr_circle
		(center 78.64983 -312.999882)
		(end 78.90383 -312.999882)
		(stroke
			(width 0.1016)
			(type default)
		)
		(fill no)
		(layer "In4.Cu")
	)
	(gr_circle
		(center 79.599536 -275.949918)
		(end 79.853536 -275.949918)
		(stroke
			(width 0.1016)
			(type default)
		)
		(fill no)
		(layer "In4.Cu")
	)
	(gr_circle
		(center 79.599536 -274.999958)
		(end 79.853536 -274.999958)
		(stroke
			(width 0.1016)
			(type default)
		)
		(fill no)
		(layer "In4.Cu")
	)
	(gr_circle
		(center 79.59979 -316.799722)
		(end 79.85379 -316.799722)
		(stroke
			(width 0.1016)
			(type default)
		)
		(fill no)
		(layer "In4.Cu")
	)
	(gr_circle
		(center 79.59979 -315.849762)
		(end 79.85379 -315.849762)
		(stroke
			(width 0.1016)
			(type default)
		)
		(fill no)
		(layer "In4.Cu")
	)
	(gr_circle
		(center 79.59979 -312.049922)
		(end 79.85379 -312.049922)
		(stroke
			(width 0.1016)
			(type default)
		)
		(fill no)
		(layer "In4.Cu")
	)
	(gr_circle
		(center 79.59979 -311.099962)
		(end 79.85379 -311.099962)
		(stroke
			(width 0.1016)
			(type default)
		)
		(fill no)
		(layer "In4.Cu")
	)
	(gr_circle
		(center 79.59979 -309.199788)
		(end 79.85379 -309.199788)
		(stroke
			(width 0.1016)
			(type default)
		)
		(fill no)
		(layer "In4.Cu")
	)
	(gr_circle
		(center 79.59979 -307.299868)
		(end 79.85379 -307.299868)
		(stroke
			(width 0.1016)
			(type default)
		)
		(fill no)
		(layer "In4.Cu")
	)
	(gr_circle
		(center 79.59979 -305.399948)
		(end 79.85379 -305.399948)
		(stroke
			(width 0.1016)
			(type default)
		)
		(fill no)
		(layer "In4.Cu")
	)
	(gr_circle
		(center 79.59979 -288.299906)
		(end 79.85379 -288.299906)
		(stroke
			(width 0.1016)
			(type default)
		)
		(fill no)
		(layer "In4.Cu")
	)
	(gr_circle
		(center 79.59979 -286.399732)
		(end 79.85379 -286.399732)
		(stroke
			(width 0.1016)
			(type default)
		)
		(fill no)
		(layer "In4.Cu")
	)
	(gr_circle
		(center 79.59979 -284.499812)
		(end 79.85379 -284.499812)
		(stroke
			(width 0.1016)
			(type default)
		)
		(fill no)
		(layer "In4.Cu")
	)
	(gr_circle
		(center 79.59979 -282.599892)
		(end 79.85379 -282.599892)
		(stroke
			(width 0.1016)
			(type default)
		)
		(fill no)
		(layer "In4.Cu")
	)
	(gr_circle
		(center 79.59979 -280.699718)
		(end 79.85379 -280.699718)
		(stroke
			(width 0.1016)
			(type default)
		)
		(fill no)
		(layer "In4.Cu")
	)
	(gr_circle
		(center 79.59979 -279.749758)
		(end 79.85379 -279.749758)
		(stroke
			(width 0.1016)
			(type default)
		)
		(fill no)
		(layer "In4.Cu")
	)
	(gr_circle
		(center 80.549496 -274.049744)
		(end 80.803496 -274.049744)
		(stroke
			(width 0.1016)
			(type default)
		)
		(fill no)
		(layer "In4.Cu")
	)
	(gr_circle
		(center 80.549496 -273.099784)
		(end 80.803496 -273.099784)
		(stroke
			(width 0.1016)
			(type default)
		)
		(fill no)
		(layer "In4.Cu")
	)
	(gr_circle
		(center 80.54975 -318.699896)
		(end 80.80375 -318.699896)
		(stroke
			(width 0.1016)
			(type default)
		)
		(fill no)
		(layer "In4.Cu")
	)
	(gr_circle
		(center 80.54975 -317.749936)
		(end 80.80375 -317.749936)
		(stroke
			(width 0.1016)
			(type default)
		)
		(fill no)
		(layer "In4.Cu")
	)
	(gr_circle
		(center 80.54975 -313.949842)
		(end 80.80375 -313.949842)
		(stroke
			(width 0.1016)
			(type default)
		)
		(fill no)
		(layer "In4.Cu")
	)
	(gr_circle
		(center 80.54975 -312.999882)
		(end 80.80375 -312.999882)
		(stroke
			(width 0.1016)
			(type default)
		)
		(fill no)
		(layer "In4.Cu")
	)
	(gr_circle
		(center 80.54975 -309.199788)
		(end 80.80375 -309.199788)
		(stroke
			(width 0.1016)
			(type default)
		)
		(fill no)
		(layer "In4.Cu")
	)
	(gr_circle
		(center 80.54975 -307.299868)
		(end 80.80375 -307.299868)
		(stroke
			(width 0.1016)
			(type default)
		)
		(fill no)
		(layer "In4.Cu")
	)
	(gr_circle
		(center 80.54975 -305.399948)
		(end 80.80375 -305.399948)
		(stroke
			(width 0.1016)
			(type default)
		)
		(fill no)
		(layer "In4.Cu")
	)
	(gr_circle
		(center 80.54975 -288.299906)
		(end 80.80375 -288.299906)
		(stroke
			(width 0.1016)
			(type default)
		)
		(fill no)
		(layer "In4.Cu")
	)
	(gr_circle
		(center 80.54975 -286.399732)
		(end 80.80375 -286.399732)
		(stroke
			(width 0.1016)
			(type default)
		)
		(fill no)
		(layer "In4.Cu")
	)
	(gr_circle
		(center 80.54975 -284.499812)
		(end 80.80375 -284.499812)
		(stroke
			(width 0.1016)
			(type default)
		)
		(fill no)
		(layer "In4.Cu")
	)
	(gr_circle
		(center 80.54975 -282.599892)
		(end 80.80375 -282.599892)
		(stroke
			(width 0.1016)
			(type default)
		)
		(fill no)
		(layer "In4.Cu")
	)
	(gr_circle
		(center 80.54975 -278.799798)
		(end 80.80375 -278.799798)
		(stroke
			(width 0.1016)
			(type default)
		)
		(fill no)
		(layer "In4.Cu")
	)
	(gr_circle
		(center 80.54975 -277.849838)
		(end 80.80375 -277.849838)
		(stroke
			(width 0.1016)
			(type default)
		)
		(fill no)
		(layer "In4.Cu")
	)
	(gr_circle
		(center 81.499964 -316.799722)
		(end 81.753964 -316.799722)
		(stroke
			(width 0.1016)
			(type default)
		)
		(fill no)
		(layer "In4.Cu")
	)
	(gr_circle
		(center 81.499964 -314.899802)
		(end 81.753964 -314.899802)
		(stroke
			(width 0.1016)
			(type default)
		)
		(fill no)
		(layer "In4.Cu")
	)
	(gr_circle
		(center 81.499964 -312.049922)
		(end 81.753964 -312.049922)
		(stroke
			(width 0.1016)
			(type default)
		)
		(fill no)
		(layer "In4.Cu")
	)
	(gr_circle
		(center 81.499964 -310.149748)
		(end 81.753964 -310.149748)
		(stroke
			(width 0.1016)
			(type default)
		)
		(fill no)
		(layer "In4.Cu")
	)
	(gr_circle
		(center 81.499964 -308.249828)
		(end 81.753964 -308.249828)
		(stroke
			(width 0.1016)
			(type default)
		)
		(fill no)
		(layer "In4.Cu")
	)
	(gr_circle
		(center 81.499964 -306.349908)
		(end 81.753964 -306.349908)
		(stroke
			(width 0.1016)
			(type default)
		)
		(fill no)
		(layer "In4.Cu")
	)
	(gr_circle
		(center 81.499964 -304.449734)
		(end 81.753964 -304.449734)
		(stroke
			(width 0.1016)
			(type default)
		)
		(fill no)
		(layer "In4.Cu")
	)
	(gr_circle
		(center 81.499964 -287.349946)
		(end 81.753964 -287.349946)
		(stroke
			(width 0.1016)
			(type default)
		)
		(fill no)
		(layer "In4.Cu")
	)
	(gr_circle
		(center 81.499964 -285.449772)
		(end 81.753964 -285.449772)
		(stroke
			(width 0.1016)
			(type default)
		)
		(fill no)
		(layer "In4.Cu")
	)
	(gr_circle
		(center 81.499964 -283.549852)
		(end 81.753964 -283.549852)
		(stroke
			(width 0.1016)
			(type default)
		)
		(fill no)
		(layer "In4.Cu")
	)
	(gr_circle
		(center 81.499964 -281.649932)
		(end 81.753964 -281.649932)
		(stroke
			(width 0.1016)
			(type default)
		)
		(fill no)
		(layer "In4.Cu")
	)
	(gr_circle
		(center 81.499964 -279.749758)
		(end 81.753964 -279.749758)
		(stroke
			(width 0.1016)
			(type default)
		)
		(fill no)
		(layer "In4.Cu")
	)
	(gr_circle
		(center 81.499964 -276.899878)
		(end 81.753964 -276.899878)
		(stroke
			(width 0.1016)
			(type default)
		)
		(fill no)
		(layer "In4.Cu")
	)
	(gr_circle
		(center 81.499964 -274.999704)
		(end 81.753964 -274.999704)
		(stroke
			(width 0.1016)
			(type default)
		)
		(fill no)
		(layer "In4.Cu")
	)
	(gr_circle
		(center 82.449924 -316.799722)
		(end 82.703924 -316.799722)
		(stroke
			(width 0.1016)
			(type default)
		)
		(fill no)
		(layer "In4.Cu")
	)
	(gr_circle
		(center 82.449924 -314.899802)
		(end 82.703924 -314.899802)
		(stroke
			(width 0.1016)
			(type default)
		)
		(fill no)
		(layer "In4.Cu")
	)
	(gr_circle
		(center 82.449924 -312.049922)
		(end 82.703924 -312.049922)
		(stroke
			(width 0.1016)
			(type default)
		)
		(fill no)
		(layer "In4.Cu")
	)
	(gr_circle
		(center 82.449924 -310.149748)
		(end 82.703924 -310.149748)
		(stroke
			(width 0.1016)
			(type default)
		)
		(fill no)
		(layer "In4.Cu")
	)
	(gr_circle
		(center 82.449924 -308.249828)
		(end 82.703924 -308.249828)
		(stroke
			(width 0.1016)
			(type default)
		)
		(fill no)
		(layer "In4.Cu")
	)
	(gr_circle
		(center 82.449924 -306.349908)
		(end 82.703924 -306.349908)
		(stroke
			(width 0.1016)
			(type default)
		)
		(fill no)
		(layer "In4.Cu")
	)
	(gr_circle
		(center 82.449924 -304.449734)
		(end 82.703924 -304.449734)
		(stroke
			(width 0.1016)
			(type default)
		)
		(fill no)
		(layer "In4.Cu")
	)
	(gr_circle
		(center 82.449924 -287.349946)
		(end 82.703924 -287.349946)
		(stroke
			(width 0.1016)
			(type default)
		)
		(fill no)
		(layer "In4.Cu")
	)
	(gr_circle
		(center 82.449924 -285.449772)
		(end 82.703924 -285.449772)
		(stroke
			(width 0.1016)
			(type default)
		)
		(fill no)
		(layer "In4.Cu")
	)
	(gr_circle
		(center 82.449924 -283.549852)
		(end 82.703924 -283.549852)
		(stroke
			(width 0.1016)
			(type default)
		)
		(fill no)
		(layer "In4.Cu")
	)
	(gr_circle
		(center 82.449924 -281.649932)
		(end 82.703924 -281.649932)
		(stroke
			(width 0.1016)
			(type default)
		)
		(fill no)
		(layer "In4.Cu")
	)
	(gr_circle
		(center 82.449924 -279.749758)
		(end 82.703924 -279.749758)
		(stroke
			(width 0.1016)
			(type default)
		)
		(fill no)
		(layer "In4.Cu")
	)
	(gr_circle
		(center 82.449924 -276.899878)
		(end 82.703924 -276.899878)
		(stroke
			(width 0.1016)
			(type default)
		)
		(fill no)
		(layer "In4.Cu")
	)
	(gr_circle
		(center 82.449924 -274.999704)
		(end 82.703924 -274.999704)
		(stroke
			(width 0.1016)
			(type default)
		)
		(fill no)
		(layer "In4.Cu")
	)
	(gr_circle
		(center 152.94991 -316.799722)
		(end 153.20391 -316.799722)
		(stroke
			(width 0.1016)
			(type default)
		)
		(fill no)
		(layer "In4.Cu")
	)
	(gr_circle
		(center 152.94991 -314.899802)
		(end 153.20391 -314.899802)
		(stroke
			(width 0.1016)
			(type default)
		)
		(fill no)
		(layer "In4.Cu")
	)
	(gr_circle
		(center 152.94991 -312.049922)
		(end 153.20391 -312.049922)
		(stroke
			(width 0.1016)
			(type default)
		)
		(fill no)
		(layer "In4.Cu")
	)
	(gr_circle
		(center 152.94991 -310.149748)
		(end 153.20391 -310.149748)
		(stroke
			(width 0.1016)
			(type default)
		)
		(fill no)
		(layer "In4.Cu")
	)
	(gr_circle
		(center 152.94991 -308.249828)
		(end 153.20391 -308.249828)
		(stroke
			(width 0.1016)
			(type default)
		)
		(fill no)
		(layer "In4.Cu")
	)
	(gr_circle
		(center 152.94991 -306.349908)
		(end 153.20391 -306.349908)
		(stroke
			(width 0.1016)
			(type default)
		)
		(fill no)
		(layer "In4.Cu")
	)
	(gr_circle
		(center 152.94991 -304.449734)
		(end 153.20391 -304.449734)
		(stroke
			(width 0.1016)
			(type default)
		)
		(fill no)
		(layer "In4.Cu")
	)
	(gr_circle
		(center 152.94991 -302.549814)
		(end 153.20391 -302.549814)
		(stroke
			(width 0.1016)
			(type default)
		)
		(fill no)
		(layer "In4.Cu")
	)
	(gr_circle
		(center 153.89987 -316.799722)
		(end 154.15387 -316.799722)
		(stroke
			(width 0.1016)
			(type default)
		)
		(fill no)
		(layer "In4.Cu")
	)
	(gr_circle
		(center 153.89987 -314.899802)
		(end 154.15387 -314.899802)
		(stroke
			(width 0.1016)
			(type default)
		)
		(fill no)
		(layer "In4.Cu")
	)
	(gr_circle
		(center 153.89987 -312.049922)
		(end 154.15387 -312.049922)
		(stroke
			(width 0.1016)
			(type default)
		)
		(fill no)
		(layer "In4.Cu")
	)
	(gr_circle
		(center 153.89987 -310.149748)
		(end 154.15387 -310.149748)
		(stroke
			(width 0.1016)
			(type default)
		)
		(fill no)
		(layer "In4.Cu")
	)
	(gr_circle
		(center 153.89987 -308.249828)
		(end 154.15387 -308.249828)
		(stroke
			(width 0.1016)
			(type default)
		)
		(fill no)
		(layer "In4.Cu")
	)
	(gr_circle
		(center 153.89987 -306.349908)
		(end 154.15387 -306.349908)
		(stroke
			(width 0.1016)
			(type default)
		)
		(fill no)
		(layer "In4.Cu")
	)
	(gr_circle
		(center 153.89987 -304.449734)
		(end 154.15387 -304.449734)
		(stroke
			(width 0.1016)
			(type default)
		)
		(fill no)
		(layer "In4.Cu")
	)
	(gr_circle
		(center 153.89987 -302.549814)
		(end 154.15387 -302.549814)
		(stroke
			(width 0.1016)
			(type default)
		)
		(fill no)
		(layer "In4.Cu")
	)
	(gr_circle
		(center 154.850084 -318.699896)
		(end 155.104084 -318.699896)
		(stroke
			(width 0.1016)
			(type default)
		)
		(fill no)
		(layer "In4.Cu")
	)
	(gr_circle
		(center 154.850084 -317.749936)
		(end 155.104084 -317.749936)
		(stroke
			(width 0.1016)
			(type default)
		)
		(fill no)
		(layer "In4.Cu")
	)
	(gr_circle
		(center 154.850084 -313.949842)
		(end 155.104084 -313.949842)
		(stroke
			(width 0.1016)
			(type default)
		)
		(fill no)
		(layer "In4.Cu")
	)
	(gr_circle
		(center 154.850084 -312.999882)
		(end 155.104084 -312.999882)
		(stroke
			(width 0.1016)
			(type default)
		)
		(fill no)
		(layer "In4.Cu")
	)
	(gr_circle
		(center 154.850084 -309.199788)
		(end 155.104084 -309.199788)
		(stroke
			(width 0.1016)
			(type default)
		)
		(fill no)
		(layer "In4.Cu")
	)
	(gr_circle
		(center 154.850084 -307.299868)
		(end 155.104084 -307.299868)
		(stroke
			(width 0.1016)
			(type default)
		)
		(fill no)
		(layer "In4.Cu")
	)
	(gr_circle
		(center 154.850084 -305.399948)
		(end 155.104084 -305.399948)
		(stroke
			(width 0.1016)
			(type default)
		)
		(fill no)
		(layer "In4.Cu")
	)
	(gr_circle
		(center 154.850084 -303.499774)
		(end 155.104084 -303.499774)
		(stroke
			(width 0.1016)
			(type default)
		)
		(fill no)
		(layer "In4.Cu")
	)
	(gr_circle
		(center 154.850084 -301.599854)
		(end 155.104084 -301.599854)
		(stroke
			(width 0.1016)
			(type default)
		)
		(fill no)
		(layer "In4.Cu")
	)
	(gr_circle
		(center 155.800044 -316.799722)
		(end 156.054044 -316.799722)
		(stroke
			(width 0.1016)
			(type default)
		)
		(fill no)
		(layer "In4.Cu")
	)
	(gr_circle
		(center 155.800044 -315.849762)
		(end 156.054044 -315.849762)
		(stroke
			(width 0.1016)
			(type default)
		)
		(fill no)
		(layer "In4.Cu")
	)
	(gr_circle
		(center 155.800044 -312.049922)
		(end 156.054044 -312.049922)
		(stroke
			(width 0.1016)
			(type default)
		)
		(fill no)
		(layer "In4.Cu")
	)
	(gr_circle
		(center 155.800044 -311.099962)
		(end 156.054044 -311.099962)
		(stroke
			(width 0.1016)
			(type default)
		)
		(fill no)
		(layer "In4.Cu")
	)
	(gr_circle
		(center 155.800044 -309.199788)
		(end 156.054044 -309.199788)
		(stroke
			(width 0.1016)
			(type default)
		)
		(fill no)
		(layer "In4.Cu")
	)
	(gr_circle
		(center 155.800044 -307.299868)
		(end 156.054044 -307.299868)
		(stroke
			(width 0.1016)
			(type default)
		)
		(fill no)
		(layer "In4.Cu")
	)
	(gr_circle
		(center 155.800044 -305.399948)
		(end 156.054044 -305.399948)
		(stroke
			(width 0.1016)
			(type default)
		)
		(fill no)
		(layer "In4.Cu")
	)
	(gr_circle
		(center 155.800044 -303.499774)
		(end 156.054044 -303.499774)
		(stroke
			(width 0.1016)
			(type default)
		)
		(fill no)
		(layer "In4.Cu")
	)
	(gr_circle
		(center 155.800044 -301.599854)
		(end 156.054044 -301.599854)
		(stroke
			(width 0.1016)
			(type default)
		)
		(fill no)
		(layer "In4.Cu")
	)
	(gr_circle
		(center 156.750004 -318.699896)
		(end 157.004004 -318.699896)
		(stroke
			(width 0.1016)
			(type default)
		)
		(fill no)
		(layer "In4.Cu")
	)
	(gr_circle
		(center 156.750004 -317.749936)
		(end 157.004004 -317.749936)
		(stroke
			(width 0.1016)
			(type default)
		)
		(fill no)
		(layer "In4.Cu")
	)
	(gr_circle
		(center 156.750004 -313.949842)
		(end 157.004004 -313.949842)
		(stroke
			(width 0.1016)
			(type default)
		)
		(fill no)
		(layer "In4.Cu")
	)
	(gr_circle
		(center 156.750004 -312.999882)
		(end 157.004004 -312.999882)
		(stroke
			(width 0.1016)
			(type default)
		)
		(fill no)
		(layer "In4.Cu")
	)
	(gr_circle
		(center 157.699964 -316.799722)
		(end 157.953964 -316.799722)
		(stroke
			(width 0.1016)
			(type default)
		)
		(fill no)
		(layer "In4.Cu")
	)
	(gr_circle
		(center 157.699964 -315.849762)
		(end 157.953964 -315.849762)
		(stroke
			(width 0.1016)
			(type default)
		)
		(fill no)
		(layer "In4.Cu")
	)
	(gr_circle
		(center 157.699964 -312.049922)
		(end 157.953964 -312.049922)
		(stroke
			(width 0.1016)
			(type default)
		)
		(fill no)
		(layer "In4.Cu")
	)
	(gr_circle
		(center 157.699964 -311.099962)
		(end 157.953964 -311.099962)
		(stroke
			(width 0.1016)
			(type default)
		)
		(fill no)
		(layer "In4.Cu")
	)
	(gr_circle
		(center 157.699964 -309.199788)
		(end 157.953964 -309.199788)
		(stroke
			(width 0.1016)
			(type default)
		)
		(fill no)
		(layer "In4.Cu")
	)
	(gr_circle
		(center 157.699964 -307.299868)
		(end 157.953964 -307.299868)
		(stroke
			(width 0.1016)
			(type default)
		)
		(fill no)
		(layer "In4.Cu")
	)
	(gr_circle
		(center 157.699964 -305.399948)
		(end 157.953964 -305.399948)
		(stroke
			(width 0.1016)
			(type default)
		)
		(fill no)
		(layer "In4.Cu")
	)
	(gr_circle
		(center 157.699964 -303.499774)
		(end 157.953964 -303.499774)
		(stroke
			(width 0.1016)
			(type default)
		)
		(fill no)
		(layer "In4.Cu")
	)
	(gr_circle
		(center 157.699964 -301.599854)
		(end 157.953964 -301.599854)
		(stroke
			(width 0.1016)
			(type default)
		)
		(fill no)
		(layer "In4.Cu")
	)
	(gr_circle
		(center 158.649924 -318.699896)
		(end 158.903924 -318.699896)
		(stroke
			(width 0.1016)
			(type default)
		)
		(fill no)
		(layer "In4.Cu")
	)
	(gr_circle
		(center 158.649924 -317.749936)
		(end 158.903924 -317.749936)
		(stroke
			(width 0.1016)
			(type default)
		)
		(fill no)
		(layer "In4.Cu")
	)
	(gr_circle
		(center 158.649924 -313.949842)
		(end 158.903924 -313.949842)
		(stroke
			(width 0.1016)
			(type default)
		)
		(fill no)
		(layer "In4.Cu")
	)
	(gr_circle
		(center 158.649924 -312.999882)
		(end 158.903924 -312.999882)
		(stroke
			(width 0.1016)
			(type default)
		)
		(fill no)
		(layer "In4.Cu")
	)
	(gr_circle
		(center 158.649924 -309.199788)
		(end 158.903924 -309.199788)
		(stroke
			(width 0.1016)
			(type default)
		)
		(fill no)
		(layer "In4.Cu")
	)
	(gr_circle
		(center 158.649924 -307.299868)
		(end 158.903924 -307.299868)
		(stroke
			(width 0.1016)
			(type default)
		)
		(fill no)
		(layer "In4.Cu")
	)
	(gr_circle
		(center 158.649924 -305.399948)
		(end 158.903924 -305.399948)
		(stroke
			(width 0.1016)
			(type default)
		)
		(fill no)
		(layer "In4.Cu")
	)
	(gr_circle
		(center 158.649924 -303.499774)
		(end 158.903924 -303.499774)
		(stroke
			(width 0.1016)
			(type default)
		)
		(fill no)
		(layer "In4.Cu")
	)
	(gr_circle
		(center 158.649924 -301.599854)
		(end 158.903924 -301.599854)
		(stroke
			(width 0.1016)
			(type default)
		)
		(fill no)
		(layer "In4.Cu")
	)
	(gr_circle
		(center 159.599884 -316.799722)
		(end 159.853884 -316.799722)
		(stroke
			(width 0.1016)
			(type default)
		)
		(fill no)
		(layer "In4.Cu")
	)
	(gr_circle
		(center 159.599884 -315.849762)
		(end 159.853884 -315.849762)
		(stroke
			(width 0.1016)
			(type default)
		)
		(fill no)
		(layer "In4.Cu")
	)
	(gr_circle
		(center 159.599884 -312.049922)
		(end 159.853884 -312.049922)
		(stroke
			(width 0.1016)
			(type default)
		)
		(fill no)
		(layer "In4.Cu")
	)
	(gr_circle
		(center 159.599884 -311.099962)
		(end 159.853884 -311.099962)
		(stroke
			(width 0.1016)
			(type default)
		)
		(fill no)
		(layer "In4.Cu")
	)
	(gr_circle
		(center 159.599884 -308.249828)
		(end 159.853884 -308.249828)
		(stroke
			(width 0.1016)
			(type default)
		)
		(fill no)
		(layer "In4.Cu")
	)
	(gr_circle
		(center 159.599884 -306.349908)
		(end 159.853884 -306.349908)
		(stroke
			(width 0.1016)
			(type default)
		)
		(fill no)
		(layer "In4.Cu")
	)
	(gr_circle
		(center 159.599884 -304.449734)
		(end 159.853884 -304.449734)
		(stroke
			(width 0.1016)
			(type default)
		)
		(fill no)
		(layer "In4.Cu")
	)
	(gr_circle
		(center 159.599884 -302.549814)
		(end 159.853884 -302.549814)
		(stroke
			(width 0.1016)
			(type default)
		)
		(fill no)
		(layer "In4.Cu")
	)
	(gr_circle
		(center 160.549844 -318.699896)
		(end 160.803844 -318.699896)
		(stroke
			(width 0.1016)
			(type default)
		)
		(fill no)
		(layer "In4.Cu")
	)
	(gr_circle
		(center 160.549844 -317.749936)
		(end 160.803844 -317.749936)
		(stroke
			(width 0.1016)
			(type default)
		)
		(fill no)
		(layer "In4.Cu")
	)
	(gr_circle
		(center 160.549844 -313.949842)
		(end 160.803844 -313.949842)
		(stroke
			(width 0.1016)
			(type default)
		)
		(fill no)
		(layer "In4.Cu")
	)
	(gr_circle
		(center 160.549844 -312.999882)
		(end 160.803844 -312.999882)
		(stroke
			(width 0.1016)
			(type default)
		)
		(fill no)
		(layer "In4.Cu")
	)
	(gr_circle
		(center 160.549844 -308.249828)
		(end 160.803844 -308.249828)
		(stroke
			(width 0.1016)
			(type default)
		)
		(fill no)
		(layer "In4.Cu")
	)
	(gr_circle
		(center 160.549844 -306.349908)
		(end 160.803844 -306.349908)
		(stroke
			(width 0.1016)
			(type default)
		)
		(fill no)
		(layer "In4.Cu")
	)
	(gr_circle
		(center 160.549844 -304.449734)
		(end 160.803844 -304.449734)
		(stroke
			(width 0.1016)
			(type default)
		)
		(fill no)
		(layer "In4.Cu")
	)
	(gr_circle
		(center 160.549844 -302.549814)
		(end 160.803844 -302.549814)
		(stroke
			(width 0.1016)
			(type default)
		)
		(fill no)
		(layer "In4.Cu")
	)
	(gr_circle
		(center 160.549844 -278.799798)
		(end 160.803844 -278.799798)
		(stroke
			(width 0.1016)
			(type default)
		)
		(fill no)
		(layer "In4.Cu")
	)
	(gr_circle
		(center 160.549844 -277.849838)
		(end 160.803844 -277.849838)
		(stroke
			(width 0.1016)
			(type default)
		)
		(fill no)
		(layer "In4.Cu")
	)
	(gr_circle
		(center 160.549844 -274.049744)
		(end 160.803844 -274.049744)
		(stroke
			(width 0.1016)
			(type default)
		)
		(fill no)
		(layer "In4.Cu")
	)
	(gr_circle
		(center 160.549844 -273.099784)
		(end 160.803844 -273.099784)
		(stroke
			(width 0.1016)
			(type default)
		)
		(fill no)
		(layer "In4.Cu")
	)
	(gr_circle
		(center 161.500058 -316.799722)
		(end 161.754058 -316.799722)
		(stroke
			(width 0.1016)
			(type default)
		)
		(fill no)
		(layer "In4.Cu")
	)
	(gr_circle
		(center 161.500058 -315.849762)
		(end 161.754058 -315.849762)
		(stroke
			(width 0.1016)
			(type default)
		)
		(fill no)
		(layer "In4.Cu")
	)
	(gr_circle
		(center 161.500058 -312.049922)
		(end 161.754058 -312.049922)
		(stroke
			(width 0.1016)
			(type default)
		)
		(fill no)
		(layer "In4.Cu")
	)
	(gr_circle
		(center 161.500058 -311.099962)
		(end 161.754058 -311.099962)
		(stroke
			(width 0.1016)
			(type default)
		)
		(fill no)
		(layer "In4.Cu")
	)
	(gr_circle
		(center 161.500058 -280.699464)
		(end 161.754058 -280.699464)
		(stroke
			(width 0.1016)
			(type default)
		)
		(fill no)
		(layer "In4.Cu")
	)
	(gr_circle
		(center 161.500058 -279.749504)
		(end 161.754058 -279.749504)
		(stroke
			(width 0.1016)
			(type default)
		)
		(fill no)
		(layer "In4.Cu")
	)
	(gr_circle
		(center 161.500058 -275.949918)
		(end 161.754058 -275.949918)
		(stroke
			(width 0.1016)
			(type default)
		)
		(fill no)
		(layer "In4.Cu")
	)
	(gr_circle
		(center 161.500058 -274.999958)
		(end 161.754058 -274.999958)
		(stroke
			(width 0.1016)
			(type default)
		)
		(fill no)
		(layer "In4.Cu")
	)
	(gr_circle
		(center 162.450018 -318.699896)
		(end 162.704018 -318.699896)
		(stroke
			(width 0.1016)
			(type default)
		)
		(fill no)
		(layer "In4.Cu")
	)
	(gr_circle
		(center 162.450018 -317.749936)
		(end 162.704018 -317.749936)
		(stroke
			(width 0.1016)
			(type default)
		)
		(fill no)
		(layer "In4.Cu")
	)
	(gr_circle
		(center 162.450018 -313.949842)
		(end 162.704018 -313.949842)
		(stroke
			(width 0.1016)
			(type default)
		)
		(fill no)
		(layer "In4.Cu")
	)
	(gr_circle
		(center 162.450018 -312.999882)
		(end 162.704018 -312.999882)
		(stroke
			(width 0.1016)
			(type default)
		)
		(fill no)
		(layer "In4.Cu")
	)
	(gr_circle
		(center 162.450018 -278.799798)
		(end 162.704018 -278.799798)
		(stroke
			(width 0.1016)
			(type default)
		)
		(fill no)
		(layer "In4.Cu")
	)
	(gr_circle
		(center 162.450018 -277.849838)
		(end 162.704018 -277.849838)
		(stroke
			(width 0.1016)
			(type default)
		)
		(fill no)
		(layer "In4.Cu")
	)
	(gr_circle
		(center 162.450018 -274.049744)
		(end 162.704018 -274.049744)
		(stroke
			(width 0.1016)
			(type default)
		)
		(fill no)
		(layer "In4.Cu")
	)
	(gr_circle
		(center 162.450018 -273.099784)
		(end 162.704018 -273.099784)
		(stroke
			(width 0.1016)
			(type default)
		)
		(fill no)
		(layer "In4.Cu")
	)
	(gr_circle
		(center 163.399978 -316.799722)
		(end 163.653978 -316.799722)
		(stroke
			(width 0.1016)
			(type default)
		)
		(fill no)
		(layer "In4.Cu")
	)
	(gr_circle
		(center 163.399978 -315.849762)
		(end 163.653978 -315.849762)
		(stroke
			(width 0.1016)
			(type default)
		)
		(fill no)
		(layer "In4.Cu")
	)
	(gr_circle
		(center 163.399978 -312.049922)
		(end 163.653978 -312.049922)
		(stroke
			(width 0.1016)
			(type default)
		)
		(fill no)
		(layer "In4.Cu")
	)
	(gr_circle
		(center 163.399978 -311.099962)
		(end 163.653978 -311.099962)
		(stroke
			(width 0.1016)
			(type default)
		)
		(fill no)
		(layer "In4.Cu")
	)
	(gr_circle
		(center 163.399978 -280.699464)
		(end 163.653978 -280.699464)
		(stroke
			(width 0.1016)
			(type default)
		)
		(fill no)
		(layer "In4.Cu")
	)
	(gr_circle
		(center 163.399978 -279.749504)
		(end 163.653978 -279.749504)
		(stroke
			(width 0.1016)
			(type default)
		)
		(fill no)
		(layer "In4.Cu")
	)
	(gr_circle
		(center 163.399978 -275.949918)
		(end 163.653978 -275.949918)
		(stroke
			(width 0.1016)
			(type default)
		)
		(fill no)
		(layer "In4.Cu")
	)
	(gr_circle
		(center 163.399978 -274.999958)
		(end 163.653978 -274.999958)
		(stroke
			(width 0.1016)
			(type default)
		)
		(fill no)
		(layer "In4.Cu")
	)
	(gr_circle
		(center 164.349938 -318.699896)
		(end 164.603938 -318.699896)
		(stroke
			(width 0.1016)
			(type default)
		)
		(fill no)
		(layer "In4.Cu")
	)
	(gr_circle
		(center 164.349938 -317.749936)
		(end 164.603938 -317.749936)
		(stroke
			(width 0.1016)
			(type default)
		)
		(fill no)
		(layer "In4.Cu")
	)
	(gr_circle
		(center 164.349938 -313.949842)
		(end 164.603938 -313.949842)
		(stroke
			(width 0.1016)
			(type default)
		)
		(fill no)
		(layer "In4.Cu")
	)
	(gr_circle
		(center 164.349938 -312.999882)
		(end 164.603938 -312.999882)
		(stroke
			(width 0.1016)
			(type default)
		)
		(fill no)
		(layer "In4.Cu")
	)
	(gr_circle
		(center 164.349938 -278.799798)
		(end 164.603938 -278.799798)
		(stroke
			(width 0.1016)
			(type default)
		)
		(fill no)
		(layer "In4.Cu")
	)
	(gr_circle
		(center 164.349938 -277.849838)
		(end 164.603938 -277.849838)
		(stroke
			(width 0.1016)
			(type default)
		)
		(fill no)
		(layer "In4.Cu")
	)
	(gr_circle
		(center 164.349938 -274.049744)
		(end 164.603938 -274.049744)
		(stroke
			(width 0.1016)
			(type default)
		)
		(fill no)
		(layer "In4.Cu")
	)
	(gr_circle
		(center 164.349938 -273.099784)
		(end 164.603938 -273.099784)
		(stroke
			(width 0.1016)
			(type default)
		)
		(fill no)
		(layer "In4.Cu")
	)
	(gr_circle
		(center 165.299898 -316.799722)
		(end 165.553898 -316.799722)
		(stroke
			(width 0.1016)
			(type default)
		)
		(fill no)
		(layer "In4.Cu")
	)
	(gr_circle
		(center 165.299898 -315.849762)
		(end 165.553898 -315.849762)
		(stroke
			(width 0.1016)
			(type default)
		)
		(fill no)
		(layer "In4.Cu")
	)
	(gr_circle
		(center 165.299898 -312.049922)
		(end 165.553898 -312.049922)
		(stroke
			(width 0.1016)
			(type default)
		)
		(fill no)
		(layer "In4.Cu")
	)
	(gr_circle
		(center 165.299898 -311.099962)
		(end 165.553898 -311.099962)
		(stroke
			(width 0.1016)
			(type default)
		)
		(fill no)
		(layer "In4.Cu")
	)
	(gr_circle
		(center 165.299898 -280.699464)
		(end 165.553898 -280.699464)
		(stroke
			(width 0.1016)
			(type default)
		)
		(fill no)
		(layer "In4.Cu")
	)
	(gr_circle
		(center 165.299898 -279.749504)
		(end 165.553898 -279.749504)
		(stroke
			(width 0.1016)
			(type default)
		)
		(fill no)
		(layer "In4.Cu")
	)
	(gr_circle
		(center 165.299898 -275.949918)
		(end 165.553898 -275.949918)
		(stroke
			(width 0.1016)
			(type default)
		)
		(fill no)
		(layer "In4.Cu")
	)
	(gr_circle
		(center 165.299898 -274.999958)
		(end 165.553898 -274.999958)
		(stroke
			(width 0.1016)
			(type default)
		)
		(fill no)
		(layer "In4.Cu")
	)
	(gr_circle
		(center 166.249858 -318.699896)
		(end 166.503858 -318.699896)
		(stroke
			(width 0.1016)
			(type default)
		)
		(fill no)
		(layer "In4.Cu")
	)
	(gr_circle
		(center 166.249858 -317.749936)
		(end 166.503858 -317.749936)
		(stroke
			(width 0.1016)
			(type default)
		)
		(fill no)
		(layer "In4.Cu")
	)
	(gr_circle
		(center 166.249858 -313.949842)
		(end 166.503858 -313.949842)
		(stroke
			(width 0.1016)
			(type default)
		)
		(fill no)
		(layer "In4.Cu")
	)
	(gr_circle
		(center 166.249858 -312.999882)
		(end 166.503858 -312.999882)
		(stroke
			(width 0.1016)
			(type default)
		)
		(fill no)
		(layer "In4.Cu")
	)
	(gr_circle
		(center 166.249858 -278.799798)
		(end 166.503858 -278.799798)
		(stroke
			(width 0.1016)
			(type default)
		)
		(fill no)
		(layer "In4.Cu")
	)
	(gr_circle
		(center 166.249858 -277.849838)
		(end 166.503858 -277.849838)
		(stroke
			(width 0.1016)
			(type default)
		)
		(fill no)
		(layer "In4.Cu")
	)
	(gr_circle
		(center 166.249858 -274.049744)
		(end 166.503858 -274.049744)
		(stroke
			(width 0.1016)
			(type default)
		)
		(fill no)
		(layer "In4.Cu")
	)
	(gr_circle
		(center 166.249858 -273.099784)
		(end 166.503858 -273.099784)
		(stroke
			(width 0.1016)
			(type default)
		)
		(fill no)
		(layer "In4.Cu")
	)
	(gr_circle
		(center 167.200072 -316.799722)
		(end 167.454072 -316.799722)
		(stroke
			(width 0.1016)
			(type default)
		)
		(fill no)
		(layer "In4.Cu")
	)
	(gr_circle
		(center 167.200072 -315.849762)
		(end 167.454072 -315.849762)
		(stroke
			(width 0.1016)
			(type default)
		)
		(fill no)
		(layer "In4.Cu")
	)
	(gr_circle
		(center 167.200072 -312.049922)
		(end 167.454072 -312.049922)
		(stroke
			(width 0.1016)
			(type default)
		)
		(fill no)
		(layer "In4.Cu")
	)
	(gr_circle
		(center 167.200072 -311.099962)
		(end 167.454072 -311.099962)
		(stroke
			(width 0.1016)
			(type default)
		)
		(fill no)
		(layer "In4.Cu")
	)
	(gr_circle
		(center 167.200072 -280.699464)
		(end 167.454072 -280.699464)
		(stroke
			(width 0.1016)
			(type default)
		)
		(fill no)
		(layer "In4.Cu")
	)
	(gr_circle
		(center 167.200072 -279.749504)
		(end 167.454072 -279.749504)
		(stroke
			(width 0.1016)
			(type default)
		)
		(fill no)
		(layer "In4.Cu")
	)
	(gr_circle
		(center 167.200072 -275.949918)
		(end 167.454072 -275.949918)
		(stroke
			(width 0.1016)
			(type default)
		)
		(fill no)
		(layer "In4.Cu")
	)
	(gr_circle
		(center 167.200072 -274.999958)
		(end 167.454072 -274.999958)
		(stroke
			(width 0.1016)
			(type default)
		)
		(fill no)
		(layer "In4.Cu")
	)
	(gr_circle
		(center 168.150032 -318.699896)
		(end 168.404032 -318.699896)
		(stroke
			(width 0.1016)
			(type default)
		)
		(fill no)
		(layer "In4.Cu")
	)
	(gr_circle
		(center 168.150032 -317.749936)
		(end 168.404032 -317.749936)
		(stroke
			(width 0.1016)
			(type default)
		)
		(fill no)
		(layer "In4.Cu")
	)
	(gr_circle
		(center 168.150032 -313.949842)
		(end 168.404032 -313.949842)
		(stroke
			(width 0.1016)
			(type default)
		)
		(fill no)
		(layer "In4.Cu")
	)
	(gr_circle
		(center 168.150032 -312.999882)
		(end 168.404032 -312.999882)
		(stroke
			(width 0.1016)
			(type default)
		)
		(fill no)
		(layer "In4.Cu")
	)
	(gr_circle
		(center 168.150032 -278.799798)
		(end 168.404032 -278.799798)
		(stroke
			(width 0.1016)
			(type default)
		)
		(fill no)
		(layer "In4.Cu")
	)
	(gr_circle
		(center 168.150032 -277.849838)
		(end 168.404032 -277.849838)
		(stroke
			(width 0.1016)
			(type default)
		)
		(fill no)
		(layer "In4.Cu")
	)
	(gr_circle
		(center 168.150032 -274.049744)
		(end 168.404032 -274.049744)
		(stroke
			(width 0.1016)
			(type default)
		)
		(fill no)
		(layer "In4.Cu")
	)
	(gr_circle
		(center 168.150032 -273.099784)
		(end 168.404032 -273.099784)
		(stroke
			(width 0.1016)
			(type default)
		)
		(fill no)
		(layer "In4.Cu")
	)
	(gr_circle
		(center 169.099992 -316.799722)
		(end 169.353992 -316.799722)
		(stroke
			(width 0.1016)
			(type default)
		)
		(fill no)
		(layer "In4.Cu")
	)
	(gr_circle
		(center 169.099992 -315.849762)
		(end 169.353992 -315.849762)
		(stroke
			(width 0.1016)
			(type default)
		)
		(fill no)
		(layer "In4.Cu")
	)
	(gr_circle
		(center 169.099992 -312.049922)
		(end 169.353992 -312.049922)
		(stroke
			(width 0.1016)
			(type default)
		)
		(fill no)
		(layer "In4.Cu")
	)
	(gr_circle
		(center 169.099992 -311.099962)
		(end 169.353992 -311.099962)
		(stroke
			(width 0.1016)
			(type default)
		)
		(fill no)
		(layer "In4.Cu")
	)
	(gr_circle
		(center 169.099992 -280.699464)
		(end 169.353992 -280.699464)
		(stroke
			(width 0.1016)
			(type default)
		)
		(fill no)
		(layer "In4.Cu")
	)
	(gr_circle
		(center 169.099992 -279.749504)
		(end 169.353992 -279.749504)
		(stroke
			(width 0.1016)
			(type default)
		)
		(fill no)
		(layer "In4.Cu")
	)
	(gr_circle
		(center 169.099992 -275.949918)
		(end 169.353992 -275.949918)
		(stroke
			(width 0.1016)
			(type default)
		)
		(fill no)
		(layer "In4.Cu")
	)
	(gr_circle
		(center 169.099992 -274.999958)
		(end 169.353992 -274.999958)
		(stroke
			(width 0.1016)
			(type default)
		)
		(fill no)
		(layer "In4.Cu")
	)
	(gr_circle
		(center 170.049952 -318.699896)
		(end 170.303952 -318.699896)
		(stroke
			(width 0.1016)
			(type default)
		)
		(fill no)
		(layer "In4.Cu")
	)
	(gr_circle
		(center 170.049952 -317.749936)
		(end 170.303952 -317.749936)
		(stroke
			(width 0.1016)
			(type default)
		)
		(fill no)
		(layer "In4.Cu")
	)
	(gr_circle
		(center 170.049952 -313.949842)
		(end 170.303952 -313.949842)
		(stroke
			(width 0.1016)
			(type default)
		)
		(fill no)
		(layer "In4.Cu")
	)
	(gr_circle
		(center 170.049952 -312.999882)
		(end 170.303952 -312.999882)
		(stroke
			(width 0.1016)
			(type default)
		)
		(fill no)
		(layer "In4.Cu")
	)
	(gr_circle
		(center 170.049952 -278.799798)
		(end 170.303952 -278.799798)
		(stroke
			(width 0.1016)
			(type default)
		)
		(fill no)
		(layer "In4.Cu")
	)
	(gr_circle
		(center 170.049952 -277.849838)
		(end 170.303952 -277.849838)
		(stroke
			(width 0.1016)
			(type default)
		)
		(fill no)
		(layer "In4.Cu")
	)
	(gr_circle
		(center 170.049952 -274.049744)
		(end 170.303952 -274.049744)
		(stroke
			(width 0.1016)
			(type default)
		)
		(fill no)
		(layer "In4.Cu")
	)
	(gr_circle
		(center 170.049952 -273.099784)
		(end 170.303952 -273.099784)
		(stroke
			(width 0.1016)
			(type default)
		)
		(fill no)
		(layer "In4.Cu")
	)
	(gr_circle
		(center 170.999912 -316.799722)
		(end 171.253912 -316.799722)
		(stroke
			(width 0.1016)
			(type default)
		)
		(fill no)
		(layer "In4.Cu")
	)
	(gr_circle
		(center 170.999912 -315.849762)
		(end 171.253912 -315.849762)
		(stroke
			(width 0.1016)
			(type default)
		)
		(fill no)
		(layer "In4.Cu")
	)
	(gr_circle
		(center 170.999912 -312.049922)
		(end 171.253912 -312.049922)
		(stroke
			(width 0.1016)
			(type default)
		)
		(fill no)
		(layer "In4.Cu")
	)
	(gr_circle
		(center 170.999912 -311.099962)
		(end 171.253912 -311.099962)
		(stroke
			(width 0.1016)
			(type default)
		)
		(fill no)
		(layer "In4.Cu")
	)
	(gr_circle
		(center 170.999912 -280.699464)
		(end 171.253912 -280.699464)
		(stroke
			(width 0.1016)
			(type default)
		)
		(fill no)
		(layer "In4.Cu")
	)
	(gr_circle
		(center 170.999912 -279.749504)
		(end 171.253912 -279.749504)
		(stroke
			(width 0.1016)
			(type default)
		)
		(fill no)
		(layer "In4.Cu")
	)
	(gr_circle
		(center 170.999912 -275.949918)
		(end 171.253912 -275.949918)
		(stroke
			(width 0.1016)
			(type default)
		)
		(fill no)
		(layer "In4.Cu")
	)
	(gr_circle
		(center 170.999912 -274.999958)
		(end 171.253912 -274.999958)
		(stroke
			(width 0.1016)
			(type default)
		)
		(fill no)
		(layer "In4.Cu")
	)
	(gr_circle
		(center 171.949872 -318.699896)
		(end 172.203872 -318.699896)
		(stroke
			(width 0.1016)
			(type default)
		)
		(fill no)
		(layer "In4.Cu")
	)
	(gr_circle
		(center 171.949872 -317.749936)
		(end 172.203872 -317.749936)
		(stroke
			(width 0.1016)
			(type default)
		)
		(fill no)
		(layer "In4.Cu")
	)
	(gr_circle
		(center 171.949872 -313.949842)
		(end 172.203872 -313.949842)
		(stroke
			(width 0.1016)
			(type default)
		)
		(fill no)
		(layer "In4.Cu")
	)
	(gr_circle
		(center 171.949872 -312.999882)
		(end 172.203872 -312.999882)
		(stroke
			(width 0.1016)
			(type default)
		)
		(fill no)
		(layer "In4.Cu")
	)
	(gr_circle
		(center 171.949872 -278.799798)
		(end 172.203872 -278.799798)
		(stroke
			(width 0.1016)
			(type default)
		)
		(fill no)
		(layer "In4.Cu")
	)
	(gr_circle
		(center 171.949872 -277.849838)
		(end 172.203872 -277.849838)
		(stroke
			(width 0.1016)
			(type default)
		)
		(fill no)
		(layer "In4.Cu")
	)
	(gr_circle
		(center 171.949872 -274.049744)
		(end 172.203872 -274.049744)
		(stroke
			(width 0.1016)
			(type default)
		)
		(fill no)
		(layer "In4.Cu")
	)
	(gr_circle
		(center 171.949872 -273.099784)
		(end 172.203872 -273.099784)
		(stroke
			(width 0.1016)
			(type default)
		)
		(fill no)
		(layer "In4.Cu")
	)
	(gr_circle
		(center 172.899832 -280.699464)
		(end 173.153832 -280.699464)
		(stroke
			(width 0.1016)
			(type default)
		)
		(fill no)
		(layer "In4.Cu")
	)
	(gr_circle
		(center 172.899832 -279.749504)
		(end 173.153832 -279.749504)
		(stroke
			(width 0.1016)
			(type default)
		)
		(fill no)
		(layer "In4.Cu")
	)
	(gr_circle
		(center 172.900086 -316.799722)
		(end 173.154086 -316.799722)
		(stroke
			(width 0.1016)
			(type default)
		)
		(fill no)
		(layer "In4.Cu")
	)
	(gr_circle
		(center 172.900086 -315.849762)
		(end 173.154086 -315.849762)
		(stroke
			(width 0.1016)
			(type default)
		)
		(fill no)
		(layer "In4.Cu")
	)
	(gr_circle
		(center 172.900086 -312.049922)
		(end 173.154086 -312.049922)
		(stroke
			(width 0.1016)
			(type default)
		)
		(fill no)
		(layer "In4.Cu")
	)
	(gr_circle
		(center 172.900086 -311.099962)
		(end 173.154086 -311.099962)
		(stroke
			(width 0.1016)
			(type default)
		)
		(fill no)
		(layer "In4.Cu")
	)
	(gr_circle
		(center 172.900086 -275.949918)
		(end 173.154086 -275.949918)
		(stroke
			(width 0.1016)
			(type default)
		)
		(fill no)
		(layer "In4.Cu")
	)
	(gr_circle
		(center 172.900086 -274.999958)
		(end 173.154086 -274.999958)
		(stroke
			(width 0.1016)
			(type default)
		)
		(fill no)
		(layer "In4.Cu")
	)
	(gr_circle
		(center 173.850046 -318.699896)
		(end 174.104046 -318.699896)
		(stroke
			(width 0.1016)
			(type default)
		)
		(fill no)
		(layer "In4.Cu")
	)
	(gr_circle
		(center 173.850046 -317.749936)
		(end 174.104046 -317.749936)
		(stroke
			(width 0.1016)
			(type default)
		)
		(fill no)
		(layer "In4.Cu")
	)
	(gr_circle
		(center 173.850046 -313.949842)
		(end 174.104046 -313.949842)
		(stroke
			(width 0.1016)
			(type default)
		)
		(fill no)
		(layer "In4.Cu")
	)
	(gr_circle
		(center 173.850046 -312.999882)
		(end 174.104046 -312.999882)
		(stroke
			(width 0.1016)
			(type default)
		)
		(fill no)
		(layer "In4.Cu")
	)
	(gr_circle
		(center 173.850046 -278.799798)
		(end 174.104046 -278.799798)
		(stroke
			(width 0.1016)
			(type default)
		)
		(fill no)
		(layer "In4.Cu")
	)
	(gr_circle
		(center 173.850046 -277.849838)
		(end 174.104046 -277.849838)
		(stroke
			(width 0.1016)
			(type default)
		)
		(fill no)
		(layer "In4.Cu")
	)
	(gr_circle
		(center 173.850046 -274.049744)
		(end 174.104046 -274.049744)
		(stroke
			(width 0.1016)
			(type default)
		)
		(fill no)
		(layer "In4.Cu")
	)
	(gr_circle
		(center 173.850046 -273.099784)
		(end 174.104046 -273.099784)
		(stroke
			(width 0.1016)
			(type default)
		)
		(fill no)
		(layer "In4.Cu")
	)
	(gr_circle
		(center 174.800006 -316.799722)
		(end 175.054006 -316.799722)
		(stroke
			(width 0.1016)
			(type default)
		)
		(fill no)
		(layer "In4.Cu")
	)
	(gr_circle
		(center 174.800006 -315.849762)
		(end 175.054006 -315.849762)
		(stroke
			(width 0.1016)
			(type default)
		)
		(fill no)
		(layer "In4.Cu")
	)
	(gr_circle
		(center 174.800006 -312.049922)
		(end 175.054006 -312.049922)
		(stroke
			(width 0.1016)
			(type default)
		)
		(fill no)
		(layer "In4.Cu")
	)
	(gr_circle
		(center 174.800006 -311.099962)
		(end 175.054006 -311.099962)
		(stroke
			(width 0.1016)
			(type default)
		)
		(fill no)
		(layer "In4.Cu")
	)
	(gr_circle
		(center 174.800006 -280.699464)
		(end 175.054006 -280.699464)
		(stroke
			(width 0.1016)
			(type default)
		)
		(fill no)
		(layer "In4.Cu")
	)
	(gr_circle
		(center 174.800006 -279.749504)
		(end 175.054006 -279.749504)
		(stroke
			(width 0.1016)
			(type default)
		)
		(fill no)
		(layer "In4.Cu")
	)
	(gr_circle
		(center 174.800006 -275.949918)
		(end 175.054006 -275.949918)
		(stroke
			(width 0.1016)
			(type default)
		)
		(fill no)
		(layer "In4.Cu")
	)
	(gr_circle
		(center 174.800006 -274.999958)
		(end 175.054006 -274.999958)
		(stroke
			(width 0.1016)
			(type default)
		)
		(fill no)
		(layer "In4.Cu")
	)
	(gr_circle
		(center 175.749712 -278.799798)
		(end 176.003712 -278.799798)
		(stroke
			(width 0.1016)
			(type default)
		)
		(fill no)
		(layer "In4.Cu")
	)
	(gr_circle
		(center 175.749712 -277.849838)
		(end 176.003712 -277.849838)
		(stroke
			(width 0.1016)
			(type default)
		)
		(fill no)
		(layer "In4.Cu")
	)
	(gr_circle
		(center 175.749712 -274.04949)
		(end 176.003712 -274.04949)
		(stroke
			(width 0.1016)
			(type default)
		)
		(fill no)
		(layer "In4.Cu")
	)
	(gr_circle
		(center 175.749712 -273.09953)
		(end 176.003712 -273.09953)
		(stroke
			(width 0.1016)
			(type default)
		)
		(fill no)
		(layer "In4.Cu")
	)
	(gr_circle
		(center 175.749966 -318.699896)
		(end 176.003966 -318.699896)
		(stroke
			(width 0.1016)
			(type default)
		)
		(fill no)
		(layer "In4.Cu")
	)
	(gr_circle
		(center 175.749966 -317.749936)
		(end 176.003966 -317.749936)
		(stroke
			(width 0.1016)
			(type default)
		)
		(fill no)
		(layer "In4.Cu")
	)
	(gr_circle
		(center 175.749966 -313.949842)
		(end 176.003966 -313.949842)
		(stroke
			(width 0.1016)
			(type default)
		)
		(fill no)
		(layer "In4.Cu")
	)
	(gr_circle
		(center 175.749966 -312.999882)
		(end 176.003966 -312.999882)
		(stroke
			(width 0.1016)
			(type default)
		)
		(fill no)
		(layer "In4.Cu")
	)
	(gr_circle
		(center 176.699672 -275.949664)
		(end 176.953672 -275.949664)
		(stroke
			(width 0.1016)
			(type default)
		)
		(fill no)
		(layer "In4.Cu")
	)
	(gr_circle
		(center 176.699672 -274.999704)
		(end 176.953672 -274.999704)
		(stroke
			(width 0.1016)
			(type default)
		)
		(fill no)
		(layer "In4.Cu")
	)
	(gr_circle
		(center 176.699926 -316.799722)
		(end 176.953926 -316.799722)
		(stroke
			(width 0.1016)
			(type default)
		)
		(fill no)
		(layer "In4.Cu")
	)
	(gr_circle
		(center 176.699926 -315.849762)
		(end 176.953926 -315.849762)
		(stroke
			(width 0.1016)
			(type default)
		)
		(fill no)
		(layer "In4.Cu")
	)
	(gr_circle
		(center 176.699926 -312.049922)
		(end 176.953926 -312.049922)
		(stroke
			(width 0.1016)
			(type default)
		)
		(fill no)
		(layer "In4.Cu")
	)
	(gr_circle
		(center 176.699926 -311.099962)
		(end 176.953926 -311.099962)
		(stroke
			(width 0.1016)
			(type default)
		)
		(fill no)
		(layer "In4.Cu")
	)
	(gr_circle
		(center 176.699926 -280.699464)
		(end 176.953926 -280.699464)
		(stroke
			(width 0.1016)
			(type default)
		)
		(fill no)
		(layer "In4.Cu")
	)
	(gr_circle
		(center 176.699926 -279.749504)
		(end 176.953926 -279.749504)
		(stroke
			(width 0.1016)
			(type default)
		)
		(fill no)
		(layer "In4.Cu")
	)
	(gr_circle
		(center 177.649632 -278.799798)
		(end 177.903632 -278.799798)
		(stroke
			(width 0.1016)
			(type default)
		)
		(fill no)
		(layer "In4.Cu")
	)
	(gr_circle
		(center 177.649632 -277.849838)
		(end 177.903632 -277.849838)
		(stroke
			(width 0.1016)
			(type default)
		)
		(fill no)
		(layer "In4.Cu")
	)
	(gr_circle
		(center 177.649632 -274.049744)
		(end 177.903632 -274.049744)
		(stroke
			(width 0.1016)
			(type default)
		)
		(fill no)
		(layer "In4.Cu")
	)
	(gr_circle
		(center 177.649632 -273.099784)
		(end 177.903632 -273.099784)
		(stroke
			(width 0.1016)
			(type default)
		)
		(fill no)
		(layer "In4.Cu")
	)
	(gr_circle
		(center 177.649886 -318.699896)
		(end 177.903886 -318.699896)
		(stroke
			(width 0.1016)
			(type default)
		)
		(fill no)
		(layer "In4.Cu")
	)
	(gr_circle
		(center 177.649886 -317.749936)
		(end 177.903886 -317.749936)
		(stroke
			(width 0.1016)
			(type default)
		)
		(fill no)
		(layer "In4.Cu")
	)
	(gr_circle
		(center 177.649886 -313.949842)
		(end 177.903886 -313.949842)
		(stroke
			(width 0.1016)
			(type default)
		)
		(fill no)
		(layer "In4.Cu")
	)
	(gr_circle
		(center 177.649886 -312.999882)
		(end 177.903886 -312.999882)
		(stroke
			(width 0.1016)
			(type default)
		)
		(fill no)
		(layer "In4.Cu")
	)
	(gr_circle
		(center 178.599592 -275.949918)
		(end 178.853592 -275.949918)
		(stroke
			(width 0.1016)
			(type default)
		)
		(fill no)
		(layer "In4.Cu")
	)
	(gr_circle
		(center 178.599592 -274.999958)
		(end 178.853592 -274.999958)
		(stroke
			(width 0.1016)
			(type default)
		)
		(fill no)
		(layer "In4.Cu")
	)
	(gr_circle
		(center 178.599846 -316.799722)
		(end 178.853846 -316.799722)
		(stroke
			(width 0.1016)
			(type default)
		)
		(fill no)
		(layer "In4.Cu")
	)
	(gr_circle
		(center 178.599846 -315.849762)
		(end 178.853846 -315.849762)
		(stroke
			(width 0.1016)
			(type default)
		)
		(fill no)
		(layer "In4.Cu")
	)
	(gr_circle
		(center 178.599846 -312.049922)
		(end 178.853846 -312.049922)
		(stroke
			(width 0.1016)
			(type default)
		)
		(fill no)
		(layer "In4.Cu")
	)
	(gr_circle
		(center 178.599846 -311.099962)
		(end 178.853846 -311.099962)
		(stroke
			(width 0.1016)
			(type default)
		)
		(fill no)
		(layer "In4.Cu")
	)
	(gr_circle
		(center 178.599846 -280.699464)
		(end 178.853846 -280.699464)
		(stroke
			(width 0.1016)
			(type default)
		)
		(fill no)
		(layer "In4.Cu")
	)
	(gr_circle
		(center 178.599846 -279.749504)
		(end 178.853846 -279.749504)
		(stroke
			(width 0.1016)
			(type default)
		)
		(fill no)
		(layer "In4.Cu")
	)
	(gr_circle
		(center 179.549806 -278.799798)
		(end 179.803806 -278.799798)
		(stroke
			(width 0.1016)
			(type default)
		)
		(fill no)
		(layer "In4.Cu")
	)
	(gr_circle
		(center 179.549806 -277.849838)
		(end 179.803806 -277.849838)
		(stroke
			(width 0.1016)
			(type default)
		)
		(fill no)
		(layer "In4.Cu")
	)
	(gr_circle
		(center 179.549806 -274.049744)
		(end 179.803806 -274.049744)
		(stroke
			(width 0.1016)
			(type default)
		)
		(fill no)
		(layer "In4.Cu")
	)
	(gr_circle
		(center 179.549806 -273.099784)
		(end 179.803806 -273.099784)
		(stroke
			(width 0.1016)
			(type default)
		)
		(fill no)
		(layer "In4.Cu")
	)
	(gr_circle
		(center 179.55006 -318.699896)
		(end 179.80406 -318.699896)
		(stroke
			(width 0.1016)
			(type default)
		)
		(fill no)
		(layer "In4.Cu")
	)
	(gr_circle
		(center 179.55006 -317.749936)
		(end 179.80406 -317.749936)
		(stroke
			(width 0.1016)
			(type default)
		)
		(fill no)
		(layer "In4.Cu")
	)
	(gr_circle
		(center 179.55006 -313.949842)
		(end 179.80406 -313.949842)
		(stroke
			(width 0.1016)
			(type default)
		)
		(fill no)
		(layer "In4.Cu")
	)
	(gr_circle
		(center 179.55006 -312.999882)
		(end 179.80406 -312.999882)
		(stroke
			(width 0.1016)
			(type default)
		)
		(fill no)
		(layer "In4.Cu")
	)
	(gr_circle
		(center 180.499766 -275.949664)
		(end 180.753766 -275.949664)
		(stroke
			(width 0.1016)
			(type default)
		)
		(fill no)
		(layer "In4.Cu")
	)
	(gr_circle
		(center 180.499766 -274.999704)
		(end 180.753766 -274.999704)
		(stroke
			(width 0.1016)
			(type default)
		)
		(fill no)
		(layer "In4.Cu")
	)
	(gr_circle
		(center 180.50002 -316.799722)
		(end 180.75402 -316.799722)
		(stroke
			(width 0.1016)
			(type default)
		)
		(fill no)
		(layer "In4.Cu")
	)
	(gr_circle
		(center 180.50002 -315.849762)
		(end 180.75402 -315.849762)
		(stroke
			(width 0.1016)
			(type default)
		)
		(fill no)
		(layer "In4.Cu")
	)
	(gr_circle
		(center 180.50002 -312.049922)
		(end 180.75402 -312.049922)
		(stroke
			(width 0.1016)
			(type default)
		)
		(fill no)
		(layer "In4.Cu")
	)
	(gr_circle
		(center 180.50002 -311.099962)
		(end 180.75402 -311.099962)
		(stroke
			(width 0.1016)
			(type default)
		)
		(fill no)
		(layer "In4.Cu")
	)
	(gr_circle
		(center 180.50002 -280.699464)
		(end 180.75402 -280.699464)
		(stroke
			(width 0.1016)
			(type default)
		)
		(fill no)
		(layer "In4.Cu")
	)
	(gr_circle
		(center 180.50002 -279.749504)
		(end 180.75402 -279.749504)
		(stroke
			(width 0.1016)
			(type default)
		)
		(fill no)
		(layer "In4.Cu")
	)
	(gr_circle
		(center 181.449726 -278.799798)
		(end 181.703726 -278.799798)
		(stroke
			(width 0.1016)
			(type default)
		)
		(fill no)
		(layer "In4.Cu")
	)
	(gr_circle
		(center 181.449726 -277.849838)
		(end 181.703726 -277.849838)
		(stroke
			(width 0.1016)
			(type default)
		)
		(fill no)
		(layer "In4.Cu")
	)
	(gr_circle
		(center 181.449726 -274.049744)
		(end 181.703726 -274.049744)
		(stroke
			(width 0.1016)
			(type default)
		)
		(fill no)
		(layer "In4.Cu")
	)
	(gr_circle
		(center 181.449726 -273.099784)
		(end 181.703726 -273.099784)
		(stroke
			(width 0.1016)
			(type default)
		)
		(fill no)
		(layer "In4.Cu")
	)
	(gr_circle
		(center 181.44998 -318.699896)
		(end 181.70398 -318.699896)
		(stroke
			(width 0.1016)
			(type default)
		)
		(fill no)
		(layer "In4.Cu")
	)
	(gr_circle
		(center 181.44998 -317.749936)
		(end 181.70398 -317.749936)
		(stroke
			(width 0.1016)
			(type default)
		)
		(fill no)
		(layer "In4.Cu")
	)
	(gr_circle
		(center 181.44998 -313.949842)
		(end 181.70398 -313.949842)
		(stroke
			(width 0.1016)
			(type default)
		)
		(fill no)
		(layer "In4.Cu")
	)
	(gr_circle
		(center 181.44998 -312.999882)
		(end 181.70398 -312.999882)
		(stroke
			(width 0.1016)
			(type default)
		)
		(fill no)
		(layer "In4.Cu")
	)
	(gr_circle
		(center 182.399686 -275.949918)
		(end 182.653686 -275.949918)
		(stroke
			(width 0.1016)
			(type default)
		)
		(fill no)
		(layer "In4.Cu")
	)
	(gr_circle
		(center 182.399686 -274.999958)
		(end 182.653686 -274.999958)
		(stroke
			(width 0.1016)
			(type default)
		)
		(fill no)
		(layer "In4.Cu")
	)
	(gr_circle
		(center 182.39994 -316.799722)
		(end 182.65394 -316.799722)
		(stroke
			(width 0.1016)
			(type default)
		)
		(fill no)
		(layer "In4.Cu")
	)
	(gr_circle
		(center 182.39994 -315.849762)
		(end 182.65394 -315.849762)
		(stroke
			(width 0.1016)
			(type default)
		)
		(fill no)
		(layer "In4.Cu")
	)
	(gr_circle
		(center 182.39994 -312.049922)
		(end 182.65394 -312.049922)
		(stroke
			(width 0.1016)
			(type default)
		)
		(fill no)
		(layer "In4.Cu")
	)
	(gr_circle
		(center 182.39994 -311.099962)
		(end 182.65394 -311.099962)
		(stroke
			(width 0.1016)
			(type default)
		)
		(fill no)
		(layer "In4.Cu")
	)
	(gr_circle
		(center 182.39994 -280.699464)
		(end 182.65394 -280.699464)
		(stroke
			(width 0.1016)
			(type default)
		)
		(fill no)
		(layer "In4.Cu")
	)
	(gr_circle
		(center 182.39994 -279.749504)
		(end 182.65394 -279.749504)
		(stroke
			(width 0.1016)
			(type default)
		)
		(fill no)
		(layer "In4.Cu")
	)
	(gr_circle
		(center 183.349646 -278.799798)
		(end 183.603646 -278.799798)
		(stroke
			(width 0.1016)
			(type default)
		)
		(fill no)
		(layer "In4.Cu")
	)
	(gr_circle
		(center 183.349646 -277.849838)
		(end 183.603646 -277.849838)
		(stroke
			(width 0.1016)
			(type default)
		)
		(fill no)
		(layer "In4.Cu")
	)
	(gr_circle
		(center 183.349646 -274.049744)
		(end 183.603646 -274.049744)
		(stroke
			(width 0.1016)
			(type default)
		)
		(fill no)
		(layer "In4.Cu")
	)
	(gr_circle
		(center 183.349646 -273.099784)
		(end 183.603646 -273.099784)
		(stroke
			(width 0.1016)
			(type default)
		)
		(fill no)
		(layer "In4.Cu")
	)
	(gr_circle
		(center 183.3499 -318.699896)
		(end 183.6039 -318.699896)
		(stroke
			(width 0.1016)
			(type default)
		)
		(fill no)
		(layer "In4.Cu")
	)
	(gr_circle
		(center 183.3499 -317.749936)
		(end 183.6039 -317.749936)
		(stroke
			(width 0.1016)
			(type default)
		)
		(fill no)
		(layer "In4.Cu")
	)
	(gr_circle
		(center 183.3499 -313.949842)
		(end 183.6039 -313.949842)
		(stroke
			(width 0.1016)
			(type default)
		)
		(fill no)
		(layer "In4.Cu")
	)
	(gr_circle
		(center 183.3499 -312.999882)
		(end 183.6039 -312.999882)
		(stroke
			(width 0.1016)
			(type default)
		)
		(fill no)
		(layer "In4.Cu")
	)
	(gr_circle
		(center 184.299606 -275.949664)
		(end 184.553606 -275.949664)
		(stroke
			(width 0.1016)
			(type default)
		)
		(fill no)
		(layer "In4.Cu")
	)
	(gr_circle
		(center 184.299606 -274.999704)
		(end 184.553606 -274.999704)
		(stroke
			(width 0.1016)
			(type default)
		)
		(fill no)
		(layer "In4.Cu")
	)
	(gr_circle
		(center 184.29986 -316.799722)
		(end 184.55386 -316.799722)
		(stroke
			(width 0.1016)
			(type default)
		)
		(fill no)
		(layer "In4.Cu")
	)
	(gr_circle
		(center 184.29986 -315.849762)
		(end 184.55386 -315.849762)
		(stroke
			(width 0.1016)
			(type default)
		)
		(fill no)
		(layer "In4.Cu")
	)
	(gr_circle
		(center 184.29986 -312.049922)
		(end 184.55386 -312.049922)
		(stroke
			(width 0.1016)
			(type default)
		)
		(fill no)
		(layer "In4.Cu")
	)
	(gr_circle
		(center 184.29986 -311.099962)
		(end 184.55386 -311.099962)
		(stroke
			(width 0.1016)
			(type default)
		)
		(fill no)
		(layer "In4.Cu")
	)
	(gr_circle
		(center 184.29986 -280.699464)
		(end 184.55386 -280.699464)
		(stroke
			(width 0.1016)
			(type default)
		)
		(fill no)
		(layer "In4.Cu")
	)
	(gr_circle
		(center 184.29986 -279.749504)
		(end 184.55386 -279.749504)
		(stroke
			(width 0.1016)
			(type default)
		)
		(fill no)
		(layer "In4.Cu")
	)
	(gr_circle
		(center 185.24982 -278.799798)
		(end 185.50382 -278.799798)
		(stroke
			(width 0.1016)
			(type default)
		)
		(fill no)
		(layer "In4.Cu")
	)
	(gr_circle
		(center 185.24982 -277.849838)
		(end 185.50382 -277.849838)
		(stroke
			(width 0.1016)
			(type default)
		)
		(fill no)
		(layer "In4.Cu")
	)
	(gr_circle
		(center 185.24982 -274.049744)
		(end 185.50382 -274.049744)
		(stroke
			(width 0.1016)
			(type default)
		)
		(fill no)
		(layer "In4.Cu")
	)
	(gr_circle
		(center 185.24982 -273.099784)
		(end 185.50382 -273.099784)
		(stroke
			(width 0.1016)
			(type default)
		)
		(fill no)
		(layer "In4.Cu")
	)
	(gr_circle
		(center 185.250074 -318.699896)
		(end 185.504074 -318.699896)
		(stroke
			(width 0.1016)
			(type default)
		)
		(fill no)
		(layer "In4.Cu")
	)
	(gr_circle
		(center 185.250074 -317.749936)
		(end 185.504074 -317.749936)
		(stroke
			(width 0.1016)
			(type default)
		)
		(fill no)
		(layer "In4.Cu")
	)
	(gr_circle
		(center 185.250074 -313.949842)
		(end 185.504074 -313.949842)
		(stroke
			(width 0.1016)
			(type default)
		)
		(fill no)
		(layer "In4.Cu")
	)
	(gr_circle
		(center 185.250074 -312.999882)
		(end 185.504074 -312.999882)
		(stroke
			(width 0.1016)
			(type default)
		)
		(fill no)
		(layer "In4.Cu")
	)
	(gr_circle
		(center 186.199526 -275.949918)
		(end 186.453526 -275.949918)
		(stroke
			(width 0.1016)
			(type default)
		)
		(fill no)
		(layer "In4.Cu")
	)
	(gr_circle
		(center 186.199526 -274.999958)
		(end 186.453526 -274.999958)
		(stroke
			(width 0.1016)
			(type default)
		)
		(fill no)
		(layer "In4.Cu")
	)
	(gr_circle
		(center 186.200034 -316.799722)
		(end 186.454034 -316.799722)
		(stroke
			(width 0.1016)
			(type default)
		)
		(fill no)
		(layer "In4.Cu")
	)
	(gr_circle
		(center 186.200034 -315.849762)
		(end 186.454034 -315.849762)
		(stroke
			(width 0.1016)
			(type default)
		)
		(fill no)
		(layer "In4.Cu")
	)
	(gr_circle
		(center 186.200034 -312.049922)
		(end 186.454034 -312.049922)
		(stroke
			(width 0.1016)
			(type default)
		)
		(fill no)
		(layer "In4.Cu")
	)
	(gr_circle
		(center 186.200034 -311.099962)
		(end 186.454034 -311.099962)
		(stroke
			(width 0.1016)
			(type default)
		)
		(fill no)
		(layer "In4.Cu")
	)
	(gr_circle
		(center 186.200034 -280.699464)
		(end 186.454034 -280.699464)
		(stroke
			(width 0.1016)
			(type default)
		)
		(fill no)
		(layer "In4.Cu")
	)
	(gr_circle
		(center 186.200034 -279.749504)
		(end 186.454034 -279.749504)
		(stroke
			(width 0.1016)
			(type default)
		)
		(fill no)
		(layer "In4.Cu")
	)
	(gr_circle
		(center 187.14974 -278.799798)
		(end 187.40374 -278.799798)
		(stroke
			(width 0.1016)
			(type default)
		)
		(fill no)
		(layer "In4.Cu")
	)
	(gr_circle
		(center 187.14974 -277.849838)
		(end 187.40374 -277.849838)
		(stroke
			(width 0.1016)
			(type default)
		)
		(fill no)
		(layer "In4.Cu")
	)
	(gr_circle
		(center 187.14974 -274.049744)
		(end 187.40374 -274.049744)
		(stroke
			(width 0.1016)
			(type default)
		)
		(fill no)
		(layer "In4.Cu")
	)
	(gr_circle
		(center 187.14974 -273.099784)
		(end 187.40374 -273.099784)
		(stroke
			(width 0.1016)
			(type default)
		)
		(fill no)
		(layer "In4.Cu")
	)
	(gr_circle
		(center 187.149994 -318.699896)
		(end 187.403994 -318.699896)
		(stroke
			(width 0.1016)
			(type default)
		)
		(fill no)
		(layer "In4.Cu")
	)
	(gr_circle
		(center 187.149994 -317.749936)
		(end 187.403994 -317.749936)
		(stroke
			(width 0.1016)
			(type default)
		)
		(fill no)
		(layer "In4.Cu")
	)
	(gr_circle
		(center 187.149994 -313.949842)
		(end 187.403994 -313.949842)
		(stroke
			(width 0.1016)
			(type default)
		)
		(fill no)
		(layer "In4.Cu")
	)
	(gr_circle
		(center 187.149994 -312.999882)
		(end 187.403994 -312.999882)
		(stroke
			(width 0.1016)
			(type default)
		)
		(fill no)
		(layer "In4.Cu")
	)
	(gr_circle
		(center 188.0997 -275.949664)
		(end 188.3537 -275.949664)
		(stroke
			(width 0.1016)
			(type default)
		)
		(fill no)
		(layer "In4.Cu")
	)
	(gr_circle
		(center 188.0997 -274.999704)
		(end 188.3537 -274.999704)
		(stroke
			(width 0.1016)
			(type default)
		)
		(fill no)
		(layer "In4.Cu")
	)
	(gr_circle
		(center 188.099954 -316.799722)
		(end 188.353954 -316.799722)
		(stroke
			(width 0.1016)
			(type default)
		)
		(fill no)
		(layer "In4.Cu")
	)
	(gr_circle
		(center 188.099954 -315.849762)
		(end 188.353954 -315.849762)
		(stroke
			(width 0.1016)
			(type default)
		)
		(fill no)
		(layer "In4.Cu")
	)
	(gr_circle
		(center 188.099954 -312.049922)
		(end 188.353954 -312.049922)
		(stroke
			(width 0.1016)
			(type default)
		)
		(fill no)
		(layer "In4.Cu")
	)
	(gr_circle
		(center 188.099954 -311.099962)
		(end 188.353954 -311.099962)
		(stroke
			(width 0.1016)
			(type default)
		)
		(fill no)
		(layer "In4.Cu")
	)
	(gr_circle
		(center 188.099954 -280.699464)
		(end 188.353954 -280.699464)
		(stroke
			(width 0.1016)
			(type default)
		)
		(fill no)
		(layer "In4.Cu")
	)
	(gr_circle
		(center 188.099954 -279.749504)
		(end 188.353954 -279.749504)
		(stroke
			(width 0.1016)
			(type default)
		)
		(fill no)
		(layer "In4.Cu")
	)
	(gr_circle
		(center 189.04966 -278.799798)
		(end 189.30366 -278.799798)
		(stroke
			(width 0.1016)
			(type default)
		)
		(fill no)
		(layer "In4.Cu")
	)
	(gr_circle
		(center 189.04966 -277.849838)
		(end 189.30366 -277.849838)
		(stroke
			(width 0.1016)
			(type default)
		)
		(fill no)
		(layer "In4.Cu")
	)
	(gr_circle
		(center 189.04966 -274.049744)
		(end 189.30366 -274.049744)
		(stroke
			(width 0.1016)
			(type default)
		)
		(fill no)
		(layer "In4.Cu")
	)
	(gr_circle
		(center 189.04966 -273.099784)
		(end 189.30366 -273.099784)
		(stroke
			(width 0.1016)
			(type default)
		)
		(fill no)
		(layer "In4.Cu")
	)
	(gr_circle
		(center 189.049914 -318.699896)
		(end 189.303914 -318.699896)
		(stroke
			(width 0.1016)
			(type default)
		)
		(fill no)
		(layer "In4.Cu")
	)
	(gr_circle
		(center 189.049914 -317.749936)
		(end 189.303914 -317.749936)
		(stroke
			(width 0.1016)
			(type default)
		)
		(fill no)
		(layer "In4.Cu")
	)
	(gr_circle
		(center 189.049914 -313.949842)
		(end 189.303914 -313.949842)
		(stroke
			(width 0.1016)
			(type default)
		)
		(fill no)
		(layer "In4.Cu")
	)
	(gr_circle
		(center 189.049914 -312.999882)
		(end 189.303914 -312.999882)
		(stroke
			(width 0.1016)
			(type default)
		)
		(fill no)
		(layer "In4.Cu")
	)
	(gr_circle
		(center 189.99962 -275.949918)
		(end 190.25362 -275.949918)
		(stroke
			(width 0.1016)
			(type default)
		)
		(fill no)
		(layer "In4.Cu")
	)
	(gr_circle
		(center 189.99962 -274.999958)
		(end 190.25362 -274.999958)
		(stroke
			(width 0.1016)
			(type default)
		)
		(fill no)
		(layer "In4.Cu")
	)
	(gr_circle
		(center 189.999874 -316.799722)
		(end 190.253874 -316.799722)
		(stroke
			(width 0.1016)
			(type default)
		)
		(fill no)
		(layer "In4.Cu")
	)
	(gr_circle
		(center 189.999874 -315.849762)
		(end 190.253874 -315.849762)
		(stroke
			(width 0.1016)
			(type default)
		)
		(fill no)
		(layer "In4.Cu")
	)
	(gr_circle
		(center 189.999874 -312.049922)
		(end 190.253874 -312.049922)
		(stroke
			(width 0.1016)
			(type default)
		)
		(fill no)
		(layer "In4.Cu")
	)
	(gr_circle
		(center 189.999874 -311.099962)
		(end 190.253874 -311.099962)
		(stroke
			(width 0.1016)
			(type default)
		)
		(fill no)
		(layer "In4.Cu")
	)
	(gr_circle
		(center 189.999874 -280.699464)
		(end 190.253874 -280.699464)
		(stroke
			(width 0.1016)
			(type default)
		)
		(fill no)
		(layer "In4.Cu")
	)
	(gr_circle
		(center 189.999874 -279.749504)
		(end 190.253874 -279.749504)
		(stroke
			(width 0.1016)
			(type default)
		)
		(fill no)
		(layer "In4.Cu")
	)
	(gr_circle
		(center 190.949834 -278.799798)
		(end 191.203834 -278.799798)
		(stroke
			(width 0.1016)
			(type default)
		)
		(fill no)
		(layer "In4.Cu")
	)
	(gr_circle
		(center 190.949834 -277.849838)
		(end 191.203834 -277.849838)
		(stroke
			(width 0.1016)
			(type default)
		)
		(fill no)
		(layer "In4.Cu")
	)
	(gr_circle
		(center 190.949834 -274.049744)
		(end 191.203834 -274.049744)
		(stroke
			(width 0.1016)
			(type default)
		)
		(fill no)
		(layer "In4.Cu")
	)
	(gr_circle
		(center 190.949834 -273.099784)
		(end 191.203834 -273.099784)
		(stroke
			(width 0.1016)
			(type default)
		)
		(fill no)
		(layer "In4.Cu")
	)
	(gr_circle
		(center 190.950088 -318.699896)
		(end 191.204088 -318.699896)
		(stroke
			(width 0.1016)
			(type default)
		)
		(fill no)
		(layer "In4.Cu")
	)
	(gr_circle
		(center 190.950088 -317.749936)
		(end 191.204088 -317.749936)
		(stroke
			(width 0.1016)
			(type default)
		)
		(fill no)
		(layer "In4.Cu")
	)
	(gr_circle
		(center 190.950088 -313.949842)
		(end 191.204088 -313.949842)
		(stroke
			(width 0.1016)
			(type default)
		)
		(fill no)
		(layer "In4.Cu")
	)
	(gr_circle
		(center 190.950088 -312.999882)
		(end 191.204088 -312.999882)
		(stroke
			(width 0.1016)
			(type default)
		)
		(fill no)
		(layer "In4.Cu")
	)
	(gr_circle
		(center 190.950088 -308.249828)
		(end 191.204088 -308.249828)
		(stroke
			(width 0.1016)
			(type default)
		)
		(fill no)
		(layer "In4.Cu")
	)
	(gr_circle
		(center 190.950088 -306.349908)
		(end 191.204088 -306.349908)
		(stroke
			(width 0.1016)
			(type default)
		)
		(fill no)
		(layer "In4.Cu")
	)
	(gr_circle
		(center 190.950088 -304.449734)
		(end 191.204088 -304.449734)
		(stroke
			(width 0.1016)
			(type default)
		)
		(fill no)
		(layer "In4.Cu")
	)
	(gr_circle
		(center 190.950088 -287.349946)
		(end 191.204088 -287.349946)
		(stroke
			(width 0.1016)
			(type default)
		)
		(fill no)
		(layer "In4.Cu")
	)
	(gr_circle
		(center 190.950088 -285.449772)
		(end 191.204088 -285.449772)
		(stroke
			(width 0.1016)
			(type default)
		)
		(fill no)
		(layer "In4.Cu")
	)
	(gr_circle
		(center 190.950088 -283.549852)
		(end 191.204088 -283.549852)
		(stroke
			(width 0.1016)
			(type default)
		)
		(fill no)
		(layer "In4.Cu")
	)
	(gr_circle
		(center 191.899794 -275.949664)
		(end 192.153794 -275.949664)
		(stroke
			(width 0.1016)
			(type default)
		)
		(fill no)
		(layer "In4.Cu")
	)
	(gr_circle
		(center 191.899794 -274.999704)
		(end 192.153794 -274.999704)
		(stroke
			(width 0.1016)
			(type default)
		)
		(fill no)
		(layer "In4.Cu")
	)
	(gr_circle
		(center 191.900048 -316.799722)
		(end 192.154048 -316.799722)
		(stroke
			(width 0.1016)
			(type default)
		)
		(fill no)
		(layer "In4.Cu")
	)
	(gr_circle
		(center 191.900048 -315.849762)
		(end 192.154048 -315.849762)
		(stroke
			(width 0.1016)
			(type default)
		)
		(fill no)
		(layer "In4.Cu")
	)
	(gr_circle
		(center 191.900048 -312.049922)
		(end 192.154048 -312.049922)
		(stroke
			(width 0.1016)
			(type default)
		)
		(fill no)
		(layer "In4.Cu")
	)
	(gr_circle
		(center 191.900048 -311.099962)
		(end 192.154048 -311.099962)
		(stroke
			(width 0.1016)
			(type default)
		)
		(fill no)
		(layer "In4.Cu")
	)
	(gr_circle
		(center 191.900048 -308.249828)
		(end 192.154048 -308.249828)
		(stroke
			(width 0.1016)
			(type default)
		)
		(fill no)
		(layer "In4.Cu")
	)
	(gr_circle
		(center 191.900048 -306.349908)
		(end 192.154048 -306.349908)
		(stroke
			(width 0.1016)
			(type default)
		)
		(fill no)
		(layer "In4.Cu")
	)
	(gr_circle
		(center 191.900048 -304.449734)
		(end 192.154048 -304.449734)
		(stroke
			(width 0.1016)
			(type default)
		)
		(fill no)
		(layer "In4.Cu")
	)
	(gr_circle
		(center 191.900048 -287.349946)
		(end 192.154048 -287.349946)
		(stroke
			(width 0.1016)
			(type default)
		)
		(fill no)
		(layer "In4.Cu")
	)
	(gr_circle
		(center 191.900048 -285.449772)
		(end 192.154048 -285.449772)
		(stroke
			(width 0.1016)
			(type default)
		)
		(fill no)
		(layer "In4.Cu")
	)
	(gr_circle
		(center 191.900048 -283.549852)
		(end 192.154048 -283.549852)
		(stroke
			(width 0.1016)
			(type default)
		)
		(fill no)
		(layer "In4.Cu")
	)
	(gr_circle
		(center 191.900048 -280.699464)
		(end 192.154048 -280.699464)
		(stroke
			(width 0.1016)
			(type default)
		)
		(fill no)
		(layer "In4.Cu")
	)
	(gr_circle
		(center 191.900048 -279.749504)
		(end 192.154048 -279.749504)
		(stroke
			(width 0.1016)
			(type default)
		)
		(fill no)
		(layer "In4.Cu")
	)
	(gr_circle
		(center 192.849754 -278.799798)
		(end 193.103754 -278.799798)
		(stroke
			(width 0.1016)
			(type default)
		)
		(fill no)
		(layer "In4.Cu")
	)
	(gr_circle
		(center 192.849754 -277.849838)
		(end 193.103754 -277.849838)
		(stroke
			(width 0.1016)
			(type default)
		)
		(fill no)
		(layer "In4.Cu")
	)
	(gr_circle
		(center 192.849754 -274.049744)
		(end 193.103754 -274.049744)
		(stroke
			(width 0.1016)
			(type default)
		)
		(fill no)
		(layer "In4.Cu")
	)
	(gr_circle
		(center 192.849754 -273.099784)
		(end 193.103754 -273.099784)
		(stroke
			(width 0.1016)
			(type default)
		)
		(fill no)
		(layer "In4.Cu")
	)
	(gr_circle
		(center 192.850008 -318.699896)
		(end 193.104008 -318.699896)
		(stroke
			(width 0.1016)
			(type default)
		)
		(fill no)
		(layer "In4.Cu")
	)
	(gr_circle
		(center 192.850008 -317.749936)
		(end 193.104008 -317.749936)
		(stroke
			(width 0.1016)
			(type default)
		)
		(fill no)
		(layer "In4.Cu")
	)
	(gr_circle
		(center 192.850008 -313.949842)
		(end 193.104008 -313.949842)
		(stroke
			(width 0.1016)
			(type default)
		)
		(fill no)
		(layer "In4.Cu")
	)
	(gr_circle
		(center 192.850008 -312.999882)
		(end 193.104008 -312.999882)
		(stroke
			(width 0.1016)
			(type default)
		)
		(fill no)
		(layer "In4.Cu")
	)
	(gr_circle
		(center 192.850008 -309.199788)
		(end 193.104008 -309.199788)
		(stroke
			(width 0.1016)
			(type default)
		)
		(fill no)
		(layer "In4.Cu")
	)
	(gr_circle
		(center 192.850008 -307.299868)
		(end 193.104008 -307.299868)
		(stroke
			(width 0.1016)
			(type default)
		)
		(fill no)
		(layer "In4.Cu")
	)
	(gr_circle
		(center 192.850008 -305.399948)
		(end 193.104008 -305.399948)
		(stroke
			(width 0.1016)
			(type default)
		)
		(fill no)
		(layer "In4.Cu")
	)
	(gr_circle
		(center 192.850008 -288.299906)
		(end 193.104008 -288.299906)
		(stroke
			(width 0.1016)
			(type default)
		)
		(fill no)
		(layer "In4.Cu")
	)
	(gr_circle
		(center 192.850008 -286.399986)
		(end 193.104008 -286.399986)
		(stroke
			(width 0.1016)
			(type default)
		)
		(fill no)
		(layer "In4.Cu")
	)
	(gr_circle
		(center 192.850008 -284.499812)
		(end 193.104008 -284.499812)
		(stroke
			(width 0.1016)
			(type default)
		)
		(fill no)
		(layer "In4.Cu")
	)
	(gr_circle
		(center 192.850008 -282.599892)
		(end 193.104008 -282.599892)
		(stroke
			(width 0.1016)
			(type default)
		)
		(fill no)
		(layer "In4.Cu")
	)
	(gr_circle
		(center 193.799714 -275.949918)
		(end 194.053714 -275.949918)
		(stroke
			(width 0.1016)
			(type default)
		)
		(fill no)
		(layer "In4.Cu")
	)
	(gr_circle
		(center 193.799714 -274.999958)
		(end 194.053714 -274.999958)
		(stroke
			(width 0.1016)
			(type default)
		)
		(fill no)
		(layer "In4.Cu")
	)
	(gr_circle
		(center 193.799968 -316.799722)
		(end 194.053968 -316.799722)
		(stroke
			(width 0.1016)
			(type default)
		)
		(fill no)
		(layer "In4.Cu")
	)
	(gr_circle
		(center 193.799968 -315.849762)
		(end 194.053968 -315.849762)
		(stroke
			(width 0.1016)
			(type default)
		)
		(fill no)
		(layer "In4.Cu")
	)
	(gr_circle
		(center 193.799968 -312.049922)
		(end 194.053968 -312.049922)
		(stroke
			(width 0.1016)
			(type default)
		)
		(fill no)
		(layer "In4.Cu")
	)
	(gr_circle
		(center 193.799968 -311.099962)
		(end 194.053968 -311.099962)
		(stroke
			(width 0.1016)
			(type default)
		)
		(fill no)
		(layer "In4.Cu")
	)
	(gr_circle
		(center 193.799968 -309.199788)
		(end 194.053968 -309.199788)
		(stroke
			(width 0.1016)
			(type default)
		)
		(fill no)
		(layer "In4.Cu")
	)
	(gr_circle
		(center 193.799968 -307.299868)
		(end 194.053968 -307.299868)
		(stroke
			(width 0.1016)
			(type default)
		)
		(fill no)
		(layer "In4.Cu")
	)
	(gr_circle
		(center 193.799968 -305.399948)
		(end 194.053968 -305.399948)
		(stroke
			(width 0.1016)
			(type default)
		)
		(fill no)
		(layer "In4.Cu")
	)
	(gr_circle
		(center 193.799968 -288.299906)
		(end 194.053968 -288.299906)
		(stroke
			(width 0.1016)
			(type default)
		)
		(fill no)
		(layer "In4.Cu")
	)
	(gr_circle
		(center 193.799968 -286.399986)
		(end 194.053968 -286.399986)
		(stroke
			(width 0.1016)
			(type default)
		)
		(fill no)
		(layer "In4.Cu")
	)
	(gr_circle
		(center 193.799968 -284.499812)
		(end 194.053968 -284.499812)
		(stroke
			(width 0.1016)
			(type default)
		)
		(fill no)
		(layer "In4.Cu")
	)
	(gr_circle
		(center 193.799968 -282.599892)
		(end 194.053968 -282.599892)
		(stroke
			(width 0.1016)
			(type default)
		)
		(fill no)
		(layer "In4.Cu")
	)
	(gr_circle
		(center 193.799968 -280.699464)
		(end 194.053968 -280.699464)
		(stroke
			(width 0.1016)
			(type default)
		)
		(fill no)
		(layer "In4.Cu")
	)
	(gr_circle
		(center 193.799968 -279.749504)
		(end 194.053968 -279.749504)
		(stroke
			(width 0.1016)
			(type default)
		)
		(fill no)
		(layer "In4.Cu")
	)
	(gr_circle
		(center 194.749674 -278.799798)
		(end 195.003674 -278.799798)
		(stroke
			(width 0.1016)
			(type default)
		)
		(fill no)
		(layer "In4.Cu")
	)
	(gr_circle
		(center 194.749674 -277.849838)
		(end 195.003674 -277.849838)
		(stroke
			(width 0.1016)
			(type default)
		)
		(fill no)
		(layer "In4.Cu")
	)
	(gr_circle
		(center 194.749674 -274.049744)
		(end 195.003674 -274.049744)
		(stroke
			(width 0.1016)
			(type default)
		)
		(fill no)
		(layer "In4.Cu")
	)
	(gr_circle
		(center 194.749674 -273.099784)
		(end 195.003674 -273.099784)
		(stroke
			(width 0.1016)
			(type default)
		)
		(fill no)
		(layer "In4.Cu")
	)
	(gr_circle
		(center 194.749928 -318.699896)
		(end 195.003928 -318.699896)
		(stroke
			(width 0.1016)
			(type default)
		)
		(fill no)
		(layer "In4.Cu")
	)
	(gr_circle
		(center 194.749928 -317.749936)
		(end 195.003928 -317.749936)
		(stroke
			(width 0.1016)
			(type default)
		)
		(fill no)
		(layer "In4.Cu")
	)
	(gr_circle
		(center 194.749928 -313.949842)
		(end 195.003928 -313.949842)
		(stroke
			(width 0.1016)
			(type default)
		)
		(fill no)
		(layer "In4.Cu")
	)
	(gr_circle
		(center 194.749928 -312.999882)
		(end 195.003928 -312.999882)
		(stroke
			(width 0.1016)
			(type default)
		)
		(fill no)
		(layer "In4.Cu")
	)
	(gr_circle
		(center 195.699634 -275.949918)
		(end 195.953634 -275.949918)
		(stroke
			(width 0.1016)
			(type default)
		)
		(fill no)
		(layer "In4.Cu")
	)
	(gr_circle
		(center 195.699634 -274.999958)
		(end 195.953634 -274.999958)
		(stroke
			(width 0.1016)
			(type default)
		)
		(fill no)
		(layer "In4.Cu")
	)
	(gr_circle
		(center 195.699888 -316.799722)
		(end 195.953888 -316.799722)
		(stroke
			(width 0.1016)
			(type default)
		)
		(fill no)
		(layer "In4.Cu")
	)
	(gr_circle
		(center 195.699888 -315.849762)
		(end 195.953888 -315.849762)
		(stroke
			(width 0.1016)
			(type default)
		)
		(fill no)
		(layer "In4.Cu")
	)
	(gr_circle
		(center 195.699888 -312.049922)
		(end 195.953888 -312.049922)
		(stroke
			(width 0.1016)
			(type default)
		)
		(fill no)
		(layer "In4.Cu")
	)
	(gr_circle
		(center 195.699888 -311.099962)
		(end 195.953888 -311.099962)
		(stroke
			(width 0.1016)
			(type default)
		)
		(fill no)
		(layer "In4.Cu")
	)
	(gr_circle
		(center 195.699888 -309.199788)
		(end 195.953888 -309.199788)
		(stroke
			(width 0.1016)
			(type default)
		)
		(fill no)
		(layer "In4.Cu")
	)
	(gr_circle
		(center 195.699888 -307.299868)
		(end 195.953888 -307.299868)
		(stroke
			(width 0.1016)
			(type default)
		)
		(fill no)
		(layer "In4.Cu")
	)
	(gr_circle
		(center 195.699888 -305.399948)
		(end 195.953888 -305.399948)
		(stroke
			(width 0.1016)
			(type default)
		)
		(fill no)
		(layer "In4.Cu")
	)
	(gr_circle
		(center 195.699888 -288.299906)
		(end 195.953888 -288.299906)
		(stroke
			(width 0.1016)
			(type default)
		)
		(fill no)
		(layer "In4.Cu")
	)
	(gr_circle
		(center 195.699888 -286.399732)
		(end 195.953888 -286.399732)
		(stroke
			(width 0.1016)
			(type default)
		)
		(fill no)
		(layer "In4.Cu")
	)
	(gr_circle
		(center 195.699888 -284.499812)
		(end 195.953888 -284.499812)
		(stroke
			(width 0.1016)
			(type default)
		)
		(fill no)
		(layer "In4.Cu")
	)
	(gr_circle
		(center 195.699888 -282.599892)
		(end 195.953888 -282.599892)
		(stroke
			(width 0.1016)
			(type default)
		)
		(fill no)
		(layer "In4.Cu")
	)
	(gr_circle
		(center 195.699888 -280.699718)
		(end 195.953888 -280.699718)
		(stroke
			(width 0.1016)
			(type default)
		)
		(fill no)
		(layer "In4.Cu")
	)
	(gr_circle
		(center 195.699888 -279.749758)
		(end 195.953888 -279.749758)
		(stroke
			(width 0.1016)
			(type default)
		)
		(fill no)
		(layer "In4.Cu")
	)
	(gr_circle
		(center 196.649594 -274.049744)
		(end 196.903594 -274.049744)
		(stroke
			(width 0.1016)
			(type default)
		)
		(fill no)
		(layer "In4.Cu")
	)
	(gr_circle
		(center 196.649594 -273.099784)
		(end 196.903594 -273.099784)
		(stroke
			(width 0.1016)
			(type default)
		)
		(fill no)
		(layer "In4.Cu")
	)
	(gr_circle
		(center 196.649848 -318.699896)
		(end 196.903848 -318.699896)
		(stroke
			(width 0.1016)
			(type default)
		)
		(fill no)
		(layer "In4.Cu")
	)
	(gr_circle
		(center 196.649848 -317.749936)
		(end 196.903848 -317.749936)
		(stroke
			(width 0.1016)
			(type default)
		)
		(fill no)
		(layer "In4.Cu")
	)
	(gr_circle
		(center 196.649848 -313.949842)
		(end 196.903848 -313.949842)
		(stroke
			(width 0.1016)
			(type default)
		)
		(fill no)
		(layer "In4.Cu")
	)
	(gr_circle
		(center 196.649848 -312.999882)
		(end 196.903848 -312.999882)
		(stroke
			(width 0.1016)
			(type default)
		)
		(fill no)
		(layer "In4.Cu")
	)
	(gr_circle
		(center 196.649848 -309.199788)
		(end 196.903848 -309.199788)
		(stroke
			(width 0.1016)
			(type default)
		)
		(fill no)
		(layer "In4.Cu")
	)
	(gr_circle
		(center 196.649848 -307.299868)
		(end 196.903848 -307.299868)
		(stroke
			(width 0.1016)
			(type default)
		)
		(fill no)
		(layer "In4.Cu")
	)
	(gr_circle
		(center 196.649848 -305.399948)
		(end 196.903848 -305.399948)
		(stroke
			(width 0.1016)
			(type default)
		)
		(fill no)
		(layer "In4.Cu")
	)
	(gr_circle
		(center 196.649848 -288.299906)
		(end 196.903848 -288.299906)
		(stroke
			(width 0.1016)
			(type default)
		)
		(fill no)
		(layer "In4.Cu")
	)
	(gr_circle
		(center 196.649848 -286.399732)
		(end 196.903848 -286.399732)
		(stroke
			(width 0.1016)
			(type default)
		)
		(fill no)
		(layer "In4.Cu")
	)
	(gr_circle
		(center 196.649848 -284.499812)
		(end 196.903848 -284.499812)
		(stroke
			(width 0.1016)
			(type default)
		)
		(fill no)
		(layer "In4.Cu")
	)
	(gr_circle
		(center 196.649848 -282.599892)
		(end 196.903848 -282.599892)
		(stroke
			(width 0.1016)
			(type default)
		)
		(fill no)
		(layer "In4.Cu")
	)
	(gr_circle
		(center 196.649848 -278.799798)
		(end 196.903848 -278.799798)
		(stroke
			(width 0.1016)
			(type default)
		)
		(fill no)
		(layer "In4.Cu")
	)
	(gr_circle
		(center 196.649848 -277.849838)
		(end 196.903848 -277.849838)
		(stroke
			(width 0.1016)
			(type default)
		)
		(fill no)
		(layer "In4.Cu")
	)
	(gr_circle
		(center 197.600062 -316.799722)
		(end 197.854062 -316.799722)
		(stroke
			(width 0.1016)
			(type default)
		)
		(fill no)
		(layer "In4.Cu")
	)
	(gr_circle
		(center 197.600062 -314.899802)
		(end 197.854062 -314.899802)
		(stroke
			(width 0.1016)
			(type default)
		)
		(fill no)
		(layer "In4.Cu")
	)
	(gr_circle
		(center 197.600062 -312.049922)
		(end 197.854062 -312.049922)
		(stroke
			(width 0.1016)
			(type default)
		)
		(fill no)
		(layer "In4.Cu")
	)
	(gr_circle
		(center 197.600062 -310.149748)
		(end 197.854062 -310.149748)
		(stroke
			(width 0.1016)
			(type default)
		)
		(fill no)
		(layer "In4.Cu")
	)
	(gr_circle
		(center 197.600062 -308.249828)
		(end 197.854062 -308.249828)
		(stroke
			(width 0.1016)
			(type default)
		)
		(fill no)
		(layer "In4.Cu")
	)
	(gr_circle
		(center 197.600062 -306.349908)
		(end 197.854062 -306.349908)
		(stroke
			(width 0.1016)
			(type default)
		)
		(fill no)
		(layer "In4.Cu")
	)
	(gr_circle
		(center 197.600062 -304.449734)
		(end 197.854062 -304.449734)
		(stroke
			(width 0.1016)
			(type default)
		)
		(fill no)
		(layer "In4.Cu")
	)
	(gr_circle
		(center 197.600062 -287.349946)
		(end 197.854062 -287.349946)
		(stroke
			(width 0.1016)
			(type default)
		)
		(fill no)
		(layer "In4.Cu")
	)
	(gr_circle
		(center 197.600062 -285.449772)
		(end 197.854062 -285.449772)
		(stroke
			(width 0.1016)
			(type default)
		)
		(fill no)
		(layer "In4.Cu")
	)
	(gr_circle
		(center 197.600062 -283.549852)
		(end 197.854062 -283.549852)
		(stroke
			(width 0.1016)
			(type default)
		)
		(fill no)
		(layer "In4.Cu")
	)
	(gr_circle
		(center 197.600062 -281.649932)
		(end 197.854062 -281.649932)
		(stroke
			(width 0.1016)
			(type default)
		)
		(fill no)
		(layer "In4.Cu")
	)
	(gr_circle
		(center 197.600062 -279.749758)
		(end 197.854062 -279.749758)
		(stroke
			(width 0.1016)
			(type default)
		)
		(fill no)
		(layer "In4.Cu")
	)
	(gr_circle
		(center 197.600062 -276.899878)
		(end 197.854062 -276.899878)
		(stroke
			(width 0.1016)
			(type default)
		)
		(fill no)
		(layer "In4.Cu")
	)
	(gr_circle
		(center 197.600062 -274.999704)
		(end 197.854062 -274.999704)
		(stroke
			(width 0.1016)
			(type default)
		)
		(fill no)
		(layer "In4.Cu")
	)
	(gr_circle
		(center 198.550022 -316.799722)
		(end 198.804022 -316.799722)
		(stroke
			(width 0.1016)
			(type default)
		)
		(fill no)
		(layer "In4.Cu")
	)
	(gr_circle
		(center 198.550022 -314.899802)
		(end 198.804022 -314.899802)
		(stroke
			(width 0.1016)
			(type default)
		)
		(fill no)
		(layer "In4.Cu")
	)
	(gr_circle
		(center 198.550022 -312.049922)
		(end 198.804022 -312.049922)
		(stroke
			(width 0.1016)
			(type default)
		)
		(fill no)
		(layer "In4.Cu")
	)
	(gr_circle
		(center 198.550022 -310.149748)
		(end 198.804022 -310.149748)
		(stroke
			(width 0.1016)
			(type default)
		)
		(fill no)
		(layer "In4.Cu")
	)
	(gr_circle
		(center 198.550022 -308.249828)
		(end 198.804022 -308.249828)
		(stroke
			(width 0.1016)
			(type default)
		)
		(fill no)
		(layer "In4.Cu")
	)
	(gr_circle
		(center 198.550022 -306.349908)
		(end 198.804022 -306.349908)
		(stroke
			(width 0.1016)
			(type default)
		)
		(fill no)
		(layer "In4.Cu")
	)
	(gr_circle
		(center 198.550022 -304.449734)
		(end 198.804022 -304.449734)
		(stroke
			(width 0.1016)
			(type default)
		)
		(fill no)
		(layer "In4.Cu")
	)
	(gr_circle
		(center 198.550022 -287.349946)
		(end 198.804022 -287.349946)
		(stroke
			(width 0.1016)
			(type default)
		)
		(fill no)
		(layer "In4.Cu")
	)
	(gr_circle
		(center 198.550022 -285.449772)
		(end 198.804022 -285.449772)
		(stroke
			(width 0.1016)
			(type default)
		)
		(fill no)
		(layer "In4.Cu")
	)
	(gr_circle
		(center 198.550022 -283.549852)
		(end 198.804022 -283.549852)
		(stroke
			(width 0.1016)
			(type default)
		)
		(fill no)
		(layer "In4.Cu")
	)
	(gr_circle
		(center 198.550022 -281.649932)
		(end 198.804022 -281.649932)
		(stroke
			(width 0.1016)
			(type default)
		)
		(fill no)
		(layer "In4.Cu")
	)
	(gr_circle
		(center 198.550022 -279.749758)
		(end 198.804022 -279.749758)
		(stroke
			(width 0.1016)
			(type default)
		)
		(fill no)
		(layer "In4.Cu")
	)
	(gr_circle
		(center 198.550022 -276.899878)
		(end 198.804022 -276.899878)
		(stroke
			(width 0.1016)
			(type default)
		)
		(fill no)
		(layer "In4.Cu")
	)
	(gr_circle
		(center 198.550022 -274.999704)
		(end 198.804022 -274.999704)
		(stroke
			(width 0.1016)
			(type default)
		)
		(fill no)
		(layer "In4.Cu")
	)
	(gr_circle
		(center 269.049754 -316.799722)
		(end 269.303754 -316.799722)
		(stroke
			(width 0.1016)
			(type default)
		)
		(fill no)
		(layer "In4.Cu")
	)
	(gr_circle
		(center 269.049754 -314.899802)
		(end 269.303754 -314.899802)
		(stroke
			(width 0.1016)
			(type default)
		)
		(fill no)
		(layer "In4.Cu")
	)
	(gr_circle
		(center 269.049754 -312.049922)
		(end 269.303754 -312.049922)
		(stroke
			(width 0.1016)
			(type default)
		)
		(fill no)
		(layer "In4.Cu")
	)
	(gr_circle
		(center 269.049754 -310.149748)
		(end 269.303754 -310.149748)
		(stroke
			(width 0.1016)
			(type default)
		)
		(fill no)
		(layer "In4.Cu")
	)
	(gr_circle
		(center 269.049754 -308.249828)
		(end 269.303754 -308.249828)
		(stroke
			(width 0.1016)
			(type default)
		)
		(fill no)
		(layer "In4.Cu")
	)
	(gr_circle
		(center 269.049754 -306.349908)
		(end 269.303754 -306.349908)
		(stroke
			(width 0.1016)
			(type default)
		)
		(fill no)
		(layer "In4.Cu")
	)
	(gr_circle
		(center 269.049754 -304.449734)
		(end 269.303754 -304.449734)
		(stroke
			(width 0.1016)
			(type default)
		)
		(fill no)
		(layer "In4.Cu")
	)
	(gr_circle
		(center 269.049754 -302.549814)
		(end 269.303754 -302.549814)
		(stroke
			(width 0.1016)
			(type default)
		)
		(fill no)
		(layer "In4.Cu")
	)
	(gr_circle
		(center 269.999714 -316.799722)
		(end 270.253714 -316.799722)
		(stroke
			(width 0.1016)
			(type default)
		)
		(fill no)
		(layer "In4.Cu")
	)
	(gr_circle
		(center 269.999714 -314.899802)
		(end 270.253714 -314.899802)
		(stroke
			(width 0.1016)
			(type default)
		)
		(fill no)
		(layer "In4.Cu")
	)
	(gr_circle
		(center 269.999714 -312.049922)
		(end 270.253714 -312.049922)
		(stroke
			(width 0.1016)
			(type default)
		)
		(fill no)
		(layer "In4.Cu")
	)
	(gr_circle
		(center 269.999714 -310.149748)
		(end 270.253714 -310.149748)
		(stroke
			(width 0.1016)
			(type default)
		)
		(fill no)
		(layer "In4.Cu")
	)
	(gr_circle
		(center 269.999714 -308.249828)
		(end 270.253714 -308.249828)
		(stroke
			(width 0.1016)
			(type default)
		)
		(fill no)
		(layer "In4.Cu")
	)
	(gr_circle
		(center 269.999714 -306.349908)
		(end 270.253714 -306.349908)
		(stroke
			(width 0.1016)
			(type default)
		)
		(fill no)
		(layer "In4.Cu")
	)
	(gr_circle
		(center 269.999714 -304.449734)
		(end 270.253714 -304.449734)
		(stroke
			(width 0.1016)
			(type default)
		)
		(fill no)
		(layer "In4.Cu")
	)
	(gr_circle
		(center 269.999714 -302.549814)
		(end 270.253714 -302.549814)
		(stroke
			(width 0.1016)
			(type default)
		)
		(fill no)
		(layer "In4.Cu")
	)
	(gr_circle
		(center 270.949928 -318.699896)
		(end 271.203928 -318.699896)
		(stroke
			(width 0.1016)
			(type default)
		)
		(fill no)
		(layer "In4.Cu")
	)
	(gr_circle
		(center 270.949928 -317.749936)
		(end 271.203928 -317.749936)
		(stroke
			(width 0.1016)
			(type default)
		)
		(fill no)
		(layer "In4.Cu")
	)
	(gr_circle
		(center 270.949928 -313.949842)
		(end 271.203928 -313.949842)
		(stroke
			(width 0.1016)
			(type default)
		)
		(fill no)
		(layer "In4.Cu")
	)
	(gr_circle
		(center 270.949928 -312.999882)
		(end 271.203928 -312.999882)
		(stroke
			(width 0.1016)
			(type default)
		)
		(fill no)
		(layer "In4.Cu")
	)
	(gr_circle
		(center 270.949928 -309.199788)
		(end 271.203928 -309.199788)
		(stroke
			(width 0.1016)
			(type default)
		)
		(fill no)
		(layer "In4.Cu")
	)
	(gr_circle
		(center 270.949928 -307.299868)
		(end 271.203928 -307.299868)
		(stroke
			(width 0.1016)
			(type default)
		)
		(fill no)
		(layer "In4.Cu")
	)
	(gr_circle
		(center 270.949928 -305.399948)
		(end 271.203928 -305.399948)
		(stroke
			(width 0.1016)
			(type default)
		)
		(fill no)
		(layer "In4.Cu")
	)
	(gr_circle
		(center 270.949928 -303.499774)
		(end 271.203928 -303.499774)
		(stroke
			(width 0.1016)
			(type default)
		)
		(fill no)
		(layer "In4.Cu")
	)
	(gr_circle
		(center 270.949928 -301.599854)
		(end 271.203928 -301.599854)
		(stroke
			(width 0.1016)
			(type default)
		)
		(fill no)
		(layer "In4.Cu")
	)
	(gr_circle
		(center 271.899888 -316.799722)
		(end 272.153888 -316.799722)
		(stroke
			(width 0.1016)
			(type default)
		)
		(fill no)
		(layer "In4.Cu")
	)
	(gr_circle
		(center 271.899888 -315.849762)
		(end 272.153888 -315.849762)
		(stroke
			(width 0.1016)
			(type default)
		)
		(fill no)
		(layer "In4.Cu")
	)
	(gr_circle
		(center 271.899888 -312.049922)
		(end 272.153888 -312.049922)
		(stroke
			(width 0.1016)
			(type default)
		)
		(fill no)
		(layer "In4.Cu")
	)
	(gr_circle
		(center 271.899888 -311.099962)
		(end 272.153888 -311.099962)
		(stroke
			(width 0.1016)
			(type default)
		)
		(fill no)
		(layer "In4.Cu")
	)
	(gr_circle
		(center 271.899888 -309.199788)
		(end 272.153888 -309.199788)
		(stroke
			(width 0.1016)
			(type default)
		)
		(fill no)
		(layer "In4.Cu")
	)
	(gr_circle
		(center 271.899888 -307.299868)
		(end 272.153888 -307.299868)
		(stroke
			(width 0.1016)
			(type default)
		)
		(fill no)
		(layer "In4.Cu")
	)
	(gr_circle
		(center 271.899888 -305.399948)
		(end 272.153888 -305.399948)
		(stroke
			(width 0.1016)
			(type default)
		)
		(fill no)
		(layer "In4.Cu")
	)
	(gr_circle
		(center 271.899888 -303.499774)
		(end 272.153888 -303.499774)
		(stroke
			(width 0.1016)
			(type default)
		)
		(fill no)
		(layer "In4.Cu")
	)
	(gr_circle
		(center 271.899888 -301.599854)
		(end 272.153888 -301.599854)
		(stroke
			(width 0.1016)
			(type default)
		)
		(fill no)
		(layer "In4.Cu")
	)
	(gr_circle
		(center 272.849848 -318.699896)
		(end 273.103848 -318.699896)
		(stroke
			(width 0.1016)
			(type default)
		)
		(fill no)
		(layer "In4.Cu")
	)
	(gr_circle
		(center 272.849848 -317.749936)
		(end 273.103848 -317.749936)
		(stroke
			(width 0.1016)
			(type default)
		)
		(fill no)
		(layer "In4.Cu")
	)
	(gr_circle
		(center 272.849848 -313.949842)
		(end 273.103848 -313.949842)
		(stroke
			(width 0.1016)
			(type default)
		)
		(fill no)
		(layer "In4.Cu")
	)
	(gr_circle
		(center 272.849848 -312.999882)
		(end 273.103848 -312.999882)
		(stroke
			(width 0.1016)
			(type default)
		)
		(fill no)
		(layer "In4.Cu")
	)
	(gr_circle
		(center 273.799808 -316.799722)
		(end 274.053808 -316.799722)
		(stroke
			(width 0.1016)
			(type default)
		)
		(fill no)
		(layer "In4.Cu")
	)
	(gr_circle
		(center 273.799808 -315.849762)
		(end 274.053808 -315.849762)
		(stroke
			(width 0.1016)
			(type default)
		)
		(fill no)
		(layer "In4.Cu")
	)
	(gr_circle
		(center 273.799808 -312.049922)
		(end 274.053808 -312.049922)
		(stroke
			(width 0.1016)
			(type default)
		)
		(fill no)
		(layer "In4.Cu")
	)
	(gr_circle
		(center 273.799808 -311.099962)
		(end 274.053808 -311.099962)
		(stroke
			(width 0.1016)
			(type default)
		)
		(fill no)
		(layer "In4.Cu")
	)
	(gr_circle
		(center 273.799808 -309.199788)
		(end 274.053808 -309.199788)
		(stroke
			(width 0.1016)
			(type default)
		)
		(fill no)
		(layer "In4.Cu")
	)
	(gr_circle
		(center 273.799808 -307.299868)
		(end 274.053808 -307.299868)
		(stroke
			(width 0.1016)
			(type default)
		)
		(fill no)
		(layer "In4.Cu")
	)
	(gr_circle
		(center 273.799808 -305.399948)
		(end 274.053808 -305.399948)
		(stroke
			(width 0.1016)
			(type default)
		)
		(fill no)
		(layer "In4.Cu")
	)
	(gr_circle
		(center 273.799808 -303.499774)
		(end 274.053808 -303.499774)
		(stroke
			(width 0.1016)
			(type default)
		)
		(fill no)
		(layer "In4.Cu")
	)
	(gr_circle
		(center 273.799808 -301.599854)
		(end 274.053808 -301.599854)
		(stroke
			(width 0.1016)
			(type default)
		)
		(fill no)
		(layer "In4.Cu")
	)
	(gr_circle
		(center 274.749768 -318.699896)
		(end 275.003768 -318.699896)
		(stroke
			(width 0.1016)
			(type default)
		)
		(fill no)
		(layer "In4.Cu")
	)
	(gr_circle
		(center 274.749768 -317.749936)
		(end 275.003768 -317.749936)
		(stroke
			(width 0.1016)
			(type default)
		)
		(fill no)
		(layer "In4.Cu")
	)
	(gr_circle
		(center 274.749768 -313.949842)
		(end 275.003768 -313.949842)
		(stroke
			(width 0.1016)
			(type default)
		)
		(fill no)
		(layer "In4.Cu")
	)
	(gr_circle
		(center 274.749768 -312.999882)
		(end 275.003768 -312.999882)
		(stroke
			(width 0.1016)
			(type default)
		)
		(fill no)
		(layer "In4.Cu")
	)
	(gr_circle
		(center 274.749768 -309.199788)
		(end 275.003768 -309.199788)
		(stroke
			(width 0.1016)
			(type default)
		)
		(fill no)
		(layer "In4.Cu")
	)
	(gr_circle
		(center 274.749768 -307.299868)
		(end 275.003768 -307.299868)
		(stroke
			(width 0.1016)
			(type default)
		)
		(fill no)
		(layer "In4.Cu")
	)
	(gr_circle
		(center 274.749768 -305.399948)
		(end 275.003768 -305.399948)
		(stroke
			(width 0.1016)
			(type default)
		)
		(fill no)
		(layer "In4.Cu")
	)
	(gr_circle
		(center 274.749768 -303.499774)
		(end 275.003768 -303.499774)
		(stroke
			(width 0.1016)
			(type default)
		)
		(fill no)
		(layer "In4.Cu")
	)
	(gr_circle
		(center 274.749768 -301.599854)
		(end 275.003768 -301.599854)
		(stroke
			(width 0.1016)
			(type default)
		)
		(fill no)
		(layer "In4.Cu")
	)
	(gr_circle
		(center 275.699728 -316.799722)
		(end 275.953728 -316.799722)
		(stroke
			(width 0.1016)
			(type default)
		)
		(fill no)
		(layer "In4.Cu")
	)
	(gr_circle
		(center 275.699728 -315.849762)
		(end 275.953728 -315.849762)
		(stroke
			(width 0.1016)
			(type default)
		)
		(fill no)
		(layer "In4.Cu")
	)
	(gr_circle
		(center 275.699728 -312.049922)
		(end 275.953728 -312.049922)
		(stroke
			(width 0.1016)
			(type default)
		)
		(fill no)
		(layer "In4.Cu")
	)
	(gr_circle
		(center 275.699728 -311.099962)
		(end 275.953728 -311.099962)
		(stroke
			(width 0.1016)
			(type default)
		)
		(fill no)
		(layer "In4.Cu")
	)
	(gr_circle
		(center 275.699728 -308.249828)
		(end 275.953728 -308.249828)
		(stroke
			(width 0.1016)
			(type default)
		)
		(fill no)
		(layer "In4.Cu")
	)
	(gr_circle
		(center 275.699728 -306.349908)
		(end 275.953728 -306.349908)
		(stroke
			(width 0.1016)
			(type default)
		)
		(fill no)
		(layer "In4.Cu")
	)
	(gr_circle
		(center 275.699728 -304.449734)
		(end 275.953728 -304.449734)
		(stroke
			(width 0.1016)
			(type default)
		)
		(fill no)
		(layer "In4.Cu")
	)
	(gr_circle
		(center 275.699728 -302.549814)
		(end 275.953728 -302.549814)
		(stroke
			(width 0.1016)
			(type default)
		)
		(fill no)
		(layer "In4.Cu")
	)
	(gr_circle
		(center 276.649688 -318.699896)
		(end 276.903688 -318.699896)
		(stroke
			(width 0.1016)
			(type default)
		)
		(fill no)
		(layer "In4.Cu")
	)
	(gr_circle
		(center 276.649688 -317.749936)
		(end 276.903688 -317.749936)
		(stroke
			(width 0.1016)
			(type default)
		)
		(fill no)
		(layer "In4.Cu")
	)
	(gr_circle
		(center 276.649688 -313.949842)
		(end 276.903688 -313.949842)
		(stroke
			(width 0.1016)
			(type default)
		)
		(fill no)
		(layer "In4.Cu")
	)
	(gr_circle
		(center 276.649688 -312.999882)
		(end 276.903688 -312.999882)
		(stroke
			(width 0.1016)
			(type default)
		)
		(fill no)
		(layer "In4.Cu")
	)
	(gr_circle
		(center 276.649688 -308.249828)
		(end 276.903688 -308.249828)
		(stroke
			(width 0.1016)
			(type default)
		)
		(fill no)
		(layer "In4.Cu")
	)
	(gr_circle
		(center 276.649688 -306.349908)
		(end 276.903688 -306.349908)
		(stroke
			(width 0.1016)
			(type default)
		)
		(fill no)
		(layer "In4.Cu")
	)
	(gr_circle
		(center 276.649688 -304.449734)
		(end 276.903688 -304.449734)
		(stroke
			(width 0.1016)
			(type default)
		)
		(fill no)
		(layer "In4.Cu")
	)
	(gr_circle
		(center 276.649688 -302.549814)
		(end 276.903688 -302.549814)
		(stroke
			(width 0.1016)
			(type default)
		)
		(fill no)
		(layer "In4.Cu")
	)
	(gr_circle
		(center 276.649688 -278.799798)
		(end 276.903688 -278.799798)
		(stroke
			(width 0.1016)
			(type default)
		)
		(fill no)
		(layer "In4.Cu")
	)
	(gr_circle
		(center 276.649688 -277.849838)
		(end 276.903688 -277.849838)
		(stroke
			(width 0.1016)
			(type default)
		)
		(fill no)
		(layer "In4.Cu")
	)
	(gr_circle
		(center 276.649688 -274.049744)
		(end 276.903688 -274.049744)
		(stroke
			(width 0.1016)
			(type default)
		)
		(fill no)
		(layer "In4.Cu")
	)
	(gr_circle
		(center 276.649688 -273.099784)
		(end 276.903688 -273.099784)
		(stroke
			(width 0.1016)
			(type default)
		)
		(fill no)
		(layer "In4.Cu")
	)
	(gr_circle
		(center 277.599902 -316.799722)
		(end 277.853902 -316.799722)
		(stroke
			(width 0.1016)
			(type default)
		)
		(fill no)
		(layer "In4.Cu")
	)
	(gr_circle
		(center 277.599902 -315.849762)
		(end 277.853902 -315.849762)
		(stroke
			(width 0.1016)
			(type default)
		)
		(fill no)
		(layer "In4.Cu")
	)
	(gr_circle
		(center 277.599902 -312.049922)
		(end 277.853902 -312.049922)
		(stroke
			(width 0.1016)
			(type default)
		)
		(fill no)
		(layer "In4.Cu")
	)
	(gr_circle
		(center 277.599902 -311.099962)
		(end 277.853902 -311.099962)
		(stroke
			(width 0.1016)
			(type default)
		)
		(fill no)
		(layer "In4.Cu")
	)
	(gr_circle
		(center 277.599902 -280.699464)
		(end 277.853902 -280.699464)
		(stroke
			(width 0.1016)
			(type default)
		)
		(fill no)
		(layer "In4.Cu")
	)
	(gr_circle
		(center 277.599902 -279.749504)
		(end 277.853902 -279.749504)
		(stroke
			(width 0.1016)
			(type default)
		)
		(fill no)
		(layer "In4.Cu")
	)
	(gr_circle
		(center 277.599902 -275.949918)
		(end 277.853902 -275.949918)
		(stroke
			(width 0.1016)
			(type default)
		)
		(fill no)
		(layer "In4.Cu")
	)
	(gr_circle
		(center 277.599902 -274.999958)
		(end 277.853902 -274.999958)
		(stroke
			(width 0.1016)
			(type default)
		)
		(fill no)
		(layer "In4.Cu")
	)
	(gr_circle
		(center 278.549862 -318.699896)
		(end 278.803862 -318.699896)
		(stroke
			(width 0.1016)
			(type default)
		)
		(fill no)
		(layer "In4.Cu")
	)
	(gr_circle
		(center 278.549862 -317.749936)
		(end 278.803862 -317.749936)
		(stroke
			(width 0.1016)
			(type default)
		)
		(fill no)
		(layer "In4.Cu")
	)
	(gr_circle
		(center 278.549862 -313.949842)
		(end 278.803862 -313.949842)
		(stroke
			(width 0.1016)
			(type default)
		)
		(fill no)
		(layer "In4.Cu")
	)
	(gr_circle
		(center 278.549862 -312.999882)
		(end 278.803862 -312.999882)
		(stroke
			(width 0.1016)
			(type default)
		)
		(fill no)
		(layer "In4.Cu")
	)
	(gr_circle
		(center 278.549862 -278.799798)
		(end 278.803862 -278.799798)
		(stroke
			(width 0.1016)
			(type default)
		)
		(fill no)
		(layer "In4.Cu")
	)
	(gr_circle
		(center 278.549862 -277.849838)
		(end 278.803862 -277.849838)
		(stroke
			(width 0.1016)
			(type default)
		)
		(fill no)
		(layer "In4.Cu")
	)
	(gr_circle
		(center 278.549862 -274.049744)
		(end 278.803862 -274.049744)
		(stroke
			(width 0.1016)
			(type default)
		)
		(fill no)
		(layer "In4.Cu")
	)
	(gr_circle
		(center 278.549862 -273.099784)
		(end 278.803862 -273.099784)
		(stroke
			(width 0.1016)
			(type default)
		)
		(fill no)
		(layer "In4.Cu")
	)
	(gr_circle
		(center 279.499822 -316.799722)
		(end 279.753822 -316.799722)
		(stroke
			(width 0.1016)
			(type default)
		)
		(fill no)
		(layer "In4.Cu")
	)
	(gr_circle
		(center 279.499822 -315.849762)
		(end 279.753822 -315.849762)
		(stroke
			(width 0.1016)
			(type default)
		)
		(fill no)
		(layer "In4.Cu")
	)
	(gr_circle
		(center 279.499822 -312.049922)
		(end 279.753822 -312.049922)
		(stroke
			(width 0.1016)
			(type default)
		)
		(fill no)
		(layer "In4.Cu")
	)
	(gr_circle
		(center 279.499822 -311.099962)
		(end 279.753822 -311.099962)
		(stroke
			(width 0.1016)
			(type default)
		)
		(fill no)
		(layer "In4.Cu")
	)
	(gr_circle
		(center 279.499822 -280.699464)
		(end 279.753822 -280.699464)
		(stroke
			(width 0.1016)
			(type default)
		)
		(fill no)
		(layer "In4.Cu")
	)
	(gr_circle
		(center 279.499822 -279.749504)
		(end 279.753822 -279.749504)
		(stroke
			(width 0.1016)
			(type default)
		)
		(fill no)
		(layer "In4.Cu")
	)
	(gr_circle
		(center 279.499822 -275.949918)
		(end 279.753822 -275.949918)
		(stroke
			(width 0.1016)
			(type default)
		)
		(fill no)
		(layer "In4.Cu")
	)
	(gr_circle
		(center 279.499822 -274.999958)
		(end 279.753822 -274.999958)
		(stroke
			(width 0.1016)
			(type default)
		)
		(fill no)
		(layer "In4.Cu")
	)
	(gr_circle
		(center 280.449782 -318.699896)
		(end 280.703782 -318.699896)
		(stroke
			(width 0.1016)
			(type default)
		)
		(fill no)
		(layer "In4.Cu")
	)
	(gr_circle
		(center 280.449782 -317.749936)
		(end 280.703782 -317.749936)
		(stroke
			(width 0.1016)
			(type default)
		)
		(fill no)
		(layer "In4.Cu")
	)
	(gr_circle
		(center 280.449782 -313.949842)
		(end 280.703782 -313.949842)
		(stroke
			(width 0.1016)
			(type default)
		)
		(fill no)
		(layer "In4.Cu")
	)
	(gr_circle
		(center 280.449782 -312.999882)
		(end 280.703782 -312.999882)
		(stroke
			(width 0.1016)
			(type default)
		)
		(fill no)
		(layer "In4.Cu")
	)
	(gr_circle
		(center 280.449782 -278.799798)
		(end 280.703782 -278.799798)
		(stroke
			(width 0.1016)
			(type default)
		)
		(fill no)
		(layer "In4.Cu")
	)
	(gr_circle
		(center 280.449782 -277.849838)
		(end 280.703782 -277.849838)
		(stroke
			(width 0.1016)
			(type default)
		)
		(fill no)
		(layer "In4.Cu")
	)
	(gr_circle
		(center 280.449782 -274.049744)
		(end 280.703782 -274.049744)
		(stroke
			(width 0.1016)
			(type default)
		)
		(fill no)
		(layer "In4.Cu")
	)
	(gr_circle
		(center 280.449782 -273.099784)
		(end 280.703782 -273.099784)
		(stroke
			(width 0.1016)
			(type default)
		)
		(fill no)
		(layer "In4.Cu")
	)
	(gr_circle
		(center 281.399742 -316.799722)
		(end 281.653742 -316.799722)
		(stroke
			(width 0.1016)
			(type default)
		)
		(fill no)
		(layer "In4.Cu")
	)
	(gr_circle
		(center 281.399742 -315.849762)
		(end 281.653742 -315.849762)
		(stroke
			(width 0.1016)
			(type default)
		)
		(fill no)
		(layer "In4.Cu")
	)
	(gr_circle
		(center 281.399742 -312.049922)
		(end 281.653742 -312.049922)
		(stroke
			(width 0.1016)
			(type default)
		)
		(fill no)
		(layer "In4.Cu")
	)
	(gr_circle
		(center 281.399742 -311.099962)
		(end 281.653742 -311.099962)
		(stroke
			(width 0.1016)
			(type default)
		)
		(fill no)
		(layer "In4.Cu")
	)
	(gr_circle
		(center 281.399742 -280.699464)
		(end 281.653742 -280.699464)
		(stroke
			(width 0.1016)
			(type default)
		)
		(fill no)
		(layer "In4.Cu")
	)
	(gr_circle
		(center 281.399742 -279.749504)
		(end 281.653742 -279.749504)
		(stroke
			(width 0.1016)
			(type default)
		)
		(fill no)
		(layer "In4.Cu")
	)
	(gr_circle
		(center 281.399742 -275.949918)
		(end 281.653742 -275.949918)
		(stroke
			(width 0.1016)
			(type default)
		)
		(fill no)
		(layer "In4.Cu")
	)
	(gr_circle
		(center 281.399742 -274.999958)
		(end 281.653742 -274.999958)
		(stroke
			(width 0.1016)
			(type default)
		)
		(fill no)
		(layer "In4.Cu")
	)
	(gr_circle
		(center 282.349702 -318.699896)
		(end 282.603702 -318.699896)
		(stroke
			(width 0.1016)
			(type default)
		)
		(fill no)
		(layer "In4.Cu")
	)
	(gr_circle
		(center 282.349702 -317.749936)
		(end 282.603702 -317.749936)
		(stroke
			(width 0.1016)
			(type default)
		)
		(fill no)
		(layer "In4.Cu")
	)
	(gr_circle
		(center 282.349702 -313.949842)
		(end 282.603702 -313.949842)
		(stroke
			(width 0.1016)
			(type default)
		)
		(fill no)
		(layer "In4.Cu")
	)
	(gr_circle
		(center 282.349702 -312.999882)
		(end 282.603702 -312.999882)
		(stroke
			(width 0.1016)
			(type default)
		)
		(fill no)
		(layer "In4.Cu")
	)
	(gr_circle
		(center 282.349702 -278.799798)
		(end 282.603702 -278.799798)
		(stroke
			(width 0.1016)
			(type default)
		)
		(fill no)
		(layer "In4.Cu")
	)
	(gr_circle
		(center 282.349702 -277.849838)
		(end 282.603702 -277.849838)
		(stroke
			(width 0.1016)
			(type default)
		)
		(fill no)
		(layer "In4.Cu")
	)
	(gr_circle
		(center 282.349702 -274.049744)
		(end 282.603702 -274.049744)
		(stroke
			(width 0.1016)
			(type default)
		)
		(fill no)
		(layer "In4.Cu")
	)
	(gr_circle
		(center 282.349702 -273.099784)
		(end 282.603702 -273.099784)
		(stroke
			(width 0.1016)
			(type default)
		)
		(fill no)
		(layer "In4.Cu")
	)
	(gr_circle
		(center 283.299916 -316.799722)
		(end 283.553916 -316.799722)
		(stroke
			(width 0.1016)
			(type default)
		)
		(fill no)
		(layer "In4.Cu")
	)
	(gr_circle
		(center 283.299916 -315.849762)
		(end 283.553916 -315.849762)
		(stroke
			(width 0.1016)
			(type default)
		)
		(fill no)
		(layer "In4.Cu")
	)
	(gr_circle
		(center 283.299916 -312.049922)
		(end 283.553916 -312.049922)
		(stroke
			(width 0.1016)
			(type default)
		)
		(fill no)
		(layer "In4.Cu")
	)
	(gr_circle
		(center 283.299916 -311.099962)
		(end 283.553916 -311.099962)
		(stroke
			(width 0.1016)
			(type default)
		)
		(fill no)
		(layer "In4.Cu")
	)
	(gr_circle
		(center 283.299916 -280.699464)
		(end 283.553916 -280.699464)
		(stroke
			(width 0.1016)
			(type default)
		)
		(fill no)
		(layer "In4.Cu")
	)
	(gr_circle
		(center 283.299916 -279.749504)
		(end 283.553916 -279.749504)
		(stroke
			(width 0.1016)
			(type default)
		)
		(fill no)
		(layer "In4.Cu")
	)
	(gr_circle
		(center 283.299916 -275.949918)
		(end 283.553916 -275.949918)
		(stroke
			(width 0.1016)
			(type default)
		)
		(fill no)
		(layer "In4.Cu")
	)
	(gr_circle
		(center 283.299916 -274.999958)
		(end 283.553916 -274.999958)
		(stroke
			(width 0.1016)
			(type default)
		)
		(fill no)
		(layer "In4.Cu")
	)
	(gr_circle
		(center 284.249876 -318.699896)
		(end 284.503876 -318.699896)
		(stroke
			(width 0.1016)
			(type default)
		)
		(fill no)
		(layer "In4.Cu")
	)
	(gr_circle
		(center 284.249876 -317.749936)
		(end 284.503876 -317.749936)
		(stroke
			(width 0.1016)
			(type default)
		)
		(fill no)
		(layer "In4.Cu")
	)
	(gr_circle
		(center 284.249876 -313.949842)
		(end 284.503876 -313.949842)
		(stroke
			(width 0.1016)
			(type default)
		)
		(fill no)
		(layer "In4.Cu")
	)
	(gr_circle
		(center 284.249876 -312.999882)
		(end 284.503876 -312.999882)
		(stroke
			(width 0.1016)
			(type default)
		)
		(fill no)
		(layer "In4.Cu")
	)
	(gr_circle
		(center 284.249876 -278.799798)
		(end 284.503876 -278.799798)
		(stroke
			(width 0.1016)
			(type default)
		)
		(fill no)
		(layer "In4.Cu")
	)
	(gr_circle
		(center 284.249876 -277.849838)
		(end 284.503876 -277.849838)
		(stroke
			(width 0.1016)
			(type default)
		)
		(fill no)
		(layer "In4.Cu")
	)
	(gr_circle
		(center 284.249876 -274.049744)
		(end 284.503876 -274.049744)
		(stroke
			(width 0.1016)
			(type default)
		)
		(fill no)
		(layer "In4.Cu")
	)
	(gr_circle
		(center 284.249876 -273.099784)
		(end 284.503876 -273.099784)
		(stroke
			(width 0.1016)
			(type default)
		)
		(fill no)
		(layer "In4.Cu")
	)
	(gr_circle
		(center 285.199836 -316.799722)
		(end 285.453836 -316.799722)
		(stroke
			(width 0.1016)
			(type default)
		)
		(fill no)
		(layer "In4.Cu")
	)
	(gr_circle
		(center 285.199836 -315.849762)
		(end 285.453836 -315.849762)
		(stroke
			(width 0.1016)
			(type default)
		)
		(fill no)
		(layer "In4.Cu")
	)
	(gr_circle
		(center 285.199836 -312.049922)
		(end 285.453836 -312.049922)
		(stroke
			(width 0.1016)
			(type default)
		)
		(fill no)
		(layer "In4.Cu")
	)
	(gr_circle
		(center 285.199836 -311.099962)
		(end 285.453836 -311.099962)
		(stroke
			(width 0.1016)
			(type default)
		)
		(fill no)
		(layer "In4.Cu")
	)
	(gr_circle
		(center 285.199836 -280.699464)
		(end 285.453836 -280.699464)
		(stroke
			(width 0.1016)
			(type default)
		)
		(fill no)
		(layer "In4.Cu")
	)
	(gr_circle
		(center 285.199836 -279.749504)
		(end 285.453836 -279.749504)
		(stroke
			(width 0.1016)
			(type default)
		)
		(fill no)
		(layer "In4.Cu")
	)
	(gr_circle
		(center 285.199836 -275.949918)
		(end 285.453836 -275.949918)
		(stroke
			(width 0.1016)
			(type default)
		)
		(fill no)
		(layer "In4.Cu")
	)
	(gr_circle
		(center 285.199836 -274.999958)
		(end 285.453836 -274.999958)
		(stroke
			(width 0.1016)
			(type default)
		)
		(fill no)
		(layer "In4.Cu")
	)
	(gr_circle
		(center 286.149796 -318.699896)
		(end 286.403796 -318.699896)
		(stroke
			(width 0.1016)
			(type default)
		)
		(fill no)
		(layer "In4.Cu")
	)
	(gr_circle
		(center 286.149796 -317.749936)
		(end 286.403796 -317.749936)
		(stroke
			(width 0.1016)
			(type default)
		)
		(fill no)
		(layer "In4.Cu")
	)
	(gr_circle
		(center 286.149796 -313.949842)
		(end 286.403796 -313.949842)
		(stroke
			(width 0.1016)
			(type default)
		)
		(fill no)
		(layer "In4.Cu")
	)
	(gr_circle
		(center 286.149796 -312.999882)
		(end 286.403796 -312.999882)
		(stroke
			(width 0.1016)
			(type default)
		)
		(fill no)
		(layer "In4.Cu")
	)
	(gr_circle
		(center 286.149796 -278.799798)
		(end 286.403796 -278.799798)
		(stroke
			(width 0.1016)
			(type default)
		)
		(fill no)
		(layer "In4.Cu")
	)
	(gr_circle
		(center 286.149796 -277.849838)
		(end 286.403796 -277.849838)
		(stroke
			(width 0.1016)
			(type default)
		)
		(fill no)
		(layer "In4.Cu")
	)
	(gr_circle
		(center 286.149796 -274.049744)
		(end 286.403796 -274.049744)
		(stroke
			(width 0.1016)
			(type default)
		)
		(fill no)
		(layer "In4.Cu")
	)
	(gr_circle
		(center 286.149796 -273.099784)
		(end 286.403796 -273.099784)
		(stroke
			(width 0.1016)
			(type default)
		)
		(fill no)
		(layer "In4.Cu")
	)
	(gr_circle
		(center 287.099756 -316.799722)
		(end 287.353756 -316.799722)
		(stroke
			(width 0.1016)
			(type default)
		)
		(fill no)
		(layer "In4.Cu")
	)
	(gr_circle
		(center 287.099756 -315.849762)
		(end 287.353756 -315.849762)
		(stroke
			(width 0.1016)
			(type default)
		)
		(fill no)
		(layer "In4.Cu")
	)
	(gr_circle
		(center 287.099756 -312.049922)
		(end 287.353756 -312.049922)
		(stroke
			(width 0.1016)
			(type default)
		)
		(fill no)
		(layer "In4.Cu")
	)
	(gr_circle
		(center 287.099756 -311.099962)
		(end 287.353756 -311.099962)
		(stroke
			(width 0.1016)
			(type default)
		)
		(fill no)
		(layer "In4.Cu")
	)
	(gr_circle
		(center 287.099756 -280.699464)
		(end 287.353756 -280.699464)
		(stroke
			(width 0.1016)
			(type default)
		)
		(fill no)
		(layer "In4.Cu")
	)
	(gr_circle
		(center 287.099756 -279.749504)
		(end 287.353756 -279.749504)
		(stroke
			(width 0.1016)
			(type default)
		)
		(fill no)
		(layer "In4.Cu")
	)
	(gr_circle
		(center 287.099756 -275.949918)
		(end 287.353756 -275.949918)
		(stroke
			(width 0.1016)
			(type default)
		)
		(fill no)
		(layer "In4.Cu")
	)
	(gr_circle
		(center 287.099756 -274.999958)
		(end 287.353756 -274.999958)
		(stroke
			(width 0.1016)
			(type default)
		)
		(fill no)
		(layer "In4.Cu")
	)
	(gr_circle
		(center 288.049716 -318.699896)
		(end 288.303716 -318.699896)
		(stroke
			(width 0.1016)
			(type default)
		)
		(fill no)
		(layer "In4.Cu")
	)
	(gr_circle
		(center 288.049716 -317.749936)
		(end 288.303716 -317.749936)
		(stroke
			(width 0.1016)
			(type default)
		)
		(fill no)
		(layer "In4.Cu")
	)
	(gr_circle
		(center 288.049716 -313.949842)
		(end 288.303716 -313.949842)
		(stroke
			(width 0.1016)
			(type default)
		)
		(fill no)
		(layer "In4.Cu")
	)
	(gr_circle
		(center 288.049716 -312.999882)
		(end 288.303716 -312.999882)
		(stroke
			(width 0.1016)
			(type default)
		)
		(fill no)
		(layer "In4.Cu")
	)
	(gr_circle
		(center 288.049716 -278.799798)
		(end 288.303716 -278.799798)
		(stroke
			(width 0.1016)
			(type default)
		)
		(fill no)
		(layer "In4.Cu")
	)
	(gr_circle
		(center 288.049716 -277.849838)
		(end 288.303716 -277.849838)
		(stroke
			(width 0.1016)
			(type default)
		)
		(fill no)
		(layer "In4.Cu")
	)
	(gr_circle
		(center 288.049716 -274.049744)
		(end 288.303716 -274.049744)
		(stroke
			(width 0.1016)
			(type default)
		)
		(fill no)
		(layer "In4.Cu")
	)
	(gr_circle
		(center 288.049716 -273.099784)
		(end 288.303716 -273.099784)
		(stroke
			(width 0.1016)
			(type default)
		)
		(fill no)
		(layer "In4.Cu")
	)
	(gr_circle
		(center 288.999676 -280.699464)
		(end 289.253676 -280.699464)
		(stroke
			(width 0.1016)
			(type default)
		)
		(fill no)
		(layer "In4.Cu")
	)
	(gr_circle
		(center 288.999676 -279.749504)
		(end 289.253676 -279.749504)
		(stroke
			(width 0.1016)
			(type default)
		)
		(fill no)
		(layer "In4.Cu")
	)
	(gr_circle
		(center 288.99993 -316.799722)
		(end 289.25393 -316.799722)
		(stroke
			(width 0.1016)
			(type default)
		)
		(fill no)
		(layer "In4.Cu")
	)
	(gr_circle
		(center 288.99993 -315.849762)
		(end 289.25393 -315.849762)
		(stroke
			(width 0.1016)
			(type default)
		)
		(fill no)
		(layer "In4.Cu")
	)
	(gr_circle
		(center 288.99993 -312.049922)
		(end 289.25393 -312.049922)
		(stroke
			(width 0.1016)
			(type default)
		)
		(fill no)
		(layer "In4.Cu")
	)
	(gr_circle
		(center 288.99993 -311.099962)
		(end 289.25393 -311.099962)
		(stroke
			(width 0.1016)
			(type default)
		)
		(fill no)
		(layer "In4.Cu")
	)
	(gr_circle
		(center 288.99993 -275.949918)
		(end 289.25393 -275.949918)
		(stroke
			(width 0.1016)
			(type default)
		)
		(fill no)
		(layer "In4.Cu")
	)
	(gr_circle
		(center 288.99993 -274.999958)
		(end 289.25393 -274.999958)
		(stroke
			(width 0.1016)
			(type default)
		)
		(fill no)
		(layer "In4.Cu")
	)
	(gr_circle
		(center 289.94989 -318.699896)
		(end 290.20389 -318.699896)
		(stroke
			(width 0.1016)
			(type default)
		)
		(fill no)
		(layer "In4.Cu")
	)
	(gr_circle
		(center 289.94989 -317.749936)
		(end 290.20389 -317.749936)
		(stroke
			(width 0.1016)
			(type default)
		)
		(fill no)
		(layer "In4.Cu")
	)
	(gr_circle
		(center 289.94989 -313.949842)
		(end 290.20389 -313.949842)
		(stroke
			(width 0.1016)
			(type default)
		)
		(fill no)
		(layer "In4.Cu")
	)
	(gr_circle
		(center 289.94989 -312.999882)
		(end 290.20389 -312.999882)
		(stroke
			(width 0.1016)
			(type default)
		)
		(fill no)
		(layer "In4.Cu")
	)
	(gr_circle
		(center 289.94989 -278.799798)
		(end 290.20389 -278.799798)
		(stroke
			(width 0.1016)
			(type default)
		)
		(fill no)
		(layer "In4.Cu")
	)
	(gr_circle
		(center 289.94989 -277.849838)
		(end 290.20389 -277.849838)
		(stroke
			(width 0.1016)
			(type default)
		)
		(fill no)
		(layer "In4.Cu")
	)
	(gr_circle
		(center 289.94989 -274.049744)
		(end 290.20389 -274.049744)
		(stroke
			(width 0.1016)
			(type default)
		)
		(fill no)
		(layer "In4.Cu")
	)
	(gr_circle
		(center 289.94989 -273.099784)
		(end 290.20389 -273.099784)
		(stroke
			(width 0.1016)
			(type default)
		)
		(fill no)
		(layer "In4.Cu")
	)
	(gr_circle
		(center 290.89985 -316.799722)
		(end 291.15385 -316.799722)
		(stroke
			(width 0.1016)
			(type default)
		)
		(fill no)
		(layer "In4.Cu")
	)
	(gr_circle
		(center 290.89985 -315.849762)
		(end 291.15385 -315.849762)
		(stroke
			(width 0.1016)
			(type default)
		)
		(fill no)
		(layer "In4.Cu")
	)
	(gr_circle
		(center 290.89985 -312.049922)
		(end 291.15385 -312.049922)
		(stroke
			(width 0.1016)
			(type default)
		)
		(fill no)
		(layer "In4.Cu")
	)
	(gr_circle
		(center 290.89985 -311.099962)
		(end 291.15385 -311.099962)
		(stroke
			(width 0.1016)
			(type default)
		)
		(fill no)
		(layer "In4.Cu")
	)
	(gr_circle
		(center 290.89985 -280.699464)
		(end 291.15385 -280.699464)
		(stroke
			(width 0.1016)
			(type default)
		)
		(fill no)
		(layer "In4.Cu")
	)
	(gr_circle
		(center 290.89985 -279.749504)
		(end 291.15385 -279.749504)
		(stroke
			(width 0.1016)
			(type default)
		)
		(fill no)
		(layer "In4.Cu")
	)
	(gr_circle
		(center 290.89985 -275.949918)
		(end 291.15385 -275.949918)
		(stroke
			(width 0.1016)
			(type default)
		)
		(fill no)
		(layer "In4.Cu")
	)
	(gr_circle
		(center 290.89985 -274.999958)
		(end 291.15385 -274.999958)
		(stroke
			(width 0.1016)
			(type default)
		)
		(fill no)
		(layer "In4.Cu")
	)
	(gr_circle
		(center 291.849556 -278.799798)
		(end 292.103556 -278.799798)
		(stroke
			(width 0.1016)
			(type default)
		)
		(fill no)
		(layer "In4.Cu")
	)
	(gr_circle
		(center 291.849556 -277.849838)
		(end 292.103556 -277.849838)
		(stroke
			(width 0.1016)
			(type default)
		)
		(fill no)
		(layer "In4.Cu")
	)
	(gr_circle
		(center 291.849556 -274.04949)
		(end 292.103556 -274.04949)
		(stroke
			(width 0.1016)
			(type default)
		)
		(fill no)
		(layer "In4.Cu")
	)
	(gr_circle
		(center 291.849556 -273.09953)
		(end 292.103556 -273.09953)
		(stroke
			(width 0.1016)
			(type default)
		)
		(fill no)
		(layer "In4.Cu")
	)
	(gr_circle
		(center 291.84981 -318.699896)
		(end 292.10381 -318.699896)
		(stroke
			(width 0.1016)
			(type default)
		)
		(fill no)
		(layer "In4.Cu")
	)
	(gr_circle
		(center 291.84981 -317.749936)
		(end 292.10381 -317.749936)
		(stroke
			(width 0.1016)
			(type default)
		)
		(fill no)
		(layer "In4.Cu")
	)
	(gr_circle
		(center 291.84981 -313.949842)
		(end 292.10381 -313.949842)
		(stroke
			(width 0.1016)
			(type default)
		)
		(fill no)
		(layer "In4.Cu")
	)
	(gr_circle
		(center 291.84981 -312.999882)
		(end 292.10381 -312.999882)
		(stroke
			(width 0.1016)
			(type default)
		)
		(fill no)
		(layer "In4.Cu")
	)
	(gr_circle
		(center 292.799516 -275.949664)
		(end 293.053516 -275.949664)
		(stroke
			(width 0.1016)
			(type default)
		)
		(fill no)
		(layer "In4.Cu")
	)
	(gr_circle
		(center 292.799516 -274.999704)
		(end 293.053516 -274.999704)
		(stroke
			(width 0.1016)
			(type default)
		)
		(fill no)
		(layer "In4.Cu")
	)
	(gr_circle
		(center 292.79977 -316.799722)
		(end 293.05377 -316.799722)
		(stroke
			(width 0.1016)
			(type default)
		)
		(fill no)
		(layer "In4.Cu")
	)
	(gr_circle
		(center 292.79977 -315.849762)
		(end 293.05377 -315.849762)
		(stroke
			(width 0.1016)
			(type default)
		)
		(fill no)
		(layer "In4.Cu")
	)
	(gr_circle
		(center 292.79977 -312.049922)
		(end 293.05377 -312.049922)
		(stroke
			(width 0.1016)
			(type default)
		)
		(fill no)
		(layer "In4.Cu")
	)
	(gr_circle
		(center 292.79977 -311.099962)
		(end 293.05377 -311.099962)
		(stroke
			(width 0.1016)
			(type default)
		)
		(fill no)
		(layer "In4.Cu")
	)
	(gr_circle
		(center 292.79977 -280.699464)
		(end 293.05377 -280.699464)
		(stroke
			(width 0.1016)
			(type default)
		)
		(fill no)
		(layer "In4.Cu")
	)
	(gr_circle
		(center 292.79977 -279.749504)
		(end 293.05377 -279.749504)
		(stroke
			(width 0.1016)
			(type default)
		)
		(fill no)
		(layer "In4.Cu")
	)
	(gr_circle
		(center 293.749476 -278.799798)
		(end 294.003476 -278.799798)
		(stroke
			(width 0.1016)
			(type default)
		)
		(fill no)
		(layer "In4.Cu")
	)
	(gr_circle
		(center 293.749476 -277.849838)
		(end 294.003476 -277.849838)
		(stroke
			(width 0.1016)
			(type default)
		)
		(fill no)
		(layer "In4.Cu")
	)
	(gr_circle
		(center 293.749476 -274.049744)
		(end 294.003476 -274.049744)
		(stroke
			(width 0.1016)
			(type default)
		)
		(fill no)
		(layer "In4.Cu")
	)
	(gr_circle
		(center 293.749476 -273.099784)
		(end 294.003476 -273.099784)
		(stroke
			(width 0.1016)
			(type default)
		)
		(fill no)
		(layer "In4.Cu")
	)
	(gr_circle
		(center 293.74973 -318.699896)
		(end 294.00373 -318.699896)
		(stroke
			(width 0.1016)
			(type default)
		)
		(fill no)
		(layer "In4.Cu")
	)
	(gr_circle
		(center 293.74973 -317.749936)
		(end 294.00373 -317.749936)
		(stroke
			(width 0.1016)
			(type default)
		)
		(fill no)
		(layer "In4.Cu")
	)
	(gr_circle
		(center 293.74973 -313.949842)
		(end 294.00373 -313.949842)
		(stroke
			(width 0.1016)
			(type default)
		)
		(fill no)
		(layer "In4.Cu")
	)
	(gr_circle
		(center 293.74973 -312.999882)
		(end 294.00373 -312.999882)
		(stroke
			(width 0.1016)
			(type default)
		)
		(fill no)
		(layer "In4.Cu")
	)
	(gr_circle
		(center 294.699436 -275.949918)
		(end 294.953436 -275.949918)
		(stroke
			(width 0.1016)
			(type default)
		)
		(fill no)
		(layer "In4.Cu")
	)
	(gr_circle
		(center 294.699436 -274.999958)
		(end 294.953436 -274.999958)
		(stroke
			(width 0.1016)
			(type default)
		)
		(fill no)
		(layer "In4.Cu")
	)
	(gr_circle
		(center 294.69969 -316.799722)
		(end 294.95369 -316.799722)
		(stroke
			(width 0.1016)
			(type default)
		)
		(fill no)
		(layer "In4.Cu")
	)
	(gr_circle
		(center 294.69969 -315.849762)
		(end 294.95369 -315.849762)
		(stroke
			(width 0.1016)
			(type default)
		)
		(fill no)
		(layer "In4.Cu")
	)
	(gr_circle
		(center 294.69969 -312.049922)
		(end 294.95369 -312.049922)
		(stroke
			(width 0.1016)
			(type default)
		)
		(fill no)
		(layer "In4.Cu")
	)
	(gr_circle
		(center 294.69969 -311.099962)
		(end 294.95369 -311.099962)
		(stroke
			(width 0.1016)
			(type default)
		)
		(fill no)
		(layer "In4.Cu")
	)
	(gr_circle
		(center 294.69969 -280.699464)
		(end 294.95369 -280.699464)
		(stroke
			(width 0.1016)
			(type default)
		)
		(fill no)
		(layer "In4.Cu")
	)
	(gr_circle
		(center 294.69969 -279.749504)
		(end 294.95369 -279.749504)
		(stroke
			(width 0.1016)
			(type default)
		)
		(fill no)
		(layer "In4.Cu")
	)
	(gr_circle
		(center 295.64965 -278.799798)
		(end 295.90365 -278.799798)
		(stroke
			(width 0.1016)
			(type default)
		)
		(fill no)
		(layer "In4.Cu")
	)
	(gr_circle
		(center 295.64965 -277.849838)
		(end 295.90365 -277.849838)
		(stroke
			(width 0.1016)
			(type default)
		)
		(fill no)
		(layer "In4.Cu")
	)
	(gr_circle
		(center 295.64965 -274.049744)
		(end 295.90365 -274.049744)
		(stroke
			(width 0.1016)
			(type default)
		)
		(fill no)
		(layer "In4.Cu")
	)
	(gr_circle
		(center 295.64965 -273.099784)
		(end 295.90365 -273.099784)
		(stroke
			(width 0.1016)
			(type default)
		)
		(fill no)
		(layer "In4.Cu")
	)
	(gr_circle
		(center 295.649904 -318.699896)
		(end 295.903904 -318.699896)
		(stroke
			(width 0.1016)
			(type default)
		)
		(fill no)
		(layer "In4.Cu")
	)
	(gr_circle
		(center 295.649904 -317.749936)
		(end 295.903904 -317.749936)
		(stroke
			(width 0.1016)
			(type default)
		)
		(fill no)
		(layer "In4.Cu")
	)
	(gr_circle
		(center 295.649904 -313.949842)
		(end 295.903904 -313.949842)
		(stroke
			(width 0.1016)
			(type default)
		)
		(fill no)
		(layer "In4.Cu")
	)
	(gr_circle
		(center 295.649904 -312.999882)
		(end 295.903904 -312.999882)
		(stroke
			(width 0.1016)
			(type default)
		)
		(fill no)
		(layer "In4.Cu")
	)
	(gr_circle
		(center 296.59961 -275.949664)
		(end 296.85361 -275.949664)
		(stroke
			(width 0.1016)
			(type default)
		)
		(fill no)
		(layer "In4.Cu")
	)
	(gr_circle
		(center 296.59961 -274.999704)
		(end 296.85361 -274.999704)
		(stroke
			(width 0.1016)
			(type default)
		)
		(fill no)
		(layer "In4.Cu")
	)
	(gr_circle
		(center 296.599864 -316.799722)
		(end 296.853864 -316.799722)
		(stroke
			(width 0.1016)
			(type default)
		)
		(fill no)
		(layer "In4.Cu")
	)
	(gr_circle
		(center 296.599864 -315.849762)
		(end 296.853864 -315.849762)
		(stroke
			(width 0.1016)
			(type default)
		)
		(fill no)
		(layer "In4.Cu")
	)
	(gr_circle
		(center 296.599864 -312.049922)
		(end 296.853864 -312.049922)
		(stroke
			(width 0.1016)
			(type default)
		)
		(fill no)
		(layer "In4.Cu")
	)
	(gr_circle
		(center 296.599864 -311.099962)
		(end 296.853864 -311.099962)
		(stroke
			(width 0.1016)
			(type default)
		)
		(fill no)
		(layer "In4.Cu")
	)
	(gr_circle
		(center 296.599864 -280.699464)
		(end 296.853864 -280.699464)
		(stroke
			(width 0.1016)
			(type default)
		)
		(fill no)
		(layer "In4.Cu")
	)
	(gr_circle
		(center 296.599864 -279.749504)
		(end 296.853864 -279.749504)
		(stroke
			(width 0.1016)
			(type default)
		)
		(fill no)
		(layer "In4.Cu")
	)
	(gr_circle
		(center 297.54957 -278.799798)
		(end 297.80357 -278.799798)
		(stroke
			(width 0.1016)
			(type default)
		)
		(fill no)
		(layer "In4.Cu")
	)
	(gr_circle
		(center 297.54957 -277.849838)
		(end 297.80357 -277.849838)
		(stroke
			(width 0.1016)
			(type default)
		)
		(fill no)
		(layer "In4.Cu")
	)
	(gr_circle
		(center 297.54957 -274.049744)
		(end 297.80357 -274.049744)
		(stroke
			(width 0.1016)
			(type default)
		)
		(fill no)
		(layer "In4.Cu")
	)
	(gr_circle
		(center 297.54957 -273.099784)
		(end 297.80357 -273.099784)
		(stroke
			(width 0.1016)
			(type default)
		)
		(fill no)
		(layer "In4.Cu")
	)
	(gr_circle
		(center 297.549824 -318.699896)
		(end 297.803824 -318.699896)
		(stroke
			(width 0.1016)
			(type default)
		)
		(fill no)
		(layer "In4.Cu")
	)
	(gr_circle
		(center 297.549824 -317.749936)
		(end 297.803824 -317.749936)
		(stroke
			(width 0.1016)
			(type default)
		)
		(fill no)
		(layer "In4.Cu")
	)
	(gr_circle
		(center 297.549824 -313.949842)
		(end 297.803824 -313.949842)
		(stroke
			(width 0.1016)
			(type default)
		)
		(fill no)
		(layer "In4.Cu")
	)
	(gr_circle
		(center 297.549824 -312.999882)
		(end 297.803824 -312.999882)
		(stroke
			(width 0.1016)
			(type default)
		)
		(fill no)
		(layer "In4.Cu")
	)
	(gr_circle
		(center 298.49953 -275.949918)
		(end 298.75353 -275.949918)
		(stroke
			(width 0.1016)
			(type default)
		)
		(fill no)
		(layer "In4.Cu")
	)
	(gr_circle
		(center 298.49953 -274.999958)
		(end 298.75353 -274.999958)
		(stroke
			(width 0.1016)
			(type default)
		)
		(fill no)
		(layer "In4.Cu")
	)
	(gr_circle
		(center 298.499784 -316.799722)
		(end 298.753784 -316.799722)
		(stroke
			(width 0.1016)
			(type default)
		)
		(fill no)
		(layer "In4.Cu")
	)
	(gr_circle
		(center 298.499784 -315.849762)
		(end 298.753784 -315.849762)
		(stroke
			(width 0.1016)
			(type default)
		)
		(fill no)
		(layer "In4.Cu")
	)
	(gr_circle
		(center 298.499784 -312.049922)
		(end 298.753784 -312.049922)
		(stroke
			(width 0.1016)
			(type default)
		)
		(fill no)
		(layer "In4.Cu")
	)
	(gr_circle
		(center 298.499784 -311.099962)
		(end 298.753784 -311.099962)
		(stroke
			(width 0.1016)
			(type default)
		)
		(fill no)
		(layer "In4.Cu")
	)
	(gr_circle
		(center 298.499784 -280.699464)
		(end 298.753784 -280.699464)
		(stroke
			(width 0.1016)
			(type default)
		)
		(fill no)
		(layer "In4.Cu")
	)
	(gr_circle
		(center 298.499784 -279.749504)
		(end 298.753784 -279.749504)
		(stroke
			(width 0.1016)
			(type default)
		)
		(fill no)
		(layer "In4.Cu")
	)
	(gr_circle
		(center 299.44949 -278.799798)
		(end 299.70349 -278.799798)
		(stroke
			(width 0.1016)
			(type default)
		)
		(fill no)
		(layer "In4.Cu")
	)
	(gr_circle
		(center 299.44949 -277.849838)
		(end 299.70349 -277.849838)
		(stroke
			(width 0.1016)
			(type default)
		)
		(fill no)
		(layer "In4.Cu")
	)
	(gr_circle
		(center 299.44949 -274.049744)
		(end 299.70349 -274.049744)
		(stroke
			(width 0.1016)
			(type default)
		)
		(fill no)
		(layer "In4.Cu")
	)
	(gr_circle
		(center 299.44949 -273.099784)
		(end 299.70349 -273.099784)
		(stroke
			(width 0.1016)
			(type default)
		)
		(fill no)
		(layer "In4.Cu")
	)
	(gr_circle
		(center 299.449744 -318.699896)
		(end 299.703744 -318.699896)
		(stroke
			(width 0.1016)
			(type default)
		)
		(fill no)
		(layer "In4.Cu")
	)
	(gr_circle
		(center 299.449744 -317.749936)
		(end 299.703744 -317.749936)
		(stroke
			(width 0.1016)
			(type default)
		)
		(fill no)
		(layer "In4.Cu")
	)
	(gr_circle
		(center 299.449744 -313.949842)
		(end 299.703744 -313.949842)
		(stroke
			(width 0.1016)
			(type default)
		)
		(fill no)
		(layer "In4.Cu")
	)
	(gr_circle
		(center 299.449744 -312.999882)
		(end 299.703744 -312.999882)
		(stroke
			(width 0.1016)
			(type default)
		)
		(fill no)
		(layer "In4.Cu")
	)
	(gr_circle
		(center 300.39945 -275.949664)
		(end 300.65345 -275.949664)
		(stroke
			(width 0.1016)
			(type default)
		)
		(fill no)
		(layer "In4.Cu")
	)
	(gr_circle
		(center 300.39945 -274.999704)
		(end 300.65345 -274.999704)
		(stroke
			(width 0.1016)
			(type default)
		)
		(fill no)
		(layer "In4.Cu")
	)
	(gr_circle
		(center 300.399704 -316.799722)
		(end 300.653704 -316.799722)
		(stroke
			(width 0.1016)
			(type default)
		)
		(fill no)
		(layer "In4.Cu")
	)
	(gr_circle
		(center 300.399704 -315.849762)
		(end 300.653704 -315.849762)
		(stroke
			(width 0.1016)
			(type default)
		)
		(fill no)
		(layer "In4.Cu")
	)
	(gr_circle
		(center 300.399704 -312.049922)
		(end 300.653704 -312.049922)
		(stroke
			(width 0.1016)
			(type default)
		)
		(fill no)
		(layer "In4.Cu")
	)
	(gr_circle
		(center 300.399704 -311.099962)
		(end 300.653704 -311.099962)
		(stroke
			(width 0.1016)
			(type default)
		)
		(fill no)
		(layer "In4.Cu")
	)
	(gr_circle
		(center 300.399704 -280.699464)
		(end 300.653704 -280.699464)
		(stroke
			(width 0.1016)
			(type default)
		)
		(fill no)
		(layer "In4.Cu")
	)
	(gr_circle
		(center 300.399704 -279.749504)
		(end 300.653704 -279.749504)
		(stroke
			(width 0.1016)
			(type default)
		)
		(fill no)
		(layer "In4.Cu")
	)
	(gr_circle
		(center 301.349664 -278.799798)
		(end 301.603664 -278.799798)
		(stroke
			(width 0.1016)
			(type default)
		)
		(fill no)
		(layer "In4.Cu")
	)
	(gr_circle
		(center 301.349664 -277.849838)
		(end 301.603664 -277.849838)
		(stroke
			(width 0.1016)
			(type default)
		)
		(fill no)
		(layer "In4.Cu")
	)
	(gr_circle
		(center 301.349664 -274.049744)
		(end 301.603664 -274.049744)
		(stroke
			(width 0.1016)
			(type default)
		)
		(fill no)
		(layer "In4.Cu")
	)
	(gr_circle
		(center 301.349664 -273.099784)
		(end 301.603664 -273.099784)
		(stroke
			(width 0.1016)
			(type default)
		)
		(fill no)
		(layer "In4.Cu")
	)
	(gr_circle
		(center 301.349918 -318.699896)
		(end 301.603918 -318.699896)
		(stroke
			(width 0.1016)
			(type default)
		)
		(fill no)
		(layer "In4.Cu")
	)
	(gr_circle
		(center 301.349918 -317.749936)
		(end 301.603918 -317.749936)
		(stroke
			(width 0.1016)
			(type default)
		)
		(fill no)
		(layer "In4.Cu")
	)
	(gr_circle
		(center 301.349918 -313.949842)
		(end 301.603918 -313.949842)
		(stroke
			(width 0.1016)
			(type default)
		)
		(fill no)
		(layer "In4.Cu")
	)
	(gr_circle
		(center 301.349918 -312.999882)
		(end 301.603918 -312.999882)
		(stroke
			(width 0.1016)
			(type default)
		)
		(fill no)
		(layer "In4.Cu")
	)
	(gr_circle
		(center 302.29937 -275.949918)
		(end 302.55337 -275.949918)
		(stroke
			(width 0.1016)
			(type default)
		)
		(fill no)
		(layer "In4.Cu")
	)
	(gr_circle
		(center 302.29937 -274.999958)
		(end 302.55337 -274.999958)
		(stroke
			(width 0.1016)
			(type default)
		)
		(fill no)
		(layer "In4.Cu")
	)
	(gr_circle
		(center 302.299878 -316.799722)
		(end 302.553878 -316.799722)
		(stroke
			(width 0.1016)
			(type default)
		)
		(fill no)
		(layer "In4.Cu")
	)
	(gr_circle
		(center 302.299878 -315.849762)
		(end 302.553878 -315.849762)
		(stroke
			(width 0.1016)
			(type default)
		)
		(fill no)
		(layer "In4.Cu")
	)
	(gr_circle
		(center 302.299878 -312.049922)
		(end 302.553878 -312.049922)
		(stroke
			(width 0.1016)
			(type default)
		)
		(fill no)
		(layer "In4.Cu")
	)
	(gr_circle
		(center 302.299878 -311.099962)
		(end 302.553878 -311.099962)
		(stroke
			(width 0.1016)
			(type default)
		)
		(fill no)
		(layer "In4.Cu")
	)
	(gr_circle
		(center 302.299878 -280.699464)
		(end 302.553878 -280.699464)
		(stroke
			(width 0.1016)
			(type default)
		)
		(fill no)
		(layer "In4.Cu")
	)
	(gr_circle
		(center 302.299878 -279.749504)
		(end 302.553878 -279.749504)
		(stroke
			(width 0.1016)
			(type default)
		)
		(fill no)
		(layer "In4.Cu")
	)
	(gr_circle
		(center 303.249584 -278.799798)
		(end 303.503584 -278.799798)
		(stroke
			(width 0.1016)
			(type default)
		)
		(fill no)
		(layer "In4.Cu")
	)
	(gr_circle
		(center 303.249584 -277.849838)
		(end 303.503584 -277.849838)
		(stroke
			(width 0.1016)
			(type default)
		)
		(fill no)
		(layer "In4.Cu")
	)
	(gr_circle
		(center 303.249584 -274.049744)
		(end 303.503584 -274.049744)
		(stroke
			(width 0.1016)
			(type default)
		)
		(fill no)
		(layer "In4.Cu")
	)
	(gr_circle
		(center 303.249584 -273.099784)
		(end 303.503584 -273.099784)
		(stroke
			(width 0.1016)
			(type default)
		)
		(fill no)
		(layer "In4.Cu")
	)
	(gr_circle
		(center 303.249838 -318.699896)
		(end 303.503838 -318.699896)
		(stroke
			(width 0.1016)
			(type default)
		)
		(fill no)
		(layer "In4.Cu")
	)
	(gr_circle
		(center 303.249838 -317.749936)
		(end 303.503838 -317.749936)
		(stroke
			(width 0.1016)
			(type default)
		)
		(fill no)
		(layer "In4.Cu")
	)
	(gr_circle
		(center 303.249838 -313.949842)
		(end 303.503838 -313.949842)
		(stroke
			(width 0.1016)
			(type default)
		)
		(fill no)
		(layer "In4.Cu")
	)
	(gr_circle
		(center 303.249838 -312.999882)
		(end 303.503838 -312.999882)
		(stroke
			(width 0.1016)
			(type default)
		)
		(fill no)
		(layer "In4.Cu")
	)
	(gr_circle
		(center 304.199544 -275.949664)
		(end 304.453544 -275.949664)
		(stroke
			(width 0.1016)
			(type default)
		)
		(fill no)
		(layer "In4.Cu")
	)
	(gr_circle
		(center 304.199544 -274.999704)
		(end 304.453544 -274.999704)
		(stroke
			(width 0.1016)
			(type default)
		)
		(fill no)
		(layer "In4.Cu")
	)
	(gr_circle
		(center 304.199798 -316.799722)
		(end 304.453798 -316.799722)
		(stroke
			(width 0.1016)
			(type default)
		)
		(fill no)
		(layer "In4.Cu")
	)
	(gr_circle
		(center 304.199798 -315.849762)
		(end 304.453798 -315.849762)
		(stroke
			(width 0.1016)
			(type default)
		)
		(fill no)
		(layer "In4.Cu")
	)
	(gr_circle
		(center 304.199798 -312.049922)
		(end 304.453798 -312.049922)
		(stroke
			(width 0.1016)
			(type default)
		)
		(fill no)
		(layer "In4.Cu")
	)
	(gr_circle
		(center 304.199798 -311.099962)
		(end 304.453798 -311.099962)
		(stroke
			(width 0.1016)
			(type default)
		)
		(fill no)
		(layer "In4.Cu")
	)
	(gr_circle
		(center 304.199798 -280.699464)
		(end 304.453798 -280.699464)
		(stroke
			(width 0.1016)
			(type default)
		)
		(fill no)
		(layer "In4.Cu")
	)
	(gr_circle
		(center 304.199798 -279.749504)
		(end 304.453798 -279.749504)
		(stroke
			(width 0.1016)
			(type default)
		)
		(fill no)
		(layer "In4.Cu")
	)
	(gr_circle
		(center 305.149504 -278.799798)
		(end 305.403504 -278.799798)
		(stroke
			(width 0.1016)
			(type default)
		)
		(fill no)
		(layer "In4.Cu")
	)
	(gr_circle
		(center 305.149504 -277.849838)
		(end 305.403504 -277.849838)
		(stroke
			(width 0.1016)
			(type default)
		)
		(fill no)
		(layer "In4.Cu")
	)
	(gr_circle
		(center 305.149504 -274.049744)
		(end 305.403504 -274.049744)
		(stroke
			(width 0.1016)
			(type default)
		)
		(fill no)
		(layer "In4.Cu")
	)
	(gr_circle
		(center 305.149504 -273.099784)
		(end 305.403504 -273.099784)
		(stroke
			(width 0.1016)
			(type default)
		)
		(fill no)
		(layer "In4.Cu")
	)
	(gr_circle
		(center 305.149758 -318.699896)
		(end 305.403758 -318.699896)
		(stroke
			(width 0.1016)
			(type default)
		)
		(fill no)
		(layer "In4.Cu")
	)
	(gr_circle
		(center 305.149758 -317.749936)
		(end 305.403758 -317.749936)
		(stroke
			(width 0.1016)
			(type default)
		)
		(fill no)
		(layer "In4.Cu")
	)
	(gr_circle
		(center 305.149758 -313.949842)
		(end 305.403758 -313.949842)
		(stroke
			(width 0.1016)
			(type default)
		)
		(fill no)
		(layer "In4.Cu")
	)
	(gr_circle
		(center 305.149758 -312.999882)
		(end 305.403758 -312.999882)
		(stroke
			(width 0.1016)
			(type default)
		)
		(fill no)
		(layer "In4.Cu")
	)
	(gr_circle
		(center 306.099464 -275.949918)
		(end 306.353464 -275.949918)
		(stroke
			(width 0.1016)
			(type default)
		)
		(fill no)
		(layer "In4.Cu")
	)
	(gr_circle
		(center 306.099464 -274.999958)
		(end 306.353464 -274.999958)
		(stroke
			(width 0.1016)
			(type default)
		)
		(fill no)
		(layer "In4.Cu")
	)
	(gr_circle
		(center 306.099718 -316.799722)
		(end 306.353718 -316.799722)
		(stroke
			(width 0.1016)
			(type default)
		)
		(fill no)
		(layer "In4.Cu")
	)
	(gr_circle
		(center 306.099718 -315.849762)
		(end 306.353718 -315.849762)
		(stroke
			(width 0.1016)
			(type default)
		)
		(fill no)
		(layer "In4.Cu")
	)
	(gr_circle
		(center 306.099718 -312.049922)
		(end 306.353718 -312.049922)
		(stroke
			(width 0.1016)
			(type default)
		)
		(fill no)
		(layer "In4.Cu")
	)
	(gr_circle
		(center 306.099718 -311.099962)
		(end 306.353718 -311.099962)
		(stroke
			(width 0.1016)
			(type default)
		)
		(fill no)
		(layer "In4.Cu")
	)
	(gr_circle
		(center 306.099718 -280.699464)
		(end 306.353718 -280.699464)
		(stroke
			(width 0.1016)
			(type default)
		)
		(fill no)
		(layer "In4.Cu")
	)
	(gr_circle
		(center 306.099718 -279.749504)
		(end 306.353718 -279.749504)
		(stroke
			(width 0.1016)
			(type default)
		)
		(fill no)
		(layer "In4.Cu")
	)
	(gr_circle
		(center 307.049678 -278.799798)
		(end 307.303678 -278.799798)
		(stroke
			(width 0.1016)
			(type default)
		)
		(fill no)
		(layer "In4.Cu")
	)
	(gr_circle
		(center 307.049678 -277.849838)
		(end 307.303678 -277.849838)
		(stroke
			(width 0.1016)
			(type default)
		)
		(fill no)
		(layer "In4.Cu")
	)
	(gr_circle
		(center 307.049678 -274.049744)
		(end 307.303678 -274.049744)
		(stroke
			(width 0.1016)
			(type default)
		)
		(fill no)
		(layer "In4.Cu")
	)
	(gr_circle
		(center 307.049678 -273.099784)
		(end 307.303678 -273.099784)
		(stroke
			(width 0.1016)
			(type default)
		)
		(fill no)
		(layer "In4.Cu")
	)
	(gr_circle
		(center 307.049932 -318.699896)
		(end 307.303932 -318.699896)
		(stroke
			(width 0.1016)
			(type default)
		)
		(fill no)
		(layer "In4.Cu")
	)
	(gr_circle
		(center 307.049932 -317.749936)
		(end 307.303932 -317.749936)
		(stroke
			(width 0.1016)
			(type default)
		)
		(fill no)
		(layer "In4.Cu")
	)
	(gr_circle
		(center 307.049932 -313.949842)
		(end 307.303932 -313.949842)
		(stroke
			(width 0.1016)
			(type default)
		)
		(fill no)
		(layer "In4.Cu")
	)
	(gr_circle
		(center 307.049932 -312.999882)
		(end 307.303932 -312.999882)
		(stroke
			(width 0.1016)
			(type default)
		)
		(fill no)
		(layer "In4.Cu")
	)
	(gr_circle
		(center 307.049932 -308.249828)
		(end 307.303932 -308.249828)
		(stroke
			(width 0.1016)
			(type default)
		)
		(fill no)
		(layer "In4.Cu")
	)
	(gr_circle
		(center 307.049932 -306.349908)
		(end 307.303932 -306.349908)
		(stroke
			(width 0.1016)
			(type default)
		)
		(fill no)
		(layer "In4.Cu")
	)
	(gr_circle
		(center 307.049932 -304.449734)
		(end 307.303932 -304.449734)
		(stroke
			(width 0.1016)
			(type default)
		)
		(fill no)
		(layer "In4.Cu")
	)
	(gr_circle
		(center 307.049932 -287.349946)
		(end 307.303932 -287.349946)
		(stroke
			(width 0.1016)
			(type default)
		)
		(fill no)
		(layer "In4.Cu")
	)
	(gr_circle
		(center 307.049932 -285.449772)
		(end 307.303932 -285.449772)
		(stroke
			(width 0.1016)
			(type default)
		)
		(fill no)
		(layer "In4.Cu")
	)
	(gr_circle
		(center 307.049932 -283.549852)
		(end 307.303932 -283.549852)
		(stroke
			(width 0.1016)
			(type default)
		)
		(fill no)
		(layer "In4.Cu")
	)
	(gr_circle
		(center 307.999638 -275.949664)
		(end 308.253638 -275.949664)
		(stroke
			(width 0.1016)
			(type default)
		)
		(fill no)
		(layer "In4.Cu")
	)
	(gr_circle
		(center 307.999638 -274.999704)
		(end 308.253638 -274.999704)
		(stroke
			(width 0.1016)
			(type default)
		)
		(fill no)
		(layer "In4.Cu")
	)
	(gr_circle
		(center 307.999892 -316.799722)
		(end 308.253892 -316.799722)
		(stroke
			(width 0.1016)
			(type default)
		)
		(fill no)
		(layer "In4.Cu")
	)
	(gr_circle
		(center 307.999892 -315.849762)
		(end 308.253892 -315.849762)
		(stroke
			(width 0.1016)
			(type default)
		)
		(fill no)
		(layer "In4.Cu")
	)
	(gr_circle
		(center 307.999892 -312.049922)
		(end 308.253892 -312.049922)
		(stroke
			(width 0.1016)
			(type default)
		)
		(fill no)
		(layer "In4.Cu")
	)
	(gr_circle
		(center 307.999892 -311.099962)
		(end 308.253892 -311.099962)
		(stroke
			(width 0.1016)
			(type default)
		)
		(fill no)
		(layer "In4.Cu")
	)
	(gr_circle
		(center 307.999892 -308.249828)
		(end 308.253892 -308.249828)
		(stroke
			(width 0.1016)
			(type default)
		)
		(fill no)
		(layer "In4.Cu")
	)
	(gr_circle
		(center 307.999892 -306.349908)
		(end 308.253892 -306.349908)
		(stroke
			(width 0.1016)
			(type default)
		)
		(fill no)
		(layer "In4.Cu")
	)
	(gr_circle
		(center 307.999892 -304.449734)
		(end 308.253892 -304.449734)
		(stroke
			(width 0.1016)
			(type default)
		)
		(fill no)
		(layer "In4.Cu")
	)
	(gr_circle
		(center 307.999892 -287.349946)
		(end 308.253892 -287.349946)
		(stroke
			(width 0.1016)
			(type default)
		)
		(fill no)
		(layer "In4.Cu")
	)
	(gr_circle
		(center 307.999892 -285.449772)
		(end 308.253892 -285.449772)
		(stroke
			(width 0.1016)
			(type default)
		)
		(fill no)
		(layer "In4.Cu")
	)
	(gr_circle
		(center 307.999892 -283.549852)
		(end 308.253892 -283.549852)
		(stroke
			(width 0.1016)
			(type default)
		)
		(fill no)
		(layer "In4.Cu")
	)
	(gr_circle
		(center 307.999892 -280.699464)
		(end 308.253892 -280.699464)
		(stroke
			(width 0.1016)
			(type default)
		)
		(fill no)
		(layer "In4.Cu")
	)
	(gr_circle
		(center 307.999892 -279.749504)
		(end 308.253892 -279.749504)
		(stroke
			(width 0.1016)
			(type default)
		)
		(fill no)
		(layer "In4.Cu")
	)
	(gr_circle
		(center 308.949598 -278.799798)
		(end 309.203598 -278.799798)
		(stroke
			(width 0.1016)
			(type default)
		)
		(fill no)
		(layer "In4.Cu")
	)
	(gr_circle
		(center 308.949598 -277.849838)
		(end 309.203598 -277.849838)
		(stroke
			(width 0.1016)
			(type default)
		)
		(fill no)
		(layer "In4.Cu")
	)
	(gr_circle
		(center 308.949598 -274.049744)
		(end 309.203598 -274.049744)
		(stroke
			(width 0.1016)
			(type default)
		)
		(fill no)
		(layer "In4.Cu")
	)
	(gr_circle
		(center 308.949598 -273.099784)
		(end 309.203598 -273.099784)
		(stroke
			(width 0.1016)
			(type default)
		)
		(fill no)
		(layer "In4.Cu")
	)
	(gr_circle
		(center 308.949852 -318.699896)
		(end 309.203852 -318.699896)
		(stroke
			(width 0.1016)
			(type default)
		)
		(fill no)
		(layer "In4.Cu")
	)
	(gr_circle
		(center 308.949852 -317.749936)
		(end 309.203852 -317.749936)
		(stroke
			(width 0.1016)
			(type default)
		)
		(fill no)
		(layer "In4.Cu")
	)
	(gr_circle
		(center 308.949852 -313.949842)
		(end 309.203852 -313.949842)
		(stroke
			(width 0.1016)
			(type default)
		)
		(fill no)
		(layer "In4.Cu")
	)
	(gr_circle
		(center 308.949852 -312.999882)
		(end 309.203852 -312.999882)
		(stroke
			(width 0.1016)
			(type default)
		)
		(fill no)
		(layer "In4.Cu")
	)
	(gr_circle
		(center 308.949852 -309.199788)
		(end 309.203852 -309.199788)
		(stroke
			(width 0.1016)
			(type default)
		)
		(fill no)
		(layer "In4.Cu")
	)
	(gr_circle
		(center 308.949852 -307.299868)
		(end 309.203852 -307.299868)
		(stroke
			(width 0.1016)
			(type default)
		)
		(fill no)
		(layer "In4.Cu")
	)
	(gr_circle
		(center 308.949852 -305.399948)
		(end 309.203852 -305.399948)
		(stroke
			(width 0.1016)
			(type default)
		)
		(fill no)
		(layer "In4.Cu")
	)
	(gr_circle
		(center 308.949852 -288.299906)
		(end 309.203852 -288.299906)
		(stroke
			(width 0.1016)
			(type default)
		)
		(fill no)
		(layer "In4.Cu")
	)
	(gr_circle
		(center 308.949852 -286.399986)
		(end 309.203852 -286.399986)
		(stroke
			(width 0.1016)
			(type default)
		)
		(fill no)
		(layer "In4.Cu")
	)
	(gr_circle
		(center 308.949852 -284.499812)
		(end 309.203852 -284.499812)
		(stroke
			(width 0.1016)
			(type default)
		)
		(fill no)
		(layer "In4.Cu")
	)
	(gr_circle
		(center 308.949852 -282.599892)
		(end 309.203852 -282.599892)
		(stroke
			(width 0.1016)
			(type default)
		)
		(fill no)
		(layer "In4.Cu")
	)
	(gr_circle
		(center 309.899558 -275.949918)
		(end 310.153558 -275.949918)
		(stroke
			(width 0.1016)
			(type default)
		)
		(fill no)
		(layer "In4.Cu")
	)
	(gr_circle
		(center 309.899558 -274.999958)
		(end 310.153558 -274.999958)
		(stroke
			(width 0.1016)
			(type default)
		)
		(fill no)
		(layer "In4.Cu")
	)
	(gr_circle
		(center 309.899812 -316.799722)
		(end 310.153812 -316.799722)
		(stroke
			(width 0.1016)
			(type default)
		)
		(fill no)
		(layer "In4.Cu")
	)
	(gr_circle
		(center 309.899812 -315.849762)
		(end 310.153812 -315.849762)
		(stroke
			(width 0.1016)
			(type default)
		)
		(fill no)
		(layer "In4.Cu")
	)
	(gr_circle
		(center 309.899812 -312.049922)
		(end 310.153812 -312.049922)
		(stroke
			(width 0.1016)
			(type default)
		)
		(fill no)
		(layer "In4.Cu")
	)
	(gr_circle
		(center 309.899812 -311.099962)
		(end 310.153812 -311.099962)
		(stroke
			(width 0.1016)
			(type default)
		)
		(fill no)
		(layer "In4.Cu")
	)
	(gr_circle
		(center 309.899812 -309.199788)
		(end 310.153812 -309.199788)
		(stroke
			(width 0.1016)
			(type default)
		)
		(fill no)
		(layer "In4.Cu")
	)
	(gr_circle
		(center 309.899812 -307.299868)
		(end 310.153812 -307.299868)
		(stroke
			(width 0.1016)
			(type default)
		)
		(fill no)
		(layer "In4.Cu")
	)
	(gr_circle
		(center 309.899812 -305.399948)
		(end 310.153812 -305.399948)
		(stroke
			(width 0.1016)
			(type default)
		)
		(fill no)
		(layer "In4.Cu")
	)
	(gr_circle
		(center 309.899812 -288.299906)
		(end 310.153812 -288.299906)
		(stroke
			(width 0.1016)
			(type default)
		)
		(fill no)
		(layer "In4.Cu")
	)
	(gr_circle
		(center 309.899812 -286.399986)
		(end 310.153812 -286.399986)
		(stroke
			(width 0.1016)
			(type default)
		)
		(fill no)
		(layer "In4.Cu")
	)
	(gr_circle
		(center 309.899812 -284.499812)
		(end 310.153812 -284.499812)
		(stroke
			(width 0.1016)
			(type default)
		)
		(fill no)
		(layer "In4.Cu")
	)
	(gr_circle
		(center 309.899812 -282.599892)
		(end 310.153812 -282.599892)
		(stroke
			(width 0.1016)
			(type default)
		)
		(fill no)
		(layer "In4.Cu")
	)
	(gr_circle
		(center 309.899812 -280.699464)
		(end 310.153812 -280.699464)
		(stroke
			(width 0.1016)
			(type default)
		)
		(fill no)
		(layer "In4.Cu")
	)
	(gr_circle
		(center 309.899812 -279.749504)
		(end 310.153812 -279.749504)
		(stroke
			(width 0.1016)
			(type default)
		)
		(fill no)
		(layer "In4.Cu")
	)
	(gr_circle
		(center 310.849518 -278.799798)
		(end 311.103518 -278.799798)
		(stroke
			(width 0.1016)
			(type default)
		)
		(fill no)
		(layer "In4.Cu")
	)
	(gr_circle
		(center 310.849518 -277.849838)
		(end 311.103518 -277.849838)
		(stroke
			(width 0.1016)
			(type default)
		)
		(fill no)
		(layer "In4.Cu")
	)
	(gr_circle
		(center 310.849518 -274.049744)
		(end 311.103518 -274.049744)
		(stroke
			(width 0.1016)
			(type default)
		)
		(fill no)
		(layer "In4.Cu")
	)
	(gr_circle
		(center 310.849518 -273.099784)
		(end 311.103518 -273.099784)
		(stroke
			(width 0.1016)
			(type default)
		)
		(fill no)
		(layer "In4.Cu")
	)
	(gr_circle
		(center 310.849772 -318.699896)
		(end 311.103772 -318.699896)
		(stroke
			(width 0.1016)
			(type default)
		)
		(fill no)
		(layer "In4.Cu")
	)
	(gr_circle
		(center 310.849772 -317.749936)
		(end 311.103772 -317.749936)
		(stroke
			(width 0.1016)
			(type default)
		)
		(fill no)
		(layer "In4.Cu")
	)
	(gr_circle
		(center 310.849772 -313.949842)
		(end 311.103772 -313.949842)
		(stroke
			(width 0.1016)
			(type default)
		)
		(fill no)
		(layer "In4.Cu")
	)
	(gr_circle
		(center 310.849772 -312.999882)
		(end 311.103772 -312.999882)
		(stroke
			(width 0.1016)
			(type default)
		)
		(fill no)
		(layer "In4.Cu")
	)
	(gr_circle
		(center 311.799478 -275.949918)
		(end 312.053478 -275.949918)
		(stroke
			(width 0.1016)
			(type default)
		)
		(fill no)
		(layer "In4.Cu")
	)
	(gr_circle
		(center 311.799478 -274.999958)
		(end 312.053478 -274.999958)
		(stroke
			(width 0.1016)
			(type default)
		)
		(fill no)
		(layer "In4.Cu")
	)
	(gr_circle
		(center 311.799732 -316.799722)
		(end 312.053732 -316.799722)
		(stroke
			(width 0.1016)
			(type default)
		)
		(fill no)
		(layer "In4.Cu")
	)
	(gr_circle
		(center 311.799732 -315.849762)
		(end 312.053732 -315.849762)
		(stroke
			(width 0.1016)
			(type default)
		)
		(fill no)
		(layer "In4.Cu")
	)
	(gr_circle
		(center 311.799732 -312.049922)
		(end 312.053732 -312.049922)
		(stroke
			(width 0.1016)
			(type default)
		)
		(fill no)
		(layer "In4.Cu")
	)
	(gr_circle
		(center 311.799732 -311.099962)
		(end 312.053732 -311.099962)
		(stroke
			(width 0.1016)
			(type default)
		)
		(fill no)
		(layer "In4.Cu")
	)
	(gr_circle
		(center 311.799732 -309.199788)
		(end 312.053732 -309.199788)
		(stroke
			(width 0.1016)
			(type default)
		)
		(fill no)
		(layer "In4.Cu")
	)
	(gr_circle
		(center 311.799732 -307.299868)
		(end 312.053732 -307.299868)
		(stroke
			(width 0.1016)
			(type default)
		)
		(fill no)
		(layer "In4.Cu")
	)
	(gr_circle
		(center 311.799732 -305.399948)
		(end 312.053732 -305.399948)
		(stroke
			(width 0.1016)
			(type default)
		)
		(fill no)
		(layer "In4.Cu")
	)
	(gr_circle
		(center 311.799732 -288.299906)
		(end 312.053732 -288.299906)
		(stroke
			(width 0.1016)
			(type default)
		)
		(fill no)
		(layer "In4.Cu")
	)
	(gr_circle
		(center 311.799732 -286.399732)
		(end 312.053732 -286.399732)
		(stroke
			(width 0.1016)
			(type default)
		)
		(fill no)
		(layer "In4.Cu")
	)
	(gr_circle
		(center 311.799732 -284.499812)
		(end 312.053732 -284.499812)
		(stroke
			(width 0.1016)
			(type default)
		)
		(fill no)
		(layer "In4.Cu")
	)
	(gr_circle
		(center 311.799732 -282.599892)
		(end 312.053732 -282.599892)
		(stroke
			(width 0.1016)
			(type default)
		)
		(fill no)
		(layer "In4.Cu")
	)
	(gr_circle
		(center 311.799732 -280.699718)
		(end 312.053732 -280.699718)
		(stroke
			(width 0.1016)
			(type default)
		)
		(fill no)
		(layer "In4.Cu")
	)
	(gr_circle
		(center 311.799732 -279.749758)
		(end 312.053732 -279.749758)
		(stroke
			(width 0.1016)
			(type default)
		)
		(fill no)
		(layer "In4.Cu")
	)
	(gr_circle
		(center 312.749438 -274.049744)
		(end 313.003438 -274.049744)
		(stroke
			(width 0.1016)
			(type default)
		)
		(fill no)
		(layer "In4.Cu")
	)
	(gr_circle
		(center 312.749438 -273.099784)
		(end 313.003438 -273.099784)
		(stroke
			(width 0.1016)
			(type default)
		)
		(fill no)
		(layer "In4.Cu")
	)
	(gr_circle
		(center 312.749692 -318.699896)
		(end 313.003692 -318.699896)
		(stroke
			(width 0.1016)
			(type default)
		)
		(fill no)
		(layer "In4.Cu")
	)
	(gr_circle
		(center 312.749692 -317.749936)
		(end 313.003692 -317.749936)
		(stroke
			(width 0.1016)
			(type default)
		)
		(fill no)
		(layer "In4.Cu")
	)
	(gr_circle
		(center 312.749692 -313.949842)
		(end 313.003692 -313.949842)
		(stroke
			(width 0.1016)
			(type default)
		)
		(fill no)
		(layer "In4.Cu")
	)
	(gr_circle
		(center 312.749692 -312.999882)
		(end 313.003692 -312.999882)
		(stroke
			(width 0.1016)
			(type default)
		)
		(fill no)
		(layer "In4.Cu")
	)
	(gr_circle
		(center 312.749692 -309.199788)
		(end 313.003692 -309.199788)
		(stroke
			(width 0.1016)
			(type default)
		)
		(fill no)
		(layer "In4.Cu")
	)
	(gr_circle
		(center 312.749692 -307.299868)
		(end 313.003692 -307.299868)
		(stroke
			(width 0.1016)
			(type default)
		)
		(fill no)
		(layer "In4.Cu")
	)
	(gr_circle
		(center 312.749692 -305.399948)
		(end 313.003692 -305.399948)
		(stroke
			(width 0.1016)
			(type default)
		)
		(fill no)
		(layer "In4.Cu")
	)
	(gr_circle
		(center 312.749692 -288.299906)
		(end 313.003692 -288.299906)
		(stroke
			(width 0.1016)
			(type default)
		)
		(fill no)
		(layer "In4.Cu")
	)
	(gr_circle
		(center 312.749692 -286.399732)
		(end 313.003692 -286.399732)
		(stroke
			(width 0.1016)
			(type default)
		)
		(fill no)
		(layer "In4.Cu")
	)
	(gr_circle
		(center 312.749692 -284.499812)
		(end 313.003692 -284.499812)
		(stroke
			(width 0.1016)
			(type default)
		)
		(fill no)
		(layer "In4.Cu")
	)
	(gr_circle
		(center 312.749692 -282.599892)
		(end 313.003692 -282.599892)
		(stroke
			(width 0.1016)
			(type default)
		)
		(fill no)
		(layer "In4.Cu")
	)
	(gr_circle
		(center 312.749692 -278.799798)
		(end 313.003692 -278.799798)
		(stroke
			(width 0.1016)
			(type default)
		)
		(fill no)
		(layer "In4.Cu")
	)
	(gr_circle
		(center 312.749692 -277.849838)
		(end 313.003692 -277.849838)
		(stroke
			(width 0.1016)
			(type default)
		)
		(fill no)
		(layer "In4.Cu")
	)
	(gr_circle
		(center 313.699906 -316.799722)
		(end 313.953906 -316.799722)
		(stroke
			(width 0.1016)
			(type default)
		)
		(fill no)
		(layer "In4.Cu")
	)
	(gr_circle
		(center 313.699906 -314.899802)
		(end 313.953906 -314.899802)
		(stroke
			(width 0.1016)
			(type default)
		)
		(fill no)
		(layer "In4.Cu")
	)
	(gr_circle
		(center 313.699906 -312.049922)
		(end 313.953906 -312.049922)
		(stroke
			(width 0.1016)
			(type default)
		)
		(fill no)
		(layer "In4.Cu")
	)
	(gr_circle
		(center 313.699906 -310.149748)
		(end 313.953906 -310.149748)
		(stroke
			(width 0.1016)
			(type default)
		)
		(fill no)
		(layer "In4.Cu")
	)
	(gr_circle
		(center 313.699906 -308.249828)
		(end 313.953906 -308.249828)
		(stroke
			(width 0.1016)
			(type default)
		)
		(fill no)
		(layer "In4.Cu")
	)
	(gr_circle
		(center 313.699906 -306.349908)
		(end 313.953906 -306.349908)
		(stroke
			(width 0.1016)
			(type default)
		)
		(fill no)
		(layer "In4.Cu")
	)
	(gr_circle
		(center 313.699906 -304.449734)
		(end 313.953906 -304.449734)
		(stroke
			(width 0.1016)
			(type default)
		)
		(fill no)
		(layer "In4.Cu")
	)
	(gr_circle
		(center 313.699906 -287.349946)
		(end 313.953906 -287.349946)
		(stroke
			(width 0.1016)
			(type default)
		)
		(fill no)
		(layer "In4.Cu")
	)
	(gr_circle
		(center 313.699906 -285.449772)
		(end 313.953906 -285.449772)
		(stroke
			(width 0.1016)
			(type default)
		)
		(fill no)
		(layer "In4.Cu")
	)
	(gr_circle
		(center 313.699906 -283.549852)
		(end 313.953906 -283.549852)
		(stroke
			(width 0.1016)
			(type default)
		)
		(fill no)
		(layer "In4.Cu")
	)
	(gr_circle
		(center 313.699906 -281.649932)
		(end 313.953906 -281.649932)
		(stroke
			(width 0.1016)
			(type default)
		)
		(fill no)
		(layer "In4.Cu")
	)
	(gr_circle
		(center 313.699906 -279.749758)
		(end 313.953906 -279.749758)
		(stroke
			(width 0.1016)
			(type default)
		)
		(fill no)
		(layer "In4.Cu")
	)
	(gr_circle
		(center 313.699906 -276.899878)
		(end 313.953906 -276.899878)
		(stroke
			(width 0.1016)
			(type default)
		)
		(fill no)
		(layer "In4.Cu")
	)
	(gr_circle
		(center 313.699906 -274.999704)
		(end 313.953906 -274.999704)
		(stroke
			(width 0.1016)
			(type default)
		)
		(fill no)
		(layer "In4.Cu")
	)
	(gr_circle
		(center 314.649866 -316.799722)
		(end 314.903866 -316.799722)
		(stroke
			(width 0.1016)
			(type default)
		)
		(fill no)
		(layer "In4.Cu")
	)
	(gr_circle
		(center 314.649866 -314.899802)
		(end 314.903866 -314.899802)
		(stroke
			(width 0.1016)
			(type default)
		)
		(fill no)
		(layer "In4.Cu")
	)
	(gr_circle
		(center 314.649866 -312.049922)
		(end 314.903866 -312.049922)
		(stroke
			(width 0.1016)
			(type default)
		)
		(fill no)
		(layer "In4.Cu")
	)
	(gr_circle
		(center 314.649866 -310.149748)
		(end 314.903866 -310.149748)
		(stroke
			(width 0.1016)
			(type default)
		)
		(fill no)
		(layer "In4.Cu")
	)
	(gr_circle
		(center 314.649866 -308.249828)
		(end 314.903866 -308.249828)
		(stroke
			(width 0.1016)
			(type default)
		)
		(fill no)
		(layer "In4.Cu")
	)
	(gr_circle
		(center 314.649866 -306.349908)
		(end 314.903866 -306.349908)
		(stroke
			(width 0.1016)
			(type default)
		)
		(fill no)
		(layer "In4.Cu")
	)
	(gr_circle
		(center 314.649866 -304.449734)
		(end 314.903866 -304.449734)
		(stroke
			(width 0.1016)
			(type default)
		)
		(fill no)
		(layer "In4.Cu")
	)
	(gr_circle
		(center 314.649866 -287.349946)
		(end 314.903866 -287.349946)
		(stroke
			(width 0.1016)
			(type default)
		)
		(fill no)
		(layer "In4.Cu")
	)
	(gr_circle
		(center 314.649866 -285.449772)
		(end 314.903866 -285.449772)
		(stroke
			(width 0.1016)
			(type default)
		)
		(fill no)
		(layer "In4.Cu")
	)
	(gr_circle
		(center 314.649866 -283.549852)
		(end 314.903866 -283.549852)
		(stroke
			(width 0.1016)
			(type default)
		)
		(fill no)
		(layer "In4.Cu")
	)
	(gr_circle
		(center 314.649866 -281.649932)
		(end 314.903866 -281.649932)
		(stroke
			(width 0.1016)
			(type default)
		)
		(fill no)
		(layer "In4.Cu")
	)
	(gr_circle
		(center 314.649866 -279.749758)
		(end 314.903866 -279.749758)
		(stroke
			(width 0.1016)
			(type default)
		)
		(fill no)
		(layer "In4.Cu")
	)
	(gr_circle
		(center 314.649866 -276.899878)
		(end 314.903866 -276.899878)
		(stroke
			(width 0.1016)
			(type default)
		)
		(fill no)
		(layer "In4.Cu")
	)
	(gr_circle
		(center 314.649866 -274.999704)
		(end 314.903866 -274.999704)
		(stroke
			(width 0.1016)
			(type default)
		)
		(fill no)
		(layer "In4.Cu")
	)
	(gr_circle
		(center 385.149852 -316.799722)
		(end 385.403852 -316.799722)
		(stroke
			(width 0.1016)
			(type default)
		)
		(fill no)
		(layer "In4.Cu")
	)
	(gr_circle
		(center 385.149852 -314.899802)
		(end 385.403852 -314.899802)
		(stroke
			(width 0.1016)
			(type default)
		)
		(fill no)
		(layer "In4.Cu")
	)
	(gr_circle
		(center 385.149852 -312.049922)
		(end 385.403852 -312.049922)
		(stroke
			(width 0.1016)
			(type default)
		)
		(fill no)
		(layer "In4.Cu")
	)
	(gr_circle
		(center 385.149852 -310.149748)
		(end 385.403852 -310.149748)
		(stroke
			(width 0.1016)
			(type default)
		)
		(fill no)
		(layer "In4.Cu")
	)
	(gr_circle
		(center 385.149852 -308.249828)
		(end 385.403852 -308.249828)
		(stroke
			(width 0.1016)
			(type default)
		)
		(fill no)
		(layer "In4.Cu")
	)
	(gr_circle
		(center 385.149852 -306.349908)
		(end 385.403852 -306.349908)
		(stroke
			(width 0.1016)
			(type default)
		)
		(fill no)
		(layer "In4.Cu")
	)
	(gr_circle
		(center 385.149852 -304.449734)
		(end 385.403852 -304.449734)
		(stroke
			(width 0.1016)
			(type default)
		)
		(fill no)
		(layer "In4.Cu")
	)
	(gr_circle
		(center 385.149852 -302.549814)
		(end 385.403852 -302.549814)
		(stroke
			(width 0.1016)
			(type default)
		)
		(fill no)
		(layer "In4.Cu")
	)
	(gr_circle
		(center 386.099812 -316.799722)
		(end 386.353812 -316.799722)
		(stroke
			(width 0.1016)
			(type default)
		)
		(fill no)
		(layer "In4.Cu")
	)
	(gr_circle
		(center 386.099812 -314.899802)
		(end 386.353812 -314.899802)
		(stroke
			(width 0.1016)
			(type default)
		)
		(fill no)
		(layer "In4.Cu")
	)
	(gr_circle
		(center 386.099812 -312.049922)
		(end 386.353812 -312.049922)
		(stroke
			(width 0.1016)
			(type default)
		)
		(fill no)
		(layer "In4.Cu")
	)
	(gr_circle
		(center 386.099812 -310.149748)
		(end 386.353812 -310.149748)
		(stroke
			(width 0.1016)
			(type default)
		)
		(fill no)
		(layer "In4.Cu")
	)
	(gr_circle
		(center 386.099812 -308.249828)
		(end 386.353812 -308.249828)
		(stroke
			(width 0.1016)
			(type default)
		)
		(fill no)
		(layer "In4.Cu")
	)
	(gr_circle
		(center 386.099812 -306.349908)
		(end 386.353812 -306.349908)
		(stroke
			(width 0.1016)
			(type default)
		)
		(fill no)
		(layer "In4.Cu")
	)
	(gr_circle
		(center 386.099812 -304.449734)
		(end 386.353812 -304.449734)
		(stroke
			(width 0.1016)
			(type default)
		)
		(fill no)
		(layer "In4.Cu")
	)
	(gr_circle
		(center 386.099812 -302.549814)
		(end 386.353812 -302.549814)
		(stroke
			(width 0.1016)
			(type default)
		)
		(fill no)
		(layer "In4.Cu")
	)
	(gr_circle
		(center 387.050026 -318.699896)
		(end 387.304026 -318.699896)
		(stroke
			(width 0.1016)
			(type default)
		)
		(fill no)
		(layer "In4.Cu")
	)
	(gr_circle
		(center 387.050026 -317.749936)
		(end 387.304026 -317.749936)
		(stroke
			(width 0.1016)
			(type default)
		)
		(fill no)
		(layer "In4.Cu")
	)
	(gr_circle
		(center 387.050026 -313.949842)
		(end 387.304026 -313.949842)
		(stroke
			(width 0.1016)
			(type default)
		)
		(fill no)
		(layer "In4.Cu")
	)
	(gr_circle
		(center 387.050026 -312.999882)
		(end 387.304026 -312.999882)
		(stroke
			(width 0.1016)
			(type default)
		)
		(fill no)
		(layer "In4.Cu")
	)
	(gr_circle
		(center 387.050026 -309.199788)
		(end 387.304026 -309.199788)
		(stroke
			(width 0.1016)
			(type default)
		)
		(fill no)
		(layer "In4.Cu")
	)
	(gr_circle
		(center 387.050026 -307.299868)
		(end 387.304026 -307.299868)
		(stroke
			(width 0.1016)
			(type default)
		)
		(fill no)
		(layer "In4.Cu")
	)
	(gr_circle
		(center 387.050026 -305.399948)
		(end 387.304026 -305.399948)
		(stroke
			(width 0.1016)
			(type default)
		)
		(fill no)
		(layer "In4.Cu")
	)
	(gr_circle
		(center 387.050026 -303.499774)
		(end 387.304026 -303.499774)
		(stroke
			(width 0.1016)
			(type default)
		)
		(fill no)
		(layer "In4.Cu")
	)
	(gr_circle
		(center 387.050026 -301.599854)
		(end 387.304026 -301.599854)
		(stroke
			(width 0.1016)
			(type default)
		)
		(fill no)
		(layer "In4.Cu")
	)
	(gr_circle
		(center 387.999986 -316.799722)
		(end 388.253986 -316.799722)
		(stroke
			(width 0.1016)
			(type default)
		)
		(fill no)
		(layer "In4.Cu")
	)
	(gr_circle
		(center 387.999986 -315.849762)
		(end 388.253986 -315.849762)
		(stroke
			(width 0.1016)
			(type default)
		)
		(fill no)
		(layer "In4.Cu")
	)
	(gr_circle
		(center 387.999986 -312.049922)
		(end 388.253986 -312.049922)
		(stroke
			(width 0.1016)
			(type default)
		)
		(fill no)
		(layer "In4.Cu")
	)
	(gr_circle
		(center 387.999986 -311.099962)
		(end 388.253986 -311.099962)
		(stroke
			(width 0.1016)
			(type default)
		)
		(fill no)
		(layer "In4.Cu")
	)
	(gr_circle
		(center 387.999986 -309.199788)
		(end 388.253986 -309.199788)
		(stroke
			(width 0.1016)
			(type default)
		)
		(fill no)
		(layer "In4.Cu")
	)
	(gr_circle
		(center 387.999986 -307.299868)
		(end 388.253986 -307.299868)
		(stroke
			(width 0.1016)
			(type default)
		)
		(fill no)
		(layer "In4.Cu")
	)
	(gr_circle
		(center 387.999986 -305.399948)
		(end 388.253986 -305.399948)
		(stroke
			(width 0.1016)
			(type default)
		)
		(fill no)
		(layer "In4.Cu")
	)
	(gr_circle
		(center 387.999986 -303.499774)
		(end 388.253986 -303.499774)
		(stroke
			(width 0.1016)
			(type default)
		)
		(fill no)
		(layer "In4.Cu")
	)
	(gr_circle
		(center 387.999986 -301.599854)
		(end 388.253986 -301.599854)
		(stroke
			(width 0.1016)
			(type default)
		)
		(fill no)
		(layer "In4.Cu")
	)
	(gr_circle
		(center 388.949946 -318.699896)
		(end 389.203946 -318.699896)
		(stroke
			(width 0.1016)
			(type default)
		)
		(fill no)
		(layer "In4.Cu")
	)
	(gr_circle
		(center 388.949946 -317.749936)
		(end 389.203946 -317.749936)
		(stroke
			(width 0.1016)
			(type default)
		)
		(fill no)
		(layer "In4.Cu")
	)
	(gr_circle
		(center 388.949946 -313.949842)
		(end 389.203946 -313.949842)
		(stroke
			(width 0.1016)
			(type default)
		)
		(fill no)
		(layer "In4.Cu")
	)
	(gr_circle
		(center 388.949946 -312.999882)
		(end 389.203946 -312.999882)
		(stroke
			(width 0.1016)
			(type default)
		)
		(fill no)
		(layer "In4.Cu")
	)
	(gr_circle
		(center 389.899906 -316.799722)
		(end 390.153906 -316.799722)
		(stroke
			(width 0.1016)
			(type default)
		)
		(fill no)
		(layer "In4.Cu")
	)
	(gr_circle
		(center 389.899906 -315.849762)
		(end 390.153906 -315.849762)
		(stroke
			(width 0.1016)
			(type default)
		)
		(fill no)
		(layer "In4.Cu")
	)
	(gr_circle
		(center 389.899906 -312.049922)
		(end 390.153906 -312.049922)
		(stroke
			(width 0.1016)
			(type default)
		)
		(fill no)
		(layer "In4.Cu")
	)
	(gr_circle
		(center 389.899906 -311.099962)
		(end 390.153906 -311.099962)
		(stroke
			(width 0.1016)
			(type default)
		)
		(fill no)
		(layer "In4.Cu")
	)
	(gr_circle
		(center 389.899906 -309.199788)
		(end 390.153906 -309.199788)
		(stroke
			(width 0.1016)
			(type default)
		)
		(fill no)
		(layer "In4.Cu")
	)
	(gr_circle
		(center 389.899906 -307.299868)
		(end 390.153906 -307.299868)
		(stroke
			(width 0.1016)
			(type default)
		)
		(fill no)
		(layer "In4.Cu")
	)
	(gr_circle
		(center 389.899906 -305.399948)
		(end 390.153906 -305.399948)
		(stroke
			(width 0.1016)
			(type default)
		)
		(fill no)
		(layer "In4.Cu")
	)
	(gr_circle
		(center 389.899906 -303.499774)
		(end 390.153906 -303.499774)
		(stroke
			(width 0.1016)
			(type default)
		)
		(fill no)
		(layer "In4.Cu")
	)
	(gr_circle
		(center 389.899906 -301.599854)
		(end 390.153906 -301.599854)
		(stroke
			(width 0.1016)
			(type default)
		)
		(fill no)
		(layer "In4.Cu")
	)
	(gr_circle
		(center 390.849866 -318.699896)
		(end 391.103866 -318.699896)
		(stroke
			(width 0.1016)
			(type default)
		)
		(fill no)
		(layer "In4.Cu")
	)
	(gr_circle
		(center 390.849866 -317.749936)
		(end 391.103866 -317.749936)
		(stroke
			(width 0.1016)
			(type default)
		)
		(fill no)
		(layer "In4.Cu")
	)
	(gr_circle
		(center 390.849866 -313.949842)
		(end 391.103866 -313.949842)
		(stroke
			(width 0.1016)
			(type default)
		)
		(fill no)
		(layer "In4.Cu")
	)
	(gr_circle
		(center 390.849866 -312.999882)
		(end 391.103866 -312.999882)
		(stroke
			(width 0.1016)
			(type default)
		)
		(fill no)
		(layer "In4.Cu")
	)
	(gr_circle
		(center 390.849866 -309.199788)
		(end 391.103866 -309.199788)
		(stroke
			(width 0.1016)
			(type default)
		)
		(fill no)
		(layer "In4.Cu")
	)
	(gr_circle
		(center 390.849866 -307.299868)
		(end 391.103866 -307.299868)
		(stroke
			(width 0.1016)
			(type default)
		)
		(fill no)
		(layer "In4.Cu")
	)
	(gr_circle
		(center 390.849866 -305.399948)
		(end 391.103866 -305.399948)
		(stroke
			(width 0.1016)
			(type default)
		)
		(fill no)
		(layer "In4.Cu")
	)
	(gr_circle
		(center 390.849866 -303.499774)
		(end 391.103866 -303.499774)
		(stroke
			(width 0.1016)
			(type default)
		)
		(fill no)
		(layer "In4.Cu")
	)
	(gr_circle
		(center 390.849866 -301.599854)
		(end 391.103866 -301.599854)
		(stroke
			(width 0.1016)
			(type default)
		)
		(fill no)
		(layer "In4.Cu")
	)
	(gr_circle
		(center 391.799826 -316.799722)
		(end 392.053826 -316.799722)
		(stroke
			(width 0.1016)
			(type default)
		)
		(fill no)
		(layer "In4.Cu")
	)
	(gr_circle
		(center 391.799826 -315.849762)
		(end 392.053826 -315.849762)
		(stroke
			(width 0.1016)
			(type default)
		)
		(fill no)
		(layer "In4.Cu")
	)
	(gr_circle
		(center 391.799826 -312.049922)
		(end 392.053826 -312.049922)
		(stroke
			(width 0.1016)
			(type default)
		)
		(fill no)
		(layer "In4.Cu")
	)
	(gr_circle
		(center 391.799826 -311.099962)
		(end 392.053826 -311.099962)
		(stroke
			(width 0.1016)
			(type default)
		)
		(fill no)
		(layer "In4.Cu")
	)
	(gr_circle
		(center 391.799826 -308.249828)
		(end 392.053826 -308.249828)
		(stroke
			(width 0.1016)
			(type default)
		)
		(fill no)
		(layer "In4.Cu")
	)
	(gr_circle
		(center 391.799826 -306.349908)
		(end 392.053826 -306.349908)
		(stroke
			(width 0.1016)
			(type default)
		)
		(fill no)
		(layer "In4.Cu")
	)
	(gr_circle
		(center 391.799826 -304.449734)
		(end 392.053826 -304.449734)
		(stroke
			(width 0.1016)
			(type default)
		)
		(fill no)
		(layer "In4.Cu")
	)
	(gr_circle
		(center 391.799826 -302.549814)
		(end 392.053826 -302.549814)
		(stroke
			(width 0.1016)
			(type default)
		)
		(fill no)
		(layer "In4.Cu")
	)
	(gr_circle
		(center 392.749786 -318.699896)
		(end 393.003786 -318.699896)
		(stroke
			(width 0.1016)
			(type default)
		)
		(fill no)
		(layer "In4.Cu")
	)
	(gr_circle
		(center 392.749786 -317.749936)
		(end 393.003786 -317.749936)
		(stroke
			(width 0.1016)
			(type default)
		)
		(fill no)
		(layer "In4.Cu")
	)
	(gr_circle
		(center 392.749786 -313.949842)
		(end 393.003786 -313.949842)
		(stroke
			(width 0.1016)
			(type default)
		)
		(fill no)
		(layer "In4.Cu")
	)
	(gr_circle
		(center 392.749786 -312.999882)
		(end 393.003786 -312.999882)
		(stroke
			(width 0.1016)
			(type default)
		)
		(fill no)
		(layer "In4.Cu")
	)
	(gr_circle
		(center 392.749786 -308.249828)
		(end 393.003786 -308.249828)
		(stroke
			(width 0.1016)
			(type default)
		)
		(fill no)
		(layer "In4.Cu")
	)
	(gr_circle
		(center 392.749786 -306.349908)
		(end 393.003786 -306.349908)
		(stroke
			(width 0.1016)
			(type default)
		)
		(fill no)
		(layer "In4.Cu")
	)
	(gr_circle
		(center 392.749786 -304.449734)
		(end 393.003786 -304.449734)
		(stroke
			(width 0.1016)
			(type default)
		)
		(fill no)
		(layer "In4.Cu")
	)
	(gr_circle
		(center 392.749786 -302.549814)
		(end 393.003786 -302.549814)
		(stroke
			(width 0.1016)
			(type default)
		)
		(fill no)
		(layer "In4.Cu")
	)
	(gr_circle
		(center 392.749786 -278.799798)
		(end 393.003786 -278.799798)
		(stroke
			(width 0.1016)
			(type default)
		)
		(fill no)
		(layer "In4.Cu")
	)
	(gr_circle
		(center 392.749786 -277.849838)
		(end 393.003786 -277.849838)
		(stroke
			(width 0.1016)
			(type default)
		)
		(fill no)
		(layer "In4.Cu")
	)
	(gr_circle
		(center 392.749786 -274.049744)
		(end 393.003786 -274.049744)
		(stroke
			(width 0.1016)
			(type default)
		)
		(fill no)
		(layer "In4.Cu")
	)
	(gr_circle
		(center 392.749786 -273.099784)
		(end 393.003786 -273.099784)
		(stroke
			(width 0.1016)
			(type default)
		)
		(fill no)
		(layer "In4.Cu")
	)
	(gr_circle
		(center 393.7 -316.799722)
		(end 393.954 -316.799722)
		(stroke
			(width 0.1016)
			(type default)
		)
		(fill no)
		(layer "In4.Cu")
	)
	(gr_circle
		(center 393.7 -315.849762)
		(end 393.954 -315.849762)
		(stroke
			(width 0.1016)
			(type default)
		)
		(fill no)
		(layer "In4.Cu")
	)
	(gr_circle
		(center 393.7 -312.049922)
		(end 393.954 -312.049922)
		(stroke
			(width 0.1016)
			(type default)
		)
		(fill no)
		(layer "In4.Cu")
	)
	(gr_circle
		(center 393.7 -311.099962)
		(end 393.954 -311.099962)
		(stroke
			(width 0.1016)
			(type default)
		)
		(fill no)
		(layer "In4.Cu")
	)
	(gr_circle
		(center 393.7 -280.699464)
		(end 393.954 -280.699464)
		(stroke
			(width 0.1016)
			(type default)
		)
		(fill no)
		(layer "In4.Cu")
	)
	(gr_circle
		(center 393.7 -279.749504)
		(end 393.954 -279.749504)
		(stroke
			(width 0.1016)
			(type default)
		)
		(fill no)
		(layer "In4.Cu")
	)
	(gr_circle
		(center 393.7 -275.949918)
		(end 393.954 -275.949918)
		(stroke
			(width 0.1016)
			(type default)
		)
		(fill no)
		(layer "In4.Cu")
	)
	(gr_circle
		(center 393.7 -274.999958)
		(end 393.954 -274.999958)
		(stroke
			(width 0.1016)
			(type default)
		)
		(fill no)
		(layer "In4.Cu")
	)
	(gr_circle
		(center 394.64996 -318.699896)
		(end 394.90396 -318.699896)
		(stroke
			(width 0.1016)
			(type default)
		)
		(fill no)
		(layer "In4.Cu")
	)
	(gr_circle
		(center 394.64996 -317.749936)
		(end 394.90396 -317.749936)
		(stroke
			(width 0.1016)
			(type default)
		)
		(fill no)
		(layer "In4.Cu")
	)
	(gr_circle
		(center 394.64996 -313.949842)
		(end 394.90396 -313.949842)
		(stroke
			(width 0.1016)
			(type default)
		)
		(fill no)
		(layer "In4.Cu")
	)
	(gr_circle
		(center 394.64996 -312.999882)
		(end 394.90396 -312.999882)
		(stroke
			(width 0.1016)
			(type default)
		)
		(fill no)
		(layer "In4.Cu")
	)
	(gr_circle
		(center 394.64996 -278.799798)
		(end 394.90396 -278.799798)
		(stroke
			(width 0.1016)
			(type default)
		)
		(fill no)
		(layer "In4.Cu")
	)
	(gr_circle
		(center 394.64996 -277.849838)
		(end 394.90396 -277.849838)
		(stroke
			(width 0.1016)
			(type default)
		)
		(fill no)
		(layer "In4.Cu")
	)
	(gr_circle
		(center 394.64996 -274.049744)
		(end 394.90396 -274.049744)
		(stroke
			(width 0.1016)
			(type default)
		)
		(fill no)
		(layer "In4.Cu")
	)
	(gr_circle
		(center 394.64996 -273.099784)
		(end 394.90396 -273.099784)
		(stroke
			(width 0.1016)
			(type default)
		)
		(fill no)
		(layer "In4.Cu")
	)
	(gr_circle
		(center 395.59992 -316.799722)
		(end 395.85392 -316.799722)
		(stroke
			(width 0.1016)
			(type default)
		)
		(fill no)
		(layer "In4.Cu")
	)
	(gr_circle
		(center 395.59992 -315.849762)
		(end 395.85392 -315.849762)
		(stroke
			(width 0.1016)
			(type default)
		)
		(fill no)
		(layer "In4.Cu")
	)
	(gr_circle
		(center 395.59992 -312.049922)
		(end 395.85392 -312.049922)
		(stroke
			(width 0.1016)
			(type default)
		)
		(fill no)
		(layer "In4.Cu")
	)
	(gr_circle
		(center 395.59992 -311.099962)
		(end 395.85392 -311.099962)
		(stroke
			(width 0.1016)
			(type default)
		)
		(fill no)
		(layer "In4.Cu")
	)
	(gr_circle
		(center 395.59992 -280.699464)
		(end 395.85392 -280.699464)
		(stroke
			(width 0.1016)
			(type default)
		)
		(fill no)
		(layer "In4.Cu")
	)
	(gr_circle
		(center 395.59992 -279.749504)
		(end 395.85392 -279.749504)
		(stroke
			(width 0.1016)
			(type default)
		)
		(fill no)
		(layer "In4.Cu")
	)
	(gr_circle
		(center 395.59992 -275.949918)
		(end 395.85392 -275.949918)
		(stroke
			(width 0.1016)
			(type default)
		)
		(fill no)
		(layer "In4.Cu")
	)
	(gr_circle
		(center 395.59992 -274.999958)
		(end 395.85392 -274.999958)
		(stroke
			(width 0.1016)
			(type default)
		)
		(fill no)
		(layer "In4.Cu")
	)
	(gr_circle
		(center 396.54988 -318.699896)
		(end 396.80388 -318.699896)
		(stroke
			(width 0.1016)
			(type default)
		)
		(fill no)
		(layer "In4.Cu")
	)
	(gr_circle
		(center 396.54988 -317.749936)
		(end 396.80388 -317.749936)
		(stroke
			(width 0.1016)
			(type default)
		)
		(fill no)
		(layer "In4.Cu")
	)
	(gr_circle
		(center 396.54988 -313.949842)
		(end 396.80388 -313.949842)
		(stroke
			(width 0.1016)
			(type default)
		)
		(fill no)
		(layer "In4.Cu")
	)
	(gr_circle
		(center 396.54988 -312.999882)
		(end 396.80388 -312.999882)
		(stroke
			(width 0.1016)
			(type default)
		)
		(fill no)
		(layer "In4.Cu")
	)
	(gr_circle
		(center 396.54988 -278.799798)
		(end 396.80388 -278.799798)
		(stroke
			(width 0.1016)
			(type default)
		)
		(fill no)
		(layer "In4.Cu")
	)
	(gr_circle
		(center 396.54988 -277.849838)
		(end 396.80388 -277.849838)
		(stroke
			(width 0.1016)
			(type default)
		)
		(fill no)
		(layer "In4.Cu")
	)
	(gr_circle
		(center 396.54988 -274.049744)
		(end 396.80388 -274.049744)
		(stroke
			(width 0.1016)
			(type default)
		)
		(fill no)
		(layer "In4.Cu")
	)
	(gr_circle
		(center 396.54988 -273.099784)
		(end 396.80388 -273.099784)
		(stroke
			(width 0.1016)
			(type default)
		)
		(fill no)
		(layer "In4.Cu")
	)
	(gr_circle
		(center 397.49984 -316.799722)
		(end 397.75384 -316.799722)
		(stroke
			(width 0.1016)
			(type default)
		)
		(fill no)
		(layer "In4.Cu")
	)
	(gr_circle
		(center 397.49984 -315.849762)
		(end 397.75384 -315.849762)
		(stroke
			(width 0.1016)
			(type default)
		)
		(fill no)
		(layer "In4.Cu")
	)
	(gr_circle
		(center 397.49984 -312.049922)
		(end 397.75384 -312.049922)
		(stroke
			(width 0.1016)
			(type default)
		)
		(fill no)
		(layer "In4.Cu")
	)
	(gr_circle
		(center 397.49984 -311.099962)
		(end 397.75384 -311.099962)
		(stroke
			(width 0.1016)
			(type default)
		)
		(fill no)
		(layer "In4.Cu")
	)
	(gr_circle
		(center 397.49984 -280.699464)
		(end 397.75384 -280.699464)
		(stroke
			(width 0.1016)
			(type default)
		)
		(fill no)
		(layer "In4.Cu")
	)
	(gr_circle
		(center 397.49984 -279.749504)
		(end 397.75384 -279.749504)
		(stroke
			(width 0.1016)
			(type default)
		)
		(fill no)
		(layer "In4.Cu")
	)
	(gr_circle
		(center 397.49984 -275.949918)
		(end 397.75384 -275.949918)
		(stroke
			(width 0.1016)
			(type default)
		)
		(fill no)
		(layer "In4.Cu")
	)
	(gr_circle
		(center 397.49984 -274.999958)
		(end 397.75384 -274.999958)
		(stroke
			(width 0.1016)
			(type default)
		)
		(fill no)
		(layer "In4.Cu")
	)
	(gr_circle
		(center 398.4498 -318.699896)
		(end 398.7038 -318.699896)
		(stroke
			(width 0.1016)
			(type default)
		)
		(fill no)
		(layer "In4.Cu")
	)
	(gr_circle
		(center 398.4498 -317.749936)
		(end 398.7038 -317.749936)
		(stroke
			(width 0.1016)
			(type default)
		)
		(fill no)
		(layer "In4.Cu")
	)
	(gr_circle
		(center 398.4498 -313.949842)
		(end 398.7038 -313.949842)
		(stroke
			(width 0.1016)
			(type default)
		)
		(fill no)
		(layer "In4.Cu")
	)
	(gr_circle
		(center 398.4498 -312.999882)
		(end 398.7038 -312.999882)
		(stroke
			(width 0.1016)
			(type default)
		)
		(fill no)
		(layer "In4.Cu")
	)
	(gr_circle
		(center 398.4498 -278.799798)
		(end 398.7038 -278.799798)
		(stroke
			(width 0.1016)
			(type default)
		)
		(fill no)
		(layer "In4.Cu")
	)
	(gr_circle
		(center 398.4498 -277.849838)
		(end 398.7038 -277.849838)
		(stroke
			(width 0.1016)
			(type default)
		)
		(fill no)
		(layer "In4.Cu")
	)
	(gr_circle
		(center 398.4498 -274.049744)
		(end 398.7038 -274.049744)
		(stroke
			(width 0.1016)
			(type default)
		)
		(fill no)
		(layer "In4.Cu")
	)
	(gr_circle
		(center 398.4498 -273.099784)
		(end 398.7038 -273.099784)
		(stroke
			(width 0.1016)
			(type default)
		)
		(fill no)
		(layer "In4.Cu")
	)
	(gr_circle
		(center 399.400014 -316.799722)
		(end 399.654014 -316.799722)
		(stroke
			(width 0.1016)
			(type default)
		)
		(fill no)
		(layer "In4.Cu")
	)
	(gr_circle
		(center 399.400014 -315.849762)
		(end 399.654014 -315.849762)
		(stroke
			(width 0.1016)
			(type default)
		)
		(fill no)
		(layer "In4.Cu")
	)
	(gr_circle
		(center 399.400014 -312.049922)
		(end 399.654014 -312.049922)
		(stroke
			(width 0.1016)
			(type default)
		)
		(fill no)
		(layer "In4.Cu")
	)
	(gr_circle
		(center 399.400014 -311.099962)
		(end 399.654014 -311.099962)
		(stroke
			(width 0.1016)
			(type default)
		)
		(fill no)
		(layer "In4.Cu")
	)
	(gr_circle
		(center 399.400014 -280.699464)
		(end 399.654014 -280.699464)
		(stroke
			(width 0.1016)
			(type default)
		)
		(fill no)
		(layer "In4.Cu")
	)
	(gr_circle
		(center 399.400014 -279.749504)
		(end 399.654014 -279.749504)
		(stroke
			(width 0.1016)
			(type default)
		)
		(fill no)
		(layer "In4.Cu")
	)
	(gr_circle
		(center 399.400014 -275.949918)
		(end 399.654014 -275.949918)
		(stroke
			(width 0.1016)
			(type default)
		)
		(fill no)
		(layer "In4.Cu")
	)
	(gr_circle
		(center 399.400014 -274.999958)
		(end 399.654014 -274.999958)
		(stroke
			(width 0.1016)
			(type default)
		)
		(fill no)
		(layer "In4.Cu")
	)
	(gr_circle
		(center 400.349974 -318.699896)
		(end 400.603974 -318.699896)
		(stroke
			(width 0.1016)
			(type default)
		)
		(fill no)
		(layer "In4.Cu")
	)
	(gr_circle
		(center 400.349974 -317.749936)
		(end 400.603974 -317.749936)
		(stroke
			(width 0.1016)
			(type default)
		)
		(fill no)
		(layer "In4.Cu")
	)
	(gr_circle
		(center 400.349974 -313.949842)
		(end 400.603974 -313.949842)
		(stroke
			(width 0.1016)
			(type default)
		)
		(fill no)
		(layer "In4.Cu")
	)
	(gr_circle
		(center 400.349974 -312.999882)
		(end 400.603974 -312.999882)
		(stroke
			(width 0.1016)
			(type default)
		)
		(fill no)
		(layer "In4.Cu")
	)
	(gr_circle
		(center 400.349974 -278.799798)
		(end 400.603974 -278.799798)
		(stroke
			(width 0.1016)
			(type default)
		)
		(fill no)
		(layer "In4.Cu")
	)
	(gr_circle
		(center 400.349974 -277.849838)
		(end 400.603974 -277.849838)
		(stroke
			(width 0.1016)
			(type default)
		)
		(fill no)
		(layer "In4.Cu")
	)
	(gr_circle
		(center 400.349974 -274.049744)
		(end 400.603974 -274.049744)
		(stroke
			(width 0.1016)
			(type default)
		)
		(fill no)
		(layer "In4.Cu")
	)
	(gr_circle
		(center 400.349974 -273.099784)
		(end 400.603974 -273.099784)
		(stroke
			(width 0.1016)
			(type default)
		)
		(fill no)
		(layer "In4.Cu")
	)
	(gr_circle
		(center 401.299934 -316.799722)
		(end 401.553934 -316.799722)
		(stroke
			(width 0.1016)
			(type default)
		)
		(fill no)
		(layer "In4.Cu")
	)
	(gr_circle
		(center 401.299934 -315.849762)
		(end 401.553934 -315.849762)
		(stroke
			(width 0.1016)
			(type default)
		)
		(fill no)
		(layer "In4.Cu")
	)
	(gr_circle
		(center 401.299934 -312.049922)
		(end 401.553934 -312.049922)
		(stroke
			(width 0.1016)
			(type default)
		)
		(fill no)
		(layer "In4.Cu")
	)
	(gr_circle
		(center 401.299934 -311.099962)
		(end 401.553934 -311.099962)
		(stroke
			(width 0.1016)
			(type default)
		)
		(fill no)
		(layer "In4.Cu")
	)
	(gr_circle
		(center 401.299934 -280.699464)
		(end 401.553934 -280.699464)
		(stroke
			(width 0.1016)
			(type default)
		)
		(fill no)
		(layer "In4.Cu")
	)
	(gr_circle
		(center 401.299934 -279.749504)
		(end 401.553934 -279.749504)
		(stroke
			(width 0.1016)
			(type default)
		)
		(fill no)
		(layer "In4.Cu")
	)
	(gr_circle
		(center 401.299934 -275.949918)
		(end 401.553934 -275.949918)
		(stroke
			(width 0.1016)
			(type default)
		)
		(fill no)
		(layer "In4.Cu")
	)
	(gr_circle
		(center 401.299934 -274.999958)
		(end 401.553934 -274.999958)
		(stroke
			(width 0.1016)
			(type default)
		)
		(fill no)
		(layer "In4.Cu")
	)
	(gr_circle
		(center 402.249894 -318.699896)
		(end 402.503894 -318.699896)
		(stroke
			(width 0.1016)
			(type default)
		)
		(fill no)
		(layer "In4.Cu")
	)
	(gr_circle
		(center 402.249894 -317.749936)
		(end 402.503894 -317.749936)
		(stroke
			(width 0.1016)
			(type default)
		)
		(fill no)
		(layer "In4.Cu")
	)
	(gr_circle
		(center 402.249894 -313.949842)
		(end 402.503894 -313.949842)
		(stroke
			(width 0.1016)
			(type default)
		)
		(fill no)
		(layer "In4.Cu")
	)
	(gr_circle
		(center 402.249894 -312.999882)
		(end 402.503894 -312.999882)
		(stroke
			(width 0.1016)
			(type default)
		)
		(fill no)
		(layer "In4.Cu")
	)
	(gr_circle
		(center 402.249894 -278.799798)
		(end 402.503894 -278.799798)
		(stroke
			(width 0.1016)
			(type default)
		)
		(fill no)
		(layer "In4.Cu")
	)
	(gr_circle
		(center 402.249894 -277.849838)
		(end 402.503894 -277.849838)
		(stroke
			(width 0.1016)
			(type default)
		)
		(fill no)
		(layer "In4.Cu")
	)
	(gr_circle
		(center 402.249894 -274.049744)
		(end 402.503894 -274.049744)
		(stroke
			(width 0.1016)
			(type default)
		)
		(fill no)
		(layer "In4.Cu")
	)
	(gr_circle
		(center 402.249894 -273.099784)
		(end 402.503894 -273.099784)
		(stroke
			(width 0.1016)
			(type default)
		)
		(fill no)
		(layer "In4.Cu")
	)
	(gr_circle
		(center 403.199854 -316.799722)
		(end 403.453854 -316.799722)
		(stroke
			(width 0.1016)
			(type default)
		)
		(fill no)
		(layer "In4.Cu")
	)
	(gr_circle
		(center 403.199854 -315.849762)
		(end 403.453854 -315.849762)
		(stroke
			(width 0.1016)
			(type default)
		)
		(fill no)
		(layer "In4.Cu")
	)
	(gr_circle
		(center 403.199854 -312.049922)
		(end 403.453854 -312.049922)
		(stroke
			(width 0.1016)
			(type default)
		)
		(fill no)
		(layer "In4.Cu")
	)
	(gr_circle
		(center 403.199854 -311.099962)
		(end 403.453854 -311.099962)
		(stroke
			(width 0.1016)
			(type default)
		)
		(fill no)
		(layer "In4.Cu")
	)
	(gr_circle
		(center 403.199854 -280.699464)
		(end 403.453854 -280.699464)
		(stroke
			(width 0.1016)
			(type default)
		)
		(fill no)
		(layer "In4.Cu")
	)
	(gr_circle
		(center 403.199854 -279.749504)
		(end 403.453854 -279.749504)
		(stroke
			(width 0.1016)
			(type default)
		)
		(fill no)
		(layer "In4.Cu")
	)
	(gr_circle
		(center 403.199854 -275.949918)
		(end 403.453854 -275.949918)
		(stroke
			(width 0.1016)
			(type default)
		)
		(fill no)
		(layer "In4.Cu")
	)
	(gr_circle
		(center 403.199854 -274.999958)
		(end 403.453854 -274.999958)
		(stroke
			(width 0.1016)
			(type default)
		)
		(fill no)
		(layer "In4.Cu")
	)
	(gr_circle
		(center 404.149814 -318.699896)
		(end 404.403814 -318.699896)
		(stroke
			(width 0.1016)
			(type default)
		)
		(fill no)
		(layer "In4.Cu")
	)
	(gr_circle
		(center 404.149814 -317.749936)
		(end 404.403814 -317.749936)
		(stroke
			(width 0.1016)
			(type default)
		)
		(fill no)
		(layer "In4.Cu")
	)
	(gr_circle
		(center 404.149814 -313.949842)
		(end 404.403814 -313.949842)
		(stroke
			(width 0.1016)
			(type default)
		)
		(fill no)
		(layer "In4.Cu")
	)
	(gr_circle
		(center 404.149814 -312.999882)
		(end 404.403814 -312.999882)
		(stroke
			(width 0.1016)
			(type default)
		)
		(fill no)
		(layer "In4.Cu")
	)
	(gr_circle
		(center 404.149814 -278.799798)
		(end 404.403814 -278.799798)
		(stroke
			(width 0.1016)
			(type default)
		)
		(fill no)
		(layer "In4.Cu")
	)
	(gr_circle
		(center 404.149814 -277.849838)
		(end 404.403814 -277.849838)
		(stroke
			(width 0.1016)
			(type default)
		)
		(fill no)
		(layer "In4.Cu")
	)
	(gr_circle
		(center 404.149814 -274.049744)
		(end 404.403814 -274.049744)
		(stroke
			(width 0.1016)
			(type default)
		)
		(fill no)
		(layer "In4.Cu")
	)
	(gr_circle
		(center 404.149814 -273.099784)
		(end 404.403814 -273.099784)
		(stroke
			(width 0.1016)
			(type default)
		)
		(fill no)
		(layer "In4.Cu")
	)
	(gr_circle
		(center 405.099774 -280.699464)
		(end 405.353774 -280.699464)
		(stroke
			(width 0.1016)
			(type default)
		)
		(fill no)
		(layer "In4.Cu")
	)
	(gr_circle
		(center 405.099774 -279.749504)
		(end 405.353774 -279.749504)
		(stroke
			(width 0.1016)
			(type default)
		)
		(fill no)
		(layer "In4.Cu")
	)
	(gr_circle
		(center 405.100028 -316.799722)
		(end 405.354028 -316.799722)
		(stroke
			(width 0.1016)
			(type default)
		)
		(fill no)
		(layer "In4.Cu")
	)
	(gr_circle
		(center 405.100028 -315.849762)
		(end 405.354028 -315.849762)
		(stroke
			(width 0.1016)
			(type default)
		)
		(fill no)
		(layer "In4.Cu")
	)
	(gr_circle
		(center 405.100028 -312.049922)
		(end 405.354028 -312.049922)
		(stroke
			(width 0.1016)
			(type default)
		)
		(fill no)
		(layer "In4.Cu")
	)
	(gr_circle
		(center 405.100028 -311.099962)
		(end 405.354028 -311.099962)
		(stroke
			(width 0.1016)
			(type default)
		)
		(fill no)
		(layer "In4.Cu")
	)
	(gr_circle
		(center 405.100028 -275.949918)
		(end 405.354028 -275.949918)
		(stroke
			(width 0.1016)
			(type default)
		)
		(fill no)
		(layer "In4.Cu")
	)
	(gr_circle
		(center 405.100028 -274.999958)
		(end 405.354028 -274.999958)
		(stroke
			(width 0.1016)
			(type default)
		)
		(fill no)
		(layer "In4.Cu")
	)
	(gr_circle
		(center 406.049988 -318.699896)
		(end 406.303988 -318.699896)
		(stroke
			(width 0.1016)
			(type default)
		)
		(fill no)
		(layer "In4.Cu")
	)
	(gr_circle
		(center 406.049988 -317.749936)
		(end 406.303988 -317.749936)
		(stroke
			(width 0.1016)
			(type default)
		)
		(fill no)
		(layer "In4.Cu")
	)
	(gr_circle
		(center 406.049988 -313.949842)
		(end 406.303988 -313.949842)
		(stroke
			(width 0.1016)
			(type default)
		)
		(fill no)
		(layer "In4.Cu")
	)
	(gr_circle
		(center 406.049988 -312.999882)
		(end 406.303988 -312.999882)
		(stroke
			(width 0.1016)
			(type default)
		)
		(fill no)
		(layer "In4.Cu")
	)
	(gr_circle
		(center 406.049988 -278.799798)
		(end 406.303988 -278.799798)
		(stroke
			(width 0.1016)
			(type default)
		)
		(fill no)
		(layer "In4.Cu")
	)
	(gr_circle
		(center 406.049988 -277.849838)
		(end 406.303988 -277.849838)
		(stroke
			(width 0.1016)
			(type default)
		)
		(fill no)
		(layer "In4.Cu")
	)
	(gr_circle
		(center 406.049988 -274.049744)
		(end 406.303988 -274.049744)
		(stroke
			(width 0.1016)
			(type default)
		)
		(fill no)
		(layer "In4.Cu")
	)
	(gr_circle
		(center 406.049988 -273.099784)
		(end 406.303988 -273.099784)
		(stroke
			(width 0.1016)
			(type default)
		)
		(fill no)
		(layer "In4.Cu")
	)
	(gr_circle
		(center 406.999948 -316.799722)
		(end 407.253948 -316.799722)
		(stroke
			(width 0.1016)
			(type default)
		)
		(fill no)
		(layer "In4.Cu")
	)
	(gr_circle
		(center 406.999948 -315.849762)
		(end 407.253948 -315.849762)
		(stroke
			(width 0.1016)
			(type default)
		)
		(fill no)
		(layer "In4.Cu")
	)
	(gr_circle
		(center 406.999948 -312.049922)
		(end 407.253948 -312.049922)
		(stroke
			(width 0.1016)
			(type default)
		)
		(fill no)
		(layer "In4.Cu")
	)
	(gr_circle
		(center 406.999948 -311.099962)
		(end 407.253948 -311.099962)
		(stroke
			(width 0.1016)
			(type default)
		)
		(fill no)
		(layer "In4.Cu")
	)
	(gr_circle
		(center 406.999948 -280.699464)
		(end 407.253948 -280.699464)
		(stroke
			(width 0.1016)
			(type default)
		)
		(fill no)
		(layer "In4.Cu")
	)
	(gr_circle
		(center 406.999948 -279.749504)
		(end 407.253948 -279.749504)
		(stroke
			(width 0.1016)
			(type default)
		)
		(fill no)
		(layer "In4.Cu")
	)
	(gr_circle
		(center 406.999948 -275.949918)
		(end 407.253948 -275.949918)
		(stroke
			(width 0.1016)
			(type default)
		)
		(fill no)
		(layer "In4.Cu")
	)
	(gr_circle
		(center 406.999948 -274.999958)
		(end 407.253948 -274.999958)
		(stroke
			(width 0.1016)
			(type default)
		)
		(fill no)
		(layer "In4.Cu")
	)
	(gr_circle
		(center 407.949654 -278.799798)
		(end 408.203654 -278.799798)
		(stroke
			(width 0.1016)
			(type default)
		)
		(fill no)
		(layer "In4.Cu")
	)
	(gr_circle
		(center 407.949654 -277.849838)
		(end 408.203654 -277.849838)
		(stroke
			(width 0.1016)
			(type default)
		)
		(fill no)
		(layer "In4.Cu")
	)
	(gr_circle
		(center 407.949654 -274.04949)
		(end 408.203654 -274.04949)
		(stroke
			(width 0.1016)
			(type default)
		)
		(fill no)
		(layer "In4.Cu")
	)
	(gr_circle
		(center 407.949654 -273.09953)
		(end 408.203654 -273.09953)
		(stroke
			(width 0.1016)
			(type default)
		)
		(fill no)
		(layer "In4.Cu")
	)
	(gr_circle
		(center 407.949908 -318.699896)
		(end 408.203908 -318.699896)
		(stroke
			(width 0.1016)
			(type default)
		)
		(fill no)
		(layer "In4.Cu")
	)
	(gr_circle
		(center 407.949908 -317.749936)
		(end 408.203908 -317.749936)
		(stroke
			(width 0.1016)
			(type default)
		)
		(fill no)
		(layer "In4.Cu")
	)
	(gr_circle
		(center 407.949908 -313.949842)
		(end 408.203908 -313.949842)
		(stroke
			(width 0.1016)
			(type default)
		)
		(fill no)
		(layer "In4.Cu")
	)
	(gr_circle
		(center 407.949908 -312.999882)
		(end 408.203908 -312.999882)
		(stroke
			(width 0.1016)
			(type default)
		)
		(fill no)
		(layer "In4.Cu")
	)
	(gr_circle
		(center 408.899614 -275.949664)
		(end 409.153614 -275.949664)
		(stroke
			(width 0.1016)
			(type default)
		)
		(fill no)
		(layer "In4.Cu")
	)
	(gr_circle
		(center 408.899614 -274.999704)
		(end 409.153614 -274.999704)
		(stroke
			(width 0.1016)
			(type default)
		)
		(fill no)
		(layer "In4.Cu")
	)
	(gr_circle
		(center 408.899868 -316.799722)
		(end 409.153868 -316.799722)
		(stroke
			(width 0.1016)
			(type default)
		)
		(fill no)
		(layer "In4.Cu")
	)
	(gr_circle
		(center 408.899868 -315.849762)
		(end 409.153868 -315.849762)
		(stroke
			(width 0.1016)
			(type default)
		)
		(fill no)
		(layer "In4.Cu")
	)
	(gr_circle
		(center 408.899868 -312.049922)
		(end 409.153868 -312.049922)
		(stroke
			(width 0.1016)
			(type default)
		)
		(fill no)
		(layer "In4.Cu")
	)
	(gr_circle
		(center 408.899868 -311.099962)
		(end 409.153868 -311.099962)
		(stroke
			(width 0.1016)
			(type default)
		)
		(fill no)
		(layer "In4.Cu")
	)
	(gr_circle
		(center 408.899868 -280.699464)
		(end 409.153868 -280.699464)
		(stroke
			(width 0.1016)
			(type default)
		)
		(fill no)
		(layer "In4.Cu")
	)
	(gr_circle
		(center 408.899868 -279.749504)
		(end 409.153868 -279.749504)
		(stroke
			(width 0.1016)
			(type default)
		)
		(fill no)
		(layer "In4.Cu")
	)
	(gr_circle
		(center 409.849574 -278.799798)
		(end 410.103574 -278.799798)
		(stroke
			(width 0.1016)
			(type default)
		)
		(fill no)
		(layer "In4.Cu")
	)
	(gr_circle
		(center 409.849574 -277.849838)
		(end 410.103574 -277.849838)
		(stroke
			(width 0.1016)
			(type default)
		)
		(fill no)
		(layer "In4.Cu")
	)
	(gr_circle
		(center 409.849574 -274.049744)
		(end 410.103574 -274.049744)
		(stroke
			(width 0.1016)
			(type default)
		)
		(fill no)
		(layer "In4.Cu")
	)
	(gr_circle
		(center 409.849574 -273.099784)
		(end 410.103574 -273.099784)
		(stroke
			(width 0.1016)
			(type default)
		)
		(fill no)
		(layer "In4.Cu")
	)
	(gr_circle
		(center 409.849828 -318.699896)
		(end 410.103828 -318.699896)
		(stroke
			(width 0.1016)
			(type default)
		)
		(fill no)
		(layer "In4.Cu")
	)
	(gr_circle
		(center 409.849828 -317.749936)
		(end 410.103828 -317.749936)
		(stroke
			(width 0.1016)
			(type default)
		)
		(fill no)
		(layer "In4.Cu")
	)
	(gr_circle
		(center 409.849828 -313.949842)
		(end 410.103828 -313.949842)
		(stroke
			(width 0.1016)
			(type default)
		)
		(fill no)
		(layer "In4.Cu")
	)
	(gr_circle
		(center 409.849828 -312.999882)
		(end 410.103828 -312.999882)
		(stroke
			(width 0.1016)
			(type default)
		)
		(fill no)
		(layer "In4.Cu")
	)
	(gr_circle
		(center 410.799534 -275.949918)
		(end 411.053534 -275.949918)
		(stroke
			(width 0.1016)
			(type default)
		)
		(fill no)
		(layer "In4.Cu")
	)
	(gr_circle
		(center 410.799534 -274.999958)
		(end 411.053534 -274.999958)
		(stroke
			(width 0.1016)
			(type default)
		)
		(fill no)
		(layer "In4.Cu")
	)
	(gr_circle
		(center 410.799788 -316.799722)
		(end 411.053788 -316.799722)
		(stroke
			(width 0.1016)
			(type default)
		)
		(fill no)
		(layer "In4.Cu")
	)
	(gr_circle
		(center 410.799788 -315.849762)
		(end 411.053788 -315.849762)
		(stroke
			(width 0.1016)
			(type default)
		)
		(fill no)
		(layer "In4.Cu")
	)
	(gr_circle
		(center 410.799788 -312.049922)
		(end 411.053788 -312.049922)
		(stroke
			(width 0.1016)
			(type default)
		)
		(fill no)
		(layer "In4.Cu")
	)
	(gr_circle
		(center 410.799788 -311.099962)
		(end 411.053788 -311.099962)
		(stroke
			(width 0.1016)
			(type default)
		)
		(fill no)
		(layer "In4.Cu")
	)
	(gr_circle
		(center 410.799788 -280.699464)
		(end 411.053788 -280.699464)
		(stroke
			(width 0.1016)
			(type default)
		)
		(fill no)
		(layer "In4.Cu")
	)
	(gr_circle
		(center 410.799788 -279.749504)
		(end 411.053788 -279.749504)
		(stroke
			(width 0.1016)
			(type default)
		)
		(fill no)
		(layer "In4.Cu")
	)
	(gr_circle
		(center 411.749748 -278.799798)
		(end 412.003748 -278.799798)
		(stroke
			(width 0.1016)
			(type default)
		)
		(fill no)
		(layer "In4.Cu")
	)
	(gr_circle
		(center 411.749748 -277.849838)
		(end 412.003748 -277.849838)
		(stroke
			(width 0.1016)
			(type default)
		)
		(fill no)
		(layer "In4.Cu")
	)
	(gr_circle
		(center 411.749748 -274.049744)
		(end 412.003748 -274.049744)
		(stroke
			(width 0.1016)
			(type default)
		)
		(fill no)
		(layer "In4.Cu")
	)
	(gr_circle
		(center 411.749748 -273.099784)
		(end 412.003748 -273.099784)
		(stroke
			(width 0.1016)
			(type default)
		)
		(fill no)
		(layer "In4.Cu")
	)
	(gr_circle
		(center 411.750002 -318.699896)
		(end 412.004002 -318.699896)
		(stroke
			(width 0.1016)
			(type default)
		)
		(fill no)
		(layer "In4.Cu")
	)
	(gr_circle
		(center 411.750002 -317.749936)
		(end 412.004002 -317.749936)
		(stroke
			(width 0.1016)
			(type default)
		)
		(fill no)
		(layer "In4.Cu")
	)
	(gr_circle
		(center 411.750002 -313.949842)
		(end 412.004002 -313.949842)
		(stroke
			(width 0.1016)
			(type default)
		)
		(fill no)
		(layer "In4.Cu")
	)
	(gr_circle
		(center 411.750002 -312.999882)
		(end 412.004002 -312.999882)
		(stroke
			(width 0.1016)
			(type default)
		)
		(fill no)
		(layer "In4.Cu")
	)
	(gr_circle
		(center 412.699708 -275.949664)
		(end 412.953708 -275.949664)
		(stroke
			(width 0.1016)
			(type default)
		)
		(fill no)
		(layer "In4.Cu")
	)
	(gr_circle
		(center 412.699708 -274.999704)
		(end 412.953708 -274.999704)
		(stroke
			(width 0.1016)
			(type default)
		)
		(fill no)
		(layer "In4.Cu")
	)
	(gr_circle
		(center 412.699962 -316.799722)
		(end 412.953962 -316.799722)
		(stroke
			(width 0.1016)
			(type default)
		)
		(fill no)
		(layer "In4.Cu")
	)
	(gr_circle
		(center 412.699962 -315.849762)
		(end 412.953962 -315.849762)
		(stroke
			(width 0.1016)
			(type default)
		)
		(fill no)
		(layer "In4.Cu")
	)
	(gr_circle
		(center 412.699962 -312.049922)
		(end 412.953962 -312.049922)
		(stroke
			(width 0.1016)
			(type default)
		)
		(fill no)
		(layer "In4.Cu")
	)
	(gr_circle
		(center 412.699962 -311.099962)
		(end 412.953962 -311.099962)
		(stroke
			(width 0.1016)
			(type default)
		)
		(fill no)
		(layer "In4.Cu")
	)
	(gr_circle
		(center 412.699962 -280.699464)
		(end 412.953962 -280.699464)
		(stroke
			(width 0.1016)
			(type default)
		)
		(fill no)
		(layer "In4.Cu")
	)
	(gr_circle
		(center 412.699962 -279.749504)
		(end 412.953962 -279.749504)
		(stroke
			(width 0.1016)
			(type default)
		)
		(fill no)
		(layer "In4.Cu")
	)
	(gr_circle
		(center 413.649668 -278.799798)
		(end 413.903668 -278.799798)
		(stroke
			(width 0.1016)
			(type default)
		)
		(fill no)
		(layer "In4.Cu")
	)
	(gr_circle
		(center 413.649668 -277.849838)
		(end 413.903668 -277.849838)
		(stroke
			(width 0.1016)
			(type default)
		)
		(fill no)
		(layer "In4.Cu")
	)
	(gr_circle
		(center 413.649668 -274.049744)
		(end 413.903668 -274.049744)
		(stroke
			(width 0.1016)
			(type default)
		)
		(fill no)
		(layer "In4.Cu")
	)
	(gr_circle
		(center 413.649668 -273.099784)
		(end 413.903668 -273.099784)
		(stroke
			(width 0.1016)
			(type default)
		)
		(fill no)
		(layer "In4.Cu")
	)
	(gr_circle
		(center 413.649922 -318.699896)
		(end 413.903922 -318.699896)
		(stroke
			(width 0.1016)
			(type default)
		)
		(fill no)
		(layer "In4.Cu")
	)
	(gr_circle
		(center 413.649922 -317.749936)
		(end 413.903922 -317.749936)
		(stroke
			(width 0.1016)
			(type default)
		)
		(fill no)
		(layer "In4.Cu")
	)
	(gr_circle
		(center 413.649922 -313.949842)
		(end 413.903922 -313.949842)
		(stroke
			(width 0.1016)
			(type default)
		)
		(fill no)
		(layer "In4.Cu")
	)
	(gr_circle
		(center 413.649922 -312.999882)
		(end 413.903922 -312.999882)
		(stroke
			(width 0.1016)
			(type default)
		)
		(fill no)
		(layer "In4.Cu")
	)
	(gr_circle
		(center 414.599628 -275.949918)
		(end 414.853628 -275.949918)
		(stroke
			(width 0.1016)
			(type default)
		)
		(fill no)
		(layer "In4.Cu")
	)
	(gr_circle
		(center 414.599628 -274.999958)
		(end 414.853628 -274.999958)
		(stroke
			(width 0.1016)
			(type default)
		)
		(fill no)
		(layer "In4.Cu")
	)
	(gr_circle
		(center 414.599882 -316.799722)
		(end 414.853882 -316.799722)
		(stroke
			(width 0.1016)
			(type default)
		)
		(fill no)
		(layer "In4.Cu")
	)
	(gr_circle
		(center 414.599882 -315.849762)
		(end 414.853882 -315.849762)
		(stroke
			(width 0.1016)
			(type default)
		)
		(fill no)
		(layer "In4.Cu")
	)
	(gr_circle
		(center 414.599882 -312.049922)
		(end 414.853882 -312.049922)
		(stroke
			(width 0.1016)
			(type default)
		)
		(fill no)
		(layer "In4.Cu")
	)
	(gr_circle
		(center 414.599882 -311.099962)
		(end 414.853882 -311.099962)
		(stroke
			(width 0.1016)
			(type default)
		)
		(fill no)
		(layer "In4.Cu")
	)
	(gr_circle
		(center 414.599882 -280.699464)
		(end 414.853882 -280.699464)
		(stroke
			(width 0.1016)
			(type default)
		)
		(fill no)
		(layer "In4.Cu")
	)
	(gr_circle
		(center 414.599882 -279.749504)
		(end 414.853882 -279.749504)
		(stroke
			(width 0.1016)
			(type default)
		)
		(fill no)
		(layer "In4.Cu")
	)
	(gr_circle
		(center 415.549588 -278.799798)
		(end 415.803588 -278.799798)
		(stroke
			(width 0.1016)
			(type default)
		)
		(fill no)
		(layer "In4.Cu")
	)
	(gr_circle
		(center 415.549588 -277.849838)
		(end 415.803588 -277.849838)
		(stroke
			(width 0.1016)
			(type default)
		)
		(fill no)
		(layer "In4.Cu")
	)
	(gr_circle
		(center 415.549588 -274.049744)
		(end 415.803588 -274.049744)
		(stroke
			(width 0.1016)
			(type default)
		)
		(fill no)
		(layer "In4.Cu")
	)
	(gr_circle
		(center 415.549588 -273.099784)
		(end 415.803588 -273.099784)
		(stroke
			(width 0.1016)
			(type default)
		)
		(fill no)
		(layer "In4.Cu")
	)
	(gr_circle
		(center 415.549842 -318.699896)
		(end 415.803842 -318.699896)
		(stroke
			(width 0.1016)
			(type default)
		)
		(fill no)
		(layer "In4.Cu")
	)
	(gr_circle
		(center 415.549842 -317.749936)
		(end 415.803842 -317.749936)
		(stroke
			(width 0.1016)
			(type default)
		)
		(fill no)
		(layer "In4.Cu")
	)
	(gr_circle
		(center 415.549842 -313.949842)
		(end 415.803842 -313.949842)
		(stroke
			(width 0.1016)
			(type default)
		)
		(fill no)
		(layer "In4.Cu")
	)
	(gr_circle
		(center 415.549842 -312.999882)
		(end 415.803842 -312.999882)
		(stroke
			(width 0.1016)
			(type default)
		)
		(fill no)
		(layer "In4.Cu")
	)
	(gr_circle
		(center 416.499548 -275.949664)
		(end 416.753548 -275.949664)
		(stroke
			(width 0.1016)
			(type default)
		)
		(fill no)
		(layer "In4.Cu")
	)
	(gr_circle
		(center 416.499548 -274.999704)
		(end 416.753548 -274.999704)
		(stroke
			(width 0.1016)
			(type default)
		)
		(fill no)
		(layer "In4.Cu")
	)
	(gr_circle
		(center 416.499802 -316.799722)
		(end 416.753802 -316.799722)
		(stroke
			(width 0.1016)
			(type default)
		)
		(fill no)
		(layer "In4.Cu")
	)
	(gr_circle
		(center 416.499802 -315.849762)
		(end 416.753802 -315.849762)
		(stroke
			(width 0.1016)
			(type default)
		)
		(fill no)
		(layer "In4.Cu")
	)
	(gr_circle
		(center 416.499802 -312.049922)
		(end 416.753802 -312.049922)
		(stroke
			(width 0.1016)
			(type default)
		)
		(fill no)
		(layer "In4.Cu")
	)
	(gr_circle
		(center 416.499802 -311.099962)
		(end 416.753802 -311.099962)
		(stroke
			(width 0.1016)
			(type default)
		)
		(fill no)
		(layer "In4.Cu")
	)
	(gr_circle
		(center 416.499802 -280.699464)
		(end 416.753802 -280.699464)
		(stroke
			(width 0.1016)
			(type default)
		)
		(fill no)
		(layer "In4.Cu")
	)
	(gr_circle
		(center 416.499802 -279.749504)
		(end 416.753802 -279.749504)
		(stroke
			(width 0.1016)
			(type default)
		)
		(fill no)
		(layer "In4.Cu")
	)
	(gr_circle
		(center 417.449762 -278.799798)
		(end 417.703762 -278.799798)
		(stroke
			(width 0.1016)
			(type default)
		)
		(fill no)
		(layer "In4.Cu")
	)
	(gr_circle
		(center 417.449762 -277.849838)
		(end 417.703762 -277.849838)
		(stroke
			(width 0.1016)
			(type default)
		)
		(fill no)
		(layer "In4.Cu")
	)
	(gr_circle
		(center 417.449762 -274.049744)
		(end 417.703762 -274.049744)
		(stroke
			(width 0.1016)
			(type default)
		)
		(fill no)
		(layer "In4.Cu")
	)
	(gr_circle
		(center 417.449762 -273.099784)
		(end 417.703762 -273.099784)
		(stroke
			(width 0.1016)
			(type default)
		)
		(fill no)
		(layer "In4.Cu")
	)
	(gr_circle
		(center 417.450016 -318.699896)
		(end 417.704016 -318.699896)
		(stroke
			(width 0.1016)
			(type default)
		)
		(fill no)
		(layer "In4.Cu")
	)
	(gr_circle
		(center 417.450016 -317.749936)
		(end 417.704016 -317.749936)
		(stroke
			(width 0.1016)
			(type default)
		)
		(fill no)
		(layer "In4.Cu")
	)
	(gr_circle
		(center 417.450016 -313.949842)
		(end 417.704016 -313.949842)
		(stroke
			(width 0.1016)
			(type default)
		)
		(fill no)
		(layer "In4.Cu")
	)
	(gr_circle
		(center 417.450016 -312.999882)
		(end 417.704016 -312.999882)
		(stroke
			(width 0.1016)
			(type default)
		)
		(fill no)
		(layer "In4.Cu")
	)
	(gr_circle
		(center 418.399468 -275.949918)
		(end 418.653468 -275.949918)
		(stroke
			(width 0.1016)
			(type default)
		)
		(fill no)
		(layer "In4.Cu")
	)
	(gr_circle
		(center 418.399468 -274.999958)
		(end 418.653468 -274.999958)
		(stroke
			(width 0.1016)
			(type default)
		)
		(fill no)
		(layer "In4.Cu")
	)
	(gr_circle
		(center 418.399976 -316.799722)
		(end 418.653976 -316.799722)
		(stroke
			(width 0.1016)
			(type default)
		)
		(fill no)
		(layer "In4.Cu")
	)
	(gr_circle
		(center 418.399976 -315.849762)
		(end 418.653976 -315.849762)
		(stroke
			(width 0.1016)
			(type default)
		)
		(fill no)
		(layer "In4.Cu")
	)
	(gr_circle
		(center 418.399976 -312.049922)
		(end 418.653976 -312.049922)
		(stroke
			(width 0.1016)
			(type default)
		)
		(fill no)
		(layer "In4.Cu")
	)
	(gr_circle
		(center 418.399976 -311.099962)
		(end 418.653976 -311.099962)
		(stroke
			(width 0.1016)
			(type default)
		)
		(fill no)
		(layer "In4.Cu")
	)
	(gr_circle
		(center 418.399976 -280.699464)
		(end 418.653976 -280.699464)
		(stroke
			(width 0.1016)
			(type default)
		)
		(fill no)
		(layer "In4.Cu")
	)
	(gr_circle
		(center 418.399976 -279.749504)
		(end 418.653976 -279.749504)
		(stroke
			(width 0.1016)
			(type default)
		)
		(fill no)
		(layer "In4.Cu")
	)
	(gr_circle
		(center 419.349682 -278.799798)
		(end 419.603682 -278.799798)
		(stroke
			(width 0.1016)
			(type default)
		)
		(fill no)
		(layer "In4.Cu")
	)
	(gr_circle
		(center 419.349682 -277.849838)
		(end 419.603682 -277.849838)
		(stroke
			(width 0.1016)
			(type default)
		)
		(fill no)
		(layer "In4.Cu")
	)
	(gr_circle
		(center 419.349682 -274.049744)
		(end 419.603682 -274.049744)
		(stroke
			(width 0.1016)
			(type default)
		)
		(fill no)
		(layer "In4.Cu")
	)
	(gr_circle
		(center 419.349682 -273.099784)
		(end 419.603682 -273.099784)
		(stroke
			(width 0.1016)
			(type default)
		)
		(fill no)
		(layer "In4.Cu")
	)
	(gr_circle
		(center 419.349936 -318.699896)
		(end 419.603936 -318.699896)
		(stroke
			(width 0.1016)
			(type default)
		)
		(fill no)
		(layer "In4.Cu")
	)
	(gr_circle
		(center 419.349936 -317.749936)
		(end 419.603936 -317.749936)
		(stroke
			(width 0.1016)
			(type default)
		)
		(fill no)
		(layer "In4.Cu")
	)
	(gr_circle
		(center 419.349936 -313.949842)
		(end 419.603936 -313.949842)
		(stroke
			(width 0.1016)
			(type default)
		)
		(fill no)
		(layer "In4.Cu")
	)
	(gr_circle
		(center 419.349936 -312.999882)
		(end 419.603936 -312.999882)
		(stroke
			(width 0.1016)
			(type default)
		)
		(fill no)
		(layer "In4.Cu")
	)
	(gr_circle
		(center 420.299642 -275.949664)
		(end 420.553642 -275.949664)
		(stroke
			(width 0.1016)
			(type default)
		)
		(fill no)
		(layer "In4.Cu")
	)
	(gr_circle
		(center 420.299642 -274.999704)
		(end 420.553642 -274.999704)
		(stroke
			(width 0.1016)
			(type default)
		)
		(fill no)
		(layer "In4.Cu")
	)
	(gr_circle
		(center 420.299896 -316.799722)
		(end 420.553896 -316.799722)
		(stroke
			(width 0.1016)
			(type default)
		)
		(fill no)
		(layer "In4.Cu")
	)
	(gr_circle
		(center 420.299896 -315.849762)
		(end 420.553896 -315.849762)
		(stroke
			(width 0.1016)
			(type default)
		)
		(fill no)
		(layer "In4.Cu")
	)
	(gr_circle
		(center 420.299896 -312.049922)
		(end 420.553896 -312.049922)
		(stroke
			(width 0.1016)
			(type default)
		)
		(fill no)
		(layer "In4.Cu")
	)
	(gr_circle
		(center 420.299896 -311.099962)
		(end 420.553896 -311.099962)
		(stroke
			(width 0.1016)
			(type default)
		)
		(fill no)
		(layer "In4.Cu")
	)
	(gr_circle
		(center 420.299896 -280.699464)
		(end 420.553896 -280.699464)
		(stroke
			(width 0.1016)
			(type default)
		)
		(fill no)
		(layer "In4.Cu")
	)
	(gr_circle
		(center 420.299896 -279.749504)
		(end 420.553896 -279.749504)
		(stroke
			(width 0.1016)
			(type default)
		)
		(fill no)
		(layer "In4.Cu")
	)
	(gr_circle
		(center 421.249602 -278.799798)
		(end 421.503602 -278.799798)
		(stroke
			(width 0.1016)
			(type default)
		)
		(fill no)
		(layer "In4.Cu")
	)
	(gr_circle
		(center 421.249602 -277.849838)
		(end 421.503602 -277.849838)
		(stroke
			(width 0.1016)
			(type default)
		)
		(fill no)
		(layer "In4.Cu")
	)
	(gr_circle
		(center 421.249602 -274.049744)
		(end 421.503602 -274.049744)
		(stroke
			(width 0.1016)
			(type default)
		)
		(fill no)
		(layer "In4.Cu")
	)
	(gr_circle
		(center 421.249602 -273.099784)
		(end 421.503602 -273.099784)
		(stroke
			(width 0.1016)
			(type default)
		)
		(fill no)
		(layer "In4.Cu")
	)
	(gr_circle
		(center 421.249856 -318.699896)
		(end 421.503856 -318.699896)
		(stroke
			(width 0.1016)
			(type default)
		)
		(fill no)
		(layer "In4.Cu")
	)
	(gr_circle
		(center 421.249856 -317.749936)
		(end 421.503856 -317.749936)
		(stroke
			(width 0.1016)
			(type default)
		)
		(fill no)
		(layer "In4.Cu")
	)
	(gr_circle
		(center 421.249856 -313.949842)
		(end 421.503856 -313.949842)
		(stroke
			(width 0.1016)
			(type default)
		)
		(fill no)
		(layer "In4.Cu")
	)
	(gr_circle
		(center 421.249856 -312.999882)
		(end 421.503856 -312.999882)
		(stroke
			(width 0.1016)
			(type default)
		)
		(fill no)
		(layer "In4.Cu")
	)
	(gr_circle
		(center 422.199562 -275.949918)
		(end 422.453562 -275.949918)
		(stroke
			(width 0.1016)
			(type default)
		)
		(fill no)
		(layer "In4.Cu")
	)
	(gr_circle
		(center 422.199562 -274.999958)
		(end 422.453562 -274.999958)
		(stroke
			(width 0.1016)
			(type default)
		)
		(fill no)
		(layer "In4.Cu")
	)
	(gr_circle
		(center 422.199816 -316.799722)
		(end 422.453816 -316.799722)
		(stroke
			(width 0.1016)
			(type default)
		)
		(fill no)
		(layer "In4.Cu")
	)
	(gr_circle
		(center 422.199816 -315.849762)
		(end 422.453816 -315.849762)
		(stroke
			(width 0.1016)
			(type default)
		)
		(fill no)
		(layer "In4.Cu")
	)
	(gr_circle
		(center 422.199816 -312.049922)
		(end 422.453816 -312.049922)
		(stroke
			(width 0.1016)
			(type default)
		)
		(fill no)
		(layer "In4.Cu")
	)
	(gr_circle
		(center 422.199816 -311.099962)
		(end 422.453816 -311.099962)
		(stroke
			(width 0.1016)
			(type default)
		)
		(fill no)
		(layer "In4.Cu")
	)
	(gr_circle
		(center 422.199816 -280.699464)
		(end 422.453816 -280.699464)
		(stroke
			(width 0.1016)
			(type default)
		)
		(fill no)
		(layer "In4.Cu")
	)
	(gr_circle
		(center 422.199816 -279.749504)
		(end 422.453816 -279.749504)
		(stroke
			(width 0.1016)
			(type default)
		)
		(fill no)
		(layer "In4.Cu")
	)
	(gr_circle
		(center 423.149776 -278.799798)
		(end 423.403776 -278.799798)
		(stroke
			(width 0.1016)
			(type default)
		)
		(fill no)
		(layer "In4.Cu")
	)
	(gr_circle
		(center 423.149776 -277.849838)
		(end 423.403776 -277.849838)
		(stroke
			(width 0.1016)
			(type default)
		)
		(fill no)
		(layer "In4.Cu")
	)
	(gr_circle
		(center 423.149776 -274.049744)
		(end 423.403776 -274.049744)
		(stroke
			(width 0.1016)
			(type default)
		)
		(fill no)
		(layer "In4.Cu")
	)
	(gr_circle
		(center 423.149776 -273.099784)
		(end 423.403776 -273.099784)
		(stroke
			(width 0.1016)
			(type default)
		)
		(fill no)
		(layer "In4.Cu")
	)
	(gr_circle
		(center 423.15003 -318.699896)
		(end 423.40403 -318.699896)
		(stroke
			(width 0.1016)
			(type default)
		)
		(fill no)
		(layer "In4.Cu")
	)
	(gr_circle
		(center 423.15003 -317.749936)
		(end 423.40403 -317.749936)
		(stroke
			(width 0.1016)
			(type default)
		)
		(fill no)
		(layer "In4.Cu")
	)
	(gr_circle
		(center 423.15003 -313.949842)
		(end 423.40403 -313.949842)
		(stroke
			(width 0.1016)
			(type default)
		)
		(fill no)
		(layer "In4.Cu")
	)
	(gr_circle
		(center 423.15003 -312.999882)
		(end 423.40403 -312.999882)
		(stroke
			(width 0.1016)
			(type default)
		)
		(fill no)
		(layer "In4.Cu")
	)
	(gr_circle
		(center 423.15003 -308.249828)
		(end 423.40403 -308.249828)
		(stroke
			(width 0.1016)
			(type default)
		)
		(fill no)
		(layer "In4.Cu")
	)
	(gr_circle
		(center 423.15003 -306.349908)
		(end 423.40403 -306.349908)
		(stroke
			(width 0.1016)
			(type default)
		)
		(fill no)
		(layer "In4.Cu")
	)
	(gr_circle
		(center 423.15003 -304.449734)
		(end 423.40403 -304.449734)
		(stroke
			(width 0.1016)
			(type default)
		)
		(fill no)
		(layer "In4.Cu")
	)
	(gr_circle
		(center 423.15003 -287.349946)
		(end 423.40403 -287.349946)
		(stroke
			(width 0.1016)
			(type default)
		)
		(fill no)
		(layer "In4.Cu")
	)
	(gr_circle
		(center 423.15003 -285.449772)
		(end 423.40403 -285.449772)
		(stroke
			(width 0.1016)
			(type default)
		)
		(fill no)
		(layer "In4.Cu")
	)
	(gr_circle
		(center 423.15003 -283.549852)
		(end 423.40403 -283.549852)
		(stroke
			(width 0.1016)
			(type default)
		)
		(fill no)
		(layer "In4.Cu")
	)
	(gr_circle
		(center 424.099736 -275.949664)
		(end 424.353736 -275.949664)
		(stroke
			(width 0.1016)
			(type default)
		)
		(fill no)
		(layer "In4.Cu")
	)
	(gr_circle
		(center 424.099736 -274.999704)
		(end 424.353736 -274.999704)
		(stroke
			(width 0.1016)
			(type default)
		)
		(fill no)
		(layer "In4.Cu")
	)
	(gr_circle
		(center 424.09999 -316.799722)
		(end 424.35399 -316.799722)
		(stroke
			(width 0.1016)
			(type default)
		)
		(fill no)
		(layer "In4.Cu")
	)
	(gr_circle
		(center 424.09999 -315.849762)
		(end 424.35399 -315.849762)
		(stroke
			(width 0.1016)
			(type default)
		)
		(fill no)
		(layer "In4.Cu")
	)
	(gr_circle
		(center 424.09999 -312.049922)
		(end 424.35399 -312.049922)
		(stroke
			(width 0.1016)
			(type default)
		)
		(fill no)
		(layer "In4.Cu")
	)
	(gr_circle
		(center 424.09999 -311.099962)
		(end 424.35399 -311.099962)
		(stroke
			(width 0.1016)
			(type default)
		)
		(fill no)
		(layer "In4.Cu")
	)
	(gr_circle
		(center 424.09999 -308.249828)
		(end 424.35399 -308.249828)
		(stroke
			(width 0.1016)
			(type default)
		)
		(fill no)
		(layer "In4.Cu")
	)
	(gr_circle
		(center 424.09999 -306.349908)
		(end 424.35399 -306.349908)
		(stroke
			(width 0.1016)
			(type default)
		)
		(fill no)
		(layer "In4.Cu")
	)
	(gr_circle
		(center 424.09999 -304.449734)
		(end 424.35399 -304.449734)
		(stroke
			(width 0.1016)
			(type default)
		)
		(fill no)
		(layer "In4.Cu")
	)
	(gr_circle
		(center 424.09999 -287.349946)
		(end 424.35399 -287.349946)
		(stroke
			(width 0.1016)
			(type default)
		)
		(fill no)
		(layer "In4.Cu")
	)
	(gr_circle
		(center 424.09999 -285.449772)
		(end 424.35399 -285.449772)
		(stroke
			(width 0.1016)
			(type default)
		)
		(fill no)
		(layer "In4.Cu")
	)
	(gr_circle
		(center 424.09999 -283.549852)
		(end 424.35399 -283.549852)
		(stroke
			(width 0.1016)
			(type default)
		)
		(fill no)
		(layer "In4.Cu")
	)
	(gr_circle
		(center 424.09999 -280.699464)
		(end 424.35399 -280.699464)
		(stroke
			(width 0.1016)
			(type default)
		)
		(fill no)
		(layer "In4.Cu")
	)
	(gr_circle
		(center 424.09999 -279.749504)
		(end 424.35399 -279.749504)
		(stroke
			(width 0.1016)
			(type default)
		)
		(fill no)
		(layer "In4.Cu")
	)
	(gr_circle
		(center 425.049696 -278.799798)
		(end 425.303696 -278.799798)
		(stroke
			(width 0.1016)
			(type default)
		)
		(fill no)
		(layer "In4.Cu")
	)
	(gr_circle
		(center 425.049696 -277.849838)
		(end 425.303696 -277.849838)
		(stroke
			(width 0.1016)
			(type default)
		)
		(fill no)
		(layer "In4.Cu")
	)
	(gr_circle
		(center 425.049696 -274.049744)
		(end 425.303696 -274.049744)
		(stroke
			(width 0.1016)
			(type default)
		)
		(fill no)
		(layer "In4.Cu")
	)
	(gr_circle
		(center 425.049696 -273.099784)
		(end 425.303696 -273.099784)
		(stroke
			(width 0.1016)
			(type default)
		)
		(fill no)
		(layer "In4.Cu")
	)
	(gr_circle
		(center 425.04995 -318.699896)
		(end 425.30395 -318.699896)
		(stroke
			(width 0.1016)
			(type default)
		)
		(fill no)
		(layer "In4.Cu")
	)
	(gr_circle
		(center 425.04995 -317.749936)
		(end 425.30395 -317.749936)
		(stroke
			(width 0.1016)
			(type default)
		)
		(fill no)
		(layer "In4.Cu")
	)
	(gr_circle
		(center 425.04995 -313.949842)
		(end 425.30395 -313.949842)
		(stroke
			(width 0.1016)
			(type default)
		)
		(fill no)
		(layer "In4.Cu")
	)
	(gr_circle
		(center 425.04995 -312.999882)
		(end 425.30395 -312.999882)
		(stroke
			(width 0.1016)
			(type default)
		)
		(fill no)
		(layer "In4.Cu")
	)
	(gr_circle
		(center 425.04995 -309.199788)
		(end 425.30395 -309.199788)
		(stroke
			(width 0.1016)
			(type default)
		)
		(fill no)
		(layer "In4.Cu")
	)
	(gr_circle
		(center 425.04995 -307.299868)
		(end 425.30395 -307.299868)
		(stroke
			(width 0.1016)
			(type default)
		)
		(fill no)
		(layer "In4.Cu")
	)
	(gr_circle
		(center 425.04995 -305.399948)
		(end 425.30395 -305.399948)
		(stroke
			(width 0.1016)
			(type default)
		)
		(fill no)
		(layer "In4.Cu")
	)
	(gr_circle
		(center 425.04995 -288.299906)
		(end 425.30395 -288.299906)
		(stroke
			(width 0.1016)
			(type default)
		)
		(fill no)
		(layer "In4.Cu")
	)
	(gr_circle
		(center 425.04995 -286.399986)
		(end 425.30395 -286.399986)
		(stroke
			(width 0.1016)
			(type default)
		)
		(fill no)
		(layer "In4.Cu")
	)
	(gr_circle
		(center 425.04995 -284.499812)
		(end 425.30395 -284.499812)
		(stroke
			(width 0.1016)
			(type default)
		)
		(fill no)
		(layer "In4.Cu")
	)
	(gr_circle
		(center 425.04995 -282.599892)
		(end 425.30395 -282.599892)
		(stroke
			(width 0.1016)
			(type default)
		)
		(fill no)
		(layer "In4.Cu")
	)
	(gr_circle
		(center 425.999656 -275.949918)
		(end 426.253656 -275.949918)
		(stroke
			(width 0.1016)
			(type default)
		)
		(fill no)
		(layer "In4.Cu")
	)
	(gr_circle
		(center 425.999656 -274.999958)
		(end 426.253656 -274.999958)
		(stroke
			(width 0.1016)
			(type default)
		)
		(fill no)
		(layer "In4.Cu")
	)
	(gr_circle
		(center 425.99991 -316.799722)
		(end 426.25391 -316.799722)
		(stroke
			(width 0.1016)
			(type default)
		)
		(fill no)
		(layer "In4.Cu")
	)
	(gr_circle
		(center 425.99991 -315.849762)
		(end 426.25391 -315.849762)
		(stroke
			(width 0.1016)
			(type default)
		)
		(fill no)
		(layer "In4.Cu")
	)
	(gr_circle
		(center 425.99991 -312.049922)
		(end 426.25391 -312.049922)
		(stroke
			(width 0.1016)
			(type default)
		)
		(fill no)
		(layer "In4.Cu")
	)
	(gr_circle
		(center 425.99991 -311.099962)
		(end 426.25391 -311.099962)
		(stroke
			(width 0.1016)
			(type default)
		)
		(fill no)
		(layer "In4.Cu")
	)
	(gr_circle
		(center 425.99991 -309.199788)
		(end 426.25391 -309.199788)
		(stroke
			(width 0.1016)
			(type default)
		)
		(fill no)
		(layer "In4.Cu")
	)
	(gr_circle
		(center 425.99991 -307.299868)
		(end 426.25391 -307.299868)
		(stroke
			(width 0.1016)
			(type default)
		)
		(fill no)
		(layer "In4.Cu")
	)
	(gr_circle
		(center 425.99991 -305.399948)
		(end 426.25391 -305.399948)
		(stroke
			(width 0.1016)
			(type default)
		)
		(fill no)
		(layer "In4.Cu")
	)
	(gr_circle
		(center 425.99991 -288.299906)
		(end 426.25391 -288.299906)
		(stroke
			(width 0.1016)
			(type default)
		)
		(fill no)
		(layer "In4.Cu")
	)
	(gr_circle
		(center 425.99991 -286.399986)
		(end 426.25391 -286.399986)
		(stroke
			(width 0.1016)
			(type default)
		)
		(fill no)
		(layer "In4.Cu")
	)
	(gr_circle
		(center 425.99991 -284.499812)
		(end 426.25391 -284.499812)
		(stroke
			(width 0.1016)
			(type default)
		)
		(fill no)
		(layer "In4.Cu")
	)
	(gr_circle
		(center 425.99991 -282.599892)
		(end 426.25391 -282.599892)
		(stroke
			(width 0.1016)
			(type default)
		)
		(fill no)
		(layer "In4.Cu")
	)
	(gr_circle
		(center 425.99991 -280.699464)
		(end 426.25391 -280.699464)
		(stroke
			(width 0.1016)
			(type default)
		)
		(fill no)
		(layer "In4.Cu")
	)
	(gr_circle
		(center 425.99991 -279.749504)
		(end 426.25391 -279.749504)
		(stroke
			(width 0.1016)
			(type default)
		)
		(fill no)
		(layer "In4.Cu")
	)
	(gr_circle
		(center 426.949616 -278.799798)
		(end 427.203616 -278.799798)
		(stroke
			(width 0.1016)
			(type default)
		)
		(fill no)
		(layer "In4.Cu")
	)
	(gr_circle
		(center 426.949616 -277.849838)
		(end 427.203616 -277.849838)
		(stroke
			(width 0.1016)
			(type default)
		)
		(fill no)
		(layer "In4.Cu")
	)
	(gr_circle
		(center 426.949616 -274.049744)
		(end 427.203616 -274.049744)
		(stroke
			(width 0.1016)
			(type default)
		)
		(fill no)
		(layer "In4.Cu")
	)
	(gr_circle
		(center 426.949616 -273.099784)
		(end 427.203616 -273.099784)
		(stroke
			(width 0.1016)
			(type default)
		)
		(fill no)
		(layer "In4.Cu")
	)
	(gr_circle
		(center 426.94987 -318.699896)
		(end 427.20387 -318.699896)
		(stroke
			(width 0.1016)
			(type default)
		)
		(fill no)
		(layer "In4.Cu")
	)
	(gr_circle
		(center 426.94987 -317.749936)
		(end 427.20387 -317.749936)
		(stroke
			(width 0.1016)
			(type default)
		)
		(fill no)
		(layer "In4.Cu")
	)
	(gr_circle
		(center 426.94987 -313.949842)
		(end 427.20387 -313.949842)
		(stroke
			(width 0.1016)
			(type default)
		)
		(fill no)
		(layer "In4.Cu")
	)
	(gr_circle
		(center 426.94987 -312.999882)
		(end 427.20387 -312.999882)
		(stroke
			(width 0.1016)
			(type default)
		)
		(fill no)
		(layer "In4.Cu")
	)
	(gr_circle
		(center 427.899576 -275.949918)
		(end 428.153576 -275.949918)
		(stroke
			(width 0.1016)
			(type default)
		)
		(fill no)
		(layer "In4.Cu")
	)
	(gr_circle
		(center 427.899576 -274.999958)
		(end 428.153576 -274.999958)
		(stroke
			(width 0.1016)
			(type default)
		)
		(fill no)
		(layer "In4.Cu")
	)
	(gr_circle
		(center 427.89983 -316.799722)
		(end 428.15383 -316.799722)
		(stroke
			(width 0.1016)
			(type default)
		)
		(fill no)
		(layer "In4.Cu")
	)
	(gr_circle
		(center 427.89983 -315.849762)
		(end 428.15383 -315.849762)
		(stroke
			(width 0.1016)
			(type default)
		)
		(fill no)
		(layer "In4.Cu")
	)
	(gr_circle
		(center 427.89983 -312.049922)
		(end 428.15383 -312.049922)
		(stroke
			(width 0.1016)
			(type default)
		)
		(fill no)
		(layer "In4.Cu")
	)
	(gr_circle
		(center 427.89983 -311.099962)
		(end 428.15383 -311.099962)
		(stroke
			(width 0.1016)
			(type default)
		)
		(fill no)
		(layer "In4.Cu")
	)
	(gr_circle
		(center 427.89983 -309.199788)
		(end 428.15383 -309.199788)
		(stroke
			(width 0.1016)
			(type default)
		)
		(fill no)
		(layer "In4.Cu")
	)
	(gr_circle
		(center 427.89983 -307.299868)
		(end 428.15383 -307.299868)
		(stroke
			(width 0.1016)
			(type default)
		)
		(fill no)
		(layer "In4.Cu")
	)
	(gr_circle
		(center 427.89983 -305.399948)
		(end 428.15383 -305.399948)
		(stroke
			(width 0.1016)
			(type default)
		)
		(fill no)
		(layer "In4.Cu")
	)
	(gr_circle
		(center 427.89983 -288.299906)
		(end 428.15383 -288.299906)
		(stroke
			(width 0.1016)
			(type default)
		)
		(fill no)
		(layer "In4.Cu")
	)
	(gr_circle
		(center 427.89983 -286.399732)
		(end 428.15383 -286.399732)
		(stroke
			(width 0.1016)
			(type default)
		)
		(fill no)
		(layer "In4.Cu")
	)
	(gr_circle
		(center 427.89983 -284.499812)
		(end 428.15383 -284.499812)
		(stroke
			(width 0.1016)
			(type default)
		)
		(fill no)
		(layer "In4.Cu")
	)
	(gr_circle
		(center 427.89983 -282.599892)
		(end 428.15383 -282.599892)
		(stroke
			(width 0.1016)
			(type default)
		)
		(fill no)
		(layer "In4.Cu")
	)
	(gr_circle
		(center 427.89983 -280.699718)
		(end 428.15383 -280.699718)
		(stroke
			(width 0.1016)
			(type default)
		)
		(fill no)
		(layer "In4.Cu")
	)
	(gr_circle
		(center 427.89983 -279.749758)
		(end 428.15383 -279.749758)
		(stroke
			(width 0.1016)
			(type default)
		)
		(fill no)
		(layer "In4.Cu")
	)
	(gr_circle
		(center 428.849536 -274.049744)
		(end 429.103536 -274.049744)
		(stroke
			(width 0.1016)
			(type default)
		)
		(fill no)
		(layer "In4.Cu")
	)
	(gr_circle
		(center 428.849536 -273.099784)
		(end 429.103536 -273.099784)
		(stroke
			(width 0.1016)
			(type default)
		)
		(fill no)
		(layer "In4.Cu")
	)
	(gr_circle
		(center 428.84979 -318.699896)
		(end 429.10379 -318.699896)
		(stroke
			(width 0.1016)
			(type default)
		)
		(fill no)
		(layer "In4.Cu")
	)
	(gr_circle
		(center 428.84979 -317.749936)
		(end 429.10379 -317.749936)
		(stroke
			(width 0.1016)
			(type default)
		)
		(fill no)
		(layer "In4.Cu")
	)
	(gr_circle
		(center 428.84979 -313.949842)
		(end 429.10379 -313.949842)
		(stroke
			(width 0.1016)
			(type default)
		)
		(fill no)
		(layer "In4.Cu")
	)
	(gr_circle
		(center 428.84979 -312.999882)
		(end 429.10379 -312.999882)
		(stroke
			(width 0.1016)
			(type default)
		)
		(fill no)
		(layer "In4.Cu")
	)
	(gr_circle
		(center 428.84979 -309.199788)
		(end 429.10379 -309.199788)
		(stroke
			(width 0.1016)
			(type default)
		)
		(fill no)
		(layer "In4.Cu")
	)
	(gr_circle
		(center 428.84979 -307.299868)
		(end 429.10379 -307.299868)
		(stroke
			(width 0.1016)
			(type default)
		)
		(fill no)
		(layer "In4.Cu")
	)
	(gr_circle
		(center 428.84979 -305.399948)
		(end 429.10379 -305.399948)
		(stroke
			(width 0.1016)
			(type default)
		)
		(fill no)
		(layer "In4.Cu")
	)
	(gr_circle
		(center 428.84979 -288.299906)
		(end 429.10379 -288.299906)
		(stroke
			(width 0.1016)
			(type default)
		)
		(fill no)
		(layer "In4.Cu")
	)
	(gr_circle
		(center 428.84979 -286.399732)
		(end 429.10379 -286.399732)
		(stroke
			(width 0.1016)
			(type default)
		)
		(fill no)
		(layer "In4.Cu")
	)
	(gr_circle
		(center 428.84979 -284.499812)
		(end 429.10379 -284.499812)
		(stroke
			(width 0.1016)
			(type default)
		)
		(fill no)
		(layer "In4.Cu")
	)
	(gr_circle
		(center 428.84979 -282.599892)
		(end 429.10379 -282.599892)
		(stroke
			(width 0.1016)
			(type default)
		)
		(fill no)
		(layer "In4.Cu")
	)
	(gr_circle
		(center 428.84979 -278.799798)
		(end 429.10379 -278.799798)
		(stroke
			(width 0.1016)
			(type default)
		)
		(fill no)
		(layer "In4.Cu")
	)
	(gr_circle
		(center 428.84979 -277.849838)
		(end 429.10379 -277.849838)
		(stroke
			(width 0.1016)
			(type default)
		)
		(fill no)
		(layer "In4.Cu")
	)
	(gr_circle
		(center 429.800004 -316.799722)
		(end 430.054004 -316.799722)
		(stroke
			(width 0.1016)
			(type default)
		)
		(fill no)
		(layer "In4.Cu")
	)
	(gr_circle
		(center 429.800004 -314.899802)
		(end 430.054004 -314.899802)
		(stroke
			(width 0.1016)
			(type default)
		)
		(fill no)
		(layer "In4.Cu")
	)
	(gr_circle
		(center 429.800004 -312.049922)
		(end 430.054004 -312.049922)
		(stroke
			(width 0.1016)
			(type default)
		)
		(fill no)
		(layer "In4.Cu")
	)
	(gr_circle
		(center 429.800004 -310.149748)
		(end 430.054004 -310.149748)
		(stroke
			(width 0.1016)
			(type default)
		)
		(fill no)
		(layer "In4.Cu")
	)
	(gr_circle
		(center 429.800004 -308.249828)
		(end 430.054004 -308.249828)
		(stroke
			(width 0.1016)
			(type default)
		)
		(fill no)
		(layer "In4.Cu")
	)
	(gr_circle
		(center 429.800004 -306.349908)
		(end 430.054004 -306.349908)
		(stroke
			(width 0.1016)
			(type default)
		)
		(fill no)
		(layer "In4.Cu")
	)
	(gr_circle
		(center 429.800004 -304.449734)
		(end 430.054004 -304.449734)
		(stroke
			(width 0.1016)
			(type default)
		)
		(fill no)
		(layer "In4.Cu")
	)
	(gr_circle
		(center 429.800004 -287.349946)
		(end 430.054004 -287.349946)
		(stroke
			(width 0.1016)
			(type default)
		)
		(fill no)
		(layer "In4.Cu")
	)
	(gr_circle
		(center 429.800004 -285.449772)
		(end 430.054004 -285.449772)
		(stroke
			(width 0.1016)
			(type default)
		)
		(fill no)
		(layer "In4.Cu")
	)
	(gr_circle
		(center 429.800004 -283.549852)
		(end 430.054004 -283.549852)
		(stroke
			(width 0.1016)
			(type default)
		)
		(fill no)
		(layer "In4.Cu")
	)
	(gr_circle
		(center 429.800004 -281.649932)
		(end 430.054004 -281.649932)
		(stroke
			(width 0.1016)
			(type default)
		)
		(fill no)
		(layer "In4.Cu")
	)
	(gr_circle
		(center 429.800004 -279.749758)
		(end 430.054004 -279.749758)
		(stroke
			(width 0.1016)
			(type default)
		)
		(fill no)
		(layer "In4.Cu")
	)
	(gr_circle
		(center 429.800004 -276.899878)
		(end 430.054004 -276.899878)
		(stroke
			(width 0.1016)
			(type default)
		)
		(fill no)
		(layer "In4.Cu")
	)
	(gr_circle
		(center 429.800004 -274.999704)
		(end 430.054004 -274.999704)
		(stroke
			(width 0.1016)
			(type default)
		)
		(fill no)
		(layer "In4.Cu")
	)
	(gr_circle
		(center 430.749964 -316.799722)
		(end 431.003964 -316.799722)
		(stroke
			(width 0.1016)
			(type default)
		)
		(fill no)
		(layer "In4.Cu")
	)
	(gr_circle
		(center 430.749964 -314.899802)
		(end 431.003964 -314.899802)
		(stroke
			(width 0.1016)
			(type default)
		)
		(fill no)
		(layer "In4.Cu")
	)
	(gr_circle
		(center 430.749964 -312.049922)
		(end 431.003964 -312.049922)
		(stroke
			(width 0.1016)
			(type default)
		)
		(fill no)
		(layer "In4.Cu")
	)
	(gr_circle
		(center 430.749964 -310.149748)
		(end 431.003964 -310.149748)
		(stroke
			(width 0.1016)
			(type default)
		)
		(fill no)
		(layer "In4.Cu")
	)
	(gr_circle
		(center 430.749964 -308.249828)
		(end 431.003964 -308.249828)
		(stroke
			(width 0.1016)
			(type default)
		)
		(fill no)
		(layer "In4.Cu")
	)
	(gr_circle
		(center 430.749964 -306.349908)
		(end 431.003964 -306.349908)
		(stroke
			(width 0.1016)
			(type default)
		)
		(fill no)
		(layer "In4.Cu")
	)
	(gr_circle
		(center 430.749964 -304.449734)
		(end 431.003964 -304.449734)
		(stroke
			(width 0.1016)
			(type default)
		)
		(fill no)
		(layer "In4.Cu")
	)
	(gr_circle
		(center 430.749964 -287.349946)
		(end 431.003964 -287.349946)
		(stroke
			(width 0.1016)
			(type default)
		)
		(fill no)
		(layer "In4.Cu")
	)
	(gr_circle
		(center 430.749964 -285.449772)
		(end 431.003964 -285.449772)
		(stroke
			(width 0.1016)
			(type default)
		)
		(fill no)
		(layer "In4.Cu")
	)
	(gr_circle
		(center 430.749964 -283.549852)
		(end 431.003964 -283.549852)
		(stroke
			(width 0.1016)
			(type default)
		)
		(fill no)
		(layer "In4.Cu")
	)
	(gr_circle
		(center 430.749964 -281.649932)
		(end 431.003964 -281.649932)
		(stroke
			(width 0.1016)
			(type default)
		)
		(fill no)
		(layer "In4.Cu")
	)
	(gr_circle
		(center 430.749964 -279.749758)
		(end 431.003964 -279.749758)
		(stroke
			(width 0.1016)
			(type default)
		)
		(fill no)
		(layer "In4.Cu")
	)
	(gr_circle
		(center 430.749964 -276.899878)
		(end 431.003964 -276.899878)
		(stroke
			(width 0.1016)
			(type default)
		)
		(fill no)
		(layer "In4.Cu")
	)
	(gr_circle
		(center 430.749964 -274.999704)
		(end 431.003964 -274.999704)
		(stroke
			(width 0.1016)
			(type default)
		)
		(fill no)
		(layer "In4.Cu")
	)
	(gr_poly
		(pts
			(xy 224.426018 -276.559264) (xy 227.55733 -273.427952) (xy 229.236778 -273.427952) (xy 230.066342 -272.598388)
			(xy 230.066342 -262.325866) (xy 229.45217 -261.711694) (xy 226.527868 -261.711694) (xy 226.520756 -261.704328)
			(xy 226.50196 -261.696708) (xy 220.295978 -261.696708) (xy 219.061284 -261.696708) (xy 218.3384 -262.419592)
			(xy 218.3384 -277.56993) (xy 218.355164 -277.586694) (xy 223.398588 -277.586694)
		)
		(stroke
			(width 0)
			(type solid)
		)
		(fill yes)
		(layer "In5.Cu")
		(net "P1V25_PEX1")
	)
	(gr_poly
		(pts
			(xy 15.043912 -258.651756)
			(arc
				(start 15.043912 -255.042924)
				(mid 15.039962 -255.023537)
				(end 15.028926 -255.00711)
			)
			(xy 14.884654 -254.862838) (xy 14.877542 -254.855472) (xy 14.858746 -254.847852)
			(arc
				(start 2.824988 -254.847852)
				(mid 2.805465 -254.851753)
				(end 2.78892 -254.862838)
			)
			(arc
				(start 1.942592 -255.709166)
				(mid 1.931481 -255.7257)
				(end 1.927606 -255.745234)
			)
			(xy 1.927606 -258.844796) (xy 2.001266 -258.918456) (xy 14.777212 -258.918456)
		)
		(stroke
			(width 0)
			(type solid)
		)
		(fill yes)
		(layer "In5.Cu")
		(net "P1V25_SERDES_VDDPLL_PEX0")
	)
	(gr_poly
		(pts
			(arc
				(start 220.049344 -261.131558)
				(mid 220.065878 -261.120447)
				(end 220.085412 -261.116572)
			)
			(xy 226.522534 -261.116572) (xy 229.762812 -261.116572) (xy 230.331264 -260.54812)
			(arc
				(start 230.331264 -257.558032)
				(mid 230.327363 -257.538509)
				(end 230.316278 -257.521964)
			)
			(arc
				(start 229.943914 -257.1496)
				(mid 229.92738 -257.138489)
				(end 229.907846 -257.134614)
			)
			(xy 219.311728 -257.134614) (xy 217.703908 -258.742434) (xy 217.703908 -260.89864) (xy 217.93708 -261.131558)
		)
		(stroke
			(width 0)
			(type solid)
		)
		(fill yes)
		(layer "In5.Cu")
		(net "P1V25_SERDES_VDDPLL_PEX1")
	)
	(gr_poly
		(pts
			(arc
				(start 81.738724 -114.102134)
				(mid 81.764753 -114.115944)
				(end 81.794096 -114.113056)
			)
			(xy 81.808574 -114.10696) (xy 81.825592 -114.081814)
			(arc
				(start 81.825592 -110.304834)
				(mid 81.81699 -110.27655)
				(end 81.794096 -110.257844)
			)
			(xy 81.779618 -110.252002) (xy 81.7499 -110.257844)
			(arc
				(start 81.536286 -110.471458)
				(mid 81.525224 -110.487875)
				(end 81.5213 -110.507272)
			)
			(arc
				(start 81.5213 -113.863628)
				(mid 81.52525 -113.883015)
				(end 81.536286 -113.899442)
			)
		)
		(stroke
			(width 0)
			(type solid)
		)
		(fill yes)
		(layer "In5.Cu")
		(net "GND")
	)
	(gr_poly
		(pts
			(arc
				(start 87.935816 -117.430296)
				(mid 87.961845 -117.444106)
				(end 87.991188 -117.441218)
			)
			(xy 88.005666 -117.435122) (xy 88.022684 -117.409976)
			(arc
				(start 88.022684 -116.351304)
				(mid 88.018734 -116.331917)
				(end 88.007698 -116.31549)
			)
			(arc
				(start 87.939118 -116.24691)
				(mid 87.922701 -116.235848)
				(end 87.903304 -116.231924)
			)
			(arc
				(start 86.86038 -116.231924)
				(mid 86.832096 -116.240526)
				(end 86.81339 -116.26342)
			)
			(xy 86.807548 -116.277898) (xy 86.81339 -116.307616)
		)
		(stroke
			(width 0)
			(type solid)
		)
		(fill yes)
		(layer "In5.Cu")
		(net "GND")
	)
	(gr_poly
		(pts
			(arc
				(start 104.515158 -196.809106)
				(mid 104.541187 -196.822916)
				(end 104.57053 -196.820028)
			)
			(xy 104.585008 -196.813932) (xy 104.601772 -196.788786)
			(arc
				(start 104.601772 -195.783454)
				(mid 104.597939 -195.764097)
				(end 104.58704 -195.74764)
			)
			(arc
				(start 103.72471 -194.88531)
				(mid 103.708293 -194.874248)
				(end 103.688896 -194.870324)
			)
			(arc
				(start 102.699312 -194.870324)
				(mid 102.671028 -194.878926)
				(end 102.652322 -194.90182)
			)
			(xy 102.64648 -194.916298) (xy 102.652322 -194.946016)
		)
		(stroke
			(width 0)
			(type solid)
		)
		(fill yes)
		(layer "In5.Cu")
		(net "GND")
	)
	(gr_poly
		(pts
			(arc
				(start 231.535986 -203.32954)
				(mid 231.278938 -203.32954)
				(end 231.535986 -203.32954)
			)
		)
		(stroke
			(width 0)
			(type solid)
		)
		(fill yes)
		(layer "In5.Cu")
		(net "GND")
	)
	(gr_poly
		(pts
			(arc
				(start 17.61236 -402.208492)
				(mid 17.309084 -402.208492)
				(end 17.61236 -402.208492)
			)
		)
		(stroke
			(width 0)
			(type solid)
		)
		(fill yes)
		(layer "In5.Cu")
		(net "GND")
	)
	(gr_poly
		(pts
			(arc
				(start 19.456908 -401.49272)
				(mid 19.153632 -401.49272)
				(end 19.456908 -401.49272)
			)
		)
		(stroke
			(width 0)
			(type solid)
		)
		(fill yes)
		(layer "In5.Cu")
		(net "GND")
	)
	(gr_poly
		(pts
			(arc
				(start 21.08962 -401.46986)
				(mid 20.786344 -401.46986)
				(end 21.08962 -401.46986)
			)
		)
		(stroke
			(width 0)
			(type solid)
		)
		(fill yes)
		(layer "In5.Cu")
		(net "GND")
	)
	(gr_poly
		(pts
			(arc
				(start 44.822872 -29.311854)
				(mid 44.519596 -29.311854)
				(end 44.822872 -29.311854)
			)
		)
		(stroke
			(width 0)
			(type solid)
		)
		(fill yes)
		(layer "In5.Cu")
		(net "GND")
	)
	(gr_poly
		(pts
			(arc
				(start 44.822872 -28.05303)
				(mid 44.519596 -28.05303)
				(end 44.822872 -28.05303)
			)
		)
		(stroke
			(width 0)
			(type solid)
		)
		(fill yes)
		(layer "In5.Cu")
		(net "GND")
	)
	(gr_poly
		(pts
			(arc
				(start 46.09084 -29.311854)
				(mid 45.787564 -29.311854)
				(end 46.09084 -29.311854)
			)
		)
		(stroke
			(width 0)
			(type solid)
		)
		(fill yes)
		(layer "In5.Cu")
		(net "GND")
	)
	(gr_poly
		(pts
			(arc
				(start 46.09084 -28.05303)
				(mid 45.787564 -28.05303)
				(end 46.09084 -28.05303)
			)
		)
		(stroke
			(width 0)
			(type solid)
		)
		(fill yes)
		(layer "In5.Cu")
		(net "GND")
	)
	(gr_poly
		(pts
			(arc
				(start 47.46498 -31.118302)
				(mid 47.161704 -31.118302)
				(end 47.46498 -31.118302)
			)
		)
		(stroke
			(width 0)
			(type solid)
		)
		(fill yes)
		(layer "In5.Cu")
		(net "GND")
	)
	(gr_poly
		(pts
			(arc
				(start 47.46498 -29.859478)
				(mid 47.161704 -29.859478)
				(end 47.46498 -29.859478)
			)
		)
		(stroke
			(width 0)
			(type solid)
		)
		(fill yes)
		(layer "In5.Cu")
		(net "GND")
	)
	(gr_poly
		(pts
			(arc
				(start 48.732948 -31.118302)
				(mid 48.429672 -31.118302)
				(end 48.732948 -31.118302)
			)
		)
		(stroke
			(width 0)
			(type solid)
		)
		(fill yes)
		(layer "In5.Cu")
		(net "GND")
	)
	(gr_poly
		(pts
			(arc
				(start 48.732948 -29.859478)
				(mid 48.429672 -29.859478)
				(end 48.732948 -29.859478)
			)
		)
		(stroke
			(width 0)
			(type solid)
		)
		(fill yes)
		(layer "In5.Cu")
		(net "GND")
	)
	(gr_poly
		(pts
			(arc
				(start 56.77027 -381.515112)
				(mid 56.466994 -381.515112)
				(end 56.77027 -381.515112)
			)
		)
		(stroke
			(width 0)
			(type solid)
		)
		(fill yes)
		(layer "In5.Cu")
		(net "GND")
	)
	(gr_poly
		(pts
			(arc
				(start 56.853328 -382.71958)
				(mid 56.550052 -382.71958)
				(end 56.853328 -382.71958)
			)
		)
		(stroke
			(width 0)
			(type solid)
		)
		(fill yes)
		(layer "In5.Cu")
		(net "GND")
	)
	(gr_poly
		(pts
			(arc
				(start 70.82282 -32.911796)
				(mid 70.519544 -32.911796)
				(end 70.82282 -32.911796)
			)
		)
		(stroke
			(width 0)
			(type solid)
		)
		(fill yes)
		(layer "In5.Cu")
		(net "GND")
	)
	(gr_poly
		(pts
			(arc
				(start 70.82282 -31.652972)
				(mid 70.519544 -31.652972)
				(end 70.82282 -31.652972)
			)
		)
		(stroke
			(width 0)
			(type solid)
		)
		(fill yes)
		(layer "In5.Cu")
		(net "GND")
	)
	(gr_poly
		(pts
			(arc
				(start 70.82282 -29.311854)
				(mid 70.519544 -29.311854)
				(end 70.82282 -29.311854)
			)
		)
		(stroke
			(width 0)
			(type solid)
		)
		(fill yes)
		(layer "In5.Cu")
		(net "GND")
	)
	(gr_poly
		(pts
			(arc
				(start 70.82282 -28.05303)
				(mid 70.519544 -28.05303)
				(end 70.82282 -28.05303)
			)
		)
		(stroke
			(width 0)
			(type solid)
		)
		(fill yes)
		(layer "In5.Cu")
		(net "GND")
	)
	(gr_poly
		(pts
			(arc
				(start 72.090788 -32.911796)
				(mid 71.787512 -32.911796)
				(end 72.090788 -32.911796)
			)
		)
		(stroke
			(width 0)
			(type solid)
		)
		(fill yes)
		(layer "In5.Cu")
		(net "GND")
	)
	(gr_poly
		(pts
			(arc
				(start 72.090788 -31.652972)
				(mid 71.787512 -31.652972)
				(end 72.090788 -31.652972)
			)
		)
		(stroke
			(width 0)
			(type solid)
		)
		(fill yes)
		(layer "In5.Cu")
		(net "GND")
	)
	(gr_poly
		(pts
			(arc
				(start 72.090788 -29.311854)
				(mid 71.787512 -29.311854)
				(end 72.090788 -29.311854)
			)
		)
		(stroke
			(width 0)
			(type solid)
		)
		(fill yes)
		(layer "In5.Cu")
		(net "GND")
	)
	(gr_poly
		(pts
			(arc
				(start 72.090788 -28.05303)
				(mid 71.787512 -28.05303)
				(end 72.090788 -28.05303)
			)
		)
		(stroke
			(width 0)
			(type solid)
		)
		(fill yes)
		(layer "In5.Cu")
		(net "GND")
	)
	(gr_poly
		(pts
			(arc
				(start 73.464928 -34.718498)
				(mid 73.161652 -34.718498)
				(end 73.464928 -34.718498)
			)
		)
		(stroke
			(width 0)
			(type solid)
		)
		(fill yes)
		(layer "In5.Cu")
		(net "GND")
	)
	(gr_poly
		(pts
			(arc
				(start 73.464928 -33.459674)
				(mid 73.161652 -33.459674)
				(end 73.464928 -33.459674)
			)
		)
		(stroke
			(width 0)
			(type solid)
		)
		(fill yes)
		(layer "In5.Cu")
		(net "GND")
	)
	(gr_poly
		(pts
			(arc
				(start 73.464928 -31.118302)
				(mid 73.161652 -31.118302)
				(end 73.464928 -31.118302)
			)
		)
		(stroke
			(width 0)
			(type solid)
		)
		(fill yes)
		(layer "In5.Cu")
		(net "GND")
	)
	(gr_poly
		(pts
			(arc
				(start 73.464928 -29.859478)
				(mid 73.161652 -29.859478)
				(end 73.464928 -29.859478)
			)
		)
		(stroke
			(width 0)
			(type solid)
		)
		(fill yes)
		(layer "In5.Cu")
		(net "GND")
	)
	(gr_poly
		(pts
			(arc
				(start 74.732896 -34.718498)
				(mid 74.42962 -34.718498)
				(end 74.732896 -34.718498)
			)
		)
		(stroke
			(width 0)
			(type solid)
		)
		(fill yes)
		(layer "In5.Cu")
		(net "GND")
	)
	(gr_poly
		(pts
			(arc
				(start 74.732896 -33.459674)
				(mid 74.42962 -33.459674)
				(end 74.732896 -33.459674)
			)
		)
		(stroke
			(width 0)
			(type solid)
		)
		(fill yes)
		(layer "In5.Cu")
		(net "GND")
	)
	(gr_poly
		(pts
			(arc
				(start 74.732896 -31.118302)
				(mid 74.42962 -31.118302)
				(end 74.732896 -31.118302)
			)
		)
		(stroke
			(width 0)
			(type solid)
		)
		(fill yes)
		(layer "In5.Cu")
		(net "GND")
	)
	(gr_poly
		(pts
			(arc
				(start 74.732896 -29.859478)
				(mid 74.42962 -29.859478)
				(end 74.732896 -29.859478)
			)
		)
		(stroke
			(width 0)
			(type solid)
		)
		(fill yes)
		(layer "In5.Cu")
		(net "GND")
	)
	(gr_poly
		(pts
			(arc
				(start 96.822768 -32.911796)
				(mid 96.519492 -32.911796)
				(end 96.822768 -32.911796)
			)
		)
		(stroke
			(width 0)
			(type solid)
		)
		(fill yes)
		(layer "In5.Cu")
		(net "GND")
	)
	(gr_poly
		(pts
			(arc
				(start 96.822768 -31.652972)
				(mid 96.519492 -31.652972)
				(end 96.822768 -31.652972)
			)
		)
		(stroke
			(width 0)
			(type solid)
		)
		(fill yes)
		(layer "In5.Cu")
		(net "GND")
	)
	(gr_poly
		(pts
			(arc
				(start 96.822768 -29.311854)
				(mid 96.519492 -29.311854)
				(end 96.822768 -29.311854)
			)
		)
		(stroke
			(width 0)
			(type solid)
		)
		(fill yes)
		(layer "In5.Cu")
		(net "GND")
	)
	(gr_poly
		(pts
			(arc
				(start 96.822768 -28.05303)
				(mid 96.519492 -28.05303)
				(end 96.822768 -28.05303)
			)
		)
		(stroke
			(width 0)
			(type solid)
		)
		(fill yes)
		(layer "In5.Cu")
		(net "GND")
	)
	(gr_poly
		(pts
			(arc
				(start 98.090736 -32.911796)
				(mid 97.78746 -32.911796)
				(end 98.090736 -32.911796)
			)
		)
		(stroke
			(width 0)
			(type solid)
		)
		(fill yes)
		(layer "In5.Cu")
		(net "GND")
	)
	(gr_poly
		(pts
			(arc
				(start 98.090736 -31.652972)
				(mid 97.78746 -31.652972)
				(end 98.090736 -31.652972)
			)
		)
		(stroke
			(width 0)
			(type solid)
		)
		(fill yes)
		(layer "In5.Cu")
		(net "GND")
	)
	(gr_poly
		(pts
			(arc
				(start 98.090736 -29.311854)
				(mid 97.78746 -29.311854)
				(end 98.090736 -29.311854)
			)
		)
		(stroke
			(width 0)
			(type solid)
		)
		(fill yes)
		(layer "In5.Cu")
		(net "GND")
	)
	(gr_poly
		(pts
			(arc
				(start 98.090736 -28.05303)
				(mid 97.78746 -28.05303)
				(end 98.090736 -28.05303)
			)
		)
		(stroke
			(width 0)
			(type solid)
		)
		(fill yes)
		(layer "In5.Cu")
		(net "GND")
	)
	(gr_poly
		(pts
			(arc
				(start 99.464876 -34.718498)
				(mid 99.1616 -34.718498)
				(end 99.464876 -34.718498)
			)
		)
		(stroke
			(width 0)
			(type solid)
		)
		(fill yes)
		(layer "In5.Cu")
		(net "GND")
	)
	(gr_poly
		(pts
			(arc
				(start 99.464876 -33.459674)
				(mid 99.1616 -33.459674)
				(end 99.464876 -33.459674)
			)
		)
		(stroke
			(width 0)
			(type solid)
		)
		(fill yes)
		(layer "In5.Cu")
		(net "GND")
	)
	(gr_poly
		(pts
			(arc
				(start 99.464876 -31.118302)
				(mid 99.1616 -31.118302)
				(end 99.464876 -31.118302)
			)
		)
		(stroke
			(width 0)
			(type solid)
		)
		(fill yes)
		(layer "In5.Cu")
		(net "GND")
	)
	(gr_poly
		(pts
			(arc
				(start 99.464876 -29.859478)
				(mid 99.1616 -29.859478)
				(end 99.464876 -29.859478)
			)
		)
		(stroke
			(width 0)
			(type solid)
		)
		(fill yes)
		(layer "In5.Cu")
		(net "GND")
	)
	(gr_poly
		(pts
			(arc
				(start 100.732844 -34.718498)
				(mid 100.429568 -34.718498)
				(end 100.732844 -34.718498)
			)
		)
		(stroke
			(width 0)
			(type solid)
		)
		(fill yes)
		(layer "In5.Cu")
		(net "GND")
	)
	(gr_poly
		(pts
			(arc
				(start 100.732844 -33.459674)
				(mid 100.429568 -33.459674)
				(end 100.732844 -33.459674)
			)
		)
		(stroke
			(width 0)
			(type solid)
		)
		(fill yes)
		(layer "In5.Cu")
		(net "GND")
	)
	(gr_poly
		(pts
			(arc
				(start 100.732844 -31.118302)
				(mid 100.429568 -31.118302)
				(end 100.732844 -31.118302)
			)
		)
		(stroke
			(width 0)
			(type solid)
		)
		(fill yes)
		(layer "In5.Cu")
		(net "GND")
	)
	(gr_poly
		(pts
			(arc
				(start 100.732844 -29.859478)
				(mid 100.429568 -29.859478)
				(end 100.732844 -29.859478)
			)
		)
		(stroke
			(width 0)
			(type solid)
		)
		(fill yes)
		(layer "In5.Cu")
		(net "GND")
	)
	(gr_poly
		(pts
			(arc
				(start 134.923022 -32.911796)
				(mid 134.619746 -32.911796)
				(end 134.923022 -32.911796)
			)
		)
		(stroke
			(width 0)
			(type solid)
		)
		(fill yes)
		(layer "In5.Cu")
		(net "GND")
	)
	(gr_poly
		(pts
			(arc
				(start 134.923022 -31.652972)
				(mid 134.619746 -31.652972)
				(end 134.923022 -31.652972)
			)
		)
		(stroke
			(width 0)
			(type solid)
		)
		(fill yes)
		(layer "In5.Cu")
		(net "GND")
	)
	(gr_poly
		(pts
			(arc
				(start 134.923022 -29.311854)
				(mid 134.619746 -29.311854)
				(end 134.923022 -29.311854)
			)
		)
		(stroke
			(width 0)
			(type solid)
		)
		(fill yes)
		(layer "In5.Cu")
		(net "GND")
	)
	(gr_poly
		(pts
			(arc
				(start 134.923022 -28.05303)
				(mid 134.619746 -28.05303)
				(end 134.923022 -28.05303)
			)
		)
		(stroke
			(width 0)
			(type solid)
		)
		(fill yes)
		(layer "In5.Cu")
		(net "GND")
	)
	(gr_poly
		(pts
			(arc
				(start 136.19099 -32.911796)
				(mid 135.887714 -32.911796)
				(end 136.19099 -32.911796)
			)
		)
		(stroke
			(width 0)
			(type solid)
		)
		(fill yes)
		(layer "In5.Cu")
		(net "GND")
	)
	(gr_poly
		(pts
			(arc
				(start 136.19099 -31.652972)
				(mid 135.887714 -31.652972)
				(end 136.19099 -31.652972)
			)
		)
		(stroke
			(width 0)
			(type solid)
		)
		(fill yes)
		(layer "In5.Cu")
		(net "GND")
	)
	(gr_poly
		(pts
			(arc
				(start 136.19099 -29.311854)
				(mid 135.887714 -29.311854)
				(end 136.19099 -29.311854)
			)
		)
		(stroke
			(width 0)
			(type solid)
		)
		(fill yes)
		(layer "In5.Cu")
		(net "GND")
	)
	(gr_poly
		(pts
			(arc
				(start 136.19099 -28.05303)
				(mid 135.887714 -28.05303)
				(end 136.19099 -28.05303)
			)
		)
		(stroke
			(width 0)
			(type solid)
		)
		(fill yes)
		(layer "In5.Cu")
		(net "GND")
	)
	(gr_poly
		(pts
			(arc
				(start 137.56513 -34.718498)
				(mid 137.261854 -34.718498)
				(end 137.56513 -34.718498)
			)
		)
		(stroke
			(width 0)
			(type solid)
		)
		(fill yes)
		(layer "In5.Cu")
		(net "GND")
	)
	(gr_poly
		(pts
			(arc
				(start 137.56513 -33.459674)
				(mid 137.261854 -33.459674)
				(end 137.56513 -33.459674)
			)
		)
		(stroke
			(width 0)
			(type solid)
		)
		(fill yes)
		(layer "In5.Cu")
		(net "GND")
	)
	(gr_poly
		(pts
			(arc
				(start 137.56513 -31.118302)
				(mid 137.261854 -31.118302)
				(end 137.56513 -31.118302)
			)
		)
		(stroke
			(width 0)
			(type solid)
		)
		(fill yes)
		(layer "In5.Cu")
		(net "GND")
	)
	(gr_poly
		(pts
			(arc
				(start 137.56513 -29.859478)
				(mid 137.261854 -29.859478)
				(end 137.56513 -29.859478)
			)
		)
		(stroke
			(width 0)
			(type solid)
		)
		(fill yes)
		(layer "In5.Cu")
		(net "GND")
	)
	(gr_poly
		(pts
			(arc
				(start 138.833098 -34.718498)
				(mid 138.529822 -34.718498)
				(end 138.833098 -34.718498)
			)
		)
		(stroke
			(width 0)
			(type solid)
		)
		(fill yes)
		(layer "In5.Cu")
		(net "GND")
	)
	(gr_poly
		(pts
			(arc
				(start 138.833098 -33.459674)
				(mid 138.529822 -33.459674)
				(end 138.833098 -33.459674)
			)
		)
		(stroke
			(width 0)
			(type solid)
		)
		(fill yes)
		(layer "In5.Cu")
		(net "GND")
	)
	(gr_poly
		(pts
			(arc
				(start 138.833098 -31.118302)
				(mid 138.529822 -31.118302)
				(end 138.833098 -31.118302)
			)
		)
		(stroke
			(width 0)
			(type solid)
		)
		(fill yes)
		(layer "In5.Cu")
		(net "GND")
	)
	(gr_poly
		(pts
			(arc
				(start 138.833098 -29.859478)
				(mid 138.529822 -29.859478)
				(end 138.833098 -29.859478)
			)
		)
		(stroke
			(width 0)
			(type solid)
		)
		(fill yes)
		(layer "In5.Cu")
		(net "GND")
	)
	(gr_poly
		(pts
			(arc
				(start 142.552928 -392.056874)
				(mid 142.249652 -392.056874)
				(end 142.552928 -392.056874)
			)
		)
		(stroke
			(width 0)
			(type solid)
		)
		(fill yes)
		(layer "In5.Cu")
		(net "GND")
	)
	(gr_poly
		(pts
			(arc
				(start 144.766284 -391.654538)
				(mid 144.463008 -391.654538)
				(end 144.766284 -391.654538)
			)
		)
		(stroke
			(width 0)
			(type solid)
		)
		(fill yes)
		(layer "In5.Cu")
		(net "GND")
	)
	(gr_poly
		(pts
			(arc
				(start 145.892774 -388.784084)
				(mid 145.589498 -388.784084)
				(end 145.892774 -388.784084)
			)
		)
		(stroke
			(width 0)
			(type solid)
		)
		(fill yes)
		(layer "In5.Cu")
		(net "GND")
	)
	(gr_poly
		(pts
			(arc
				(start 146.873468 -391.409428)
				(mid 146.570192 -391.409428)
				(end 146.873468 -391.409428)
			)
		)
		(stroke
			(width 0)
			(type solid)
		)
		(fill yes)
		(layer "In5.Cu")
		(net "GND")
	)
	(gr_poly
		(pts
			(arc
				(start 148.401532 -388.402068)
				(mid 148.098256 -388.402068)
				(end 148.401532 -388.402068)
			)
		)
		(stroke
			(width 0)
			(type solid)
		)
		(fill yes)
		(layer "In5.Cu")
		(net "GND")
	)
	(gr_poly
		(pts
			(arc
				(start 160.92297 -32.911796)
				(mid 160.619694 -32.911796)
				(end 160.92297 -32.911796)
			)
		)
		(stroke
			(width 0)
			(type solid)
		)
		(fill yes)
		(layer "In5.Cu")
		(net "GND")
	)
	(gr_poly
		(pts
			(arc
				(start 160.92297 -31.652972)
				(mid 160.619694 -31.652972)
				(end 160.92297 -31.652972)
			)
		)
		(stroke
			(width 0)
			(type solid)
		)
		(fill yes)
		(layer "In5.Cu")
		(net "GND")
	)
	(gr_poly
		(pts
			(arc
				(start 160.92297 -29.311854)
				(mid 160.619694 -29.311854)
				(end 160.92297 -29.311854)
			)
		)
		(stroke
			(width 0)
			(type solid)
		)
		(fill yes)
		(layer "In5.Cu")
		(net "GND")
	)
	(gr_poly
		(pts
			(arc
				(start 160.92297 -28.05303)
				(mid 160.619694 -28.05303)
				(end 160.92297 -28.05303)
			)
		)
		(stroke
			(width 0)
			(type solid)
		)
		(fill yes)
		(layer "In5.Cu")
		(net "GND")
	)
	(gr_poly
		(pts
			(arc
				(start 162.190938 -32.911796)
				(mid 161.887662 -32.911796)
				(end 162.190938 -32.911796)
			)
		)
		(stroke
			(width 0)
			(type solid)
		)
		(fill yes)
		(layer "In5.Cu")
		(net "GND")
	)
	(gr_poly
		(pts
			(arc
				(start 162.190938 -31.652972)
				(mid 161.887662 -31.652972)
				(end 162.190938 -31.652972)
			)
		)
		(stroke
			(width 0)
			(type solid)
		)
		(fill yes)
		(layer "In5.Cu")
		(net "GND")
	)
	(gr_poly
		(pts
			(arc
				(start 162.190938 -29.311854)
				(mid 161.887662 -29.311854)
				(end 162.190938 -29.311854)
			)
		)
		(stroke
			(width 0)
			(type solid)
		)
		(fill yes)
		(layer "In5.Cu")
		(net "GND")
	)
	(gr_poly
		(pts
			(arc
				(start 162.190938 -28.05303)
				(mid 161.887662 -28.05303)
				(end 162.190938 -28.05303)
			)
		)
		(stroke
			(width 0)
			(type solid)
		)
		(fill yes)
		(layer "In5.Cu")
		(net "GND")
	)
	(gr_poly
		(pts
			(arc
				(start 163.565078 -34.718498)
				(mid 163.261802 -34.718498)
				(end 163.565078 -34.718498)
			)
		)
		(stroke
			(width 0)
			(type solid)
		)
		(fill yes)
		(layer "In5.Cu")
		(net "GND")
	)
	(gr_poly
		(pts
			(arc
				(start 163.565078 -33.459674)
				(mid 163.261802 -33.459674)
				(end 163.565078 -33.459674)
			)
		)
		(stroke
			(width 0)
			(type solid)
		)
		(fill yes)
		(layer "In5.Cu")
		(net "GND")
	)
	(gr_poly
		(pts
			(arc
				(start 163.565078 -31.118302)
				(mid 163.261802 -31.118302)
				(end 163.565078 -31.118302)
			)
		)
		(stroke
			(width 0)
			(type solid)
		)
		(fill yes)
		(layer "In5.Cu")
		(net "GND")
	)
	(gr_poly
		(pts
			(arc
				(start 163.565078 -29.859478)
				(mid 163.261802 -29.859478)
				(end 163.565078 -29.859478)
			)
		)
		(stroke
			(width 0)
			(type solid)
		)
		(fill yes)
		(layer "In5.Cu")
		(net "GND")
	)
	(gr_poly
		(pts
			(arc
				(start 164.833046 -34.718498)
				(mid 164.52977 -34.718498)
				(end 164.833046 -34.718498)
			)
		)
		(stroke
			(width 0)
			(type solid)
		)
		(fill yes)
		(layer "In5.Cu")
		(net "GND")
	)
	(gr_poly
		(pts
			(arc
				(start 164.833046 -33.459674)
				(mid 164.52977 -33.459674)
				(end 164.833046 -33.459674)
			)
		)
		(stroke
			(width 0)
			(type solid)
		)
		(fill yes)
		(layer "In5.Cu")
		(net "GND")
	)
	(gr_poly
		(pts
			(arc
				(start 164.833046 -31.118302)
				(mid 164.52977 -31.118302)
				(end 164.833046 -31.118302)
			)
		)
		(stroke
			(width 0)
			(type solid)
		)
		(fill yes)
		(layer "In5.Cu")
		(net "GND")
	)
	(gr_poly
		(pts
			(arc
				(start 164.833046 -29.859478)
				(mid 164.52977 -29.859478)
				(end 164.833046 -29.859478)
			)
		)
		(stroke
			(width 0)
			(type solid)
		)
		(fill yes)
		(layer "In5.Cu")
		(net "GND")
	)
	(gr_poly
		(pts
			(arc
				(start 186.922918 -32.911796)
				(mid 186.619642 -32.911796)
				(end 186.922918 -32.911796)
			)
		)
		(stroke
			(width 0)
			(type solid)
		)
		(fill yes)
		(layer "In5.Cu")
		(net "GND")
	)
	(gr_poly
		(pts
			(arc
				(start 186.922918 -31.652972)
				(mid 186.619642 -31.652972)
				(end 186.922918 -31.652972)
			)
		)
		(stroke
			(width 0)
			(type solid)
		)
		(fill yes)
		(layer "In5.Cu")
		(net "GND")
	)
	(gr_poly
		(pts
			(arc
				(start 186.922918 -29.311854)
				(mid 186.619642 -29.311854)
				(end 186.922918 -29.311854)
			)
		)
		(stroke
			(width 0)
			(type solid)
		)
		(fill yes)
		(layer "In5.Cu")
		(net "GND")
	)
	(gr_poly
		(pts
			(arc
				(start 186.922918 -28.05303)
				(mid 186.619642 -28.05303)
				(end 186.922918 -28.05303)
			)
		)
		(stroke
			(width 0)
			(type solid)
		)
		(fill yes)
		(layer "In5.Cu")
		(net "GND")
	)
	(gr_poly
		(pts
			(arc
				(start 188.190886 -32.911796)
				(mid 187.88761 -32.911796)
				(end 188.190886 -32.911796)
			)
		)
		(stroke
			(width 0)
			(type solid)
		)
		(fill yes)
		(layer "In5.Cu")
		(net "GND")
	)
	(gr_poly
		(pts
			(arc
				(start 188.190886 -31.652972)
				(mid 187.88761 -31.652972)
				(end 188.190886 -31.652972)
			)
		)
		(stroke
			(width 0)
			(type solid)
		)
		(fill yes)
		(layer "In5.Cu")
		(net "GND")
	)
	(gr_poly
		(pts
			(arc
				(start 188.190886 -29.311854)
				(mid 187.88761 -29.311854)
				(end 188.190886 -29.311854)
			)
		)
		(stroke
			(width 0)
			(type solid)
		)
		(fill yes)
		(layer "In5.Cu")
		(net "GND")
	)
	(gr_poly
		(pts
			(arc
				(start 188.190886 -28.05303)
				(mid 187.88761 -28.05303)
				(end 188.190886 -28.05303)
			)
		)
		(stroke
			(width 0)
			(type solid)
		)
		(fill yes)
		(layer "In5.Cu")
		(net "GND")
	)
	(gr_poly
		(pts
			(arc
				(start 189.565026 -34.718498)
				(mid 189.26175 -34.718498)
				(end 189.565026 -34.718498)
			)
		)
		(stroke
			(width 0)
			(type solid)
		)
		(fill yes)
		(layer "In5.Cu")
		(net "GND")
	)
	(gr_poly
		(pts
			(arc
				(start 189.565026 -33.459674)
				(mid 189.26175 -33.459674)
				(end 189.565026 -33.459674)
			)
		)
		(stroke
			(width 0)
			(type solid)
		)
		(fill yes)
		(layer "In5.Cu")
		(net "GND")
	)
	(gr_poly
		(pts
			(arc
				(start 189.565026 -31.118302)
				(mid 189.26175 -31.118302)
				(end 189.565026 -31.118302)
			)
		)
		(stroke
			(width 0)
			(type solid)
		)
		(fill yes)
		(layer "In5.Cu")
		(net "GND")
	)
	(gr_poly
		(pts
			(arc
				(start 189.565026 -29.859478)
				(mid 189.26175 -29.859478)
				(end 189.565026 -29.859478)
			)
		)
		(stroke
			(width 0)
			(type solid)
		)
		(fill yes)
		(layer "In5.Cu")
		(net "GND")
	)
	(gr_poly
		(pts
			(arc
				(start 190.832994 -34.718498)
				(mid 190.529718 -34.718498)
				(end 190.832994 -34.718498)
			)
		)
		(stroke
			(width 0)
			(type solid)
		)
		(fill yes)
		(layer "In5.Cu")
		(net "GND")
	)
	(gr_poly
		(pts
			(arc
				(start 190.832994 -33.459674)
				(mid 190.529718 -33.459674)
				(end 190.832994 -33.459674)
			)
		)
		(stroke
			(width 0)
			(type solid)
		)
		(fill yes)
		(layer "In5.Cu")
		(net "GND")
	)
	(gr_poly
		(pts
			(arc
				(start 190.832994 -31.118302)
				(mid 190.529718 -31.118302)
				(end 190.832994 -31.118302)
			)
		)
		(stroke
			(width 0)
			(type solid)
		)
		(fill yes)
		(layer "In5.Cu")
		(net "GND")
	)
	(gr_poly
		(pts
			(arc
				(start 190.832994 -29.859478)
				(mid 190.529718 -29.859478)
				(end 190.832994 -29.859478)
			)
		)
		(stroke
			(width 0)
			(type solid)
		)
		(fill yes)
		(layer "In5.Cu")
		(net "GND")
	)
	(gr_poly
		(pts
			(arc
				(start 212.922866 -32.911796)
				(mid 212.61959 -32.911796)
				(end 212.922866 -32.911796)
			)
		)
		(stroke
			(width 0)
			(type solid)
		)
		(fill yes)
		(layer "In5.Cu")
		(net "GND")
	)
	(gr_poly
		(pts
			(arc
				(start 212.922866 -31.652972)
				(mid 212.61959 -31.652972)
				(end 212.922866 -31.652972)
			)
		)
		(stroke
			(width 0)
			(type solid)
		)
		(fill yes)
		(layer "In5.Cu")
		(net "GND")
	)
	(gr_poly
		(pts
			(arc
				(start 212.922866 -29.311854)
				(mid 212.61959 -29.311854)
				(end 212.922866 -29.311854)
			)
		)
		(stroke
			(width 0)
			(type solid)
		)
		(fill yes)
		(layer "In5.Cu")
		(net "GND")
	)
	(gr_poly
		(pts
			(arc
				(start 212.922866 -28.05303)
				(mid 212.61959 -28.05303)
				(end 212.922866 -28.05303)
			)
		)
		(stroke
			(width 0)
			(type solid)
		)
		(fill yes)
		(layer "In5.Cu")
		(net "GND")
	)
	(gr_poly
		(pts
			(arc
				(start 214.190834 -32.911796)
				(mid 213.887558 -32.911796)
				(end 214.190834 -32.911796)
			)
		)
		(stroke
			(width 0)
			(type solid)
		)
		(fill yes)
		(layer "In5.Cu")
		(net "GND")
	)
	(gr_poly
		(pts
			(arc
				(start 214.190834 -31.652972)
				(mid 213.887558 -31.652972)
				(end 214.190834 -31.652972)
			)
		)
		(stroke
			(width 0)
			(type solid)
		)
		(fill yes)
		(layer "In5.Cu")
		(net "GND")
	)
	(gr_poly
		(pts
			(arc
				(start 214.190834 -29.311854)
				(mid 213.887558 -29.311854)
				(end 214.190834 -29.311854)
			)
		)
		(stroke
			(width 0)
			(type solid)
		)
		(fill yes)
		(layer "In5.Cu")
		(net "GND")
	)
	(gr_poly
		(pts
			(arc
				(start 214.190834 -28.05303)
				(mid 213.887558 -28.05303)
				(end 214.190834 -28.05303)
			)
		)
		(stroke
			(width 0)
			(type solid)
		)
		(fill yes)
		(layer "In5.Cu")
		(net "GND")
	)
	(gr_poly
		(pts
			(arc
				(start 215.564974 -34.718498)
				(mid 215.261698 -34.718498)
				(end 215.564974 -34.718498)
			)
		)
		(stroke
			(width 0)
			(type solid)
		)
		(fill yes)
		(layer "In5.Cu")
		(net "GND")
	)
	(gr_poly
		(pts
			(arc
				(start 215.564974 -33.459674)
				(mid 215.261698 -33.459674)
				(end 215.564974 -33.459674)
			)
		)
		(stroke
			(width 0)
			(type solid)
		)
		(fill yes)
		(layer "In5.Cu")
		(net "GND")
	)
	(gr_poly
		(pts
			(arc
				(start 215.564974 -31.118302)
				(mid 215.261698 -31.118302)
				(end 215.564974 -31.118302)
			)
		)
		(stroke
			(width 0)
			(type solid)
		)
		(fill yes)
		(layer "In5.Cu")
		(net "GND")
	)
	(gr_poly
		(pts
			(arc
				(start 215.564974 -29.859478)
				(mid 215.261698 -29.859478)
				(end 215.564974 -29.859478)
			)
		)
		(stroke
			(width 0)
			(type solid)
		)
		(fill yes)
		(layer "In5.Cu")
		(net "GND")
	)
	(gr_poly
		(pts
			(arc
				(start 216.832942 -34.718498)
				(mid 216.529666 -34.718498)
				(end 216.832942 -34.718498)
			)
		)
		(stroke
			(width 0)
			(type solid)
		)
		(fill yes)
		(layer "In5.Cu")
		(net "GND")
	)
	(gr_poly
		(pts
			(arc
				(start 216.832942 -33.459674)
				(mid 216.529666 -33.459674)
				(end 216.832942 -33.459674)
			)
		)
		(stroke
			(width 0)
			(type solid)
		)
		(fill yes)
		(layer "In5.Cu")
		(net "GND")
	)
	(gr_poly
		(pts
			(arc
				(start 216.832942 -31.118302)
				(mid 216.529666 -31.118302)
				(end 216.832942 -31.118302)
			)
		)
		(stroke
			(width 0)
			(type solid)
		)
		(fill yes)
		(layer "In5.Cu")
		(net "GND")
	)
	(gr_poly
		(pts
			(arc
				(start 216.832942 -29.859478)
				(mid 216.529666 -29.859478)
				(end 216.832942 -29.859478)
			)
		)
		(stroke
			(width 0)
			(type solid)
		)
		(fill yes)
		(layer "In5.Cu")
		(net "GND")
	)
	(gr_poly
		(pts
			(arc
				(start 222.579438 -330.1238)
				(mid 222.276162 -330.1238)
				(end 222.579438 -330.1238)
			)
		)
		(stroke
			(width 0)
			(type solid)
		)
		(fill yes)
		(layer "In5.Cu")
		(net "GND")
	)
	(gr_poly
		(pts
			(arc
				(start 226.39909 -333.027528)
				(mid 226.095814 -333.027528)
				(end 226.39909 -333.027528)
			)
		)
		(stroke
			(width 0)
			(type solid)
		)
		(fill yes)
		(layer "In5.Cu")
		(net "GND")
	)
	(gr_poly
		(pts
			(arc
				(start 237.198154 -332.301342)
				(mid 236.894878 -332.301342)
				(end 237.198154 -332.301342)
			)
		)
		(stroke
			(width 0)
			(type solid)
		)
		(fill yes)
		(layer "In5.Cu")
		(net "GND")
	)
	(gr_poly
		(pts
			(arc
				(start 251.022866 -32.911796)
				(mid 250.71959 -32.911796)
				(end 251.022866 -32.911796)
			)
		)
		(stroke
			(width 0)
			(type solid)
		)
		(fill yes)
		(layer "In5.Cu")
		(net "GND")
	)
	(gr_poly
		(pts
			(arc
				(start 251.022866 -31.652972)
				(mid 250.71959 -31.652972)
				(end 251.022866 -31.652972)
			)
		)
		(stroke
			(width 0)
			(type solid)
		)
		(fill yes)
		(layer "In5.Cu")
		(net "GND")
	)
	(gr_poly
		(pts
			(arc
				(start 251.022866 -29.311854)
				(mid 250.71959 -29.311854)
				(end 251.022866 -29.311854)
			)
		)
		(stroke
			(width 0)
			(type solid)
		)
		(fill yes)
		(layer "In5.Cu")
		(net "GND")
	)
	(gr_poly
		(pts
			(arc
				(start 251.022866 -28.05303)
				(mid 250.71959 -28.05303)
				(end 251.022866 -28.05303)
			)
		)
		(stroke
			(width 0)
			(type solid)
		)
		(fill yes)
		(layer "In5.Cu")
		(net "GND")
	)
	(gr_poly
		(pts
			(arc
				(start 252.290834 -32.911796)
				(mid 251.987558 -32.911796)
				(end 252.290834 -32.911796)
			)
		)
		(stroke
			(width 0)
			(type solid)
		)
		(fill yes)
		(layer "In5.Cu")
		(net "GND")
	)
	(gr_poly
		(pts
			(arc
				(start 252.290834 -31.652972)
				(mid 251.987558 -31.652972)
				(end 252.290834 -31.652972)
			)
		)
		(stroke
			(width 0)
			(type solid)
		)
		(fill yes)
		(layer "In5.Cu")
		(net "GND")
	)
	(gr_poly
		(pts
			(arc
				(start 252.290834 -29.311854)
				(mid 251.987558 -29.311854)
				(end 252.290834 -29.311854)
			)
		)
		(stroke
			(width 0)
			(type solid)
		)
		(fill yes)
		(layer "In5.Cu")
		(net "GND")
	)
	(gr_poly
		(pts
			(arc
				(start 252.290834 -28.05303)
				(mid 251.987558 -28.05303)
				(end 252.290834 -28.05303)
			)
		)
		(stroke
			(width 0)
			(type solid)
		)
		(fill yes)
		(layer "In5.Cu")
		(net "GND")
	)
	(gr_poly
		(pts
			(arc
				(start 253.664974 -31.118302)
				(mid 253.361698 -31.118302)
				(end 253.664974 -31.118302)
			)
		)
		(stroke
			(width 0)
			(type solid)
		)
		(fill yes)
		(layer "In5.Cu")
		(net "GND")
	)
	(gr_poly
		(pts
			(arc
				(start 253.664974 -29.859478)
				(mid 253.361698 -29.859478)
				(end 253.664974 -29.859478)
			)
		)
		(stroke
			(width 0)
			(type solid)
		)
		(fill yes)
		(layer "In5.Cu")
		(net "GND")
	)
	(gr_poly
		(pts
			(arc
				(start 254.932942 -34.718498)
				(mid 254.629666 -34.718498)
				(end 254.932942 -34.718498)
			)
		)
		(stroke
			(width 0)
			(type solid)
		)
		(fill yes)
		(layer "In5.Cu")
		(net "GND")
	)
	(gr_poly
		(pts
			(arc
				(start 254.932942 -33.459674)
				(mid 254.629666 -33.459674)
				(end 254.932942 -33.459674)
			)
		)
		(stroke
			(width 0)
			(type solid)
		)
		(fill yes)
		(layer "In5.Cu")
		(net "GND")
	)
	(gr_poly
		(pts
			(arc
				(start 277.022814 -32.911796)
				(mid 276.719538 -32.911796)
				(end 277.022814 -32.911796)
			)
		)
		(stroke
			(width 0)
			(type solid)
		)
		(fill yes)
		(layer "In5.Cu")
		(net "GND")
	)
	(gr_poly
		(pts
			(arc
				(start 277.022814 -31.652972)
				(mid 276.719538 -31.652972)
				(end 277.022814 -31.652972)
			)
		)
		(stroke
			(width 0)
			(type solid)
		)
		(fill yes)
		(layer "In5.Cu")
		(net "GND")
	)
	(gr_poly
		(pts
			(arc
				(start 277.022814 -29.311854)
				(mid 276.719538 -29.311854)
				(end 277.022814 -29.311854)
			)
		)
		(stroke
			(width 0)
			(type solid)
		)
		(fill yes)
		(layer "In5.Cu")
		(net "GND")
	)
	(gr_poly
		(pts
			(arc
				(start 277.022814 -28.05303)
				(mid 276.719538 -28.05303)
				(end 277.022814 -28.05303)
			)
		)
		(stroke
			(width 0)
			(type solid)
		)
		(fill yes)
		(layer "In5.Cu")
		(net "GND")
	)
	(gr_poly
		(pts
			(arc
				(start 278.290782 -32.911796)
				(mid 277.987506 -32.911796)
				(end 278.290782 -32.911796)
			)
		)
		(stroke
			(width 0)
			(type solid)
		)
		(fill yes)
		(layer "In5.Cu")
		(net "GND")
	)
	(gr_poly
		(pts
			(arc
				(start 278.290782 -31.652972)
				(mid 277.987506 -31.652972)
				(end 278.290782 -31.652972)
			)
		)
		(stroke
			(width 0)
			(type solid)
		)
		(fill yes)
		(layer "In5.Cu")
		(net "GND")
	)
	(gr_poly
		(pts
			(arc
				(start 278.290782 -29.311854)
				(mid 277.987506 -29.311854)
				(end 278.290782 -29.311854)
			)
		)
		(stroke
			(width 0)
			(type solid)
		)
		(fill yes)
		(layer "In5.Cu")
		(net "GND")
	)
	(gr_poly
		(pts
			(arc
				(start 278.290782 -28.05303)
				(mid 277.987506 -28.05303)
				(end 278.290782 -28.05303)
			)
		)
		(stroke
			(width 0)
			(type solid)
		)
		(fill yes)
		(layer "In5.Cu")
		(net "GND")
	)
	(gr_poly
		(pts
			(arc
				(start 279.664922 -34.718498)
				(mid 279.361646 -34.718498)
				(end 279.664922 -34.718498)
			)
		)
		(stroke
			(width 0)
			(type solid)
		)
		(fill yes)
		(layer "In5.Cu")
		(net "GND")
	)
	(gr_poly
		(pts
			(arc
				(start 279.664922 -33.459674)
				(mid 279.361646 -33.459674)
				(end 279.664922 -33.459674)
			)
		)
		(stroke
			(width 0)
			(type solid)
		)
		(fill yes)
		(layer "In5.Cu")
		(net "GND")
	)
	(gr_poly
		(pts
			(arc
				(start 279.664922 -31.118302)
				(mid 279.361646 -31.118302)
				(end 279.664922 -31.118302)
			)
		)
		(stroke
			(width 0)
			(type solid)
		)
		(fill yes)
		(layer "In5.Cu")
		(net "GND")
	)
	(gr_poly
		(pts
			(arc
				(start 279.664922 -29.859478)
				(mid 279.361646 -29.859478)
				(end 279.664922 -29.859478)
			)
		)
		(stroke
			(width 0)
			(type solid)
		)
		(fill yes)
		(layer "In5.Cu")
		(net "GND")
	)
	(gr_poly
		(pts
			(arc
				(start 280.93289 -34.718498)
				(mid 280.629614 -34.718498)
				(end 280.93289 -34.718498)
			)
		)
		(stroke
			(width 0)
			(type solid)
		)
		(fill yes)
		(layer "In5.Cu")
		(net "GND")
	)
	(gr_poly
		(pts
			(arc
				(start 280.93289 -33.459674)
				(mid 280.629614 -33.459674)
				(end 280.93289 -33.459674)
			)
		)
		(stroke
			(width 0)
			(type solid)
		)
		(fill yes)
		(layer "In5.Cu")
		(net "GND")
	)
	(gr_poly
		(pts
			(arc
				(start 280.93289 -31.118302)
				(mid 280.629614 -31.118302)
				(end 280.93289 -31.118302)
			)
		)
		(stroke
			(width 0)
			(type solid)
		)
		(fill yes)
		(layer "In5.Cu")
		(net "GND")
	)
	(gr_poly
		(pts
			(arc
				(start 303.022762 -32.911796)
				(mid 302.719486 -32.911796)
				(end 303.022762 -32.911796)
			)
		)
		(stroke
			(width 0)
			(type solid)
		)
		(fill yes)
		(layer "In5.Cu")
		(net "GND")
	)
	(gr_poly
		(pts
			(arc
				(start 303.022762 -31.652972)
				(mid 302.719486 -31.652972)
				(end 303.022762 -31.652972)
			)
		)
		(stroke
			(width 0)
			(type solid)
		)
		(fill yes)
		(layer "In5.Cu")
		(net "GND")
	)
	(gr_poly
		(pts
			(arc
				(start 303.022762 -29.311854)
				(mid 302.719486 -29.311854)
				(end 303.022762 -29.311854)
			)
		)
		(stroke
			(width 0)
			(type solid)
		)
		(fill yes)
		(layer "In5.Cu")
		(net "GND")
	)
	(gr_poly
		(pts
			(arc
				(start 303.022762 -28.05303)
				(mid 302.719486 -28.05303)
				(end 303.022762 -28.05303)
			)
		)
		(stroke
			(width 0)
			(type solid)
		)
		(fill yes)
		(layer "In5.Cu")
		(net "GND")
	)
	(gr_poly
		(pts
			(arc
				(start 304.29073 -32.911796)
				(mid 303.987454 -32.911796)
				(end 304.29073 -32.911796)
			)
		)
		(stroke
			(width 0)
			(type solid)
		)
		(fill yes)
		(layer "In5.Cu")
		(net "GND")
	)
	(gr_poly
		(pts
			(arc
				(start 304.29073 -31.652972)
				(mid 303.987454 -31.652972)
				(end 304.29073 -31.652972)
			)
		)
		(stroke
			(width 0)
			(type solid)
		)
		(fill yes)
		(layer "In5.Cu")
		(net "GND")
	)
	(gr_poly
		(pts
			(arc
				(start 304.29073 -29.311854)
				(mid 303.987454 -29.311854)
				(end 304.29073 -29.311854)
			)
		)
		(stroke
			(width 0)
			(type solid)
		)
		(fill yes)
		(layer "In5.Cu")
		(net "GND")
	)
	(gr_poly
		(pts
			(arc
				(start 304.29073 -28.05303)
				(mid 303.987454 -28.05303)
				(end 304.29073 -28.05303)
			)
		)
		(stroke
			(width 0)
			(type solid)
		)
		(fill yes)
		(layer "In5.Cu")
		(net "GND")
	)
	(gr_poly
		(pts
			(arc
				(start 305.66487 -34.718498)
				(mid 305.361594 -34.718498)
				(end 305.66487 -34.718498)
			)
		)
		(stroke
			(width 0)
			(type solid)
		)
		(fill yes)
		(layer "In5.Cu")
		(net "GND")
	)
	(gr_poly
		(pts
			(arc
				(start 305.66487 -33.459674)
				(mid 305.361594 -33.459674)
				(end 305.66487 -33.459674)
			)
		)
		(stroke
			(width 0)
			(type solid)
		)
		(fill yes)
		(layer "In5.Cu")
		(net "GND")
	)
	(gr_poly
		(pts
			(arc
				(start 305.66487 -31.118302)
				(mid 305.361594 -31.118302)
				(end 305.66487 -31.118302)
			)
		)
		(stroke
			(width 0)
			(type solid)
		)
		(fill yes)
		(layer "In5.Cu")
		(net "GND")
	)
	(gr_poly
		(pts
			(arc
				(start 305.66487 -29.859478)
				(mid 305.361594 -29.859478)
				(end 305.66487 -29.859478)
			)
		)
		(stroke
			(width 0)
			(type solid)
		)
		(fill yes)
		(layer "In5.Cu")
		(net "GND")
	)
	(gr_poly
		(pts
			(arc
				(start 306.932838 -34.718498)
				(mid 306.629562 -34.718498)
				(end 306.932838 -34.718498)
			)
		)
		(stroke
			(width 0)
			(type solid)
		)
		(fill yes)
		(layer "In5.Cu")
		(net "GND")
	)
	(gr_poly
		(pts
			(arc
				(start 306.932838 -33.459674)
				(mid 306.629562 -33.459674)
				(end 306.932838 -33.459674)
			)
		)
		(stroke
			(width 0)
			(type solid)
		)
		(fill yes)
		(layer "In5.Cu")
		(net "GND")
	)
	(gr_poly
		(pts
			(arc
				(start 306.932838 -31.118302)
				(mid 306.629562 -31.118302)
				(end 306.932838 -31.118302)
			)
		)
		(stroke
			(width 0)
			(type solid)
		)
		(fill yes)
		(layer "In5.Cu")
		(net "GND")
	)
	(gr_poly
		(pts
			(arc
				(start 306.932838 -29.859478)
				(mid 306.629562 -29.859478)
				(end 306.932838 -29.859478)
			)
		)
		(stroke
			(width 0)
			(type solid)
		)
		(fill yes)
		(layer "In5.Cu")
		(net "GND")
	)
	(gr_poly
		(pts
			(arc
				(start 325.732394 -95.209106)
				(mid 325.439278 -95.209106)
				(end 325.732394 -95.209106)
			)
		)
		(stroke
			(width 0)
			(type solid)
		)
		(fill yes)
		(layer "In5.Cu")
		(net "GND")
	)
	(gr_poly
		(pts
			(arc
				(start 329.02271 -32.911796)
				(mid 328.719434 -32.911796)
				(end 329.02271 -32.911796)
			)
		)
		(stroke
			(width 0)
			(type solid)
		)
		(fill yes)
		(layer "In5.Cu")
		(net "GND")
	)
	(gr_poly
		(pts
			(arc
				(start 329.02271 -31.652972)
				(mid 328.719434 -31.652972)
				(end 329.02271 -31.652972)
			)
		)
		(stroke
			(width 0)
			(type solid)
		)
		(fill yes)
		(layer "In5.Cu")
		(net "GND")
	)
	(gr_poly
		(pts
			(arc
				(start 329.02271 -29.311854)
				(mid 328.719434 -29.311854)
				(end 329.02271 -29.311854)
			)
		)
		(stroke
			(width 0)
			(type solid)
		)
		(fill yes)
		(layer "In5.Cu")
		(net "GND")
	)
	(gr_poly
		(pts
			(arc
				(start 329.02271 -28.05303)
				(mid 328.719434 -28.05303)
				(end 329.02271 -28.05303)
			)
		)
		(stroke
			(width 0)
			(type solid)
		)
		(fill yes)
		(layer "In5.Cu")
		(net "GND")
	)
	(gr_poly
		(pts
			(arc
				(start 330.290678 -32.911796)
				(mid 329.987402 -32.911796)
				(end 330.290678 -32.911796)
			)
		)
		(stroke
			(width 0)
			(type solid)
		)
		(fill yes)
		(layer "In5.Cu")
		(net "GND")
	)
	(gr_poly
		(pts
			(arc
				(start 330.290678 -31.652972)
				(mid 329.987402 -31.652972)
				(end 330.290678 -31.652972)
			)
		)
		(stroke
			(width 0)
			(type solid)
		)
		(fill yes)
		(layer "In5.Cu")
		(net "GND")
	)
	(gr_poly
		(pts
			(arc
				(start 330.290678 -29.311854)
				(mid 329.987402 -29.311854)
				(end 330.290678 -29.311854)
			)
		)
		(stroke
			(width 0)
			(type solid)
		)
		(fill yes)
		(layer "In5.Cu")
		(net "GND")
	)
	(gr_poly
		(pts
			(arc
				(start 330.290678 -28.05303)
				(mid 329.987402 -28.05303)
				(end 330.290678 -28.05303)
			)
		)
		(stroke
			(width 0)
			(type solid)
		)
		(fill yes)
		(layer "In5.Cu")
		(net "GND")
	)
	(gr_poly
		(pts
			(arc
				(start 331.664818 -34.718498)
				(mid 331.361542 -34.718498)
				(end 331.664818 -34.718498)
			)
		)
		(stroke
			(width 0)
			(type solid)
		)
		(fill yes)
		(layer "In5.Cu")
		(net "GND")
	)
	(gr_poly
		(pts
			(arc
				(start 331.664818 -33.459674)
				(mid 331.361542 -33.459674)
				(end 331.664818 -33.459674)
			)
		)
		(stroke
			(width 0)
			(type solid)
		)
		(fill yes)
		(layer "In5.Cu")
		(net "GND")
	)
	(gr_poly
		(pts
			(arc
				(start 331.664818 -31.118302)
				(mid 331.361542 -31.118302)
				(end 331.664818 -31.118302)
			)
		)
		(stroke
			(width 0)
			(type solid)
		)
		(fill yes)
		(layer "In5.Cu")
		(net "GND")
	)
	(gr_poly
		(pts
			(arc
				(start 331.664818 -29.859478)
				(mid 331.361542 -29.859478)
				(end 331.664818 -29.859478)
			)
		)
		(stroke
			(width 0)
			(type solid)
		)
		(fill yes)
		(layer "In5.Cu")
		(net "GND")
	)
	(gr_poly
		(pts
			(arc
				(start 332.932786 -34.718498)
				(mid 332.62951 -34.718498)
				(end 332.932786 -34.718498)
			)
		)
		(stroke
			(width 0)
			(type solid)
		)
		(fill yes)
		(layer "In5.Cu")
		(net "GND")
	)
	(gr_poly
		(pts
			(arc
				(start 332.932786 -33.459674)
				(mid 332.62951 -33.459674)
				(end 332.932786 -33.459674)
			)
		)
		(stroke
			(width 0)
			(type solid)
		)
		(fill yes)
		(layer "In5.Cu")
		(net "GND")
	)
	(gr_poly
		(pts
			(arc
				(start 332.932786 -31.118302)
				(mid 332.62951 -31.118302)
				(end 332.932786 -31.118302)
			)
		)
		(stroke
			(width 0)
			(type solid)
		)
		(fill yes)
		(layer "In5.Cu")
		(net "GND")
	)
	(gr_poly
		(pts
			(arc
				(start 332.932786 -29.859478)
				(mid 332.62951 -29.859478)
				(end 332.932786 -29.859478)
			)
		)
		(stroke
			(width 0)
			(type solid)
		)
		(fill yes)
		(layer "In5.Cu")
		(net "GND")
	)
	(gr_poly
		(pts
			(arc
				(start 334.812894 -79.516732)
				(mid 334.519778 -79.516732)
				(end 334.812894 -79.516732)
			)
		)
		(stroke
			(width 0)
			(type solid)
		)
		(fill yes)
		(layer "In5.Cu")
		(net "GND")
	)
	(gr_poly
		(pts
			(arc
				(start 336.071718 -79.516732)
				(mid 335.778602 -79.516732)
				(end 336.071718 -79.516732)
			)
		)
		(stroke
			(width 0)
			(type solid)
		)
		(fill yes)
		(layer "In5.Cu")
		(net "GND")
	)
	(gr_poly
		(pts
			(arc
				(start 336.81289 -78.754732)
				(mid 336.519774 -78.754732)
				(end 336.81289 -78.754732)
			)
		)
		(stroke
			(width 0)
			(type solid)
		)
		(fill yes)
		(layer "In5.Cu")
		(net "GND")
	)
	(gr_poly
		(pts
			(arc
				(start 338.071714 -78.754732)
				(mid 337.778598 -78.754732)
				(end 338.071714 -78.754732)
			)
		)
		(stroke
			(width 0)
			(type solid)
		)
		(fill yes)
		(layer "In5.Cu")
		(net "GND")
	)
	(gr_poly
		(pts
			(arc
				(start 338.812632 -94.20987)
				(mid 338.519516 -94.20987)
				(end 338.812632 -94.20987)
			)
		)
		(stroke
			(width 0)
			(type solid)
		)
		(fill yes)
		(layer "In5.Cu")
		(net "GND")
	)
	(gr_poly
		(pts
			(arc
				(start 338.812886 -79.516732)
				(mid 338.51977 -79.516732)
				(end 338.812886 -79.516732)
			)
		)
		(stroke
			(width 0)
			(type solid)
		)
		(fill yes)
		(layer "In5.Cu")
		(net "GND")
	)
	(gr_poly
		(pts
			(arc
				(start 340.071456 -94.20987)
				(mid 339.77834 -94.20987)
				(end 340.071456 -94.20987)
			)
		)
		(stroke
			(width 0)
			(type solid)
		)
		(fill yes)
		(layer "In5.Cu")
		(net "GND")
	)
	(gr_poly
		(pts
			(arc
				(start 340.07171 -79.516732)
				(mid 339.778594 -79.516732)
				(end 340.07171 -79.516732)
			)
		)
		(stroke
			(width 0)
			(type solid)
		)
		(fill yes)
		(layer "In5.Cu")
		(net "GND")
	)
	(gr_poly
		(pts
			(arc
				(start 345.850464 -88.341962)
				(mid 345.557348 -88.341962)
				(end 345.850464 -88.341962)
			)
		)
		(stroke
			(width 0)
			(type solid)
		)
		(fill yes)
		(layer "In5.Cu")
		(net "GND")
	)
	(gr_poly
		(pts
			(arc
				(start 345.850464 -87.083138)
				(mid 345.557348 -87.083138)
				(end 345.850464 -87.083138)
			)
		)
		(stroke
			(width 0)
			(type solid)
		)
		(fill yes)
		(layer "In5.Cu")
		(net "GND")
	)
	(gr_poly
		(pts
			(arc
				(start 345.850464 -84.34197)
				(mid 345.557348 -84.34197)
				(end 345.850464 -84.34197)
			)
		)
		(stroke
			(width 0)
			(type solid)
		)
		(fill yes)
		(layer "In5.Cu")
		(net "GND")
	)
	(gr_poly
		(pts
			(arc
				(start 345.850464 -83.083146)
				(mid 345.557348 -83.083146)
				(end 345.850464 -83.083146)
			)
		)
		(stroke
			(width 0)
			(type solid)
		)
		(fill yes)
		(layer "In5.Cu")
		(net "GND")
	)
	(gr_poly
		(pts
			(arc
				(start 346.612464 -90.341958)
				(mid 346.319348 -90.341958)
				(end 346.612464 -90.341958)
			)
		)
		(stroke
			(width 0)
			(type solid)
		)
		(fill yes)
		(layer "In5.Cu")
		(net "GND")
	)
	(gr_poly
		(pts
			(arc
				(start 346.612464 -89.083134)
				(mid 346.319348 -89.083134)
				(end 346.612464 -89.083134)
			)
		)
		(stroke
			(width 0)
			(type solid)
		)
		(fill yes)
		(layer "In5.Cu")
		(net "GND")
	)
	(gr_poly
		(pts
			(arc
				(start 346.612464 -86.341966)
				(mid 346.319348 -86.341966)
				(end 346.612464 -86.341966)
			)
		)
		(stroke
			(width 0)
			(type solid)
		)
		(fill yes)
		(layer "In5.Cu")
		(net "GND")
	)
	(gr_poly
		(pts
			(arc
				(start 346.612464 -85.083142)
				(mid 346.319348 -85.083142)
				(end 346.612464 -85.083142)
			)
		)
		(stroke
			(width 0)
			(type solid)
		)
		(fill yes)
		(layer "In5.Cu")
		(net "GND")
	)
	(gr_poly
		(pts
			(arc
				(start 349.07855 -101.030532)
				(mid 348.785434 -101.030532)
				(end 349.07855 -101.030532)
			)
		)
		(stroke
			(width 0)
			(type solid)
		)
		(fill yes)
		(layer "In5.Cu")
		(net "GND")
	)
	(gr_poly
		(pts
			(arc
				(start 349.491808 -108.96473)
				(mid 349.198692 -108.96473)
				(end 349.491808 -108.96473)
			)
		)
		(stroke
			(width 0)
			(type solid)
		)
		(fill yes)
		(layer "In5.Cu")
		(net "GND")
	)
	(gr_poly
		(pts
			(arc
				(start 351.74682 -88.093804)
				(mid 351.453704 -88.093804)
				(end 351.74682 -88.093804)
			)
		)
		(stroke
			(width 0)
			(type solid)
		)
		(fill yes)
		(layer "In5.Cu")
		(net "GND")
	)
	(gr_poly
		(pts
			(arc
				(start 352.183192 -85.544914)
				(mid 351.890076 -85.544914)
				(end 352.183192 -85.544914)
			)
		)
		(stroke
			(width 0)
			(type solid)
		)
		(fill yes)
		(layer "In5.Cu")
		(net "GND")
	)
	(gr_poly
		(pts
			(arc
				(start 352.183192 -83.232752)
				(mid 351.890076 -83.232752)
				(end 352.183192 -83.232752)
			)
		)
		(stroke
			(width 0)
			(type solid)
		)
		(fill yes)
		(layer "In5.Cu")
		(net "GND")
	)
	(gr_poly
		(pts
			(arc
				(start 352.205036 -86.6648)
				(mid 351.91192 -86.6648)
				(end 352.205036 -86.6648)
			)
		)
		(stroke
			(width 0)
			(type solid)
		)
		(fill yes)
		(layer "In5.Cu")
		(net "GND")
	)
	(gr_poly
		(pts
			(arc
				(start 352.22688 -84.323428)
				(mid 351.933764 -84.323428)
				(end 352.22688 -84.323428)
			)
		)
		(stroke
			(width 0)
			(type solid)
		)
		(fill yes)
		(layer "In5.Cu")
		(net "GND")
	)
	(gr_poly
		(pts
			(arc
				(start 352.263202 -88.955372)
				(mid 351.970086 -88.955372)
				(end 352.263202 -88.955372)
			)
		)
		(stroke
			(width 0)
			(type solid)
		)
		(fill yes)
		(layer "In5.Cu")
		(net "GND")
	)
	(gr_poly
		(pts
			(arc
				(start 352.396044 -105.199942)
				(mid 352.102928 -105.199942)
				(end 352.396044 -105.199942)
			)
		)
		(stroke
			(width 0)
			(type solid)
		)
		(fill yes)
		(layer "In5.Cu")
		(net "GND")
	)
	(gr_poly
		(pts
			(arc
				(start 352.651314 -100.872544)
				(mid 352.358198 -100.872544)
				(end 352.651314 -100.872544)
			)
		)
		(stroke
			(width 0)
			(type solid)
		)
		(fill yes)
		(layer "In5.Cu")
		(net "GND")
	)
	(gr_poly
		(pts
			(arc
				(start 352.89871 -108.800392)
				(mid 352.605594 -108.800392)
				(end 352.89871 -108.800392)
			)
		)
		(stroke
			(width 0)
			(type solid)
		)
		(fill yes)
		(layer "In5.Cu")
		(net "GND")
	)
	(gr_poly
		(pts
			(arc
				(start 353.027488 -103.744522)
				(mid 352.734372 -103.744522)
				(end 353.027488 -103.744522)
			)
		)
		(stroke
			(width 0)
			(type solid)
		)
		(fill yes)
		(layer "In5.Cu")
		(net "GND")
	)
	(gr_poly
		(pts
			(arc
				(start 355.124258 -99.182936)
				(mid 354.831142 -99.182936)
				(end 355.124258 -99.182936)
			)
		)
		(stroke
			(width 0)
			(type solid)
		)
		(fill yes)
		(layer "In5.Cu")
		(net "GND")
	)
	(gr_poly
		(pts
			(arc
				(start 358.642158 -101.100128)
				(mid 358.349042 -101.100128)
				(end 358.642158 -101.100128)
			)
		)
		(stroke
			(width 0)
			(type solid)
		)
		(fill yes)
		(layer "In5.Cu")
		(net "GND")
	)
	(gr_poly
		(pts
			(arc
				(start 359.274364 -105.573068)
				(mid 358.981248 -105.573068)
				(end 359.274364 -105.573068)
			)
		)
		(stroke
			(width 0)
			(type solid)
		)
		(fill yes)
		(layer "In5.Cu")
		(net "GND")
	)
	(gr_poly
		(pts
			(arc
				(start 359.898696 -97.630742)
				(mid 359.60558 -97.630742)
				(end 359.898696 -97.630742)
			)
		)
		(stroke
			(width 0)
			(type solid)
		)
		(fill yes)
		(layer "In5.Cu")
		(net "GND")
	)
	(gr_poly
		(pts
			(arc
				(start 360.021378 -103.412036)
				(mid 359.728262 -103.412036)
				(end 360.021378 -103.412036)
			)
		)
		(stroke
			(width 0)
			(type solid)
		)
		(fill yes)
		(layer "In5.Cu")
		(net "GND")
	)
	(gr_poly
		(pts
			(arc
				(start 367.122964 -32.911796)
				(mid 366.819688 -32.911796)
				(end 367.122964 -32.911796)
			)
		)
		(stroke
			(width 0)
			(type solid)
		)
		(fill yes)
		(layer "In5.Cu")
		(net "GND")
	)
	(gr_poly
		(pts
			(arc
				(start 367.122964 -31.652972)
				(mid 366.819688 -31.652972)
				(end 367.122964 -31.652972)
			)
		)
		(stroke
			(width 0)
			(type solid)
		)
		(fill yes)
		(layer "In5.Cu")
		(net "GND")
	)
	(gr_poly
		(pts
			(arc
				(start 367.122964 -29.311854)
				(mid 366.819688 -29.311854)
				(end 367.122964 -29.311854)
			)
		)
		(stroke
			(width 0)
			(type solid)
		)
		(fill yes)
		(layer "In5.Cu")
		(net "GND")
	)
	(gr_poly
		(pts
			(arc
				(start 367.122964 -28.05303)
				(mid 366.819688 -28.05303)
				(end 367.122964 -28.05303)
			)
		)
		(stroke
			(width 0)
			(type solid)
		)
		(fill yes)
		(layer "In5.Cu")
		(net "GND")
	)
	(gr_poly
		(pts
			(arc
				(start 368.390932 -32.911796)
				(mid 368.087656 -32.911796)
				(end 368.390932 -32.911796)
			)
		)
		(stroke
			(width 0)
			(type solid)
		)
		(fill yes)
		(layer "In5.Cu")
		(net "GND")
	)
	(gr_poly
		(pts
			(arc
				(start 368.390932 -31.652972)
				(mid 368.087656 -31.652972)
				(end 368.390932 -31.652972)
			)
		)
		(stroke
			(width 0)
			(type solid)
		)
		(fill yes)
		(layer "In5.Cu")
		(net "GND")
	)
	(gr_poly
		(pts
			(arc
				(start 368.390932 -29.311854)
				(mid 368.087656 -29.311854)
				(end 368.390932 -29.311854)
			)
		)
		(stroke
			(width 0)
			(type solid)
		)
		(fill yes)
		(layer "In5.Cu")
		(net "GND")
	)
	(gr_poly
		(pts
			(arc
				(start 368.390932 -28.05303)
				(mid 368.087656 -28.05303)
				(end 368.390932 -28.05303)
			)
		)
		(stroke
			(width 0)
			(type solid)
		)
		(fill yes)
		(layer "In5.Cu")
		(net "GND")
	)
	(gr_poly
		(pts
			(arc
				(start 368.747802 -89.013538)
				(mid 368.454686 -89.013538)
				(end 368.747802 -89.013538)
			)
		)
		(stroke
			(width 0)
			(type solid)
		)
		(fill yes)
		(layer "In5.Cu")
		(net "GND")
	)
	(gr_poly
		(pts
			(arc
				(start 368.755168 -82.091022)
				(mid 368.462052 -82.091022)
				(end 368.755168 -82.091022)
			)
		)
		(stroke
			(width 0)
			(type solid)
		)
		(fill yes)
		(layer "In5.Cu")
		(net "GND")
	)
	(gr_poly
		(pts
			(arc
				(start 368.769646 -86.606634)
				(mid 368.47653 -86.606634)
				(end 368.769646 -86.606634)
			)
		)
		(stroke
			(width 0)
			(type solid)
		)
		(fill yes)
		(layer "In5.Cu")
		(net "GND")
	)
	(gr_poly
		(pts
			(arc
				(start 368.776758 -84.38515)
				(mid 368.483642 -84.38515)
				(end 368.776758 -84.38515)
			)
		)
		(stroke
			(width 0)
			(type solid)
		)
		(fill yes)
		(layer "In5.Cu")
		(net "GND")
	)
	(gr_poly
		(pts
			(arc
				(start 368.784378 -83.207352)
				(mid 368.491262 -83.207352)
				(end 368.784378 -83.207352)
			)
		)
		(stroke
			(width 0)
			(type solid)
		)
		(fill yes)
		(layer "In5.Cu")
		(net "GND")
	)
	(gr_poly
		(pts
			(arc
				(start 368.787934 -85.50148)
				(mid 368.494818 -85.50148)
				(end 368.787934 -85.50148)
			)
		)
		(stroke
			(width 0)
			(type solid)
		)
		(fill yes)
		(layer "In5.Cu")
		(net "GND")
	)
	(gr_poly
		(pts
			(arc
				(start 368.798856 -87.784686)
				(mid 368.50574 -87.784686)
				(end 368.798856 -87.784686)
			)
		)
		(stroke
			(width 0)
			(type solid)
		)
		(fill yes)
		(layer "In5.Cu")
		(net "GND")
	)
	(gr_poly
		(pts
			(arc
				(start 369.765072 -34.718498)
				(mid 369.461796 -34.718498)
				(end 369.765072 -34.718498)
			)
		)
		(stroke
			(width 0)
			(type solid)
		)
		(fill yes)
		(layer "In5.Cu")
		(net "GND")
	)
	(gr_poly
		(pts
			(arc
				(start 369.765072 -33.459674)
				(mid 369.461796 -33.459674)
				(end 369.765072 -33.459674)
			)
		)
		(stroke
			(width 0)
			(type solid)
		)
		(fill yes)
		(layer "In5.Cu")
		(net "GND")
	)
	(gr_poly
		(pts
			(arc
				(start 369.765072 -31.118302)
				(mid 369.461796 -31.118302)
				(end 369.765072 -31.118302)
			)
		)
		(stroke
			(width 0)
			(type solid)
		)
		(fill yes)
		(layer "In5.Cu")
		(net "GND")
	)
	(gr_poly
		(pts
			(arc
				(start 369.765072 -29.859478)
				(mid 369.461796 -29.859478)
				(end 369.765072 -29.859478)
			)
		)
		(stroke
			(width 0)
			(type solid)
		)
		(fill yes)
		(layer "In5.Cu")
		(net "GND")
	)
	(gr_poly
		(pts
			(arc
				(start 371.03304 -34.718498)
				(mid 370.729764 -34.718498)
				(end 371.03304 -34.718498)
			)
		)
		(stroke
			(width 0)
			(type solid)
		)
		(fill yes)
		(layer "In5.Cu")
		(net "GND")
	)
	(gr_poly
		(pts
			(arc
				(start 371.03304 -33.459674)
				(mid 370.729764 -33.459674)
				(end 371.03304 -33.459674)
			)
		)
		(stroke
			(width 0)
			(type solid)
		)
		(fill yes)
		(layer "In5.Cu")
		(net "GND")
	)
	(gr_poly
		(pts
			(arc
				(start 371.03304 -31.118302)
				(mid 370.729764 -31.118302)
				(end 371.03304 -31.118302)
			)
		)
		(stroke
			(width 0)
			(type solid)
		)
		(fill yes)
		(layer "In5.Cu")
		(net "GND")
	)
	(gr_poly
		(pts
			(arc
				(start 371.03304 -29.859478)
				(mid 370.729764 -29.859478)
				(end 371.03304 -29.859478)
			)
		)
		(stroke
			(width 0)
			(type solid)
		)
		(fill yes)
		(layer "In5.Cu")
		(net "GND")
	)
	(gr_poly
		(pts
			(arc
				(start 377.255786 -85.952076)
				(mid 376.96267 -85.952076)
				(end 377.255786 -85.952076)
			)
		)
		(stroke
			(width 0)
			(type solid)
		)
		(fill yes)
		(layer "In5.Cu")
		(net "GND")
	)
	(gr_poly
		(pts
			(arc
				(start 377.284742 -81.371186)
				(mid 376.991626 -81.371186)
				(end 377.284742 -81.371186)
			)
		)
		(stroke
			(width 0)
			(type solid)
		)
		(fill yes)
		(layer "In5.Cu")
		(net "GND")
	)
	(gr_poly
		(pts
			(arc
				(start 377.305062 -83.661758)
				(mid 377.011946 -83.661758)
				(end 377.305062 -83.661758)
			)
		)
		(stroke
			(width 0)
			(type solid)
		)
		(fill yes)
		(layer "In5.Cu")
		(net "GND")
	)
	(gr_poly
		(pts
			(arc
				(start 377.32843 -82.55635)
				(mid 377.035314 -82.55635)
				(end 377.32843 -82.55635)
			)
		)
		(stroke
			(width 0)
			(type solid)
		)
		(fill yes)
		(layer "In5.Cu")
		(net "GND")
	)
	(gr_poly
		(pts
			(arc
				(start 378.163328 -87.101934)
				(mid 377.870212 -87.101934)
				(end 378.163328 -87.101934)
			)
		)
		(stroke
			(width 0)
			(type solid)
		)
		(fill yes)
		(layer "In5.Cu")
		(net "GND")
	)
	(gr_poly
		(pts
			(arc
				(start 380.577598 -85.481922)
				(mid 380.284482 -85.481922)
				(end 380.577598 -85.481922)
			)
		)
		(stroke
			(width 0)
			(type solid)
		)
		(fill yes)
		(layer "In5.Cu")
		(net "GND")
	)
	(gr_poly
		(pts
			(arc
				(start 391.696194 -82.0039)
				(mid 391.403078 -82.0039)
				(end 391.696194 -82.0039)
			)
		)
		(stroke
			(width 0)
			(type solid)
		)
		(fill yes)
		(layer "In5.Cu")
		(net "GND")
	)
	(gr_poly
		(pts
			(arc
				(start 393.122912 -32.911796)
				(mid 392.819636 -32.911796)
				(end 393.122912 -32.911796)
			)
		)
		(stroke
			(width 0)
			(type solid)
		)
		(fill yes)
		(layer "In5.Cu")
		(net "GND")
	)
	(gr_poly
		(pts
			(arc
				(start 393.122912 -31.652972)
				(mid 392.819636 -31.652972)
				(end 393.122912 -31.652972)
			)
		)
		(stroke
			(width 0)
			(type solid)
		)
		(fill yes)
		(layer "In5.Cu")
		(net "GND")
	)
	(gr_poly
		(pts
			(arc
				(start 393.122912 -29.311854)
				(mid 392.819636 -29.311854)
				(end 393.122912 -29.311854)
			)
		)
		(stroke
			(width 0)
			(type solid)
		)
		(fill yes)
		(layer "In5.Cu")
		(net "GND")
	)
	(gr_poly
		(pts
			(arc
				(start 393.122912 -28.05303)
				(mid 392.819636 -28.05303)
				(end 393.122912 -28.05303)
			)
		)
		(stroke
			(width 0)
			(type solid)
		)
		(fill yes)
		(layer "In5.Cu")
		(net "GND")
	)
	(gr_poly
		(pts
			(arc
				(start 394.39088 -32.911796)
				(mid 394.087604 -32.911796)
				(end 394.39088 -32.911796)
			)
		)
		(stroke
			(width 0)
			(type solid)
		)
		(fill yes)
		(layer "In5.Cu")
		(net "GND")
	)
	(gr_poly
		(pts
			(arc
				(start 394.39088 -31.652972)
				(mid 394.087604 -31.652972)
				(end 394.39088 -31.652972)
			)
		)
		(stroke
			(width 0)
			(type solid)
		)
		(fill yes)
		(layer "In5.Cu")
		(net "GND")
	)
	(gr_poly
		(pts
			(arc
				(start 394.39088 -29.311854)
				(mid 394.087604 -29.311854)
				(end 394.39088 -29.311854)
			)
		)
		(stroke
			(width 0)
			(type solid)
		)
		(fill yes)
		(layer "In5.Cu")
		(net "GND")
	)
	(gr_poly
		(pts
			(arc
				(start 394.39088 -28.05303)
				(mid 394.087604 -28.05303)
				(end 394.39088 -28.05303)
			)
		)
		(stroke
			(width 0)
			(type solid)
		)
		(fill yes)
		(layer "In5.Cu")
		(net "GND")
	)
	(gr_poly
		(pts
			(arc
				(start 395.408912 -80.923384)
				(mid 395.115796 -80.923384)
				(end 395.408912 -80.923384)
			)
		)
		(stroke
			(width 0)
			(type solid)
		)
		(fill yes)
		(layer "In5.Cu")
		(net "GND")
	)
	(gr_poly
		(pts
			(arc
				(start 395.445234 -83.264756)
				(mid 395.152118 -83.264756)
				(end 395.445234 -83.264756)
			)
		)
		(stroke
			(width 0)
			(type solid)
		)
		(fill yes)
		(layer "In5.Cu")
		(net "GND")
	)
	(gr_poly
		(pts
			(arc
				(start 395.481556 -84.333588)
				(mid 395.18844 -84.333588)
				(end 395.481556 -84.333588)
			)
		)
		(stroke
			(width 0)
			(type solid)
		)
		(fill yes)
		(layer "In5.Cu")
		(net "GND")
	)
	(gr_poly
		(pts
			(arc
				(start 395.76502 -34.718498)
				(mid 395.461744 -34.718498)
				(end 395.76502 -34.718498)
			)
		)
		(stroke
			(width 0)
			(type solid)
		)
		(fill yes)
		(layer "In5.Cu")
		(net "GND")
	)
	(gr_poly
		(pts
			(arc
				(start 395.76502 -33.459674)
				(mid 395.461744 -33.459674)
				(end 395.76502 -33.459674)
			)
		)
		(stroke
			(width 0)
			(type solid)
		)
		(fill yes)
		(layer "In5.Cu")
		(net "GND")
	)
	(gr_poly
		(pts
			(arc
				(start 395.76502 -31.118302)
				(mid 395.461744 -31.118302)
				(end 395.76502 -31.118302)
			)
		)
		(stroke
			(width 0)
			(type solid)
		)
		(fill yes)
		(layer "In5.Cu")
		(net "GND")
	)
	(gr_poly
		(pts
			(arc
				(start 395.76502 -29.859478)
				(mid 395.461744 -29.859478)
				(end 395.76502 -29.859478)
			)
		)
		(stroke
			(width 0)
			(type solid)
		)
		(fill yes)
		(layer "In5.Cu")
		(net "GND")
	)
	(gr_poly
		(pts
			(arc
				(start 397.032988 -34.718498)
				(mid 396.729712 -34.718498)
				(end 397.032988 -34.718498)
			)
		)
		(stroke
			(width 0)
			(type solid)
		)
		(fill yes)
		(layer "In5.Cu")
		(net "GND")
	)
	(gr_poly
		(pts
			(arc
				(start 397.032988 -33.459674)
				(mid 396.729712 -33.459674)
				(end 397.032988 -33.459674)
			)
		)
		(stroke
			(width 0)
			(type solid)
		)
		(fill yes)
		(layer "In5.Cu")
		(net "GND")
	)
	(gr_poly
		(pts
			(arc
				(start 397.032988 -31.118302)
				(mid 396.729712 -31.118302)
				(end 397.032988 -31.118302)
			)
		)
		(stroke
			(width 0)
			(type solid)
		)
		(fill yes)
		(layer "In5.Cu")
		(net "GND")
	)
	(gr_poly
		(pts
			(arc
				(start 397.032988 -29.859478)
				(mid 396.729712 -29.859478)
				(end 397.032988 -29.859478)
			)
		)
		(stroke
			(width 0)
			(type solid)
		)
		(fill yes)
		(layer "In5.Cu")
		(net "GND")
	)
	(gr_poly
		(pts
			(arc
				(start 400.157188 -86.066122)
				(mid 399.864072 -86.066122)
				(end 400.157188 -86.066122)
			)
		)
		(stroke
			(width 0)
			(type solid)
		)
		(fill yes)
		(layer "In5.Cu")
		(net "GND")
	)
	(gr_poly
		(pts
			(arc
				(start 404.842218 -86.328504)
				(mid 404.549102 -86.328504)
				(end 404.842218 -86.328504)
			)
		)
		(stroke
			(width 0)
			(type solid)
		)
		(fill yes)
		(layer "In5.Cu")
		(net "GND")
	)
	(gr_poly
		(pts
			(arc
				(start 414.732978 -83.9216)
				(mid 414.439862 -83.9216)
				(end 414.732978 -83.9216)
			)
		)
		(stroke
			(width 0)
			(type solid)
		)
		(fill yes)
		(layer "In5.Cu")
		(net "GND")
	)
	(gr_poly
		(pts
			(arc
				(start 419.12286 -32.911796)
				(mid 418.819584 -32.911796)
				(end 419.12286 -32.911796)
			)
		)
		(stroke
			(width 0)
			(type solid)
		)
		(fill yes)
		(layer "In5.Cu")
		(net "GND")
	)
	(gr_poly
		(pts
			(arc
				(start 419.12286 -31.652972)
				(mid 418.819584 -31.652972)
				(end 419.12286 -31.652972)
			)
		)
		(stroke
			(width 0)
			(type solid)
		)
		(fill yes)
		(layer "In5.Cu")
		(net "GND")
	)
	(gr_poly
		(pts
			(arc
				(start 419.12286 -29.311854)
				(mid 418.819584 -29.311854)
				(end 419.12286 -29.311854)
			)
		)
		(stroke
			(width 0)
			(type solid)
		)
		(fill yes)
		(layer "In5.Cu")
		(net "GND")
	)
	(gr_poly
		(pts
			(arc
				(start 419.12286 -28.05303)
				(mid 418.819584 -28.05303)
				(end 419.12286 -28.05303)
			)
		)
		(stroke
			(width 0)
			(type solid)
		)
		(fill yes)
		(layer "In5.Cu")
		(net "GND")
	)
	(gr_poly
		(pts
			(arc
				(start 420.390828 -32.911796)
				(mid 420.087552 -32.911796)
				(end 420.390828 -32.911796)
			)
		)
		(stroke
			(width 0)
			(type solid)
		)
		(fill yes)
		(layer "In5.Cu")
		(net "GND")
	)
	(gr_poly
		(pts
			(arc
				(start 420.390828 -31.652972)
				(mid 420.087552 -31.652972)
				(end 420.390828 -31.652972)
			)
		)
		(stroke
			(width 0)
			(type solid)
		)
		(fill yes)
		(layer "In5.Cu")
		(net "GND")
	)
	(gr_poly
		(pts
			(arc
				(start 420.390828 -29.311854)
				(mid 420.087552 -29.311854)
				(end 420.390828 -29.311854)
			)
		)
		(stroke
			(width 0)
			(type solid)
		)
		(fill yes)
		(layer "In5.Cu")
		(net "GND")
	)
	(gr_poly
		(pts
			(arc
				(start 420.390828 -28.05303)
				(mid 420.087552 -28.05303)
				(end 420.390828 -28.05303)
			)
		)
		(stroke
			(width 0)
			(type solid)
		)
		(fill yes)
		(layer "In5.Cu")
		(net "GND")
	)
	(gr_poly
		(pts
			(arc
				(start 421.764968 -34.718498)
				(mid 421.461692 -34.718498)
				(end 421.764968 -34.718498)
			)
		)
		(stroke
			(width 0)
			(type solid)
		)
		(fill yes)
		(layer "In5.Cu")
		(net "GND")
	)
	(gr_poly
		(pts
			(arc
				(start 421.764968 -33.459674)
				(mid 421.461692 -33.459674)
				(end 421.764968 -33.459674)
			)
		)
		(stroke
			(width 0)
			(type solid)
		)
		(fill yes)
		(layer "In5.Cu")
		(net "GND")
	)
	(gr_poly
		(pts
			(arc
				(start 421.764968 -31.118302)
				(mid 421.461692 -31.118302)
				(end 421.764968 -31.118302)
			)
		)
		(stroke
			(width 0)
			(type solid)
		)
		(fill yes)
		(layer "In5.Cu")
		(net "GND")
	)
	(gr_poly
		(pts
			(arc
				(start 421.764968 -29.859478)
				(mid 421.461692 -29.859478)
				(end 421.764968 -29.859478)
			)
		)
		(stroke
			(width 0)
			(type solid)
		)
		(fill yes)
		(layer "In5.Cu")
		(net "GND")
	)
	(gr_poly
		(pts
			(arc
				(start 423.032936 -34.718498)
				(mid 422.72966 -34.718498)
				(end 423.032936 -34.718498)
			)
		)
		(stroke
			(width 0)
			(type solid)
		)
		(fill yes)
		(layer "In5.Cu")
		(net "GND")
	)
	(gr_poly
		(pts
			(arc
				(start 423.032936 -33.459674)
				(mid 422.72966 -33.459674)
				(end 423.032936 -33.459674)
			)
		)
		(stroke
			(width 0)
			(type solid)
		)
		(fill yes)
		(layer "In5.Cu")
		(net "GND")
	)
	(gr_poly
		(pts
			(arc
				(start 423.032936 -31.118302)
				(mid 422.72966 -31.118302)
				(end 423.032936 -31.118302)
			)
		)
		(stroke
			(width 0)
			(type solid)
		)
		(fill yes)
		(layer "In5.Cu")
		(net "GND")
	)
	(gr_poly
		(pts
			(arc
				(start 423.032936 -29.859478)
				(mid 422.72966 -29.859478)
				(end 423.032936 -29.859478)
			)
		)
		(stroke
			(width 0)
			(type solid)
		)
		(fill yes)
		(layer "In5.Cu")
		(net "GND")
	)
	(gr_poly
		(pts
			(arc
				(start 440.792362 -95.630746)
				(mid 440.499246 -95.630746)
				(end 440.792362 -95.630746)
			)
		)
		(stroke
			(width 0)
			(type solid)
		)
		(fill yes)
		(layer "In5.Cu")
		(net "GND")
	)
	(gr_poly
		(pts
			(arc
				(start 444.027052 -97.830894)
				(mid 443.733936 -97.830894)
				(end 444.027052 -97.830894)
			)
		)
		(stroke
			(width 0)
			(type solid)
		)
		(fill yes)
		(layer "In5.Cu")
		(net "GND")
	)
	(gr_poly
		(pts
			(arc
				(start 445.122808 -32.911796)
				(mid 444.819532 -32.911796)
				(end 445.122808 -32.911796)
			)
		)
		(stroke
			(width 0)
			(type solid)
		)
		(fill yes)
		(layer "In5.Cu")
		(net "GND")
	)
	(gr_poly
		(pts
			(arc
				(start 445.122808 -31.652972)
				(mid 444.819532 -31.652972)
				(end 445.122808 -31.652972)
			)
		)
		(stroke
			(width 0)
			(type solid)
		)
		(fill yes)
		(layer "In5.Cu")
		(net "GND")
	)
	(gr_poly
		(pts
			(arc
				(start 445.122808 -29.311854)
				(mid 444.819532 -29.311854)
				(end 445.122808 -29.311854)
			)
		)
		(stroke
			(width 0)
			(type solid)
		)
		(fill yes)
		(layer "In5.Cu")
		(net "GND")
	)
	(gr_poly
		(pts
			(arc
				(start 445.122808 -28.05303)
				(mid 444.819532 -28.05303)
				(end 445.122808 -28.05303)
			)
		)
		(stroke
			(width 0)
			(type solid)
		)
		(fill yes)
		(layer "In5.Cu")
		(net "GND")
	)
	(gr_poly
		(pts
			(arc
				(start 446.390776 -32.911796)
				(mid 446.0875 -32.911796)
				(end 446.390776 -32.911796)
			)
		)
		(stroke
			(width 0)
			(type solid)
		)
		(fill yes)
		(layer "In5.Cu")
		(net "GND")
	)
	(gr_poly
		(pts
			(arc
				(start 446.390776 -31.652972)
				(mid 446.0875 -31.652972)
				(end 446.390776 -31.652972)
			)
		)
		(stroke
			(width 0)
			(type solid)
		)
		(fill yes)
		(layer "In5.Cu")
		(net "GND")
	)
	(gr_poly
		(pts
			(arc
				(start 446.390776 -29.311854)
				(mid 446.0875 -29.311854)
				(end 446.390776 -29.311854)
			)
		)
		(stroke
			(width 0)
			(type solid)
		)
		(fill yes)
		(layer "In5.Cu")
		(net "GND")
	)
	(gr_poly
		(pts
			(arc
				(start 446.390776 -28.05303)
				(mid 446.0875 -28.05303)
				(end 446.390776 -28.05303)
			)
		)
		(stroke
			(width 0)
			(type solid)
		)
		(fill yes)
		(layer "In5.Cu")
		(net "GND")
	)
	(gr_poly
		(pts
			(arc
				(start 447.764916 -34.718498)
				(mid 447.46164 -34.718498)
				(end 447.764916 -34.718498)
			)
		)
		(stroke
			(width 0)
			(type solid)
		)
		(fill yes)
		(layer "In5.Cu")
		(net "GND")
	)
	(gr_poly
		(pts
			(arc
				(start 447.764916 -33.459674)
				(mid 447.46164 -33.459674)
				(end 447.764916 -33.459674)
			)
		)
		(stroke
			(width 0)
			(type solid)
		)
		(fill yes)
		(layer "In5.Cu")
		(net "GND")
	)
	(gr_poly
		(pts
			(arc
				(start 447.764916 -31.118302)
				(mid 447.46164 -31.118302)
				(end 447.764916 -31.118302)
			)
		)
		(stroke
			(width 0)
			(type solid)
		)
		(fill yes)
		(layer "In5.Cu")
		(net "GND")
	)
	(gr_poly
		(pts
			(arc
				(start 447.764916 -29.859478)
				(mid 447.46164 -29.859478)
				(end 447.764916 -29.859478)
			)
		)
		(stroke
			(width 0)
			(type solid)
		)
		(fill yes)
		(layer "In5.Cu")
		(net "GND")
	)
	(gr_poly
		(pts
			(arc
				(start 449.032884 -34.718498)
				(mid 448.729608 -34.718498)
				(end 449.032884 -34.718498)
			)
		)
		(stroke
			(width 0)
			(type solid)
		)
		(fill yes)
		(layer "In5.Cu")
		(net "GND")
	)
	(gr_poly
		(pts
			(arc
				(start 449.032884 -33.459674)
				(mid 448.729608 -33.459674)
				(end 449.032884 -33.459674)
			)
		)
		(stroke
			(width 0)
			(type solid)
		)
		(fill yes)
		(layer "In5.Cu")
		(net "GND")
	)
	(gr_poly
		(pts
			(arc
				(start 449.032884 -31.118302)
				(mid 448.729608 -31.118302)
				(end 449.032884 -31.118302)
			)
		)
		(stroke
			(width 0)
			(type solid)
		)
		(fill yes)
		(layer "In5.Cu")
		(net "GND")
	)
	(gr_poly
		(pts
			(arc
				(start 449.032884 -29.859478)
				(mid 448.729608 -29.859478)
				(end 449.032884 -29.859478)
			)
		)
		(stroke
			(width 0)
			(type solid)
		)
		(fill yes)
		(layer "In5.Cu")
		(net "GND")
	)
	(gr_poly
		(pts
			(arc
				(start 239.385348 -70.857872)
				(mid 239.071912 -70.857872)
				(end 239.385348 -70.857872)
			)
		)
		(stroke
			(width 0)
			(type solid)
		)
		(fill yes)
		(layer "In5.Cu")
		(net "GND")
	)
	(gr_poly
		(pts
			(arc
				(start 261.823454 -73.332086)
				(mid 261.510018 -73.332086)
				(end 261.823454 -73.332086)
			)
		)
		(stroke
			(width 0)
			(type solid)
		)
		(fill yes)
		(layer "In5.Cu")
		(net "GND")
	)
	(gr_poly
		(pts
			(arc
				(start 262.56615 -75.892406)
				(mid 262.254746 -75.892406)
				(end 262.56615 -75.892406)
			)
		)
		(stroke
			(width 0)
			(type solid)
		)
		(fill yes)
		(layer "In5.Cu")
		(net "GND")
	)
	(gr_poly
		(pts
			(arc
				(start 263.82599 -75.892406)
				(mid 263.512554 -75.892406)
				(end 263.82599 -75.892406)
			)
		)
		(stroke
			(width 0)
			(type solid)
		)
		(fill yes)
		(layer "In5.Cu")
		(net "GND")
	)
	(gr_poly
		(pts
			(arc
				(start 217.246454 -91.187016)
				(mid 216.901522 -91.187016)
				(end 217.246454 -91.187016)
			)
		)
		(stroke
			(width 0)
			(type solid)
		)
		(fill yes)
		(layer "In5.Cu")
		(net "GND")
	)
	(gr_poly
		(pts
			(arc
				(start 221.503494 -94.988634)
				(mid 221.158562 -94.988634)
				(end 221.503494 -94.988634)
			)
		)
		(stroke
			(width 0)
			(type solid)
		)
		(fill yes)
		(layer "In5.Cu")
		(net "GND")
	)
	(gr_poly
		(pts
			(arc
				(start 371.17909 -244.920262)
				(mid 370.83365 -244.920262)
				(end 371.17909 -244.920262)
			)
		)
		(stroke
			(width 0)
			(type solid)
		)
		(fill yes)
		(layer "In5.Cu")
		(net "GND")
	)
	(gr_poly
		(pts
			(arc
				(start 252.431042 -397.963136)
				(mid 252.450565 -397.959235)
				(end 252.46711 -397.94815)
			)
			(arc
				(start 252.932438 -397.482822)
				(mid 252.943549 -397.466288)
				(end 252.947424 -397.446754)
			)
			(arc
				(start 252.947424 -392.961114)
				(mid 252.943523 -392.941591)
				(end 252.932438 -392.925046)
			)
			(arc
				(start 252.451362 -392.44397)
				(mid 252.434828 -392.432859)
				(end 252.415294 -392.428984)
			)
			(arc
				(start 245.184422 -392.428984)
				(mid 245.164899 -392.432885)
				(end 245.148354 -392.44397)
			)
			(arc
				(start 244.746526 -392.845798)
				(mid 244.735415 -392.862332)
				(end 244.73154 -392.881866)
			)
			(arc
				(start 244.73154 -397.594328)
				(mid 244.735441 -397.613851)
				(end 244.746526 -397.630396)
			)
			(arc
				(start 245.06428 -397.94815)
				(mid 245.080814 -397.959261)
				(end 245.100348 -397.963136)
			)
		)
		(stroke
			(width 0)
			(type solid)
		)
		(fill yes)
		(layer "In5.Cu")
		(net "P12V_STBY_FUSE")
	)
	(gr_poly
		(pts
			(arc
				(start 261.653274 -355.276658)
				(mid 261.672797 -355.272757)
				(end 261.689342 -355.261672)
			)
			(arc
				(start 262.021574 -354.92944)
				(mid 262.032685 -354.912906)
				(end 262.03656 -354.893372)
			)
			(arc
				(start 262.03656 -352.36277)
				(mid 262.035574 -352.353061)
				(end 262.03275 -352.34372)
			)
			(arc
				(start 261.770876 -351.70237)
				(mid 261.752065 -351.679405)
				(end 261.723632 -351.670874)
			)
			(arc
				(start 256.266442 -351.670874)
				(mid 256.246919 -351.674775)
				(end 256.230374 -351.68586)
			)
			(arc
				(start 256.076196 -351.840038)
				(mid 256.065085 -351.856572)
				(end 256.06121 -351.876106)
			)
			(arc
				(start 256.06121 -354.912168)
				(mid 256.065111 -354.931691)
				(end 256.076196 -354.948236)
			)
			(arc
				(start 256.389632 -355.261672)
				(mid 256.406166 -355.272783)
				(end 256.4257 -355.276658)
			)
		)
		(stroke
			(width 0)
			(type solid)
		)
		(fill yes)
		(layer "In5.Cu")
		(net "GND")
	)
	(gr_poly
		(pts
			(arc
				(start 101.97211 -196.601334)
				(mid 101.998133 -196.615213)
				(end 102.027482 -196.612256)
			)
			(xy 102.041706 -196.606414) (xy 102.058724 -196.581014)
			(arc
				(start 102.058724 -196.504052)
				(mid 102.07571 -196.472816)
				(end 102.109016 -196.460364)
			)
			(arc
				(start 103.105458 -196.460364)
				(mid 103.133497 -196.451757)
				(end 103.152194 -196.429122)
			)
			(xy 103.15829 -196.414644) (xy 103.152448 -196.384672)
			(arc
				(start 102.059232 -195.29171)
				(mid 102.042815 -195.280648)
				(end 102.023418 -195.276724)
			)
			(arc
				(start 100.9142 -195.276724)
				(mid 100.878279 -195.291603)
				(end 100.8634 -195.327524)
			)
			(arc
				(start 100.8634 -195.471542)
				(mid 100.867301 -195.491065)
				(end 100.878386 -195.50761)
			)
		)
		(stroke
			(width 0)
			(type solid)
		)
		(fill yes)
		(layer "In5.Cu")
		(net "GND")
	)
	(gr_poly
		(pts
			(arc
				(start 241.82197 -376.463306)
				(mid 241.841493 -376.459405)
				(end 241.858038 -376.44832)
			)
			(arc
				(start 242.310666 -375.995692)
				(mid 242.321777 -375.979158)
				(end 242.325652 -375.959624)
			)
			(arc
				(start 242.325652 -368.584988)
				(mid 242.321751 -368.565465)
				(end 242.310666 -368.54892)
			)
			(arc
				(start 242.213638 -368.451892)
				(mid 242.197104 -368.440781)
				(end 242.17757 -368.436906)
			)
			(arc
				(start 236.987334 -368.436906)
				(mid 236.967811 -368.440807)
				(end 236.951266 -368.451892)
			)
			(arc
				(start 236.373924 -368.451892)
				(mid 236.354401 -368.455793)
				(end 236.337856 -368.466878)
			)
			(arc
				(start 236.101128 -368.703606)
				(mid 236.090017 -368.72014)
				(end 236.086142 -368.739674)
			)
			(arc
				(start 236.086142 -376.112786)
				(mid 236.090043 -376.132309)
				(end 236.101128 -376.148854)
			)
			(arc
				(start 236.400594 -376.44832)
				(mid 236.417128 -376.459431)
				(end 236.436662 -376.463306)
			)
		)
		(stroke
			(width 0)
			(type solid)
		)
		(fill yes)
		(layer "In5.Cu")
		(net "P12V_STBY_R1")
	)
	(gr_poly
		(pts
			(arc
				(start 107.582208 -193.779902)
				(mid 107.608237 -193.793712)
				(end 107.63758 -193.790824)
			)
			(xy 107.652058 -193.784728) (xy 107.669076 -193.759582)
			(arc
				(start 107.669076 -193.620136)
				(mid 107.665126 -193.600749)
				(end 107.65409 -193.584322)
			)
			(arc
				(start 105.643934 -191.574166)
				(mid 105.627517 -191.563104)
				(end 105.60812 -191.55918)
			)
			(arc
				(start 101.928168 -191.55918)
				(mid 101.801169 -191.534012)
				(end 101.693472 -191.462152)
			)
			(arc
				(start 101.04247 -190.810896)
				(mid 101.016441 -190.797086)
				(end 100.987098 -190.799974)
			)
			(xy 100.97262 -190.80607) (xy 100.955856 -190.831216)
			(arc
				(start 100.955856 -191.426846)
				(mid 100.959689 -191.446203)
				(end 100.970588 -191.46266)
			)
			(arc
				(start 101.83368 -192.325752)
				(mid 101.850126 -192.336678)
				(end 101.869494 -192.340484)
			)
			(arc
				(start 106.00563 -192.340484)
				(mid 106.132658 -192.365769)
				(end 106.240326 -192.437766)
			)
		)
		(stroke
			(width 0)
			(type solid)
		)
		(fill yes)
		(layer "In5.Cu")
		(net "GND")
	)
	(gr_poly
		(pts
			(arc
				(start 265.959082 -366.188752)
				(mid 265.978605 -366.184851)
				(end 265.99515 -366.173766)
			)
			(arc
				(start 266.33932 -365.829596)
				(mid 266.350431 -365.813062)
				(end 266.354306 -365.793528)
			)
			(arc
				(start 266.354306 -362.15955)
				(mid 266.350494 -362.140495)
				(end 266.339828 -362.124244)
			)
			(xy 266.04087 -361.817158) (xy 266.040362 -361.81665)
			(arc
				(start 261.133336 -356.909624)
				(mid 261.116802 -356.898513)
				(end 261.097268 -356.894638)
			)
			(arc
				(start 252.613414 -356.894638)
				(mid 252.593891 -356.898539)
				(end 252.577346 -356.909624)
			)
			(arc
				(start 249.725942 -359.761028)
				(mid 249.709408 -359.772139)
				(end 249.689874 -359.776014)
			)
			(arc
				(start 246.79783 -359.776014)
				(mid 246.778307 -359.779915)
				(end 246.761762 -359.791)
			)
			(xy 246.757952 -359.79481) (xy 246.73941 -359.80243)
			(arc
				(start 238.167926 -359.80243)
				(mid 238.148403 -359.806331)
				(end 238.131858 -359.817416)
			)
			(arc
				(start 236.869478 -361.079796)
				(mid 236.858367 -361.09633)
				(end 236.854492 -361.115864)
			)
			(arc
				(start 236.854492 -365.817404)
				(mid 236.858393 -365.836927)
				(end 236.869478 -365.853472)
			)
			(arc
				(start 237.189772 -366.173766)
				(mid 237.206306 -366.184877)
				(end 237.22584 -366.188752)
			)
		)
		(stroke
			(width 0)
			(type solid)
		)
		(fill yes)
		(layer "In5.Cu")
		(net "P12V_AUX")
	)
	(gr_poly
		(pts
			(arc
				(start 385.662424 -228.086666)
				(mid 385.681947 -228.082765)
				(end 385.698492 -228.07168)
			)
			(xy 385.70154 -228.068632)
			(arc
				(start 385.70154 -225.691954)
				(mid 385.697639 -225.672431)
				(end 385.686554 -225.655886)
			)
			(arc
				(start 384.83032 -224.799652)
				(mid 384.813786 -224.788541)
				(end 384.794252 -224.784666)
			)
			(arc
				(start 381.029718 -224.784666)
				(mid 381.010195 -224.788567)
				(end 380.99365 -224.799652)
			)
			(xy 380.769622 -225.02368) (xy 380.762256 -225.030792) (xy 380.754636 -225.049588)
			(arc
				(start 380.754636 -226.96678)
				(mid 380.758961 -226.987292)
				(end 380.771146 -227.004372)
			)
			(arc
				(start 380.771146 -227.004372)
				(mid 380.862533 -227.131963)
				(end 380.894844 -227.28555)
			)
			(xy 380.89459 -227.298504) (xy 380.894336 -227.309172) (xy 380.901956 -227.32873)
			(arc
				(start 380.9873 -227.414074)
				(mid 380.998411 -227.430608)
				(end 381.002286 -227.450142)
			)
			(arc
				(start 381.002286 -227.532184)
				(mid 381.006187 -227.551707)
				(end 381.017272 -227.568252)
			)
			(arc
				(start 381.14478 -227.69576)
				(mid 381.161314 -227.706871)
				(end 381.180848 -227.710746)
			)
			(arc
				(start 381.850646 -227.710746)
				(mid 381.870169 -227.714647)
				(end 381.886714 -227.725732)
			)
			(arc
				(start 382.232662 -228.07168)
				(mid 382.249196 -228.082791)
				(end 382.26873 -228.086666)
			)
		)
		(stroke
			(width 0)
			(type solid)
		)
		(fill yes)
		(layer "In5.Cu")
		(net "GND")
	)
	(gr_poly
		(pts
			(xy 105.341166 -198.941436)
			(arc
				(start 106.232198 -198.050404)
				(mid 106.24326 -198.033987)
				(end 106.247184 -198.01459)
			)
			(arc
				(start 106.247184 -195.66636)
				(mid 106.243234 -195.646973)
				(end 106.232198 -195.630546)
			)
			(arc
				(start 104.120442 -193.51879)
				(mid 104.104025 -193.507728)
				(end 104.084628 -193.503804)
			)
			(arc
				(start 101.440488 -193.503804)
				(mid 101.313489 -193.478636)
				(end 101.205792 -193.406776)
			)
			(arc
				(start 100.950014 -193.150998)
				(mid 100.923991 -193.137119)
				(end 100.894642 -193.140076)
			)
			(xy 100.880418 -193.145918) (xy 100.8634 -193.171318)
			(arc
				(start 100.8634 -194.098926)
				(mid 100.867301 -194.118449)
				(end 100.878386 -194.134994)
			)
			(arc
				(start 100.935282 -194.19189)
				(mid 100.951699 -194.202952)
				(end 100.971096 -194.206876)
			)
			(arc
				(start 103.847392 -194.206876)
				(mid 103.974391 -194.232044)
				(end 104.082088 -194.303904)
			)
			(arc
				(start 105.168446 -195.390262)
				(mid 105.240449 -195.497927)
				(end 105.265728 -195.624958)
			)
			(arc
				(start 105.265728 -198.894446)
				(mid 105.274167 -198.922741)
				(end 105.29697 -198.941436)
			)
			(xy 105.311448 -198.947278)
		)
		(stroke
			(width 0)
			(type solid)
		)
		(fill yes)
		(layer "In5.Cu")
		(net "GND")
	)
	(gr_poly
		(pts
			(arc
				(start 132.2832 -179.03444)
				(mid 132.325377 -179.027631)
				(end 132.368036 -179.025296)
			)
			(arc
				(start 132.368036 -179.025296)
				(mid 132.410693 -179.027645)
				(end 132.452872 -179.03444)
			)
			(xy 132.457952 -179.035456)
			(arc
				(start 133.987286 -179.035456)
				(mid 134.006809 -179.031555)
				(end 134.023354 -179.02047)
			)
			(arc
				(start 134.097268 -178.946556)
				(mid 134.108379 -178.930022)
				(end 134.112254 -178.910488)
			)
			(arc
				(start 134.112254 -176.398428)
				(mid 134.108353 -176.378905)
				(end 134.097268 -176.36236)
			)
			(arc
				(start 134.003796 -176.268888)
				(mid 133.987262 -176.257777)
				(end 133.967728 -176.253902)
			)
			(arc
				(start 131.460748 -176.253902)
				(mid 131.441225 -176.257803)
				(end 131.42468 -176.268888)
			)
			(arc
				(start 131.335018 -176.35855)
				(mid 131.323907 -176.375084)
				(end 131.320032 -176.394618)
			)
			(xy 131.320032 -176.597056)
			(arc
				(start 131.322318 -176.604168)
				(mid 131.339848 -176.722278)
				(end 131.322318 -176.840388)
			)
			(xy 131.320032 -176.8475) (xy 131.320032 -178.0032)
			(arc
				(start 131.322826 -178.011074)
				(mid 131.339356 -178.076198)
				(end 131.344924 -178.143154)
			)
			(arc
				(start 131.344924 -178.143154)
				(mid 131.339336 -178.210107)
				(end 131.322826 -178.275234)
			)
			(xy 131.320032 -178.283108)
			(arc
				(start 131.320032 -178.682396)
				(mid 131.323933 -178.701919)
				(end 131.335018 -178.718464)
			)
			(arc
				(start 131.637024 -179.02047)
				(mid 131.653558 -179.031581)
				(end 131.673092 -179.035456)
			)
			(xy 132.27812 -179.035456)
		)
		(stroke
			(width 0)
			(type solid)
		)
		(fill yes)
		(layer "In5.Cu")
		(net "GND")
	)
	(gr_poly
		(pts
			(arc
				(start 263.911842 -377.745752)
				(mid 263.945438 -377.733057)
				(end 263.962134 -377.701302)
			)
			(arc
				(start 263.962134 -377.701302)
				(mid 264.830462 -374.954053)
				(end 266.61618 -372.69293)
			)
			(arc
				(start 266.61618 -372.69293)
				(mid 266.62895 -372.67562)
				(end 266.633452 -372.654576)
			)
			(arc
				(start 266.633452 -368.922046)
				(mid 266.629551 -368.902523)
				(end 266.618466 -368.885978)
			)
			(arc
				(start 266.291568 -368.55908)
				(mid 266.275034 -368.547969)
				(end 266.2555 -368.544094)
			)
			(xy 243.539264 -368.544094) (xy 243.533676 -368.538506)
			(arc
				(start 242.778534 -368.538506)
				(mid 242.759011 -368.542407)
				(end 242.742466 -368.553492)
			)
			(arc
				(start 242.620038 -368.67592)
				(mid 242.608927 -368.692454)
				(end 242.605052 -368.711988)
			)
			(arc
				(start 242.605052 -377.229624)
				(mid 242.608953 -377.249147)
				(end 242.620038 -377.265692)
			)
			(arc
				(start 243.085112 -377.730766)
				(mid 243.101646 -377.741877)
				(end 243.12118 -377.745752)
			)
		)
		(stroke
			(width 0)
			(type solid)
		)
		(fill yes)
		(layer "In5.Cu")
		(net "P12V_STBY_R2")
	)
	(gr_poly
		(pts
			(arc
				(start 9.894824 -35.348164)
				(mid 9.914211 -35.344214)
				(end 9.930638 -35.333178)
			)
			(arc
				(start 12.084304 -33.179512)
				(mid 12.09523 -33.163066)
				(end 12.099036 -33.143698)
			)
			(arc
				(start 12.099036 -32.165798)
				(mid 12.143724 -31.941608)
				(end 12.27074 -31.751524)
			)
			(arc
				(start 14.948662 -29.073602)
				(mid 14.962668 -29.047611)
				(end 14.959838 -29.01823)
			)
			(xy 14.953742 -29.003752) (xy 14.928596 -28.986988)
			(arc
				(start 14.343888 -28.986988)
				(mid 14.324531 -28.990821)
				(end 14.308074 -29.00172)
			)
			(arc
				(start 12.514326 -30.795468)
				(mid 12.324271 -30.922552)
				(end 12.100052 -30.967172)
			)
			(arc
				(start 11.616944 -30.967172)
				(mid 11.597587 -30.971005)
				(end 11.58113 -30.981904)
			)
			(arc
				(start 11.480038 -31.082996)
				(mid 11.468976 -31.099413)
				(end 11.465052 -31.11881)
			)
			(arc
				(start 11.465052 -32.644588)
				(mid 11.420549 -32.868789)
				(end 11.293602 -33.058862)
			)
			(arc
				(start 9.091168 -35.261296)
				(mid 9.077162 -35.287287)
				(end 9.079992 -35.316668)
			)
			(xy 9.086088 -35.331146) (xy 9.111234 -35.348164)
		)
		(stroke
			(width 0)
			(type solid)
		)
		(fill yes)
		(layer "In5.Cu")
		(net "GND")
	)
	(gr_poly
		(pts
			(arc
				(start 209.129122 -366.379252)
				(mid 209.148479 -366.375419)
				(end 209.164936 -366.36452)
			)
			(arc
				(start 209.256122 -366.273334)
				(mid 209.267233 -366.2568)
				(end 209.271108 -366.237266)
			)
			(arc
				(start 209.271108 -365.67872)
				(mid 209.275009 -365.659197)
				(end 209.286094 -365.642652)
			)
			(arc
				(start 209.818224 -365.110522)
				(mid 209.834758 -365.099411)
				(end 209.854292 -365.095536)
			)
			(arc
				(start 210.50885 -365.095536)
				(mid 210.528373 -365.091635)
				(end 210.544918 -365.08055)
			)
			(arc
				(start 211.34578 -364.279688)
				(mid 211.356891 -364.263154)
				(end 211.360766 -364.24362)
			)
			(arc
				(start 211.360766 -362.605066)
				(mid 211.356865 -362.585543)
				(end 211.34578 -362.568998)
			)
			(arc
				(start 211.050632 -362.27385)
				(mid 211.034098 -362.262739)
				(end 211.014564 -362.258864)
			)
			(arc
				(start 208.57718 -362.258864)
				(mid 208.557657 -362.262765)
				(end 208.541112 -362.27385)
			)
			(arc
				(start 207.398366 -363.416596)
				(mid 207.381832 -363.427707)
				(end 207.362298 -363.431582)
			)
			(arc
				(start 205.782672 -363.431582)
				(mid 205.763149 -363.435483)
				(end 205.746604 -363.446568)
			)
			(arc
				(start 205.55331 -363.639862)
				(mid 205.542248 -363.656279)
				(end 205.538324 -363.675676)
			)
			(arc
				(start 205.538324 -364.310168)
				(mid 205.513156 -364.437167)
				(end 205.441296 -364.544864)
			)
			(arc
				(start 205.320646 -364.665514)
				(mid 205.309535 -364.682048)
				(end 205.30566 -364.701582)
			)
			(arc
				(start 205.30566 -366.184942)
				(mid 205.309561 -366.204465)
				(end 205.320646 -366.22101)
			)
			(arc
				(start 205.464156 -366.36452)
				(mid 205.480602 -366.375446)
				(end 205.49997 -366.379252)
			)
		)
		(stroke
			(width 0)
			(type solid)
		)
		(fill yes)
		(layer "In5.Cu")
		(net "P12V_AUX")
	)
	(gr_poly
		(pts
			(arc
				(start 17.779238 -24.554688)
				(mid 17.798625 -24.550738)
				(end 17.815052 -24.539702)
			)
			(arc
				(start 18.225262 -24.129492)
				(mid 18.332956 -24.057626)
				(end 18.459958 -24.032464)
			)
			(arc
				(start 19.54149 -24.032464)
				(mid 19.554934 -24.030513)
				(end 19.567398 -24.025098)
			)
			(arc
				(start 19.567398 -24.025098)
				(mid 19.661213 -23.9853)
				(end 19.762216 -23.971758)
			)
			(arc
				(start 19.762216 -23.971758)
				(mid 19.853658 -23.982941)
				(end 19.939762 -24.0157)
			)
			(xy 19.94535 -24.018494) (xy 19.957288 -24.021288)
			(arc
				(start 20.495006 -24.021288)
				(mid 20.523193 -24.012751)
				(end 20.541996 -23.990046)
			)
			(xy 20.547838 -23.975568) (xy 20.541996 -23.94585)
			(arc
				(start 20.302982 -23.706836)
				(mid 20.286536 -23.69591)
				(end 20.267168 -23.692104)
			)
			(xy 16.854932 -23.692104) (xy 16.829024 -23.709884)
			(arc
				(start 16.823436 -23.72487)
				(mid 16.466566 -23.971502)
				(end 16.109696 -23.72487)
			)
			(xy 16.104108 -23.709884) (xy 16.0782 -23.692104)
			(arc
				(start 15.551404 -23.692104)
				(mid 15.532047 -23.695937)
				(end 15.51559 -23.706836)
			)
			(arc
				(start 14.754606 -24.46782)
				(mid 14.7406 -24.493811)
				(end 14.74343 -24.523192)
			)
			(xy 14.749526 -24.53767) (xy 14.774672 -24.554688)
		)
		(stroke
			(width 0)
			(type solid)
		)
		(fill yes)
		(layer "In5.Cu")
		(net "GND")
	)
	(gr_poly
		(pts
			(xy 117.95633 -207.809846) (xy 117.9633 -207.816723) (xy 117.980986 -207.825085) (xy 118.000514 -207.826263)
			(xy 118.009924 -207.823562) (xy 118.0338 -207.815434) (xy 118.043691 -207.811553) (xy 118.059355 -207.797235)
			(xy 118.067852 -207.777788) (xy 118.068344 -207.767174) (xy 118.068344 -204.55636) (xy 118.067912 -204.546294)
			(xy 118.060181 -204.527706) (xy 118.053358 -204.520292) (xy 117.562376 -204.02931) (xy 117.55503 -204.022502)
			(xy 117.536567 -204.014777) (xy 117.526562 -204.014324) (xy 114.283998 -204.014324) (xy 114.273954 -204.014749)
			(xy 114.255403 -204.022458) (xy 114.24123 -204.036695) (xy 114.237008 -204.04582) (xy 114.231166 -204.060298)
			(xy 114.237008 -204.090016) (xy 115.1636 -205.016608) (xy 116.266212 -205.016608) (xy 116.270283 -204.960986)
			(xy 116.282409 -204.906549) (xy 116.302332 -204.854458) (xy 116.329628 -204.805823) (xy 116.363714 -204.76168)
			(xy 116.403863 -204.722971) (xy 116.449221 -204.69052) (xy 116.498821 -204.665019) (xy 116.551605 -204.647012)
			(xy 116.606448 -204.636882) (xy 116.662182 -204.634845) (xy 116.717619 -204.640945) (xy 116.771576 -204.655051)
			(xy 116.822905 -204.676863) (xy 116.870511 -204.705917) (xy 116.913379 -204.741592) (xy 116.950596 -204.783129)
			(xy 116.981369 -204.829642) (xy 117.005041 -204.880139) (xy 117.021109 -204.933546) (xy 117.029229 -204.988722)
			(xy 117.029738 -205.016608) (xy 117.029229 -205.044494) (xy 117.021109 -205.09967) (xy 117.005041 -205.153077)
			(xy 116.981369 -205.203574) (xy 116.950596 -205.250087) (xy 116.913379 -205.291624) (xy 116.870511 -205.327299)
			(xy 116.822905 -205.356353) (xy 116.771576 -205.378165) (xy 116.717619 -205.392271) (xy 116.662182 -205.398371)
			(xy 116.606448 -205.396334) (xy 116.551605 -205.386204) (xy 116.498821 -205.368197) (xy 116.449221 -205.342696)
			(xy 116.403863 -205.310245) (xy 116.363714 -205.271536) (xy 116.329628 -205.227393) (xy 116.302332 -205.178758)
			(xy 116.282409 -205.126667) (xy 116.270283 -205.07223) (xy 116.266212 -205.016608) (xy 115.1636 -205.016608)
			(xy 117.947694 -207.800702)
		)
		(stroke
			(width 0)
			(type solid)
		)
		(fill yes)
		(layer "In5.Cu")
		(net "GND")
	)
	(gr_poly
		(pts
			(xy 138.45159 -198.186548) (xy 138.456924 -198.184008) (xy 138.48323 -198.171702) (xy 138.538636 -198.154298)
			(xy 138.596035 -198.145469) (xy 138.625072 -198.144892) (xy 139.475464 -198.144892) (xy 139.488672 -198.144892)
			(xy 139.517751 -198.145447) (xy 139.575235 -198.154275) (xy 139.630722 -198.171701) (xy 139.657074 -198.184008)
			(xy 139.662408 -198.186548) (xy 139.67333 -198.189088) (xy 143.612362 -198.189088) (xy 143.620911 -198.188767)
			(xy 143.637058 -198.183148) (xy 143.650454 -198.172523) (xy 143.655288 -198.165466) (xy 143.708374 -198.082154)
			(xy 143.709898 -198.056246) (xy 143.704564 -198.044562) (xy 143.693211 -198.019114) (xy 143.677164 -197.965751)
			(xy 143.669028 -197.910625) (xy 143.668496 -197.882764) (xy 143.668947 -197.85603) (xy 143.676416 -197.803087)
			(xy 143.691202 -197.751705) (xy 143.713015 -197.70289) (xy 143.741429 -197.657597) (xy 143.775887 -197.616715)
			(xy 143.795496 -197.598538) (xy 143.795496 -196.4944) (xy 139.338304 -192.037208) (xy 135.70585 -192.037208)
			(xy 134.97306 -192.770252) (xy 134.97306 -196.196712) (xy 136.162794 -196.196712) (xy 136.166865 -196.14109)
			(xy 136.178991 -196.086653) (xy 136.198914 -196.034562) (xy 136.22621 -195.985927) (xy 136.260296 -195.941784)
			(xy 136.300445 -195.903075) (xy 136.345803 -195.870624) (xy 136.395403 -195.845123) (xy 136.448187 -195.827116)
			(xy 136.50303 -195.816986) (xy 136.558764 -195.814949) (xy 136.614201 -195.821049) (xy 136.668158 -195.835155)
			(xy 136.719487 -195.856967) (xy 136.767093 -195.886021) (xy 136.809961 -195.921696) (xy 136.847178 -195.963233)
			(xy 136.877951 -196.009746) (xy 136.901623 -196.060243) (xy 136.917691 -196.11365) (xy 136.925811 -196.168826)
			(xy 136.92632 -196.196712) (xy 136.925811 -196.224598) (xy 136.917691 -196.279774) (xy 136.901623 -196.333181)
			(xy 136.877951 -196.383678) (xy 136.847178 -196.430191) (xy 136.809961 -196.471728) (xy 136.767093 -196.507403)
			(xy 136.719487 -196.536457) (xy 136.668158 -196.558269) (xy 136.614201 -196.572375) (xy 136.558764 -196.578475)
			(xy 136.50303 -196.576438) (xy 136.448187 -196.566308) (xy 136.395403 -196.548301) (xy 136.345803 -196.5228)
			(xy 136.300445 -196.490349) (xy 136.260296 -196.45164) (xy 136.22621 -196.407497) (xy 136.198914 -196.358862)
			(xy 136.178991 -196.306771) (xy 136.166865 -196.252334) (xy 136.162794 -196.196712) (xy 134.97306 -196.196712)
			(xy 134.97306 -197.839584) (xy 135.322564 -198.189088) (xy 138.440414 -198.189088)
		)
		(stroke
			(width 0)
			(type solid)
		)
		(fill yes)
		(layer "In5.Cu")
		(net "GND")
	)
	(gr_poly
		(pts
			(arc
				(start 24.769572 -28.928822)
				(mid 24.805493 -28.913943)
				(end 24.820372 -28.878022)
			)
			(arc
				(start 24.820372 -28.536138)
				(mid 24.816422 -28.516751)
				(end 24.805386 -28.500324)
			)
			(arc
				(start 21.005038 -24.699976)
				(mid 20.988592 -24.68905)
				(end 20.969224 -24.685244)
			)
			(xy 19.957288 -24.685244) (xy 19.94535 -24.688038)
			(arc
				(start 19.939762 -24.690832)
				(mid 19.853662 -24.72361)
				(end 19.762216 -24.734774)
			)
			(arc
				(start 19.762216 -24.734774)
				(mid 19.681509 -24.726085)
				(end 19.604482 -24.700484)
			)
			(xy 19.594322 -24.695912)
			(arc
				(start 18.992342 -24.695912)
				(mid 18.967192 -24.702719)
				(end 18.948654 -24.721058)
			)
			(xy 18.897346 -24.80818) (xy 18.897092 -24.835104)
			(arc
				(start 18.903442 -24.846788)
				(mid 18.939214 -24.936316)
				(end 18.951448 -25.031954)
			)
			(arc
				(start 18.951448 -25.031954)
				(mid 18.839707 -25.301721)
				(end 18.56994 -25.413462)
			)
			(arc
				(start 18.56994 -25.413462)
				(mid 18.376213 -25.360574)
				(end 18.236184 -25.216612)
			)
			(xy 18.231358 -25.207722) (xy 18.215356 -25.195276) (xy 18.126964 -25.169876) (xy 18.106898 -25.172162)
			(arc
				(start 18.098262 -25.176988)
				(mid 18.020609 -25.207748)
				(end 17.937734 -25.218136)
			)
			(arc
				(start 17.863566 -25.218136)
				(mid 17.835282 -25.226738)
				(end 17.816576 -25.249632)
			)
			(xy 17.810734 -25.26411) (xy 17.816576 -25.293828)
			(arc
				(start 18.491962 -25.969214)
				(mid 18.508379 -25.980276)
				(end 18.527776 -25.9842)
			)
			(arc
				(start 18.636234 -25.9842)
				(mid 18.655621 -25.98025)
				(end 18.672048 -25.969214)
			)
			(arc
				(start 18.998946 -25.642316)
				(mid 19.10664 -25.57045)
				(end 19.233642 -25.545288)
			)
			(arc
				(start 21.249386 -25.545288)
				(mid 21.376385 -25.570456)
				(end 21.484082 -25.642316)
			)
			(arc
				(start 24.667972 -28.826206)
				(mid 24.699174 -28.86225)
				(end 24.724868 -28.902406)
			)
			(xy 24.731726 -28.914852) (xy 24.755348 -28.928822)
		)
		(stroke
			(width 0)
			(type solid)
		)
		(fill yes)
		(layer "In5.Cu")
		(net "GND")
	)
	(gr_poly
		(pts
			(arc
				(start 342.250522 -262.029448)
				(mid 342.270045 -262.025547)
				(end 342.28659 -262.014462)
			)
			(arc
				(start 342.489282 -261.81177)
				(mid 342.500393 -261.795236)
				(end 342.504268 -261.775702)
			)
			(arc
				(start 342.504268 -259.381498)
				(mid 342.508169 -259.361975)
				(end 342.519254 -259.34543)
			)
			(arc
				(start 343.227914 -258.63677)
				(mid 343.244448 -258.625659)
				(end 343.263982 -258.621784)
			)
			(arc
				(start 345.042236 -258.621784)
				(mid 345.061759 -258.625685)
				(end 345.078304 -258.63677)
			)
			(arc
				(start 345.226132 -258.784598)
				(mid 345.237243 -258.801132)
				(end 345.241118 -258.820666)
			)
			(xy 345.241118 -258.922774)
			(arc
				(start 345.242642 -258.92887)
				(mid 345.251013 -258.974378)
				(end 345.253818 -259.020564)
			)
			(arc
				(start 345.253818 -259.020564)
				(mid 345.252662 -259.049989)
				(end 345.249246 -259.079238)
			)
			(xy 345.247468 -259.09143) (xy 345.254834 -259.11429)
			(arc
				(start 345.458796 -259.318252)
				(mid 345.47533 -259.329363)
				(end 345.494864 -259.333238)
			)
			(arc
				(start 345.94546 -259.333238)
				(mid 345.964983 -259.329337)
				(end 345.981528 -259.318252)
			)
			(arc
				(start 346.343986 -258.955794)
				(mid 346.355097 -258.93926)
				(end 346.358972 -258.919726)
			)
			(arc
				(start 346.358972 -257.467354)
				(mid 346.355071 -257.447831)
				(end 346.343986 -257.431286)
			)
			(arc
				(start 345.90863 -256.99593)
				(mid 345.892096 -256.984819)
				(end 345.872562 -256.980944)
			)
			(arc
				(start 340.385654 -256.980944)
				(mid 340.366131 -256.977043)
				(end 340.349586 -256.965958)
			)
			(xy 335.188814 -251.805186) (xy 335.17586 -251.798074)
			(arc
				(start 335.168748 -251.79655)
				(mid 334.978271 -251.693149)
				(end 334.87487 -251.502672)
			)
			(xy 334.873346 -251.49556) (xy 334.866234 -251.482606)
			(arc
				(start 334.844136 -251.460508)
				(mid 334.833025 -251.443974)
				(end 334.82915 -251.42444)
			)
			(arc
				(start 334.82915 -250.83008)
				(mid 334.825249 -250.810557)
				(end 334.814164 -250.794012)
			)
			(arc
				(start 334.755236 -250.735084)
				(mid 334.738702 -250.723973)
				(end 334.719168 -250.720098)
			)
			(arc
				(start 333.632302 -250.720098)
				(mid 333.612779 -250.723999)
				(end 333.596234 -250.735084)
			)
			(arc
				(start 333.407258 -250.92406)
				(mid 333.396147 -250.940594)
				(end 333.392272 -250.960128)
			)
			(arc
				(start 333.392272 -253.101602)
				(mid 333.396173 -253.121125)
				(end 333.407258 -253.13767)
			)
			(arc
				(start 339.875368 -259.60578)
				(mid 339.886479 -259.622314)
				(end 339.890354 -259.641848)
			)
			(arc
				(start 339.890354 -261.69366)
				(mid 339.894255 -261.713183)
				(end 339.90534 -261.729728)
			)
			(arc
				(start 340.190074 -262.014462)
				(mid 340.206608 -262.025573)
				(end 340.226142 -262.029448)
			)
		)
		(stroke
			(width 0)
			(type solid)
		)
		(fill yes)
		(layer "In5.Cu")
		(net "P5V_AUX")
	)
	(gr_poly
		(pts
			(xy 25.668732 -58.309764) (xy 26.002996 -57.9755) (xy 26.009346 -57.964832)
			(arc
				(start 26.011378 -57.95899)
				(mid 26.149462 -57.765099)
				(end 26.375614 -57.690766)
			)
			(arc
				(start 26.375614 -57.690766)
				(mid 26.4291 -57.694531)
				(end 26.481532 -57.705752)
			)
			(xy 26.493216 -57.709054) (xy 26.51633 -57.704736)
			(arc
				(start 26.591006 -57.648602)
				(mid 26.605744 -57.630753)
				(end 26.611072 -57.608216)
			)
			(arc
				(start 26.611072 -57.385458)
				(mid 26.607239 -57.366101)
				(end 26.59634 -57.349644)
			)
			(arc
				(start 26.57221 -57.325514)
				(mid 26.500207 -57.217849)
				(end 26.474928 -57.090818)
			)
			(arc
				(start 26.474928 -56.178958)
				(mid 26.469417 -56.15569)
				(end 26.453846 -56.137556)
			)
			(xy 26.376376 -56.082438) (xy 26.352246 -56.078882)
			(arc
				(start 26.340308 -56.082946)
				(mid 26.279069 -56.0985)
				(end 26.216102 -56.103774)
			)
			(arc
				(start 26.216102 -56.103774)
				(mid 25.834594 -55.722266)
				(end 26.216102 -55.340758)
			)
			(arc
				(start 26.216102 -55.340758)
				(mid 26.397829 -55.386856)
				(end 26.535634 -55.513986)
			)
			(xy 26.541984 -55.523638) (xy 26.561542 -55.535576)
			(arc
				(start 26.651458 -55.544974)
				(mid 26.673689 -55.542246)
				(end 26.692606 -55.530242)
			)
			(arc
				(start 26.731214 -55.491634)
				(mid 26.838879 -55.419631)
				(end 26.96591 -55.394352)
			)
			(arc
				(start 27.32659 -55.394352)
				(mid 27.345947 -55.390519)
				(end 27.362404 -55.37962)
			)
			(arc
				(start 27.62885 -55.113174)
				(mid 27.639912 -55.096757)
				(end 27.643836 -55.07736)
			)
			(arc
				(start 27.643836 -53.862224)
				(mid 27.639886 -53.842837)
				(end 27.62885 -53.82641)
			)
			(arc
				(start 27.359102 -53.556662)
				(mid 27.323288 -53.541901)
				(end 27.287474 -53.556662)
			)
			(arc
				(start 25.608026 -55.23611)
				(mid 25.596964 -55.252527)
				(end 25.59304 -55.271924)
			)
			(arc
				(start 25.59304 -58.262774)
				(mid 25.601642 -58.291058)
				(end 25.624536 -58.309764)
			)
			(xy 25.639014 -58.315606)
		)
		(stroke
			(width 0)
			(type solid)
		)
		(fill yes)
		(layer "In5.Cu")
		(net "GND")
	)
	(gr_poly
		(pts
			(arc
				(start 223.50476 -366.431576)
				(mid 223.533279 -366.422815)
				(end 223.552004 -366.399572)
			)
			(xy 223.592644 -366.29721) (xy 223.58604 -366.26673)
			(arc
				(start 223.57461 -366.256062)
				(mid 223.485809 -366.129549)
				(end 223.454468 -365.978186)
			)
			(arc
				(start 223.454468 -365.978186)
				(mid 223.835976 -365.596678)
				(end 224.217484 -365.978186)
			)
			(arc
				(start 224.217484 -365.978186)
				(mid 224.186168 -366.12956)
				(end 224.097342 -366.256062)
			)
			(xy 224.085912 -366.26673) (xy 224.079308 -366.29721)
			(arc
				(start 224.119948 -366.399572)
				(mid 224.138647 -366.422853)
				(end 224.167192 -366.431576)
			)
			(arc
				(start 226.29876 -366.431576)
				(mid 226.327279 -366.422815)
				(end 226.346004 -366.399572)
			)
			(xy 226.386644 -366.29721) (xy 226.38004 -366.26673)
			(arc
				(start 226.36861 -366.256062)
				(mid 226.279809 -366.129549)
				(end 226.248468 -365.978186)
			)
			(arc
				(start 226.248468 -365.978186)
				(mid 226.629976 -365.596678)
				(end 227.011484 -365.978186)
			)
			(arc
				(start 227.011484 -365.978186)
				(mid 226.980168 -366.12956)
				(end 226.891342 -366.256062)
			)
			(xy 226.879912 -366.26673) (xy 226.873308 -366.29721)
			(arc
				(start 226.913948 -366.399572)
				(mid 226.932647 -366.422853)
				(end 226.961192 -366.431576)
			)
			(arc
				(start 233.333798 -366.431576)
				(mid 233.353321 -366.427675)
				(end 233.369866 -366.41659)
			)
			(arc
				(start 233.528616 -366.25784)
				(mid 233.539727 -366.241306)
				(end 233.543602 -366.221772)
			)
			(arc
				(start 233.543602 -362.278676)
				(mid 233.539701 -362.259153)
				(end 233.528616 -362.242608)
			)
			(arc
				(start 233.22407 -361.938062)
				(mid 233.207536 -361.926951)
				(end 233.188002 -361.923076)
			)
			(xy 218.093036 -361.923076)
			(arc
				(start 216.370662 -361.923076)
				(mid 216.367813 -361.932542)
				(end 216.366852 -361.94238)
			)
			(arc
				(start 216.366852 -365.113316)
				(mid 216.370685 -365.132673)
				(end 216.381584 -365.14913)
			)
			(arc
				(start 217.649298 -366.41659)
				(mid 217.665715 -366.427652)
				(end 217.685112 -366.431576)
			)
		)
		(stroke
			(width 0)
			(type solid)
		)
		(fill yes)
		(layer "In5.Cu")
		(net "P12V_AUX")
	)
	(gr_poly
		(pts
			(arc
				(start 331.80401 -206.549498)
				(mid 331.823397 -206.545548)
				(end 331.839824 -206.534512)
			)
			(arc
				(start 332.08468 -206.289656)
				(mid 332.186884 -206.220901)
				(end 332.307438 -206.195676)
			)
			(xy 332.317344 -206.195422) (xy 332.335378 -206.187802)
			(arc
				(start 332.551786 -205.971394)
				(mid 332.562897 -205.95486)
				(end 332.566772 -205.935326)
			)
			(arc
				(start 332.566772 -205.747874)
				(mid 332.567709 -205.737906)
				(end 332.570582 -205.728316)
			)
			(arc
				(start 332.577948 -205.711044)
				(mid 332.580821 -205.701454)
				(end 332.581758 -205.691486)
			)
			(arc
				(start 332.581758 -203.269088)
				(mid 332.577857 -203.249565)
				(end 332.566772 -203.23302)
			)
			(xy 331.92466 -202.590908) (xy 331.917548 -202.583542) (xy 331.898752 -202.575922)
			(arc
				(start 330.280518 -202.575922)
				(mid 330.254639 -202.583008)
				(end 330.236068 -202.602338)
			)
			(xy 330.186538 -202.693016) (xy 330.187808 -202.720956)
			(arc
				(start 330.195428 -202.73264)
				(mid 330.240885 -202.83174)
				(end 330.256388 -202.93965)
			)
			(arc
				(start 330.256388 -202.946254)
				(mid 330.142342 -203.211782)
				(end 329.87488 -203.321158)
			)
			(arc
				(start 329.87488 -203.321158)
				(mid 329.681427 -203.268513)
				(end 329.541378 -203.12507)
			)
			(xy 329.535028 -203.113386) (xy 329.512676 -203.09967) (xy 329.3999 -203.094336) (xy 329.376532 -203.10602)
			(arc
				(start 329.368912 -203.116942)
				(mid 329.232183 -203.238258)
				(end 329.054714 -203.282042)
			)
			(arc
				(start 329.054714 -203.282042)
				(mid 328.952274 -203.267961)
				(end 328.857356 -203.226924)
			)
			(xy 328.845418 -203.219812) (xy 328.81824 -203.219304)
			(arc
				(start 328.72934 -203.269342)
				(mid 328.710345 -203.287921)
				(end 328.703432 -203.313538)
			)
			(arc
				(start 328.703432 -205.820518)
				(mid 328.707382 -205.839905)
				(end 328.718418 -205.856332)
			)
			(arc
				(start 328.97445 -206.11211)
				(mid 328.990867 -206.123172)
				(end 329.010264 -206.127096)
			)
			(arc
				(start 330.464922 -206.127096)
				(mid 330.482353 -206.124012)
				(end 330.497688 -206.115158)
			)
			(arc
				(start 330.497688 -206.115158)
				(mid 330.612677 -206.048492)
				(end 330.74356 -206.025242)
			)
			(arc
				(start 330.74356 -206.025242)
				(mid 330.874474 -206.048407)
				(end 330.989432 -206.115158)
			)
			(arc
				(start 330.989432 -206.115158)
				(mid 331.004756 -206.124042)
				(end 331.022198 -206.127096)
			)
			(arc
				(start 331.14107 -206.127096)
				(mid 331.160593 -206.130997)
				(end 331.177138 -206.142082)
			)
			(arc
				(start 331.185012 -206.149956)
				(mid 331.196123 -206.16649)
				(end 331.199998 -206.186024)
			)
			(arc
				(start 331.199998 -206.388462)
				(mid 331.203899 -206.407985)
				(end 331.214984 -206.42453)
			)
			(arc
				(start 331.324966 -206.534512)
				(mid 331.3415 -206.545623)
				(end 331.361034 -206.549498)
			)
		)
		(stroke
			(width 0)
			(type solid)
		)
		(fill yes)
		(layer "In5.Cu")
		(net "GND")
	)
	(gr_poly
		(pts
			(xy 42.390314 -13.820648) (xy 42.390314 -13.401548) (xy 42.34688 -13.358114)
			(arc
				(start 34.964878 -13.358114)
				(mid 33.898562 -12.916432)
				(end 33.45688 -11.850116)
			)
			(arc
				(start 33.45688 -1.999996)
				(mid 33.019884 -0.944996)
				(end 31.964884 -0.508)
			)
			(arc
				(start 19.964908 -0.508)
				(mid 18.909908 -0.944996)
				(end 18.472912 -1.999996)
			)
			(xy 18.472912 -11.631422) (xy 18.980404 -11.631422)
			(arc
				(start 18.980404 -1.999996)
				(mid 19.268759 -1.303847)
				(end 19.964908 -1.015492)
			)
			(arc
				(start 31.964884 -1.015492)
				(mid 32.661033 -1.303847)
				(end 32.949388 -1.999996)
			)
			(arc
				(start 32.949388 -11.850116)
				(mid 33.539801 -13.275118)
				(end 34.964878 -13.865352)
			)
			(xy 42.34561 -13.865352)
		)
		(stroke
			(width 0)
			(type solid)
		)
		(fill yes)
		(layer "In5.Cu")
		(net "GND")
	)
	(gr_poly
		(pts
			(xy 68.431156 -13.728954) (xy 68.431156 -13.494512) (xy 68.294758 -13.358114)
			(arc
				(start 60.96508 -13.358114)
				(mid 59.898764 -12.916432)
				(end 59.457082 -11.850116)
			)
			(arc
				(start 59.457082 -1.999996)
				(mid 59.020086 -0.944996)
				(end 57.965086 -0.508)
			)
			(arc
				(start 45.96511 -0.508)
				(mid 44.91011 -0.944996)
				(end 44.473114 -1.999996)
			)
			(xy 44.473114 -11.726418) (xy 44.980352 -11.726418)
			(arc
				(start 44.980352 -1.999996)
				(mid 45.268617 -1.303936)
				(end 45.964602 -1.015492)
			)
			(arc
				(start 57.965086 -1.015492)
				(mid 58.661325 -1.303831)
				(end 58.949844 -1.999996)
			)
			(arc
				(start 58.949844 -11.850116)
				(mid 59.540093 -13.275103)
				(end 60.96508 -13.865352)
			)
			(xy 68.294758 -13.865352)
		)
		(stroke
			(width 0)
			(type solid)
		)
		(fill yes)
		(layer "In5.Cu")
		(net "GND")
	)
	(gr_poly
		(pts
			(xy 94.285816 -13.833856) (xy 94.285816 -13.444728) (xy 94.199202 -13.358114)
			(arc
				(start 86.965028 -13.358114)
				(mid 85.898712 -12.916432)
				(end 85.45703 -11.850116)
			)
			(arc
				(start 85.45703 -1.999996)
				(mid 85.020034 -0.944996)
				(end 83.965034 -0.508)
			)
			(arc
				(start 71.965058 -0.508)
				(mid 70.910058 -0.944996)
				(end 70.473062 -1.999996)
			)
			(xy 70.473062 -11.716004) (xy 70.9803 -11.716004)
			(arc
				(start 70.9803 -1.999996)
				(mid 71.268565 -1.303936)
				(end 71.96455 -1.015492)
			)
			(arc
				(start 83.965034 -1.015492)
				(mid 84.661273 -1.303831)
				(end 84.949792 -1.999996)
			)
			(arc
				(start 84.949792 -11.850116)
				(mid 85.540041 -13.275103)
				(end 86.965028 -13.865352)
			)
			(xy 94.25432 -13.865352)
		)
		(stroke
			(width 0)
			(type solid)
		)
		(fill yes)
		(layer "In5.Cu")
		(net "GND")
	)
	(gr_poly
		(pts
			(xy 132.291582 -13.80998) (xy 132.291582 -13.413486) (xy 132.23621 -13.358114)
			(arc
				(start 125.065028 -13.358114)
				(mid 123.998712 -12.916432)
				(end 123.55703 -11.850116)
			)
			(arc
				(start 123.55703 -1.999996)
				(mid 123.120034 -0.944996)
				(end 122.065034 -0.508)
			)
			(arc
				(start 97.965006 -0.508)
				(mid 96.910006 -0.944996)
				(end 96.47301 -1.999996)
			)
			(xy 96.47301 -11.72464) (xy 96.980248 -11.72464)
			(arc
				(start 96.980248 -1.999996)
				(mid 97.268513 -1.303936)
				(end 97.964498 -1.015492)
			)
			(arc
				(start 122.065034 -1.015492)
				(mid 122.761273 -1.303831)
				(end 123.049792 -1.999996)
			)
			(arc
				(start 123.049792 -11.850116)
				(mid 123.640041 -13.275103)
				(end 125.065028 -13.865352)
			)
			(xy 132.23621 -13.865352)
		)
		(stroke
			(width 0)
			(type solid)
		)
		(fill yes)
		(layer "In5.Cu")
		(net "GND")
	)
	(gr_poly
		(pts
			(xy 158.365444 -13.805662) (xy 158.365444 -13.417804) (xy 158.305754 -13.358114)
			(arc
				(start 151.064976 -13.358114)
				(mid 149.99866 -12.916432)
				(end 149.556978 -11.850116)
			)
			(arc
				(start 149.556978 -1.999996)
				(mid 149.119982 -0.944996)
				(end 148.064982 -0.508)
			)
			(arc
				(start 136.065006 -0.508)
				(mid 135.010006 -0.944996)
				(end 134.57301 -1.999996)
			)
			(xy 134.57301 -11.817604) (xy 135.080248 -11.817604)
			(arc
				(start 135.080248 -1.999996)
				(mid 135.368513 -1.303936)
				(end 136.064498 -1.015492)
			)
			(arc
				(start 148.064982 -1.015492)
				(mid 148.761221 -1.303831)
				(end 149.04974 -1.999996)
			)
			(arc
				(start 149.04974 -11.850116)
				(mid 149.639989 -13.275103)
				(end 151.064976 -13.865352)
			)
			(xy 158.305754 -13.865352)
		)
		(stroke
			(width 0)
			(type solid)
		)
		(fill yes)
		(layer "In5.Cu")
		(net "GND")
	)
	(gr_poly
		(pts
			(xy 184.389268 -13.77569) (xy 184.389268 -13.447776) (xy 184.299606 -13.358114)
			(arc
				(start 177.064924 -13.358114)
				(mid 175.998608 -12.916432)
				(end 175.556926 -11.850116)
			)
			(arc
				(start 175.556926 -1.999996)
				(mid 175.11993 -0.944996)
				(end 174.06493 -0.508)
			)
			(arc
				(start 162.064954 -0.508)
				(mid 161.009954 -0.944996)
				(end 160.572958 -1.999996)
			)
			(xy 160.572958 -11.62304) (xy 161.080196 -11.62304)
			(arc
				(start 161.080196 -1.999996)
				(mid 161.368461 -1.303936)
				(end 162.064446 -1.015492)
			)
			(arc
				(start 174.06493 -1.015492)
				(mid 174.761169 -1.303831)
				(end 175.049688 -1.999996)
			)
			(arc
				(start 175.049688 -11.850116)
				(mid 175.639937 -13.275103)
				(end 177.064924 -13.865352)
			)
			(xy 184.299606 -13.865352)
		)
		(stroke
			(width 0)
			(type solid)
		)
		(fill yes)
		(layer "In5.Cu")
		(net "GND")
	)
	(gr_poly
		(pts
			(xy 210.250024 -13.829284) (xy 210.250024 -13.394182) (xy 210.213956 -13.358114)
			(arc
				(start 203.064872 -13.358114)
				(mid 201.998721 -12.916342)
				(end 201.556874 -11.850116)
			)
			(arc
				(start 201.556874 -1.999996)
				(mid 201.119878 -0.944996)
				(end 200.064878 -0.508)
			)
			(arc
				(start 188.064902 -0.508)
				(mid 187.009902 -0.944996)
				(end 186.572906 -1.999996)
			)
			(xy 186.572906 -11.750294) (xy 187.080144 -11.750294)
			(arc
				(start 187.080144 -1.999996)
				(mid 187.368409 -1.303936)
				(end 188.064394 -1.015492)
			)
			(arc
				(start 200.064878 -1.015492)
				(mid 200.761117 -1.303831)
				(end 201.049636 -1.999996)
			)
			(arc
				(start 201.049636 -11.850116)
				(mid 201.63987 -13.275193)
				(end 203.064872 -13.865352)
			)
			(xy 210.213956 -13.865352)
		)
		(stroke
			(width 0)
			(type solid)
		)
		(fill yes)
		(layer "In5.Cu")
		(net "GND")
	)
	(gr_poly
		(pts
			(xy 300.515782 -13.7541) (xy 300.515782 -13.469366) (xy 300.40453 -13.358114)
			(arc
				(start 293.165022 -13.358114)
				(mid 292.098706 -12.916432)
				(end 291.657024 -11.850116)
			)
			(arc
				(start 291.657024 -1.999996)
				(mid 291.220028 -0.944996)
				(end 290.165028 -0.508)
			)
			(arc
				(start 278.165052 -0.508)
				(mid 277.110052 -0.944996)
				(end 276.673056 -1.999996)
			)
			(xy 276.673056 -11.825732) (xy 277.180548 -11.825732)
			(arc
				(start 277.180548 -1.999996)
				(mid 277.468903 -1.303847)
				(end 278.165052 -1.015492)
			)
			(arc
				(start 290.165028 -1.015492)
				(mid 290.861177 -1.303847)
				(end 291.149532 -1.999996)
			)
			(arc
				(start 291.149532 -11.850116)
				(mid 291.739945 -13.275118)
				(end 293.165022 -13.865352)
			)
			(xy 300.40453 -13.865352)
		)
		(stroke
			(width 0)
			(type solid)
		)
		(fill yes)
		(layer "In5.Cu")
		(net "GND")
	)
	(gr_poly
		(pts
			(xy 442.67882 -13.82903) (xy 442.67882 -13.394436) (xy 442.642498 -13.358114)
			(arc
				(start 435.265068 -13.358114)
				(mid 434.198752 -12.916432)
				(end 433.75707 -11.850116)
			)
			(arc
				(start 433.75707 -1.999996)
				(mid 433.320074 -0.944996)
				(end 432.265074 -0.508)
			)
			(arc
				(start 420.265098 -0.508)
				(mid 419.210098 -0.944996)
				(end 418.773102 -1.999996)
			)
			(xy 418.773102 -11.73734) (xy 419.28034 -11.73734)
			(arc
				(start 419.28034 -1.999996)
				(mid 419.568605 -1.303936)
				(end 420.26459 -1.015492)
			)
			(arc
				(start 432.265074 -1.015492)
				(mid 432.961313 -1.303831)
				(end 433.249832 -1.999996)
			)
			(arc
				(start 433.249832 -11.850116)
				(mid 433.840081 -13.275103)
				(end 435.265068 -13.865352)
			)
			(xy 442.642498 -13.865352)
		)
		(stroke
			(width 0)
			(type solid)
		)
		(fill yes)
		(layer "In5.Cu")
		(net "GND")
	)
	(gr_poly
		(pts
			(xy 248.61139 -13.829538) (xy 248.61139 -13.393928) (xy 248.575576 -13.358114)
			(arc
				(start 241.164872 -13.358114)
				(mid 240.098721 -12.916342)
				(end 239.656874 -11.850116)
			)
			(arc
				(start 239.656874 -1.999996)
				(mid 239.219878 -0.944996)
				(end 238.164878 -0.508)
			)
			(arc
				(start 214.065104 -0.508)
				(mid 213.010104 -0.944996)
				(end 212.573108 -1.999996)
			)
			(xy 212.573108 -11.851132) (xy 212.571584 -11.91895) (xy 213.07933 -11.91895) (xy 213.0806 -11.850116)
			(arc
				(start 213.0806 -1.999996)
				(mid 213.368955 -1.303847)
				(end 214.065104 -1.015492)
			)
			(arc
				(start 238.164878 -1.015492)
				(mid 238.861117 -1.303831)
				(end 239.149636 -1.999996)
			)
			(arc
				(start 239.149636 -11.850116)
				(mid 239.73987 -13.275193)
				(end 241.164872 -13.865352)
			)
			(xy 248.575576 -13.865352)
		)
		(stroke
			(width 0)
			(type solid)
		)
		(fill yes)
		(layer "In5.Cu")
		(net "GND")
	)
	(gr_poly
		(pts
			(xy 274.599654 -13.810742) (xy 274.599654 -13.412724) (xy 274.545044 -13.358114)
			(arc
				(start 267.165074 -13.358114)
				(mid 266.098758 -12.916432)
				(end 265.657076 -11.850116)
			)
			(arc
				(start 265.657076 -1.999996)
				(mid 265.22008 -0.944996)
				(end 264.16508 -0.508)
			)
			(arc
				(start 252.165104 -0.508)
				(mid 251.110104 -0.944996)
				(end 250.673108 -1.999996)
			)
			(xy 250.673108 -11.850116) (xy 250.673108 -11.851386) (xy 251.1806 -11.851386) (xy 251.1806 -11.850116)
			(arc
				(start 251.1806 -1.999996)
				(mid 251.468955 -1.303847)
				(end 252.165104 -1.015492)
			)
			(arc
				(start 264.16508 -1.015492)
				(mid 264.861229 -1.303847)
				(end 265.149584 -1.999996)
			)
			(arc
				(start 265.149584 -11.850116)
				(mid 265.739997 -13.275118)
				(end 267.165074 -13.865352)
			)
			(xy 274.545044 -13.865352)
		)
		(stroke
			(width 0)
			(type solid)
		)
		(fill yes)
		(layer "In5.Cu")
		(net "GND")
	)
	(gr_poly
		(pts
			(xy 416.458146 -13.816076) (xy 416.458146 -13.40739) (xy 416.40887 -13.358114)
			(arc
				(start 409.26512 -13.358114)
				(mid 408.198804 -12.916432)
				(end 407.757122 -11.850116)
			)
			(arc
				(start 407.757122 -1.999996)
				(mid 407.320126 -0.944996)
				(end 406.265126 -0.508)
			)
			(arc
				(start 394.264896 -0.508)
				(mid 393.209896 -0.944996)
				(end 392.7729 -1.999996)
			)
			(arc
				(start 392.7729 -11.850116)
				(mid 392.702216 -12.306469)
				(end 392.496802 -12.720066)
			)
			(xy 392.496802 -12.748514) (xy 392.499088 -12.7508)
			(arc
				(start 393.067794 -12.7508)
				(mid 393.226496 -12.312827)
				(end 393.280392 -11.850116)
			)
			(arc
				(start 393.280392 -1.999996)
				(mid 393.568747 -1.303847)
				(end 394.264896 -1.015492)
			)
			(arc
				(start 406.265126 -1.015492)
				(mid 406.961365 -1.303831)
				(end 407.249884 -1.999996)
			)
			(arc
				(start 407.249884 -11.850116)
				(mid 407.840133 -13.275103)
				(end 409.26512 -13.865352)
			)
			(xy 416.40887 -13.865352)
		)
		(stroke
			(width 0)
			(type solid)
		)
		(fill yes)
		(layer "In5.Cu")
		(net "GND")
	)
	(gr_poly
		(pts
			(xy 364.71606 -13.770102) (xy 364.71606 -13.453364) (xy 364.62081 -13.358114)
			(arc
				(start 357.26497 -13.358114)
				(mid 356.198654 -12.916432)
				(end 355.756972 -11.850116)
			)
			(arc
				(start 355.756972 -1.999996)
				(mid 355.319976 -0.944996)
				(end 354.264976 -0.508)
			)
			(arc
				(start 330.164948 -0.508)
				(mid 329.109948 -0.944996)
				(end 328.672952 -1.999996)
			)
			(arc
				(start 328.672952 -11.850116)
				(mid 328.570197 -12.397292)
				(end 328.27595 -12.869926)
			)
			(xy 328.27595 -12.876784) (xy 328.28738 -12.888214) (xy 328.885042 -12.888214)
			(arc
				(start 328.90333 -12.869926)
				(mid 329.10994 -12.378512)
				(end 329.180444 -11.850116)
			)
			(arc
				(start 329.180444 -1.999996)
				(mid 329.468799 -1.303847)
				(end 330.164948 -1.015492)
			)
			(arc
				(start 354.264976 -1.015492)
				(mid 354.961125 -1.303847)
				(end 355.24948 -1.999996)
			)
			(arc
				(start 355.24948 -11.850116)
				(mid 355.839893 -13.275118)
				(end 357.26497 -13.865352)
			)
			(xy 364.62081 -13.865352)
		)
		(stroke
			(width 0)
			(type solid)
		)
		(fill yes)
		(layer "In5.Cu")
		(net "GND")
	)
	(gr_poly
		(pts
			(xy 390.499092 -13.810996) (xy 390.499092 -13.41247) (xy 390.444736 -13.358114)
			(arc
				(start 383.264918 -13.358114)
				(mid 382.198602 -12.916432)
				(end 381.75692 -11.850116)
			)
			(arc
				(start 381.75692 -1.999996)
				(mid 381.319924 -0.944996)
				(end 380.264924 -0.508)
			)
			(arc
				(start 368.264948 -0.508)
				(mid 367.209948 -0.944996)
				(end 366.772952 -1.999996)
			)
			(arc
				(start 366.772952 -11.850116)
				(mid 366.670132 -12.397459)
				(end 366.375696 -12.87018)
			)
			(xy 366.375696 -12.899644) (xy 366.434878 -12.958826) (xy 366.914684 -12.958826)
			(arc
				(start 367.00333 -12.87018)
				(mid 367.209881 -12.378884)
				(end 367.280444 -11.850624)
			)
			(arc
				(start 367.280444 -1.999996)
				(mid 367.568799 -1.303847)
				(end 368.264948 -1.015492)
			)
			(arc
				(start 380.264924 -1.015492)
				(mid 380.961073 -1.303847)
				(end 381.249428 -1.999996)
			)
			(arc
				(start 381.249428 -11.850116)
				(mid 381.839841 -13.275118)
				(end 383.264918 -13.865352)
			)
			(xy 390.444736 -13.865352)
		)
		(stroke
			(width 0)
			(type solid)
		)
		(fill yes)
		(layer "In5.Cu")
		(net "GND")
	)
	(gr_poly
		(pts
			(xy 326.45985 -13.852906) (xy 326.45985 -13.37945) (xy 326.438514 -13.358114)
			(arc
				(start 319.16497 -13.358114)
				(mid 318.098654 -12.916432)
				(end 317.656972 -11.850116)
			)
			(arc
				(start 317.656972 -1.999996)
				(mid 317.219976 -0.944996)
				(end 316.164976 -0.508)
			)
			(arc
				(start 304.165 -0.508)
				(mid 303.11 -0.944996)
				(end 302.673004 -1.999996)
			)
			(arc
				(start 302.673004 -11.850116)
				(mid 302.577528 -12.378214)
				(end 302.30318 -12.839446)
			)
			(xy 302.30318 -12.884912) (xy 302.304196 -12.885928) (xy 302.874426 -12.885928)
			(arc
				(start 302.920908 -12.839446)
				(mid 303.114524 -12.361527)
				(end 303.180496 -11.850116)
			)
			(arc
				(start 303.180496 -1.999996)
				(mid 303.468851 -1.303847)
				(end 304.165 -1.015492)
			)
			(arc
				(start 316.164976 -1.015492)
				(mid 316.861125 -1.303847)
				(end 317.14948 -1.999996)
			)
			(arc
				(start 317.14948 -11.850116)
				(mid 317.739893 -13.275118)
				(end 319.16497 -13.865352)
			)
			(xy 326.438514 -13.865352) (xy 326.447404 -13.865352)
		)
		(stroke
			(width 0)
			(type solid)
		)
		(fill yes)
		(layer "In5.Cu")
		(net "GND")
	)
	(gr_poly
		(pts
			(arc
				(start 239.526318 -205.606396)
				(mid 239.546502 -205.602214)
				(end 239.563402 -205.590394)
			)
			(xy 239.621314 -205.528926) (xy 239.628426 -205.509622) (xy 239.627664 -205.498954)
			(arc
				(start 239.627156 -205.47711)
				(mid 240.008664 -205.095602)
				(end 240.390172 -205.47711)
			)
			(arc
				(start 240.390172 -205.47711)
				(mid 240.388581 -205.511926)
				(end 240.383822 -205.546452)
			)
			(xy 240.38306 -205.551024)
			(arc
				(start 240.38306 -205.555596)
				(mid 240.397939 -205.591517)
				(end 240.43386 -205.606396)
			)
			(arc
				(start 240.446052 -205.606396)
				(mid 240.465575 -205.602495)
				(end 240.48212 -205.59141)
			)
			(arc
				(start 240.78057 -205.29296)
				(mid 240.791681 -205.276426)
				(end 240.795556 -205.256892)
			)
			(arc
				(start 240.795556 -200.381108)
				(mid 240.791655 -200.361585)
				(end 240.78057 -200.34504)
			)
			(arc
				(start 240.643156 -200.207626)
				(mid 240.626622 -200.196515)
				(end 240.607088 -200.19264)
			)
			(arc
				(start 239.886236 -200.19264)
				(mid 239.862297 -200.198634)
				(end 239.844072 -200.215246)
			)
			(xy 239.78997 -200.296018) (xy 239.78743 -200.321164)
			(arc
				(start 239.792256 -200.333102)
				(mid 239.813879 -200.404451)
				(end 239.821212 -200.478644)
			)
			(arc
				(start 239.821212 -200.478644)
				(mid 239.439704 -200.860152)
				(end 239.058196 -200.478644)
			)
			(arc
				(start 239.058196 -200.478644)
				(mid 239.06553 -200.404452)
				(end 239.087152 -200.333102)
			)
			(xy 239.091978 -200.321164) (xy 239.089438 -200.296018)
			(arc
				(start 239.035336 -200.215246)
				(mid 239.017074 -200.198703)
				(end 238.993172 -200.19264)
			)
			(arc
				(start 237.593378 -200.19264)
				(mid 237.573855 -200.196541)
				(end 237.55731 -200.207626)
			)
			(arc
				(start 237.352586 -200.41235)
				(mid 237.341475 -200.428884)
				(end 237.3376 -200.448418)
			)
			(arc
				(start 237.3376 -202.521312)
				(mid 237.339925 -202.536505)
				(end 237.346744 -202.550268)
			)
			(arc
				(start 237.346744 -202.550268)
				(mid 237.414583 -202.767438)
				(end 237.346744 -202.984608)
			)
			(arc
				(start 237.346744 -202.984608)
				(mid 237.339991 -202.998392)
				(end 237.3376 -203.013564)
			)
			(arc
				(start 237.3376 -205.018132)
				(mid 237.34155 -205.037519)
				(end 237.352586 -205.053946)
			)
			(arc
				(start 237.788704 -205.490318)
				(mid 237.813909 -205.504158)
				(end 237.842552 -205.502002)
			)
			(xy 237.943136 -205.463902) (xy 237.960916 -205.440026)
			(arc
				(start 237.961932 -205.42504)
				(mid 238.081662 -205.171157)
				(end 238.342678 -205.067916)
			)
			(arc
				(start 238.342678 -205.067916)
				(mid 238.612445 -205.179657)
				(end 238.724186 -205.449424)
			)
			(arc
				(start 238.724186 -205.449424)
				(mid 238.723543 -205.471304)
				(end 238.721646 -205.493112)
			)
			(xy 238.720376 -205.504288) (xy 238.726726 -205.524608)
			(arc
				(start 238.784638 -205.589378)
				(mid 238.80175 -205.601896)
				(end 238.822484 -205.606396)
			)
		)
		(stroke
			(width 0)
			(type solid)
		)
		(fill yes)
		(layer "In5.Cu")
		(net "GND")
	)
	(gr_poly
		(pts
			(xy 79.361284 -74.940922) (xy 79.906622 -74.395584) (xy 79.913438 -74.388242) (xy 79.921177 -74.369778)
			(xy 79.921608 -74.35977) (xy 79.921608 -63.566802) (xy 79.921133 -63.556051) (xy 79.912322 -63.53644)
			(xy 79.90459 -63.528956) (xy 79.840582 -63.471044) (xy 79.820262 -63.46444) (xy 79.80934 -63.46571)
			(xy 79.799399 -63.466677) (xy 79.77945 -63.467692) (xy 79.769462 -63.467742) (xy 79.74221 -63.467254)
			(xy 79.688262 -63.459492) (xy 79.635967 -63.444132) (xy 79.58639 -63.421487) (xy 79.54054 -63.392017)
			(xy 79.499351 -63.356322) (xy 79.46366 -63.315129) (xy 79.434195 -63.269277) (xy 79.411555 -63.219698)
			(xy 79.3962 -63.167401) (xy 79.388444 -63.113452) (xy 79.388444 -63.058948) (xy 79.3962 -63.004999)
			(xy 79.411555 -62.952702) (xy 79.434195 -62.903123) (xy 79.46366 -62.857271) (xy 79.499351 -62.816078)
			(xy 79.54054 -62.780383) (xy 79.58639 -62.750913) (xy 79.635967 -62.728268) (xy 79.688262 -62.712908)
			(xy 79.74221 -62.705146) (xy 79.769462 -62.704726) (xy 79.77945 -62.704779) (xy 79.799399 -62.705798)
			(xy 79.80934 -62.706758) (xy 79.820262 -62.708028) (xy 79.840582 -62.701424) (xy 79.90459 -62.643512)
			(xy 79.912215 -62.635949) (xy 79.921023 -62.616389) (xy 79.921608 -62.605666) (xy 79.921608 -62.588394)
			(xy 79.921069 -62.578407) (xy 79.913355 -62.559976) (xy 79.906622 -62.55258) (xy 79.6798 -62.326012)
			(xy 79.66234 -62.307827) (xy 79.632727 -62.267032) (xy 79.609843 -62.222115) (xy 79.594246 -62.174178)
			(xy 79.586321 -62.124395) (xy 79.58582 -62.09919) (xy 79.58582 -53.789834) (xy 79.585289 -53.779843)
			(xy 79.577587 -53.7614) (xy 79.570834 -53.75402) (xy 79.358998 -53.542438) (xy 79.351637 -53.535669)
			(xy 79.333175 -53.528022) (xy 79.313193 -53.528022) (xy 79.294731 -53.535669) (xy 79.28737 -53.542438)
			(xy 77.597762 -55.231792) (xy 77.590943 -55.239134) (xy 77.583198 -55.257597) (xy 77.582776 -55.267606)
			(xy 77.582776 -55.722266) (xy 77.83398 -55.722266) (xy 77.838051 -55.666644) (xy 77.850177 -55.612207)
			(xy 77.8701 -55.560116) (xy 77.897396 -55.511481) (xy 77.931482 -55.467338) (xy 77.971631 -55.428629)
			(xy 78.016989 -55.396178) (xy 78.066589 -55.370677) (xy 78.119373 -55.35267) (xy 78.174216 -55.34254)
			(xy 78.22995 -55.340503) (xy 78.285387 -55.346603) (xy 78.339344 -55.360709) (xy 78.390673 -55.382521)
			(xy 78.438279 -55.411575) (xy 78.481147 -55.44725) (xy 78.518364 -55.488787) (xy 78.549137 -55.5353)
			(xy 78.572809 -55.585797) (xy 78.588877 -55.639204) (xy 78.596997 -55.69438) (xy 78.597506 -55.722266)
			(xy 78.596997 -55.750152) (xy 78.588877 -55.805328) (xy 78.572809 -55.858735) (xy 78.549137 -55.909232)
			(xy 78.518364 -55.955745) (xy 78.481147 -55.997282) (xy 78.438279 -56.032957) (xy 78.390673 -56.062011)
			(xy 78.339344 -56.083823) (xy 78.285387 -56.097929) (xy 78.22995 -56.104029) (xy 78.174216 -56.101992)
			(xy 78.119373 -56.091862) (xy 78.066589 -56.073855) (xy 78.016989 -56.048354) (xy 77.971631 -56.015903)
			(xy 77.931482 -55.977194) (xy 77.897396 -55.933051) (xy 77.8701 -55.884416) (xy 77.850177 -55.832325)
			(xy 77.838051 -55.777888) (xy 77.83398 -55.722266) (xy 77.582776 -55.722266) (xy 77.582776 -56.585104)
			(xy 77.583421 -56.597657) (xy 77.595287 -56.619779) (xy 77.605382 -56.627268) (xy 77.686154 -56.681624)
			(xy 77.711046 -56.68391) (xy 77.722984 -56.679084) (xy 77.745965 -56.670099) (xy 77.793659 -56.65745)
			(xy 77.842585 -56.65105) (xy 77.867256 -56.650636) (xy 77.867764 -56.650636) (xy 77.895706 -56.651122)
			(xy 77.950993 -56.659273) (xy 78.004499 -56.675405) (xy 78.055077 -56.699173) (xy 78.101645 -56.730068)
			(xy 78.143206 -56.767428) (xy 78.178869 -56.810454) (xy 78.207871 -56.858224) (xy 78.229591 -56.909715)
			(xy 78.23708 -56.93664) (xy 78.238858 -56.943498) (xy 78.245462 -56.954928) (xy 78.410816 -57.120028)
			(xy 78.428273 -57.138214) (xy 78.457879 -57.179011) (xy 78.480757 -57.223928) (xy 78.496346 -57.271865)
			(xy 78.504266 -57.321647) (xy 78.504796 -57.34685) (xy 78.504796 -57.63768) (xy 78.533545 -57.646753)
			(xy 78.588537 -57.671454) (xy 78.639772 -57.703222) (xy 78.686348 -57.741497) (xy 78.727443 -57.785605)
			(xy 78.762332 -57.834768) (xy 78.77683 -57.8612) (xy 78.964028 -58.048398) (xy 78.964028 -59.33694)
			(xy 78.927198 -59.37377) (xy 78.927198 -65.390268) (xy 79.285592 -65.748662) (xy 79.285592 -66.49593)
			(xy 79.285592 -74.893932) (xy 79.286022 -74.903975) (xy 79.293735 -74.92252) (xy 79.307969 -74.936691)
			(xy 79.317088 -74.940922) (xy 79.331566 -74.946764)
		)
		(stroke
			(width 0)
			(type solid)
		)
		(fill yes)
		(layer "In5.Cu")
		(net "GND")
	)
	(gr_poly
		(pts
			(arc
				(start 8.790686 -275.325078)
				(mid 8.810209 -275.321177)
				(end 8.826754 -275.310092)
			)
			(arc
				(start 9.165844 -274.971002)
				(mid 9.176955 -274.954468)
				(end 9.18083 -274.934934)
			)
			(arc
				(start 9.18083 -273.51482)
				(mid 9.184731 -273.495297)
				(end 9.195816 -273.478752)
			)
			(arc
				(start 11.62177 -271.052798)
				(mid 11.638304 -271.041687)
				(end 11.657838 -271.037812)
			)
			(arc
				(start 14.914626 -271.037812)
				(mid 14.934149 -271.033911)
				(end 14.950694 -271.022826)
			)
			(arc
				(start 15.03934 -270.93418)
				(mid 15.050451 -270.917646)
				(end 15.054326 -270.898112)
			)
			(arc
				(start 15.054326 -259.858002)
				(mid 15.050425 -259.838479)
				(end 15.03934 -259.821934)
			)
			(arc
				(start 14.555724 -259.338318)
				(mid 14.53919 -259.327207)
				(end 14.519656 -259.323332)
			)
			(arc
				(start 1.879092 -259.323332)
				(mid 1.859569 -259.327233)
				(end 1.843024 -259.338318)
			)
			(arc
				(start 1.389126 -259.792216)
				(mid 1.378015 -259.80875)
				(end 1.37414 -259.828284)
			)
			(arc
				(start 1.37414 -270.11376)
				(mid 1.378799 -270.135012)
				(end 1.39192 -270.152368)
			)
			(xy 1.45923 -270.209772) (xy 1.480566 -270.215614)
			(arc
				(start 1.491742 -270.21409)
				(mid 1.521492 -270.210507)
				(end 1.551432 -270.209264)
			)
			(arc
				(start 1.551432 -270.209264)
				(mid 1.93294 -270.590772)
				(end 1.551432 -270.97228)
			)
			(arc
				(start 1.551432 -270.97228)
				(mid 1.521492 -270.971043)
				(end 1.491742 -270.967454)
			)
			(xy 1.480566 -270.96593) (xy 1.45923 -270.971772)
			(arc
				(start 1.39192 -271.029176)
				(mid 1.378797 -271.046531)
				(end 1.37414 -271.067784)
			)
			(arc
				(start 1.37414 -271.458182)
				(mid 1.378799 -271.479434)
				(end 1.39192 -271.49679)
			)
			(xy 1.45923 -271.554194) (xy 1.480566 -271.560036)
			(arc
				(start 1.491742 -271.558512)
				(mid 1.521492 -271.554929)
				(end 1.551432 -271.553686)
			)
			(arc
				(start 1.551432 -271.553686)
				(mid 1.93294 -271.935194)
				(end 1.551432 -272.316702)
			)
			(arc
				(start 1.551432 -272.316702)
				(mid 1.521492 -272.315465)
				(end 1.491742 -272.311876)
			)
			(xy 1.480566 -272.310352) (xy 1.45923 -272.316194)
			(arc
				(start 1.39192 -272.373598)
				(mid 1.378797 -272.390953)
				(end 1.37414 -272.412206)
			)
			(arc
				(start 1.37414 -272.826988)
				(mid 1.37895 -272.848565)
				(end 1.392428 -272.866104)
			)
			(xy 1.461516 -272.923254) (xy 1.48336 -272.928842)
			(arc
				(start 1.494536 -272.92681)
				(mid 1.529562 -272.921882)
				(end 1.564894 -272.920206)
			)
			(arc
				(start 1.564894 -272.920206)
				(mid 1.946402 -273.301714)
				(end 1.564894 -273.683222)
			)
			(arc
				(start 1.564894 -273.683222)
				(mid 1.529561 -273.681559)
				(end 1.494536 -273.676618)
			)
			(xy 1.48336 -273.674586) (xy 1.461516 -273.680174)
			(arc
				(start 1.392428 -273.737324)
				(mid 1.378892 -273.754837)
				(end 1.37414 -273.77644)
			)
			(arc
				(start 1.37414 -274.172426)
				(mid 1.37865 -274.193352)
				(end 1.391412 -274.210526)
			)
			(xy 1.456944 -274.268184) (xy 1.477772 -274.274534)
			(arc
				(start 1.488694 -274.27301)
				(mid 1.513029 -274.270696)
				(end 1.537462 -274.269962)
			)
			(arc
				(start 1.537462 -274.269962)
				(mid 1.807229 -274.381703)
				(end 1.91897 -274.65147)
			)
			(arc
				(start 1.91897 -274.65147)
				(mid 1.83294 -274.892802)
				(end 1.613662 -275.025358)
			)
			(xy 1.599946 -275.028152) (xy 1.579372 -275.046948)
			(arc
				(start 1.5494 -275.146008)
				(mid 1.548735 -275.17306)
				(end 1.5621 -275.196554)
			)
			(arc
				(start 1.675638 -275.310092)
				(mid 1.692172 -275.321203)
				(end 1.711706 -275.325078)
			)
		)
		(stroke
			(width 0)
			(type solid)
		)
		(fill yes)
		(layer "In5.Cu")
		(net "P1V25_PEX0")
	)
	(gr_poly
		(pts
			(xy 229.95636 -152.922224) (xy 229.966426 -152.921791) (xy 229.985017 -152.914064) (xy 229.992428 -152.907238)
			(xy 230.260144 -152.639522) (xy 230.266984 -152.632122) (xy 230.274699 -152.613523) (xy 230.27513 -152.603454)
			(xy 230.27513 -150.581614) (xy 230.274623 -150.571564) (xy 230.266901 -150.553004) (xy 230.260144 -150.545546)
			(xy 230.197152 -150.482554) (xy 230.19004 -150.475188) (xy 230.171244 -150.467568) (xy 226.614482 -150.467568)
			(xy 226.604414 -150.467141) (xy 226.585817 -150.459418) (xy 226.578414 -150.452582) (xy 225.71583 -149.589998)
			(xy 225.708981 -149.582601) (xy 225.701242 -149.564003) (xy 225.700844 -149.55393) (xy 225.700844 -144.612868)
			(xy 225.701274 -144.602801) (xy 225.709002 -144.58421) (xy 225.71583 -144.5768) (xy 226.652836 -143.639794)
			(xy 226.659689 -143.632398) (xy 226.667431 -143.6138) (xy 226.667822 -143.603726) (xy 226.667822 -140.856716)
			(xy 226.667316 -140.846666) (xy 226.659593 -140.828107) (xy 226.652836 -140.820648) (xy 225.976434 -140.144246)
			(xy 225.969322 -140.13688) (xy 225.950526 -140.12926) (xy 225.126804 -140.12926) (xy 225.116735 -140.129684)
			(xy 225.098135 -140.137404) (xy 225.090736 -140.144246) (xy 224.219262 -141.01572) (xy 224.212646 -141.022998)
			(xy 224.205008 -141.041102) (xy 224.204707 -141.06075) (xy 224.207832 -141.070076) (xy 224.246948 -141.170914)
			(xy 224.271078 -141.18844) (xy 224.286572 -141.189202) (xy 224.312973 -141.19087) (xy 224.364973 -141.200581)
			(xy 224.415133 -141.217382) (xy 224.462492 -141.24095) (xy 224.506141 -141.270833) (xy 224.545245 -141.306458)
			(xy 224.579054 -141.347144) (xy 224.606918 -141.392109) (xy 224.628305 -141.440492) (xy 224.642805 -141.491365)
			(xy 224.650138 -141.543753) (xy 224.650554 -141.570202) (xy 224.650068 -141.597454) (xy 224.642312 -141.651404)
			(xy 224.626957 -141.703701) (xy 224.604316 -141.753281) (xy 224.574851 -141.799135) (xy 224.53916 -141.840329)
			(xy 224.49797 -141.876024) (xy 224.45212 -141.905495) (xy 224.402543 -141.928141) (xy 224.350247 -141.943502)
			(xy 224.296298 -141.951265) (xy 224.269046 -141.95171) (xy 224.242595 -141.951261) (xy 224.190201 -141.943955)
			(xy 224.139319 -141.929476) (xy 224.090927 -141.908102) (xy 224.045955 -141.880244) (xy 224.005265 -141.846437)
			(xy 223.969639 -141.80733) (xy 223.939761 -141.763673) (xy 223.916205 -141.716306) (xy 223.899423 -141.666137)
			(xy 223.889737 -141.614129) (xy 223.888046 -141.587728) (xy 223.887284 -141.572234) (xy 223.869758 -141.548104)
			(xy 223.76892 -141.508988) (xy 223.759598 -141.505808) (xy 223.739924 -141.50606) (xy 223.721813 -141.513751)
			(xy 223.714564 -141.520418) (xy 222.443294 -142.791688) (xy 222.435928 -142.7988) (xy 222.428308 -142.817596)
			(xy 222.428308 -143.945102) (xy 225.0219 -143.945102) (xy 225.025971 -143.88948) (xy 225.038097 -143.835043)
			(xy 225.05802 -143.782952) (xy 225.085316 -143.734317) (xy 225.119402 -143.690174) (xy 225.159551 -143.651465)
			(xy 225.204909 -143.619014) (xy 225.254509 -143.593513) (xy 225.307293 -143.575506) (xy 225.362136 -143.565376)
			(xy 225.41787 -143.563339) (xy 225.473307 -143.569439) (xy 225.527264 -143.583545) (xy 225.578593 -143.605357)
			(xy 225.626199 -143.634411) (xy 225.669067 -143.670086) (xy 225.706284 -143.711623) (xy 225.737057 -143.758136)
			(xy 225.760729 -143.808633) (xy 225.776797 -143.86204) (xy 225.784917 -143.917216) (xy 225.785426 -143.945102)
			(xy 225.784917 -143.972988) (xy 225.776797 -144.028164) (xy 225.760729 -144.081571) (xy 225.737057 -144.132068)
			(xy 225.706284 -144.178581) (xy 225.669067 -144.220118) (xy 225.626199 -144.255793) (xy 225.578593 -144.284847)
			(xy 225.527264 -144.306659) (xy 225.473307 -144.320765) (xy 225.41787 -144.326865) (xy 225.362136 -144.324828)
			(xy 225.307293 -144.314698) (xy 225.254509 -144.296691) (xy 225.204909 -144.27119) (xy 225.159551 -144.238739)
			(xy 225.119402 -144.20003) (xy 225.085316 -144.155887) (xy 225.05802 -144.107252) (xy 225.038097 -144.055161)
			(xy 225.025971 -144.000724) (xy 225.0219 -143.945102) (xy 222.428308 -143.945102) (xy 222.428308 -144.707864)
			(xy 222.428647 -144.716474) (xy 222.434336 -144.732728) (xy 222.445057 -144.746204) (xy 222.452184 -144.751044)
			(xy 222.52559 -144.79651) (xy 222.533032 -144.800773) (xy 222.549753 -144.804533) (xy 222.566774 -144.80253)
			(xy 222.574612 -144.79905) (xy 222.57512 -144.798796) (xy 222.575374 -144.798796) (xy 222.601868 -144.786213)
			(xy 222.657762 -144.768442) (xy 222.71572 -144.759453) (xy 222.745046 -144.758918) (xy 222.75038 -144.758918)
			(xy 222.777384 -144.759761) (xy 222.83076 -144.768122) (xy 222.882423 -144.78393) (xy 222.931339 -144.806868)
			(xy 222.976529 -144.836477) (xy 223.017091 -144.872166) (xy 223.052212 -144.91322) (xy 223.08119 -144.958818)
			(xy 223.103446 -145.008048) (xy 223.118533 -145.059925) (xy 223.126152 -145.113413) (xy 223.126554 -145.140426)
			(xy 223.126066 -145.167677) (xy 223.118307 -145.221625) (xy 223.10295 -145.273919) (xy 223.080308 -145.323496)
			(xy 223.050842 -145.369346) (xy 223.015151 -145.410537) (xy 222.973962 -145.44623) (xy 222.928113 -145.475699)
			(xy 222.878538 -145.498343) (xy 222.826244 -145.513703) (xy 222.772297 -145.521465) (xy 222.745046 -145.521934)
			(xy 222.715723 -145.521374) (xy 222.657772 -145.512367) (xy 222.601875 -145.494619) (xy 222.575374 -145.482056)
			(xy 222.57512 -145.482056) (xy 222.574612 -145.481802) (xy 222.566759 -145.47838) (xy 222.549753 -145.476412)
			(xy 222.533037 -145.480111) (xy 222.52559 -145.484342) (xy 222.452184 -145.529808) (xy 222.445057 -145.534652)
			(xy 222.43431 -145.548107) (xy 222.428663 -145.564376) (xy 222.428308 -145.572988) (xy 222.428308 -146.602958)
			(xy 222.446088 -146.628866) (xy 222.46082 -146.634454) (xy 222.485855 -146.644616) (xy 222.533016 -146.670978)
			(xy 222.575988 -146.703727) (xy 222.613914 -146.742208) (xy 222.646035 -146.785652) (xy 222.671709 -146.833192)
			(xy 222.690424 -146.883876) (xy 222.701805 -146.936693) (xy 222.705626 -146.990586) (xy 222.701809 -147.04448)
			(xy 222.690432 -147.097298) (xy 222.67172 -147.147983) (xy 222.646049 -147.195524) (xy 222.613932 -147.238971)
			(xy 222.576009 -147.277454) (xy 222.533039 -147.310207) (xy 222.48588 -147.336573) (xy 222.46082 -147.34667)
			(xy 222.446088 -147.352258) (xy 222.428308 -147.378166) (xy 222.428308 -150.781258) (xy 222.428742 -150.791323)
			(xy 222.436472 -150.809912) (xy 222.443294 -150.817326) (xy 224.533206 -152.907238) (xy 224.540602 -152.91409)
			(xy 224.559201 -152.921832) (xy 224.569274 -152.922224)
		)
		(stroke
			(width 0)
			(type solid)
		)
		(fill yes)
		(layer "In5.Cu")
		(net "P3V3_CLK_GEN_VDDMXCK_CK440_PEX")
	)
	(gr_poly
		(pts
			(arc
				(start 388.54761 -226.304094)
				(mid 388.573639 -226.317904)
				(end 388.602982 -226.315016)
			)
			(xy 388.61746 -226.30892) (xy 388.634224 -226.283774)
			(arc
				(start 388.634224 -224.461832)
				(mid 388.630391 -224.442475)
				(end 388.619492 -224.426018)
			)
			(arc
				(start 386.216398 -222.022924)
				(mid 386.194429 -222.009904)
				(end 386.1689 -222.009208)
			)
			(xy 386.071872 -222.032068) (xy 386.052568 -222.049594)
			(arc
				(start 386.04825 -222.06204)
				(mid 385.909292 -222.249968)
				(end 385.686808 -222.321628)
			)
			(arc
				(start 385.686808 -222.321628)
				(mid 385.417041 -222.209887)
				(end 385.3053 -221.94012)
			)
			(arc
				(start 385.3053 -221.94012)
				(mid 385.376914 -221.717603)
				(end 385.564888 -221.578678)
			)
			(xy 385.577334 -221.57436) (xy 385.59486 -221.555056)
			(arc
				(start 385.61772 -221.458028)
				(mid 385.617027 -221.432498)
				(end 385.604004 -221.41053)
			)
			(arc
				(start 384.70713 -220.513656)
				(mid 384.688104 -220.501583)
				(end 384.665728 -220.498924)
			)
			(xy 384.575558 -220.508576) (xy 384.556 -220.520768)
			(arc
				(start 384.549904 -220.53042)
				(mid 384.41173 -220.658992)
				(end 384.228848 -220.70568)
			)
			(arc
				(start 384.228848 -220.70568)
				(mid 383.959081 -220.593939)
				(end 383.84734 -220.324172)
			)
			(arc
				(start 383.84734 -220.324172)
				(mid 383.894003 -220.141276)
				(end 384.0226 -220.003116)
			)
			(xy 384.032252 -219.99702) (xy 384.044444 -219.977462)
			(arc
				(start 384.054096 -219.887292)
				(mid 384.051435 -219.864917)
				(end 384.039364 -219.84589)
			)
			(arc
				(start 382.739138 -218.54541)
				(mid 382.71972 -218.533366)
				(end 382.696974 -218.530932)
			)
			(xy 382.606042 -218.541854) (xy 382.586484 -218.554554)
			(arc
				(start 382.580388 -218.564714)
				(mid 382.441324 -218.699088)
				(end 382.254252 -218.748102)
			)
			(arc
				(start 382.254252 -218.748102)
				(mid 381.984485 -218.636361)
				(end 381.872744 -218.366594)
			)
			(arc
				(start 381.872744 -218.366594)
				(mid 381.921729 -218.179506)
				(end 382.056132 -218.040458)
			)
			(xy 382.066292 -218.034362) (xy 382.078992 -218.014804)
			(arc
				(start 382.089914 -217.923872)
				(mid 382.087588 -217.901089)
				(end 382.075436 -217.881708)
			)
			(arc
				(start 381.43942 -217.245946)
				(mid 381.423003 -217.234884)
				(end 381.403606 -217.23096)
			)
			(arc
				(start 379.597412 -217.23096)
				(mid 379.569128 -217.239562)
				(end 379.550422 -217.262456)
			)
			(xy 379.54458 -217.276934) (xy 379.550422 -217.306652)
			(arc
				(start 380.561088 -218.317572)
				(mid 380.583095 -218.330421)
				(end 380.608586 -218.331034)
			)
			(xy 380.705106 -218.308682) (xy 380.724664 -218.291156)
			(arc
				(start 380.728982 -218.27871)
				(mid 380.868198 -218.092471)
				(end 381.089662 -218.021662)
			)
			(arc
				(start 381.089662 -218.021662)
				(mid 381.359429 -218.133403)
				(end 381.47117 -218.40317)
			)
			(arc
				(start 381.47117 -218.40317)
				(mid 381.400327 -218.62461)
				(end 381.214122 -218.76385)
			)
			(xy 381.201676 -218.768168) (xy 381.18415 -218.787726)
			(arc
				(start 381.161798 -218.884246)
				(mid 381.162352 -218.909754)
				(end 381.17526 -218.931744)
			)
			(arc
				(start 385.253992 -223.010476)
				(mid 385.271854 -223.021961)
				(end 385.292854 -223.025208)
			)
			(xy 385.379468 -223.020382) (xy 385.398264 -223.010476)
			(arc
				(start 385.405376 -223.00184)
				(mid 385.538026 -222.896272)
				(end 385.703318 -222.858584)
			)
			(arc
				(start 385.703318 -222.858584)
				(mid 385.973085 -222.970325)
				(end 386.084826 -223.240092)
			)
			(arc
				(start 386.084826 -223.240092)
				(mid 386.047155 -223.405393)
				(end 385.94157 -223.538034)
			)
			(xy 385.932934 -223.545146) (xy 385.923028 -223.563942)
			(arc
				(start 385.918202 -223.650556)
				(mid 385.92139 -223.671578)
				(end 385.932934 -223.689418)
			)
		)
		(stroke
			(width 0)
			(type solid)
		)
		(fill yes)
		(layer "In5.Cu")
		(net "GND")
	)
	(gr_poly
		(pts
			(xy 228.485954 -289.953192) (xy 228.485954 -288.244534) (xy 228.111304 -287.869884) (xy 228.111304 -286.18942)
			(xy 228.111304 -279.650444) (xy 227.716588 -279.255982) (xy 227.706519 -279.255556) (xy 227.68792 -279.247837)
			(xy 227.68052 -279.240996) (xy 227.295964 -278.85644) (xy 227.28912 -278.849041) (xy 227.281397 -278.830442)
			(xy 227.280978 -278.820372) (xy 227.280978 -276.768052) (xy 227.281409 -276.757985) (xy 227.289133 -276.739391)
			(xy 227.295964 -276.731984) (xy 227.621592 -276.406356) (xy 227.628987 -276.399502) (xy 227.647586 -276.391756)
			(xy 227.65766 -276.39137) (xy 229.65029 -276.39137) (xy 229.66036 -276.390948) (xy 229.678965 -276.383233)
			(xy 229.686358 -276.376384) (xy 229.775004 -276.287738) (xy 229.78184 -276.280336) (xy 229.789552 -276.261738)
			(xy 229.78999 -276.25167) (xy 229.78999 -274.444206) (xy 229.653592 -274.307808) (xy 228.357176 -274.307808)
			(xy 225.651568 -277.013416) (xy 225.644172 -277.020267) (xy 225.625573 -277.028003) (xy 225.6155 -277.028402)
			(xy 225.005392 -277.028402) (xy 224.995323 -277.028827) (xy 224.97672 -277.036543) (xy 224.969324 -277.043388)
			(xy 223.91751 -278.095202) (xy 223.910112 -278.10205) (xy 223.891514 -278.109788) (xy 223.881442 -278.110188)
			(xy 220.592904 -278.110188) (xy 220.582833 -278.11061) (xy 220.564226 -278.118322) (xy 220.556836 -278.125174)
			(xy 220.448632 -278.233378) (xy 225.945952 -278.233378) (xy 225.950023 -278.177756) (xy 225.962149 -278.123319)
			(xy 225.982072 -278.071228) (xy 226.009368 -278.022593) (xy 226.043454 -277.97845) (xy 226.083603 -277.939741)
			(xy 226.128961 -277.90729) (xy 226.178561 -277.881789) (xy 226.231345 -277.863782) (xy 226.286188 -277.853652)
			(xy 226.341922 -277.851615) (xy 226.397359 -277.857715) (xy 226.451316 -277.871821) (xy 226.502645 -277.893633)
			(xy 226.550251 -277.922687) (xy 226.593119 -277.958362) (xy 226.630336 -277.999899) (xy 226.661109 -278.046412)
			(xy 226.684781 -278.096909) (xy 226.700849 -278.150316) (xy 226.708969 -278.205492) (xy 226.709478 -278.233378)
			(xy 226.708969 -278.261264) (xy 226.700849 -278.31644) (xy 226.684781 -278.369847) (xy 226.661109 -278.420344)
			(xy 226.630336 -278.466857) (xy 226.593119 -278.508394) (xy 226.550251 -278.544069) (xy 226.502645 -278.573123)
			(xy 226.451316 -278.594935) (xy 226.397359 -278.609041) (xy 226.341922 -278.615141) (xy 226.286188 -278.613104)
			(xy 226.231345 -278.602974) (xy 226.178561 -278.584967) (xy 226.128961 -278.559466) (xy 226.083603 -278.527015)
			(xy 226.043454 -278.488306) (xy 226.009368 -278.444163) (xy 225.982072 -278.395528) (xy 225.962149 -278.343437)
			(xy 225.950023 -278.289) (xy 225.945952 -278.233378) (xy 220.448632 -278.233378) (xy 220.132402 -278.549608)
			(xy 220.125557 -278.557007) (xy 220.117825 -278.575605) (xy 220.117416 -278.585676) (xy 220.117416 -279.075896)
			(xy 224.380042 -279.075896) (xy 224.384113 -279.020274) (xy 224.396239 -278.965837) (xy 224.416162 -278.913746)
			(xy 224.443458 -278.865111) (xy 224.477544 -278.820968) (xy 224.517693 -278.782259) (xy 224.563051 -278.749808)
			(xy 224.612651 -278.724307) (xy 224.665435 -278.7063) (xy 224.720278 -278.69617) (xy 224.776012 -278.694133)
			(xy 224.831449 -278.700233) (xy 224.885406 -278.714339) (xy 224.936735 -278.736151) (xy 224.984341 -278.765205)
			(xy 225.027209 -278.80088) (xy 225.064426 -278.842417) (xy 225.095199 -278.88893) (xy 225.118871 -278.939427)
			(xy 225.134939 -278.992834) (xy 225.143059 -279.04801) (xy 225.143568 -279.075896) (xy 225.143059 -279.103782)
			(xy 225.134939 -279.158958) (xy 225.118871 -279.212365) (xy 225.095199 -279.262862) (xy 225.064426 -279.309375)
			(xy 225.027209 -279.350912) (xy 224.984341 -279.386587) (xy 224.936735 -279.415641) (xy 224.885406 -279.437453)
			(xy 224.831449 -279.451559) (xy 224.776012 -279.457659) (xy 224.720278 -279.455622) (xy 224.665435 -279.445492)
			(xy 224.612651 -279.427485) (xy 224.563051 -279.401984) (xy 224.517693 -279.369533) (xy 224.477544 -279.330824)
			(xy 224.443458 -279.286681) (xy 224.416162 -279.238046) (xy 224.396239 -279.185955) (xy 224.384113 -279.131518)
			(xy 224.380042 -279.075896) (xy 220.117416 -279.075896) (xy 220.117416 -280.10104) (xy 224.384106 -280.10104)
			(xy 224.388177 -280.045418) (xy 224.400303 -279.990981) (xy 224.420226 -279.93889) (xy 224.447522 -279.890255)
			(xy 224.481608 -279.846112) (xy 224.521757 -279.807403) (xy 224.567115 -279.774952) (xy 224.616715 -279.749451)
			(xy 224.669499 -279.731444) (xy 224.724342 -279.721314) (xy 224.780076 -279.719277) (xy 224.835513 -279.725377)
			(xy 224.88947 -279.739483) (xy 224.940799 -279.761295) (xy 224.988405 -279.790349) (xy 225.031273 -279.826024)
			(xy 225.06849 -279.867561) (xy 225.099263 -279.914074) (xy 225.122935 -279.964571) (xy 225.139003 -280.017978)
			(xy 225.147123 -280.073154) (xy 225.147632 -280.10104) (xy 226.403406 -280.10104) (xy 226.407477 -280.045418)
			(xy 226.419603 -279.990981) (xy 226.439526 -279.93889) (xy 226.466822 -279.890255) (xy 226.500908 -279.846112)
			(xy 226.541057 -279.807403) (xy 226.586415 -279.774952) (xy 226.636015 -279.749451) (xy 226.688799 -279.731444)
			(xy 226.743642 -279.721314) (xy 226.799376 -279.719277) (xy 226.854813 -279.725377) (xy 226.90877 -279.739483)
			(xy 226.960099 -279.761295) (xy 227.007705 -279.790349) (xy 227.050573 -279.826024) (xy 227.08779 -279.867561)
			(xy 227.118563 -279.914074) (xy 227.142235 -279.964571) (xy 227.158303 -280.017978) (xy 227.166423 -280.073154)
			(xy 227.166932 -280.10104) (xy 227.166423 -280.128926) (xy 227.158303 -280.184102) (xy 227.142235 -280.237509)
			(xy 227.118563 -280.288006) (xy 227.08779 -280.334519) (xy 227.050573 -280.376056) (xy 227.007705 -280.411731)
			(xy 226.960099 -280.440785) (xy 226.90877 -280.462597) (xy 226.854813 -280.476703) (xy 226.799376 -280.482803)
			(xy 226.743642 -280.480766) (xy 226.688799 -280.470636) (xy 226.636015 -280.452629) (xy 226.586415 -280.427128)
			(xy 226.541057 -280.394677) (xy 226.500908 -280.355968) (xy 226.466822 -280.311825) (xy 226.439526 -280.26319)
			(xy 226.419603 -280.211099) (xy 226.407477 -280.156662) (xy 226.403406 -280.10104) (xy 225.147632 -280.10104)
			(xy 225.147123 -280.128926) (xy 225.139003 -280.184102) (xy 225.122935 -280.237509) (xy 225.099263 -280.288006)
			(xy 225.06849 -280.334519) (xy 225.031273 -280.376056) (xy 224.988405 -280.411731) (xy 224.940799 -280.440785)
			(xy 224.88947 -280.462597) (xy 224.835513 -280.476703) (xy 224.780076 -280.482803) (xy 224.724342 -280.480766)
			(xy 224.669499 -280.470636) (xy 224.616715 -280.452629) (xy 224.567115 -280.427128) (xy 224.521757 -280.394677)
			(xy 224.481608 -280.355968) (xy 224.447522 -280.311825) (xy 224.420226 -280.26319) (xy 224.400303 -280.211099)
			(xy 224.388177 -280.156662) (xy 224.384106 -280.10104) (xy 220.117416 -280.10104) (xy 220.117416 -280.886662)
			(xy 220.116982 -280.896728) (xy 220.109254 -280.915317) (xy 220.10243 -280.92273) (xy 220.10243 -289.040824)
			(xy 220.102892 -289.0507) (xy 220.11034 -289.068994) (xy 220.116908 -289.076384) (xy 220.117162 -289.076638)
			(xy 221.354142 -290.313618) (xy 221.35465 -290.314126) (xy 221.36203 -290.320712) (xy 221.380329 -290.328167)
			(xy 221.39021 -290.328604) (xy 228.110542 -290.328604)
		)
		(stroke
			(width 0)
			(type solid)
		)
		(fill yes)
		(layer "In5.Cu")
		(net "P1V25_PEX1_R")
	)
	(gr_poly
		(pts
			(arc
				(start 1.015492 -246.48795)
				(mid 1.090466 -246.111319)
				(end 1.303782 -245.79199)
			)
			(arc
				(start 3.93192 -243.163852)
				(mid 4.58575 -242.18556)
				(end 4.815332 -241.031522)
			)
			(arc
				(start 4.815332 -87.588344)
				(mid 4.585694 -86.434435)
				(end 3.93192 -85.456268)
			)
			(arc
				(start 1.303528 -82.827876)
				(mid 1.090411 -82.508641)
				(end 1.015492 -82.13217)
			)
			(arc
				(start 1.015492 -1.999996)
				(mid 1.303847 -1.303847)
				(end 1.999996 -1.015492)
			)
			(arc
				(start 5.964936 -1.015492)
				(mid 6.661085 -1.303847)
				(end 6.94944 -1.999996)
			)
			(arc
				(start 6.94944 -11.850116)
				(mid 7.539853 -13.275118)
				(end 8.96493 -13.865352)
			)
			(xy 16.2814 -13.865352) (xy 16.371316 -13.775436) (xy 16.371316 -13.44803) (xy 16.2814 -13.358114)
			(arc
				(start 8.96493 -13.358114)
				(mid 7.898614 -12.916432)
				(end 7.456932 -11.850116)
			)
			(arc
				(start 7.456932 -1.999996)
				(mid 7.019936 -0.944996)
				(end 5.964936 -0.508)
			)
			(arc
				(start 1.999996 -0.508)
				(mid 0.944996 -0.944996)
				(end 0.508 -1.999996)
			)
			(arc
				(start 0.508 -82.131916)
				(mid 0.621601 -82.702644)
				(end 0.94488 -83.186524)
			)
			(arc
				(start 3.573272 -85.81517)
				(mid 4.117081 -86.628665)
				(end 4.308094 -87.588344)
			)
			(arc
				(start 4.308094 -241.031522)
				(mid 4.117082 -241.991334)
				(end 3.573272 -242.80495)
			)
			(arc
				(start 0.94488 -245.433342)
				(mid 0.621552 -245.917331)
				(end 0.508 -246.488204)
			)
			(xy 0.508 -307.918358) (xy 1.015492 -307.918358)
		)
		(stroke
			(width 0)
			(type solid)
		)
		(fill yes)
		(layer "In5.Cu")
		(net "GND")
	)
	(gr_poly
		(pts
			(xy 115.170712 -208.895442) (xy 115.180721 -208.894952) (xy 115.199216 -208.887292) (xy 115.213375 -208.873141)
			(xy 115.221047 -208.854651) (xy 115.221512 -208.844642) (xy 115.221512 -207.278986) (xy 115.221035 -207.269019)
			(xy 115.213462 -207.25058) (xy 115.20678 -207.243172) (xy 110.720378 -202.75677) (xy 110.712255 -202.749398)
			(xy 110.691719 -202.74175) (xy 110.680754 -202.742038) (xy 110.59287 -202.748388) (xy 110.57382 -202.758802)
			(xy 110.567216 -202.767692) (xy 110.549084 -202.791072) (xy 110.506815 -202.832468) (xy 110.458662 -202.866843)
			(xy 110.40578 -202.893372) (xy 110.349436 -202.911419) (xy 110.290982 -202.920553) (xy 110.2614 -202.921108)
			(xy 110.234149 -202.920622) (xy 110.180201 -202.912866) (xy 110.127906 -202.897511) (xy 110.078329 -202.874869)
			(xy 110.032479 -202.845403) (xy 109.991288 -202.809712) (xy 109.955597 -202.768521) (xy 109.926131 -202.722671)
			(xy 109.903489 -202.673094) (xy 109.888134 -202.620799) (xy 109.880378 -202.566851) (xy 109.879892 -202.5396)
			(xy 109.880449 -202.510018) (xy 109.889582 -202.451564) (xy 109.90763 -202.395221) (xy 109.934159 -202.342339)
			(xy 109.968533 -202.294186) (xy 110.009929 -202.251917) (xy 110.033308 -202.233784) (xy 110.042198 -202.22718)
			(xy 110.052612 -202.20813) (xy 110.058962 -202.120246) (xy 110.05926 -202.109276) (xy 110.051627 -202.088727)
			(xy 110.04423 -202.080622) (xy 109.300518 -201.33691) (xy 109.293169 -201.330111) (xy 109.274706 -201.322407)
			(xy 109.264704 -201.321924) (xy 108.4072 -201.321924) (xy 108.381125 -201.321455) (xy 108.329612 -201.313326)
			(xy 108.280006 -201.297237) (xy 108.233529 -201.273584) (xy 108.191324 -201.242951) (xy 108.172504 -201.224896)
			(xy 107.308904 -200.361296) (xy 107.291854 -200.343596) (xy 107.262629 -200.304086) (xy 107.239545 -200.260701)
			(xy 107.223107 -200.214387) (xy 107.217972 -200.190354) (xy 107.21594 -200.179686) (xy 107.204002 -200.162414)
			(xy 107.121452 -200.112122) (xy 107.100624 -200.109328) (xy 107.09021 -200.112376) (xy 107.064405 -200.11927)
			(xy 107.011507 -200.126667) (xy 106.9848 -200.127108) (xy 106.957549 -200.126622) (xy 106.903601 -200.118866)
			(xy 106.851306 -200.103511) (xy 106.801729 -200.080869) (xy 106.755879 -200.051403) (xy 106.714688 -200.015712)
			(xy 106.678997 -199.974521) (xy 106.649531 -199.928671) (xy 106.626889 -199.879094) (xy 106.611534 -199.826799)
			(xy 106.603778 -199.772851) (xy 106.603778 -199.718349) (xy 106.611534 -199.664401) (xy 106.626889 -199.612106)
			(xy 106.649531 -199.562529) (xy 106.678997 -199.516679) (xy 106.714688 -199.475488) (xy 106.755879 -199.439797)
			(xy 106.801729 -199.410331) (xy 106.851306 -199.387689) (xy 106.903601 -199.372334) (xy 106.957549 -199.364578)
			(xy 106.9848 -199.364092) (xy 107.009858 -199.364456) (xy 107.05955 -199.370958) (xy 107.08386 -199.377046)
			(xy 107.09529 -199.380348) (xy 107.118404 -199.375522) (xy 107.19181 -199.319388) (xy 107.200805 -199.311798)
			(xy 107.211283 -199.290754) (xy 107.211876 -199.279002) (xy 107.211876 -194.368928) (xy 107.211343 -194.358939)
			(xy 107.203634 -194.340502) (xy 107.19689 -194.333114) (xy 105.882948 -193.019172) (xy 105.87554 -193.012483)
			(xy 105.857104 -193.004888) (xy 105.847134 -193.00444) (xy 104.667304 -193.00444) (xy 104.657272 -193.004794)
			(xy 104.638709 -193.012391) (xy 104.624519 -193.026567) (xy 104.620314 -193.035682) (xy 104.614472 -193.05016)
			(xy 104.620314 -193.079878) (xy 106.813604 -195.273168) (xy 106.831689 -195.291961) (xy 106.862318 -195.334173)
			(xy 106.885964 -195.380657) (xy 106.902045 -195.43027) (xy 106.910165 -195.481787) (xy 106.910632 -195.507864)
			(xy 106.910632 -198.173086) (xy 106.910164 -198.199162) (xy 106.902037 -198.250675) (xy 106.88595 -198.300283)
			(xy 106.862299 -198.346763) (xy 106.831667 -198.388969) (xy 106.813604 -198.407782) (xy 105.88371 -199.337676)
			(xy 105.87691 -199.345025) (xy 105.869204 -199.363488) (xy 105.868724 -199.37349) (xy 105.868724 -200.780904)
			(xy 105.869263 -200.790891) (xy 105.87698 -200.809319) (xy 105.88371 -200.816718) (xy 107.079034 -202.012296)
			(xy 107.085648 -202.018365) (xy 107.101947 -202.02586) (xy 107.119828 -202.027313) (xy 107.128564 -202.02525)
			(xy 107.22737 -201.997818) (xy 107.246166 -201.978514) (xy 107.249468 -201.964798) (xy 107.256771 -201.937621)
			(xy 107.278271 -201.885617) (xy 107.307171 -201.837331) (xy 107.342846 -201.793811) (xy 107.384522 -201.755998)
			(xy 107.431297 -201.724712) (xy 107.482157 -201.700631) (xy 107.536002 -201.684276) (xy 107.591663 -201.676002)
			(xy 107.6198 -201.675492) (xy 107.647051 -201.675978) (xy 107.700999 -201.683734) (xy 107.753294 -201.699089)
			(xy 107.802871 -201.721731) (xy 107.848721 -201.751197) (xy 107.889912 -201.786888) (xy 107.925603 -201.828079)
			(xy 107.955069 -201.873929) (xy 107.977711 -201.923506) (xy 107.993066 -201.975801) (xy 108.000822 -202.029749)
			(xy 108.001308 -202.057) (xy 108.000292 -202.08367) (xy 107.99953 -202.096878) (xy 108.010198 -202.120246)
			(xy 108.101384 -202.186794) (xy 108.126784 -202.190096) (xy 108.13923 -202.185016) (xy 108.16174 -202.176481)
			(xy 108.208366 -202.164494) (xy 108.256129 -202.158459) (xy 108.2802 -202.158092) (xy 108.307451 -202.158578)
			(xy 108.361399 -202.166334) (xy 108.413694 -202.181689) (xy 108.463271 -202.204331) (xy 108.509121 -202.233797)
			(xy 108.550312 -202.269488) (xy 108.586003 -202.310679) (xy 108.615469 -202.356529) (xy 108.638111 -202.406106)
			(xy 108.653466 -202.458401) (xy 108.661222 -202.512349) (xy 108.661222 -202.5396) (xy 108.990382 -202.5396)
			(xy 108.994453 -202.483978) (xy 109.006579 -202.429541) (xy 109.026502 -202.37745) (xy 109.053798 -202.328815)
			(xy 109.087884 -202.284672) (xy 109.128033 -202.245963) (xy 109.173391 -202.213512) (xy 109.222991 -202.188011)
			(xy 109.275775 -202.170004) (xy 109.330618 -202.159874) (xy 109.386352 -202.157837) (xy 109.441789 -202.163937)
			(xy 109.495746 -202.178043) (xy 109.547075 -202.199855) (xy 109.594681 -202.228909) (xy 109.637549 -202.264584)
			(xy 109.674766 -202.306121) (xy 109.705539 -202.352634) (xy 109.729211 -202.403131) (xy 109.745279 -202.456538)
			(xy 109.753399 -202.511714) (xy 109.753908 -202.5396) (xy 109.753399 -202.567486) (xy 109.745279 -202.622662)
			(xy 109.729211 -202.676069) (xy 109.705539 -202.726566) (xy 109.674766 -202.773079) (xy 109.637549 -202.814616)
			(xy 109.594681 -202.850291) (xy 109.547075 -202.879345) (xy 109.495746 -202.901157) (xy 109.441789 -202.915263)
			(xy 109.386352 -202.921363) (xy 109.330618 -202.919326) (xy 109.275775 -202.909196) (xy 109.222991 -202.891189)
			(xy 109.173391 -202.865688) (xy 109.128033 -202.833237) (xy 109.087884 -202.794528) (xy 109.053798 -202.750385)
			(xy 109.026502 -202.70175) (xy 109.006579 -202.649659) (xy 108.994453 -202.595222) (xy 108.990382 -202.5396)
			(xy 108.661222 -202.5396) (xy 108.661222 -202.566851) (xy 108.653466 -202.620799) (xy 108.638111 -202.673094)
			(xy 108.615469 -202.722671) (xy 108.586003 -202.768521) (xy 108.550312 -202.809712) (xy 108.509121 -202.845403)
			(xy 108.463271 -202.874869) (xy 108.413694 -202.897511) (xy 108.361399 -202.912866) (xy 108.307451 -202.920622)
			(xy 108.2802 -202.921108) (xy 108.270403 -202.921039) (xy 108.250835 -202.920022) (xy 108.241084 -202.919076)
			(xy 108.224828 -202.917552) (xy 108.197142 -202.933046) (xy 108.148882 -203.034138) (xy 108.144863 -203.043819)
			(xy 108.144154 -203.064747) (xy 108.15179 -203.084245) (xy 108.158788 -203.09205) (xy 113.947448 -208.880456)
			(xy 113.954847 -208.8873) (xy 113.973446 -208.895023) (xy 113.983516 -208.895442)
		)
		(stroke
			(width 0)
			(type solid)
		)
		(fill yes)
		(layer "In5.Cu")
		(net "GND")
	)
	(gr_poly
		(pts
			(xy 326.370442 -320.900044) (xy 326.36994 -320.804724) (xy 326.361903 -320.614253) (xy 326.345844 -320.42429)
			(xy 326.321791 -320.235174) (xy 326.289786 -320.047239) (xy 326.249888 -319.860821) (xy 326.202166 -319.67625)
			(xy 326.146706 -319.493855) (xy 326.083606 -319.31396) (xy 326.012979 -319.136886) (xy 325.934949 -318.962946)
			(xy 325.849656 -318.79245) (xy 325.757251 -318.625701) (xy 325.657899 -318.462997) (xy 325.551776 -318.304625)
			(xy 325.439071 -318.150867) (xy 325.319985 -318.001998) (xy 325.194728 -317.858281) (xy 325.063524 -317.719973)
			(xy 324.926607 -317.587318) (xy 324.784218 -317.460553) (xy 324.636613 -317.339904) (xy 324.484052 -317.225585)
			(xy 324.326808 -317.117798) (xy 324.165159 -317.016736) (xy 323.999394 -316.922579) (xy 323.829807 -316.835493)
			(xy 323.656699 -316.755634) (xy 323.480379 -316.683144) (xy 323.30116 -316.618151) (xy 323.11936 -316.560771)
			(xy 322.935302 -316.511106) (xy 322.749315 -316.469245) (xy 322.561728 -316.435261) (xy 322.372875 -316.409216)
			(xy 322.183092 -316.391155) (xy 321.992717 -316.38111) (xy 321.802087 -316.379101) (xy 321.611542 -316.385129)
			(xy 321.421421 -316.399185) (xy 321.232061 -316.421243) (xy 321.0438 -316.451264) (xy 320.856971 -316.489195)
			(xy 320.671907 -316.534968) (xy 320.488938 -316.588502) (xy 320.308388 -316.649702) (xy 320.130579 -316.718459)
			(xy 319.955826 -316.794651) (xy 319.78444 -316.878142) (xy 319.616727 -316.968784) (xy 319.452984 -317.066415)
			(xy 319.293502 -317.170862) (xy 319.138565 -317.28194) (xy 318.988449 -317.399451) (xy 318.843419 -317.523185)
			(xy 318.703735 -317.652924) (xy 318.569645 -317.788435) (xy 318.441386 -317.929479) (xy 318.319187 -318.075805)
			(xy 318.203266 -318.227152) (xy 318.093827 -318.383251) (xy 317.991067 -318.543825) (xy 317.895167 -318.708589)
			(xy 317.806299 -318.877248) (xy 317.724619 -319.049504) (xy 317.650274 -319.225051) (xy 317.583396 -319.403575)
			(xy 317.524102 -319.58476) (xy 317.4725 -319.768284) (xy 317.42868 -319.953819) (xy 317.392721 -320.141038)
			(xy 317.364686 -320.329605) (xy 317.344625 -320.519187) (xy 317.332575 -320.709446) (xy 317.328556 -320.900044)
			(xy 319.082429 -320.900044) (xy 319.086418 -320.751504) (xy 319.098375 -320.603391) (xy 319.118265 -320.456134)
			(xy 319.14603 -320.310158) (xy 319.181591 -320.165881) (xy 319.224845 -320.023722) (xy 319.275667 -319.884089)
			(xy 319.333911 -319.747386) (xy 319.399409 -319.614006) (xy 319.471972 -319.484334) (xy 319.55139 -319.358744)
			(xy 319.637435 -319.237597) (xy 319.729859 -319.121244) (xy 319.828395 -319.01002) (xy 319.932759 -318.904245)
			(xy 320.042651 -318.804225) (xy 320.157752 -318.710247) (xy 320.277732 -318.622583) (xy 320.402245 -318.541486)
			(xy 320.530931 -318.467189) (xy 320.66342 -318.399907) (xy 320.799329 -318.339833) (xy 320.938267 -318.287141)
			(xy 321.079833 -318.241982) (xy 321.223619 -318.204487) (xy 321.36921 -318.174765) (xy 321.516186 -318.1529)
			(xy 321.664125 -318.138956) (xy 321.812598 -318.132972) (xy 321.961179 -318.134967) (xy 322.109438 -318.144935)
			(xy 322.256949 -318.162846) (xy 322.403285 -318.188649) (xy 322.548026 -318.222269) (xy 322.690753 -318.263611)
			(xy 322.831056 -318.312554) (xy 322.968529 -318.368957) (xy 323.102776 -318.432658) (xy 323.233411 -318.503474)
			(xy 323.360056 -318.581199) (xy 323.482346 -318.66561) (xy 323.599929 -318.756463) (xy 323.712466 -318.853497)
			(xy 323.819633 -318.956432) (xy 323.92112 -319.064971) (xy 324.016634 -319.1788) (xy 324.105901 -319.297593)
			(xy 324.188662 -319.421005) (xy 324.26468 -319.548683) (xy 324.333735 -319.680256) (xy 324.395628 -319.815347)
			(xy 324.450181 -319.953564) (xy 324.497236 -320.094511) (xy 324.536658 -320.237781) (xy 324.568332 -320.38296)
			(xy 324.592168 -320.529629) (xy 324.608097 -320.677367) (xy 324.616073 -320.825747) (xy 324.616572 -320.900044)
			(xy 324.616073 -320.974341) (xy 324.608097 -321.122721) (xy 324.592168 -321.270459) (xy 324.568332 -321.417128)
			(xy 324.536658 -321.562307) (xy 324.497236 -321.705577) (xy 324.450181 -321.846524) (xy 324.395628 -321.984741)
			(xy 324.333735 -322.119832) (xy 324.26468 -322.251405) (xy 324.188662 -322.379083) (xy 324.105901 -322.502495)
			(xy 324.016634 -322.621288) (xy 323.92112 -322.735117) (xy 323.819633 -322.843656) (xy 323.712466 -322.946591)
			(xy 323.599929 -323.043625) (xy 323.482346 -323.134478) (xy 323.360056 -323.218889) (xy 323.233411 -323.296614)
			(xy 323.102776 -323.36743) (xy 322.968529 -323.431131) (xy 322.831056 -323.487534) (xy 322.690753 -323.536477)
			(xy 322.548026 -323.577819) (xy 322.403285 -323.611439) (xy 322.256949 -323.637242) (xy 322.109438 -323.655153)
			(xy 321.961179 -323.665121) (xy 321.812598 -323.667116) (xy 321.664125 -323.661132) (xy 321.516186 -323.647188)
			(xy 321.36921 -323.625323) (xy 321.223619 -323.595601) (xy 321.079833 -323.558106) (xy 320.938267 -323.512947)
			(xy 320.799329 -323.460255) (xy 320.66342 -323.400181) (xy 320.530931 -323.332899) (xy 320.402245 -323.258602)
			(xy 320.277732 -323.177505) (xy 320.157752 -323.089841) (xy 320.042651 -322.995863) (xy 319.932759 -322.895843)
			(xy 319.828395 -322.790068) (xy 319.729859 -322.678844) (xy 319.637435 -322.562491) (xy 319.55139 -322.441344)
			(xy 319.471972 -322.315754) (xy 319.399409 -322.186082) (xy 319.333911 -322.052702) (xy 319.275667 -321.915999)
			(xy 319.224845 -321.776366) (xy 319.181591 -321.634207) (xy 319.14603 -321.48993) (xy 319.118265 -321.343954)
			(xy 319.098375 -321.196697) (xy 319.086418 -321.048584) (xy 319.082429 -320.900044) (xy 317.328556 -320.900044)
			(xy 317.332575 -321.090642) (xy 317.344625 -321.280901) (xy 317.364686 -321.470483) (xy 317.392721 -321.65905)
			(xy 317.42868 -321.846269) (xy 317.4725 -322.031804) (xy 317.524102 -322.215328) (xy 317.583396 -322.396513)
			(xy 317.650274 -322.575037) (xy 317.724619 -322.750584) (xy 317.806299 -322.92284) (xy 317.895167 -323.091499)
			(xy 317.991067 -323.256263) (xy 318.093827 -323.416837) (xy 318.203266 -323.572936) (xy 318.319187 -323.724283)
			(xy 318.441386 -323.870609) (xy 318.569645 -324.011653) (xy 318.703735 -324.147164) (xy 318.843419 -324.276903)
			(xy 318.988449 -324.400637) (xy 319.138565 -324.518148) (xy 319.293502 -324.629226) (xy 319.452984 -324.733673)
			(xy 319.616727 -324.831304) (xy 319.78444 -324.921946) (xy 319.955826 -325.005437) (xy 320.130579 -325.081629)
			(xy 320.308388 -325.150386) (xy 320.488938 -325.211586) (xy 320.671907 -325.26512) (xy 320.856971 -325.310893)
			(xy 321.0438 -325.348824) (xy 321.232061 -325.378845) (xy 321.421421 -325.400903) (xy 321.611542 -325.414959)
			(xy 321.802087 -325.420987) (xy 321.992717 -325.418978) (xy 322.183092 -325.408933) (xy 322.372875 -325.390872)
			(xy 322.561728 -325.364827) (xy 322.749315 -325.330843) (xy 322.935302 -325.288982) (xy 323.11936 -325.239317)
			(xy 323.30116 -325.181937) (xy 323.480379 -325.116944) (xy 323.656699 -325.044454) (xy 323.829807 -324.964595)
			(xy 323.999394 -324.877509) (xy 324.165159 -324.783352) (xy 324.326808 -324.68229) (xy 324.484052 -324.574503)
			(xy 324.636613 -324.460184) (xy 324.784218 -324.339535) (xy 324.926607 -324.21277) (xy 325.063524 -324.080115)
			(xy 325.194728 -323.941807) (xy 325.319985 -323.79809) (xy 325.439071 -323.649221) (xy 325.551776 -323.495463)
			(xy 325.657899 -323.337091) (xy 325.757251 -323.174387) (xy 325.849656 -323.007638) (xy 325.934949 -322.837142)
			(xy 326.012979 -322.663202) (xy 326.083606 -322.486128) (xy 326.146706 -322.306233) (xy 326.202166 -322.123838)
			(xy 326.249888 -321.939267) (xy 326.289786 -321.752849) (xy 326.321791 -321.564914) (xy 326.345844 -321.375798)
			(xy 326.361903 -321.185835) (xy 326.36994 -320.995364)
		)
		(stroke
			(width 0)
			(type solid)
		)
		(fill yes)
		(layer "In5.Cu")
		(net "GND")
	)
	(gr_poly
		(pts
			(xy 244.327934 -290.328604) (xy 244.338002 -290.328175) (xy 244.356597 -290.320452) (xy 244.364002 -290.313618)
			(xy 244.709442 -289.968178) (xy 244.716291 -289.960781) (xy 244.724027 -289.942182) (xy 244.724428 -289.93211)
			(xy 244.724428 -288.265616) (xy 244.723922 -288.255566) (xy 244.716199 -288.237006) (xy 244.709442 -288.229548)
			(xy 244.364764 -287.88487) (xy 244.357915 -287.877473) (xy 244.350182 -287.858874) (xy 244.349778 -287.848802)
			(xy 244.349778 -279.671526) (xy 244.349341 -279.661462) (xy 244.341605 -279.642879) (xy 244.334792 -279.635458)
			(xy 243.967 -279.26792) (xy 243.964424 -279.265411) (xy 243.958688 -279.261075) (xy 243.95557 -279.259284)
			(xy 243.949982 -279.256236) (xy 243.943124 -279.254458) (xy 243.94287 -279.254458) (xy 243.936184 -279.252557)
			(xy 243.924078 -279.245736) (xy 243.918994 -279.240996) (xy 243.534438 -278.85644) (xy 243.527597 -278.84904)
			(xy 243.519878 -278.830441) (xy 243.519452 -278.820372) (xy 243.519452 -276.768052) (xy 243.519885 -276.757987)
			(xy 243.527618 -276.7394) (xy 243.534438 -276.731984) (xy 243.860066 -276.406356) (xy 243.867465 -276.399514)
			(xy 243.886064 -276.391795) (xy 243.896134 -276.39137) (xy 245.898924 -276.39137) (xy 245.91772 -276.38375)
			(xy 245.924832 -276.376384) (xy 246.013478 -276.287738) (xy 246.020317 -276.280337) (xy 246.028032 -276.261739)
			(xy 246.028464 -276.25167) (xy 246.028464 -274.13077) (xy 246.020844 -274.111974) (xy 246.013478 -274.104862)
			(xy 245.924832 -274.016216) (xy 245.91743 -274.009379) (xy 245.898832 -274.001667) (xy 245.888764 -274.00123)
			(xy 244.91315 -274.00123) (xy 244.894354 -274.00885) (xy 244.887242 -274.016216) (xy 241.890042 -277.013416)
			(xy 241.882644 -277.020262) (xy 241.864045 -277.027989) (xy 241.853974 -277.028402) (xy 241.233706 -277.028402)
			(xy 241.21491 -277.036022) (xy 241.207798 -277.043388) (xy 240.155984 -278.095202) (xy 240.148584 -278.102045)
			(xy 240.129987 -278.109774) (xy 240.119916 -278.110188) (xy 236.821218 -278.110188) (xy 236.802422 -278.117808)
			(xy 236.79531 -278.125174) (xy 236.687106 -278.233378) (xy 242.19611 -278.233378) (xy 242.200181 -278.177756)
			(xy 242.212307 -278.123319) (xy 242.23223 -278.071228) (xy 242.259526 -278.022593) (xy 242.293612 -277.97845)
			(xy 242.333761 -277.939741) (xy 242.379119 -277.90729) (xy 242.428719 -277.881789) (xy 242.481503 -277.863782)
			(xy 242.536346 -277.853652) (xy 242.59208 -277.851615) (xy 242.647517 -277.857715) (xy 242.701474 -277.871821)
			(xy 242.752803 -277.893633) (xy 242.800409 -277.922687) (xy 242.843277 -277.958362) (xy 242.880494 -277.999899)
			(xy 242.911267 -278.046412) (xy 242.934939 -278.096909) (xy 242.951007 -278.150316) (xy 242.959127 -278.205492)
			(xy 242.959636 -278.233378) (xy 242.959127 -278.261264) (xy 242.951007 -278.31644) (xy 242.934939 -278.369847)
			(xy 242.911267 -278.420344) (xy 242.880494 -278.466857) (xy 242.843277 -278.508394) (xy 242.800409 -278.544069)
			(xy 242.752803 -278.573123) (xy 242.701474 -278.594935) (xy 242.647517 -278.609041) (xy 242.59208 -278.615141)
			(xy 242.536346 -278.613104) (xy 242.481503 -278.602974) (xy 242.428719 -278.584967) (xy 242.379119 -278.559466)
			(xy 242.333761 -278.527015) (xy 242.293612 -278.488306) (xy 242.259526 -278.444163) (xy 242.23223 -278.395528)
			(xy 242.212307 -278.343437) (xy 242.200181 -278.289) (xy 242.19611 -278.233378) (xy 236.687106 -278.233378)
			(xy 236.370876 -278.549608) (xy 236.364023 -278.557003) (xy 236.356279 -278.575602) (xy 236.35589 -278.585676)
			(xy 236.35589 -279.075896) (xy 240.6302 -279.075896) (xy 240.634271 -279.020274) (xy 240.646397 -278.965837)
			(xy 240.66632 -278.913746) (xy 240.693616 -278.865111) (xy 240.727702 -278.820968) (xy 240.767851 -278.782259)
			(xy 240.813209 -278.749808) (xy 240.862809 -278.724307) (xy 240.915593 -278.7063) (xy 240.970436 -278.69617)
			(xy 241.02617 -278.694133) (xy 241.081607 -278.700233) (xy 241.135564 -278.714339) (xy 241.186893 -278.736151)
			(xy 241.234499 -278.765205) (xy 241.277367 -278.80088) (xy 241.314584 -278.842417) (xy 241.345357 -278.88893)
			(xy 241.369029 -278.939427) (xy 241.385097 -278.992834) (xy 241.393217 -279.04801) (xy 241.393726 -279.075896)
			(xy 241.393217 -279.103782) (xy 241.385097 -279.158958) (xy 241.369029 -279.212365) (xy 241.345357 -279.262862)
			(xy 241.314584 -279.309375) (xy 241.277367 -279.350912) (xy 241.234499 -279.386587) (xy 241.186893 -279.415641)
			(xy 241.135564 -279.437453) (xy 241.081607 -279.451559) (xy 241.02617 -279.457659) (xy 240.970436 -279.455622)
			(xy 240.915593 -279.445492) (xy 240.862809 -279.427485) (xy 240.813209 -279.401984) (xy 240.767851 -279.369533)
			(xy 240.727702 -279.330824) (xy 240.693616 -279.286681) (xy 240.66632 -279.238046) (xy 240.646397 -279.185955)
			(xy 240.634271 -279.131518) (xy 240.6302 -279.075896) (xy 236.35589 -279.075896) (xy 236.35589 -280.10104)
			(xy 240.634264 -280.10104) (xy 240.638335 -280.045418) (xy 240.650461 -279.990981) (xy 240.670384 -279.93889)
			(xy 240.69768 -279.890255) (xy 240.731766 -279.846112) (xy 240.771915 -279.807403) (xy 240.817273 -279.774952)
			(xy 240.866873 -279.749451) (xy 240.919657 -279.731444) (xy 240.9745 -279.721314) (xy 241.030234 -279.719277)
			(xy 241.085671 -279.725377) (xy 241.139628 -279.739483) (xy 241.190957 -279.761295) (xy 241.238563 -279.790349)
			(xy 241.281431 -279.826024) (xy 241.318648 -279.867561) (xy 241.349421 -279.914074) (xy 241.373093 -279.964571)
			(xy 241.389161 -280.017978) (xy 241.397281 -280.073154) (xy 241.39779 -280.10104) (xy 242.653564 -280.10104)
			(xy 242.657635 -280.045418) (xy 242.669761 -279.990981) (xy 242.689684 -279.93889) (xy 242.71698 -279.890255)
			(xy 242.751066 -279.846112) (xy 242.791215 -279.807403) (xy 242.836573 -279.774952) (xy 242.886173 -279.749451)
			(xy 242.938957 -279.731444) (xy 242.9938 -279.721314) (xy 243.049534 -279.719277) (xy 243.104971 -279.725377)
			(xy 243.158928 -279.739483) (xy 243.210257 -279.761295) (xy 243.257863 -279.790349) (xy 243.300731 -279.826024)
			(xy 243.337948 -279.867561) (xy 243.368721 -279.914074) (xy 243.392393 -279.964571) (xy 243.408461 -280.017978)
			(xy 243.416581 -280.073154) (xy 243.41709 -280.10104) (xy 243.416581 -280.128926) (xy 243.408461 -280.184102)
			(xy 243.392393 -280.237509) (xy 243.368721 -280.288006) (xy 243.337948 -280.334519) (xy 243.300731 -280.376056)
			(xy 243.257863 -280.411731) (xy 243.210257 -280.440785) (xy 243.158928 -280.462597) (xy 243.104971 -280.476703)
			(xy 243.049534 -280.482803) (xy 242.9938 -280.480766) (xy 242.938957 -280.470636) (xy 242.886173 -280.452629)
			(xy 242.836573 -280.427128) (xy 242.791215 -280.394677) (xy 242.751066 -280.355968) (xy 242.71698 -280.311825)
			(xy 242.689684 -280.26319) (xy 242.669761 -280.211099) (xy 242.657635 -280.156662) (xy 242.653564 -280.10104)
			(xy 241.39779 -280.10104) (xy 241.397281 -280.128926) (xy 241.389161 -280.184102) (xy 241.373093 -280.237509)
			(xy 241.349421 -280.288006) (xy 241.318648 -280.334519) (xy 241.281431 -280.376056) (xy 241.238563 -280.411731)
			(xy 241.190957 -280.440785) (xy 241.139628 -280.462597) (xy 241.085671 -280.476703) (xy 241.030234 -280.482803)
			(xy 240.9745 -280.480766) (xy 240.919657 -280.470636) (xy 240.866873 -280.452629) (xy 240.817273 -280.427128)
			(xy 240.771915 -280.394677) (xy 240.731766 -280.355968) (xy 240.69768 -280.311825) (xy 240.670384 -280.26319)
			(xy 240.650461 -280.211099) (xy 240.638335 -280.156662) (xy 240.634264 -280.10104) (xy 236.35589 -280.10104)
			(xy 236.35589 -280.886662) (xy 236.355652 -280.893614) (xy 236.351918 -280.907007) (xy 236.348524 -280.913078)
			(xy 236.34827 -280.913332) (xy 236.344714 -280.919428) (xy 236.342936 -280.925778) (xy 236.340904 -280.939748)
			(xy 236.340904 -289.040824) (xy 236.341332 -289.050892) (xy 236.349053 -289.06949) (xy 236.35589 -289.076892)
			(xy 237.592616 -290.313618) (xy 237.600011 -290.320471) (xy 237.61861 -290.328212) (xy 237.628684 -290.328604)
		)
		(stroke
			(width 0)
			(type solid)
		)
		(fill yes)
		(layer "In5.Cu")
		(net "P1V25_PEX2_R")
	)
	(gr_poly
		(pts
			(arc
				(start 235.636562 -413.132016)
				(mid 235.656085 -413.128115)
				(end 235.67263 -413.11703)
			)
			(arc
				(start 236.812328 -411.977332)
				(mid 236.823439 -411.960798)
				(end 236.827314 -411.941264)
			)
			(arc
				(start 236.827314 -402.776436)
				(mid 236.831215 -402.756913)
				(end 236.8423 -402.740368)
			)
			(arc
				(start 238.886238 -400.69643)
				(mid 238.902772 -400.685319)
				(end 238.922306 -400.681444)
			)
			(arc
				(start 242.916964 -400.681444)
				(mid 242.936487 -400.677543)
				(end 242.953032 -400.666458)
			)
			(arc
				(start 243.86286 -399.75663)
				(mid 243.873971 -399.740096)
				(end 243.877846 -399.720562)
			)
			(arc
				(start 243.877846 -392.486896)
				(mid 243.881747 -392.467373)
				(end 243.892832 -392.450828)
			)
			(xy 243.896388 -392.447272)
			(arc
				(start 243.896388 -391.97026)
				(mid 243.900289 -391.950737)
				(end 243.911374 -391.934192)
			)
			(arc
				(start 245.02999 -390.815576)
				(mid 245.046524 -390.804465)
				(end 245.066058 -390.80059)
			)
			(arc
				(start 259.092954 -390.80059)
				(mid 259.112477 -390.796689)
				(end 259.129022 -390.785604)
			)
			(arc
				(start 262.060944 -387.853682)
				(mid 262.072055 -387.837148)
				(end 262.07593 -387.817614)
			)
			(arc
				(start 262.07593 -379.165866)
				(mid 262.072029 -379.146343)
				(end 262.060944 -379.129798)
			)
			(arc
				(start 261.987538 -379.056392)
				(mid 261.971004 -379.045281)
				(end 261.95147 -379.041406)
			)
			(xy 243.1415 -379.041406) (xy 243.140484 -379.042422)
			(arc
				(start 240.581688 -379.042422)
				(mid 240.562165 -379.046323)
				(end 240.54562 -379.057408)
			)
			(arc
				(start 239.903 -379.700028)
				(mid 239.886466 -379.711139)
				(end 239.866932 -379.715014)
			)
			(arc
				(start 237.06963 -379.715014)
				(mid 237.050107 -379.711113)
				(end 237.033562 -379.700028)
			)
			(arc
				(start 236.41558 -379.082046)
				(mid 236.399163 -379.070984)
				(end 236.379766 -379.06706)
			)
			(arc
				(start 236.321346 -379.06706)
				(mid 236.175393 -379.038122)
				(end 236.051598 -378.955554)
			)
			(arc
				(start 233.504486 -376.408442)
				(mid 233.421874 -376.284666)
				(end 233.39298 -376.138694)
			)
			(arc
				(start 233.39298 -376.080274)
				(mid 233.38903 -376.060887)
				(end 233.377994 -376.04446)
			)
			(arc
				(start 232.94086 -375.607326)
				(mid 232.929749 -375.590792)
				(end 232.925874 -375.571258)
			)
			(arc
				(start 232.925874 -372.098062)
				(mid 232.921973 -372.078539)
				(end 232.910888 -372.061994)
			)
			(arc
				(start 232.189274 -371.34038)
				(mid 232.178163 -371.323846)
				(end 232.174288 -371.304312)
			)
			(arc
				(start 232.174288 -371.057424)
				(mid 232.170387 -371.037901)
				(end 232.159302 -371.021356)
			)
			(xy 232.119932 -370.981986) (xy 232.118408 -370.981986)
			(arc
				(start 232.015284 -370.878862)
				(mid 232.004173 -370.862328)
				(end 232.000298 -370.842794)
			)
			(arc
				(start 232.000298 -367.379758)
				(mid 231.996397 -367.360235)
				(end 231.985312 -367.34369)
			)
			(arc
				(start 231.905048 -367.263426)
				(mid 231.888514 -367.252315)
				(end 231.86898 -367.24844)
			)
			(arc
				(start 228.707696 -367.24844)
				(mid 228.688173 -367.252341)
				(end 228.671628 -367.263426)
			)
			(arc
				(start 228.614478 -367.320576)
				(mid 228.603367 -367.33711)
				(end 228.599492 -367.356644)
			)
			(arc
				(start 228.599492 -370.828062)
				(mid 228.595591 -370.847585)
				(end 228.584506 -370.86413)
			)
			(arc
				(start 228.431344 -371.017292)
				(mid 228.420233 -371.033826)
				(end 228.416358 -371.05336)
			)
			(arc
				(start 228.416358 -371.446552)
				(mid 228.412457 -371.466075)
				(end 228.401372 -371.48262)
			)
			(arc
				(start 227.137722 -372.74627)
				(mid 227.126611 -372.762804)
				(end 227.122736 -372.782338)
			)
			(arc
				(start 227.122736 -374.248426)
				(mid 227.118835 -374.267949)
				(end 227.10775 -374.284494)
			)
			(arc
				(start 225.693224 -375.69902)
				(mid 225.67669 -375.710131)
				(end 225.657156 -375.714006)
			)
			(arc
				(start 223.582484 -375.714006)
				(mid 223.562961 -375.710105)
				(end 223.546416 -375.69902)
			)
			(arc
				(start 221.539816 -373.69242)
				(mid 221.528705 -373.675886)
				(end 221.52483 -373.656352)
			)
			(arc
				(start 221.52483 -371.070124)
				(mid 221.520929 -371.050601)
				(end 221.509844 -371.034056)
			)
			(arc
				(start 221.337632 -370.861844)
				(mid 221.326521 -370.84531)
				(end 221.322646 -370.825776)
			)
			(arc
				(start 221.322646 -367.359692)
				(mid 221.318745 -367.340169)
				(end 221.30766 -367.323624)
			)
			(arc
				(start 221.24416 -367.260124)
				(mid 221.227626 -367.249013)
				(end 221.208092 -367.245138)
			)
			(arc
				(start 218.078304 -367.245138)
				(mid 218.058781 -367.249039)
				(end 218.042236 -367.260124)
			)
			(arc
				(start 217.916506 -367.385854)
				(mid 217.905395 -367.402388)
				(end 217.90152 -367.421922)
			)
			(arc
				(start 217.90152 -370.80063)
				(mid 217.897619 -370.820153)
				(end 217.886534 -370.836698)
			)
			(arc
				(start 216.72931 -371.993922)
				(mid 216.712776 -372.005033)
				(end 216.693242 -372.008908)
			)
			(arc
				(start 210.338924 -372.008908)
				(mid 210.319401 -372.005007)
				(end 210.302856 -371.993922)
			)
			(arc
				(start 210.054698 -371.745764)
				(mid 210.043587 -371.72923)
				(end 210.039712 -371.709696)
			)
			(arc
				(start 210.039712 -371.274086)
				(mid 210.035811 -371.254563)
				(end 210.024726 -371.238018)
			)
			(arc
				(start 209.986626 -371.199918)
				(mid 209.970063 -371.188944)
				(end 209.950558 -371.185186)
			)
			(arc
				(start 209.475324 -371.185186)
				(mid 209.455801 -371.181285)
				(end 209.439256 -371.1702)
			)
			(arc
				(start 208.832196 -370.56314)
				(mid 208.821085 -370.546606)
				(end 208.81721 -370.527072)
			)
			(arc
				(start 208.81721 -370.46027)
				(mid 208.813309 -370.440747)
				(end 208.802224 -370.424202)
			)
			(xy 208.795366 -370.417344)
			(arc
				(start 208.220056 -370.417344)
				(mid 208.200533 -370.413443)
				(end 208.183988 -370.402358)
			)
			(arc
				(start 208.098898 -370.317268)
				(mid 208.087787 -370.300734)
				(end 208.083912 -370.2812)
			)
			(arc
				(start 208.083912 -367.453672)
				(mid 208.069033 -367.417751)
				(end 208.033112 -367.402872)
			)
			(arc
				(start 204.716634 -367.402872)
				(mid 204.680713 -367.417751)
				(end 204.665834 -367.453672)
			)
			(arc
				(start 204.665834 -370.837714)
				(mid 204.669735 -370.857237)
				(end 204.68082 -370.873782)
			)
			(arc
				(start 204.794104 -370.987066)
				(mid 204.805215 -371.0036)
				(end 204.80909 -371.023134)
			)
			(arc
				(start 204.80909 -372.841012)
				(mid 204.815471 -372.865662)
				(end 204.832966 -372.884192)
			)
			(xy 204.917548 -372.93677) (xy 204.94371 -372.93804)
			(arc
				(start 204.955648 -372.932198)
				(mid 205.037716 -372.902845)
				(end 205.124304 -372.892828)
			)
			(arc
				(start 205.124304 -372.892828)
				(mid 205.505812 -373.274336)
				(end 205.124304 -373.655844)
			)
			(arc
				(start 205.124304 -373.655844)
				(mid 205.037702 -373.645885)
				(end 204.955648 -373.616474)
			)
			(xy 204.94371 -373.610632) (xy 204.917548 -373.611902)
			(arc
				(start 204.832966 -373.66448)
				(mid 204.815396 -373.682968)
				(end 204.80909 -373.70766)
			)
			(arc
				(start 204.80909 -374.498616)
				(mid 204.812991 -374.518139)
				(end 204.824076 -374.534684)
			)
			(arc
				(start 204.905102 -374.61571)
				(mid 204.916213 -374.632244)
				(end 204.920088 -374.651778)
			)
			(arc
				(start 204.920088 -387.060948)
				(mid 204.923989 -387.080471)
				(end 204.935074 -387.097016)
			)
			(arc
				(start 207.491838 -389.65378)
				(mid 207.502949 -389.670314)
				(end 207.506824 -389.689848)
			)
			(arc
				(start 207.506824 -411.710124)
				(mid 207.510725 -411.729647)
				(end 207.52181 -411.746192)
			)
			(arc
				(start 208.892648 -413.11703)
				(mid 208.909182 -413.128141)
				(end 208.928716 -413.132016)
			)
		)
		(stroke
			(width 0)
			(type solid)
		)
		(fill yes)
		(layer "In5.Cu")
		(net "P12V_STBY")
	)
	(gr_poly
		(pts
			(xy 107.10418 -399.584164) (xy 107.114243 -399.583726) (xy 107.132823 -399.575987) (xy 107.140248 -399.569178)
			(xy 107.479084 -399.230342) (xy 107.485923 -399.222941) (xy 107.493639 -399.204343) (xy 107.49407 -399.194274)
			(xy 107.49407 -397.675608) (xy 107.493648 -397.665538) (xy 107.485932 -397.646934) (xy 107.479084 -397.63954)
			(xy 106.572304 -396.73276) (xy 106.564909 -396.725906) (xy 106.54631 -396.718161) (xy 106.536236 -396.717774)
			(xy 104.63022 -396.717774) (xy 104.618681 -396.718312) (xy 104.597901 -396.728346) (xy 104.590342 -396.737078)
			(xy 104.572146 -396.759206) (xy 104.530246 -396.798274) (xy 104.482976 -396.830637) (xy 104.431398 -396.855569)
			(xy 104.376672 -396.872508) (xy 104.320028 -396.881074) (xy 104.26274 -396.881074) (xy 104.206096 -396.872508)
			(xy 104.15137 -396.855569) (xy 104.099792 -396.830637) (xy 104.052522 -396.798274) (xy 104.010622 -396.759206)
			(xy 103.992426 -396.737078) (xy 103.984849 -396.728362) (xy 103.964084 -396.718309) (xy 103.952548 -396.717774)
			(xy 103.33482 -396.717774) (xy 103.323281 -396.718312) (xy 103.302501 -396.728346) (xy 103.294942 -396.737078)
			(xy 103.276746 -396.759206) (xy 103.234846 -396.798274) (xy 103.187576 -396.830637) (xy 103.135998 -396.855569)
			(xy 103.081272 -396.872508) (xy 103.024628 -396.881074) (xy 102.96734 -396.881074) (xy 102.910696 -396.872508)
			(xy 102.85597 -396.855569) (xy 102.804392 -396.830637) (xy 102.757122 -396.798274) (xy 102.715222 -396.759206)
			(xy 102.697026 -396.737078) (xy 102.689449 -396.728362) (xy 102.668684 -396.718309) (xy 102.657148 -396.717774)
			(xy 102.03942 -396.717774) (xy 102.027881 -396.718312) (xy 102.007101 -396.728346) (xy 101.999542 -396.737078)
			(xy 101.981346 -396.759206) (xy 101.939446 -396.798274) (xy 101.892176 -396.830637) (xy 101.840598 -396.855569)
			(xy 101.785872 -396.872508) (xy 101.729228 -396.881074) (xy 101.67194 -396.881074) (xy 101.615296 -396.872508)
			(xy 101.56057 -396.855569) (xy 101.508992 -396.830637) (xy 101.461722 -396.798274) (xy 101.419822 -396.759206)
			(xy 101.401626 -396.737078) (xy 101.394049 -396.728362) (xy 101.373284 -396.718309) (xy 101.361748 -396.717774)
			(xy 100.74402 -396.717774) (xy 100.732481 -396.718312) (xy 100.711701 -396.728346) (xy 100.704142 -396.737078)
			(xy 100.685944 -396.759205) (xy 100.644044 -396.798273) (xy 100.596773 -396.830639) (xy 100.545196 -396.855576)
			(xy 100.490472 -396.872522) (xy 100.433828 -396.881098) (xy 100.405184 -396.881604) (xy 100.377934 -396.881117)
			(xy 100.323988 -396.873359) (xy 100.271695 -396.858002) (xy 100.22212 -396.83536) (xy 100.176272 -396.805893)
			(xy 100.135084 -396.770202) (xy 100.099395 -396.729012) (xy 100.06993 -396.683162) (xy 100.047291 -396.633586)
			(xy 100.031937 -396.581293) (xy 100.024181 -396.527346) (xy 100.023676 -396.500096) (xy 100.024148 -396.473316)
			(xy 100.031669 -396.420287) (xy 100.038662 -396.394432) (xy 100.042472 -396.38097) (xy 100.035614 -396.3543)
			(xy 98.966782 -395.285468) (xy 98.959932 -395.278072) (xy 98.952196 -395.259473) (xy 98.951796 -395.2494)
			(xy 98.951796 -390.778492) (xy 98.928936 -390.750552) (xy 98.910648 -390.746996) (xy 98.88358 -390.741204)
			(xy 98.831359 -390.722849) (xy 98.782338 -390.69714) (xy 98.737548 -390.664616) (xy 98.697929 -390.625959)
			(xy 98.664313 -390.581983) (xy 98.637406 -390.53361) (xy 98.617773 -390.481856) (xy 98.605825 -390.427808)
			(xy 98.601814 -390.3726) (xy 98.605825 -390.317392) (xy 98.617773 -390.263344) (xy 98.637406 -390.21159)
			(xy 98.664313 -390.163217) (xy 98.697929 -390.119241) (xy 98.737548 -390.080584) (xy 98.782338 -390.04806)
			(xy 98.831359 -390.022351) (xy 98.88358 -390.003996) (xy 98.910648 -389.998204) (xy 98.928936 -389.994648)
			(xy 98.951796 -389.966708) (xy 98.951796 -366.70361) (xy 98.952314 -366.693711) (xy 98.959891 -366.675413)
			(xy 98.966528 -366.66805) (xy 98.972624 -366.6617) (xy 98.97927 -366.654343) (xy 98.986846 -366.636042)
			(xy 98.987356 -366.62614) (xy 98.987356 -363.693964) (xy 98.987787 -363.683898) (xy 98.995517 -363.665308)
			(xy 99.002342 -363.657896) (xy 100.973382 -361.686602) (xy 100.980231 -361.679204) (xy 100.987969 -361.660606)
			(xy 100.988368 -361.650534) (xy 100.988368 -361.32389) (xy 100.987942 -361.313821) (xy 100.980222 -361.295222)
			(xy 100.973382 -361.287822) (xy 100.703634 -361.018074) (xy 100.696235 -361.01123) (xy 100.677636 -361.003508)
			(xy 100.667566 -361.003088) (xy 98.230436 -361.003088) (xy 98.217887 -361.003743) (xy 98.195773 -361.01561)
			(xy 98.188272 -361.025694) (xy 95.725996 -364.710472) (xy 95.72117 -364.719108) (xy 94.96425 -366.546638)
			(xy 94.96248 -366.551266) (xy 94.960567 -366.560988) (xy 94.96044 -366.565942) (xy 94.96044 -393.1158)
			(xy 96.6503 -393.1158) (xy 96.654371 -393.060178) (xy 96.666497 -393.005741) (xy 96.68642 -392.95365)
			(xy 96.713716 -392.905015) (xy 96.747802 -392.860872) (xy 96.787951 -392.822163) (xy 96.833309 -392.789712)
			(xy 96.882909 -392.764211) (xy 96.935693 -392.746204) (xy 96.990536 -392.736074) (xy 97.04627 -392.734037)
			(xy 97.101707 -392.740137) (xy 97.155664 -392.754243) (xy 97.206993 -392.776055) (xy 97.254599 -392.805109)
			(xy 97.297467 -392.840784) (xy 97.334684 -392.882321) (xy 97.365457 -392.928834) (xy 97.389129 -392.979331)
			(xy 97.405197 -393.032738) (xy 97.413317 -393.087914) (xy 97.413826 -393.1158) (xy 97.413317 -393.143686)
			(xy 97.405197 -393.198862) (xy 97.389129 -393.252269) (xy 97.365457 -393.302766) (xy 97.334684 -393.349279)
			(xy 97.297467 -393.390816) (xy 97.254599 -393.426491) (xy 97.206993 -393.455545) (xy 97.155664 -393.477357)
			(xy 97.101707 -393.491463) (xy 97.04627 -393.497563) (xy 96.990536 -393.495526) (xy 96.935693 -393.485396)
			(xy 96.882909 -393.467389) (xy 96.833309 -393.441888) (xy 96.787951 -393.409437) (xy 96.747802 -393.370728)
			(xy 96.713716 -393.326585) (xy 96.68642 -393.27795) (xy 96.666497 -393.225859) (xy 96.654371 -393.171422)
			(xy 96.6503 -393.1158) (xy 94.96044 -393.1158) (xy 94.96044 -394.1318) (xy 96.6503 -394.1318) (xy 96.654371 -394.076178)
			(xy 96.666497 -394.021741) (xy 96.68642 -393.96965) (xy 96.713716 -393.921015) (xy 96.747802 -393.876872)
			(xy 96.787951 -393.838163) (xy 96.833309 -393.805712) (xy 96.882909 -393.780211) (xy 96.935693 -393.762204)
			(xy 96.990536 -393.752074) (xy 97.04627 -393.750037) (xy 97.101707 -393.756137) (xy 97.155664 -393.770243)
			(xy 97.206993 -393.792055) (xy 97.254599 -393.821109) (xy 97.297467 -393.856784) (xy 97.334684 -393.898321)
			(xy 97.365457 -393.944834) (xy 97.389129 -393.995331) (xy 97.405197 -394.048738) (xy 97.413317 -394.103914)
			(xy 97.413826 -394.1318) (xy 97.413317 -394.159686) (xy 97.405197 -394.214862) (xy 97.389129 -394.268269)
			(xy 97.365457 -394.318766) (xy 97.334684 -394.365279) (xy 97.297467 -394.406816) (xy 97.254599 -394.442491)
			(xy 97.206993 -394.471545) (xy 97.155664 -394.493357) (xy 97.101707 -394.507463) (xy 97.04627 -394.513563)
			(xy 96.990536 -394.511526) (xy 96.935693 -394.501396) (xy 96.882909 -394.483389) (xy 96.833309 -394.457888)
			(xy 96.787951 -394.425437) (xy 96.747802 -394.386728) (xy 96.713716 -394.342585) (xy 96.68642 -394.29395)
			(xy 96.666497 -394.241859) (xy 96.654371 -394.187422) (xy 96.6503 -394.1318) (xy 94.96044 -394.1318)
			(xy 94.96044 -395.1478) (xy 96.6503 -395.1478) (xy 96.654371 -395.092178) (xy 96.666497 -395.037741)
			(xy 96.68642 -394.98565) (xy 96.713716 -394.937015) (xy 96.747802 -394.892872) (xy 96.787951 -394.854163)
			(xy 96.833309 -394.821712) (xy 96.882909 -394.796211) (xy 96.935693 -394.778204) (xy 96.990536 -394.768074)
			(xy 97.04627 -394.766037) (xy 97.101707 -394.772137) (xy 97.155664 -394.786243) (xy 97.206993 -394.808055)
			(xy 97.254599 -394.837109) (xy 97.297467 -394.872784) (xy 97.334684 -394.914321) (xy 97.365457 -394.960834)
			(xy 97.389129 -395.011331) (xy 97.405197 -395.064738) (xy 97.413317 -395.119914) (xy 97.413826 -395.1478)
			(xy 97.413317 -395.175686) (xy 97.405197 -395.230862) (xy 97.389129 -395.284269) (xy 97.365457 -395.334766)
			(xy 97.334684 -395.381279) (xy 97.297467 -395.422816) (xy 97.254599 -395.458491) (xy 97.206993 -395.487545)
			(xy 97.155664 -395.509357) (xy 97.101707 -395.523463) (xy 97.04627 -395.529563) (xy 96.990536 -395.527526)
			(xy 96.935693 -395.517396) (xy 96.882909 -395.499389) (xy 96.833309 -395.473888) (xy 96.787951 -395.441437)
			(xy 96.747802 -395.402728) (xy 96.713716 -395.358585) (xy 96.68642 -395.30995) (xy 96.666497 -395.257859)
			(xy 96.654371 -395.203422) (xy 96.6503 -395.1478) (xy 94.96044 -395.1478) (xy 94.96044 -396.04442)
			(xy 94.960868 -396.054488) (xy 94.968592 -396.073083) (xy 94.975426 -396.080488) (xy 97.563178 -398.66824)
			(xy 102.605076 -398.66824) (xy 102.609147 -398.612618) (xy 102.621273 -398.558181) (xy 102.641196 -398.50609)
			(xy 102.668492 -398.457455) (xy 102.702578 -398.413312) (xy 102.742727 -398.374603) (xy 102.788085 -398.342152)
			(xy 102.837685 -398.316651) (xy 102.890469 -398.298644) (xy 102.945312 -398.288514) (xy 103.001046 -398.286477)
			(xy 103.056483 -398.292577) (xy 103.11044 -398.306683) (xy 103.161769 -398.328495) (xy 103.209375 -398.357549)
			(xy 103.252243 -398.393224) (xy 103.28946 -398.434761) (xy 103.320233 -398.481274) (xy 103.343905 -398.531771)
			(xy 103.359973 -398.585178) (xy 103.368093 -398.640354) (xy 103.368602 -398.66824) (xy 103.621076 -398.66824)
			(xy 103.625147 -398.612618) (xy 103.637273 -398.558181) (xy 103.657196 -398.50609) (xy 103.684492 -398.457455)
			(xy 103.718578 -398.413312) (xy 103.758727 -398.374603) (xy 103.804085 -398.342152) (xy 103.853685 -398.316651)
			(xy 103.906469 -398.298644) (xy 103.961312 -398.288514) (xy 104.017046 -398.286477) (xy 104.072483 -398.292577)
			(xy 104.12644 -398.306683) (xy 104.177769 -398.328495) (xy 104.225375 -398.357549) (xy 104.268243 -398.393224)
			(xy 104.30546 -398.434761) (xy 104.336233 -398.481274) (xy 104.359905 -398.531771) (xy 104.375973 -398.585178)
			(xy 104.384093 -398.640354) (xy 104.384602 -398.66824) (xy 104.637076 -398.66824) (xy 104.641147 -398.612618)
			(xy 104.653273 -398.558181) (xy 104.673196 -398.50609) (xy 104.700492 -398.457455) (xy 104.734578 -398.413312)
			(xy 104.774727 -398.374603) (xy 104.820085 -398.342152) (xy 104.869685 -398.316651) (xy 104.922469 -398.298644)
			(xy 104.977312 -398.288514) (xy 105.033046 -398.286477) (xy 105.088483 -398.292577) (xy 105.14244 -398.306683)
			(xy 105.193769 -398.328495) (xy 105.241375 -398.357549) (xy 105.284243 -398.393224) (xy 105.32146 -398.434761)
			(xy 105.352233 -398.481274) (xy 105.375905 -398.531771) (xy 105.391973 -398.585178) (xy 105.400093 -398.640354)
			(xy 105.400602 -398.66824) (xy 105.400093 -398.696126) (xy 105.391973 -398.751302) (xy 105.375905 -398.804709)
			(xy 105.352233 -398.855206) (xy 105.32146 -398.901719) (xy 105.284243 -398.943256) (xy 105.241375 -398.978931)
			(xy 105.193769 -399.007985) (xy 105.14244 -399.029797) (xy 105.088483 -399.043903) (xy 105.033046 -399.050003)
			(xy 104.977312 -399.047966) (xy 104.922469 -399.037836) (xy 104.869685 -399.019829) (xy 104.820085 -398.994328)
			(xy 104.774727 -398.961877) (xy 104.734578 -398.923168) (xy 104.700492 -398.879025) (xy 104.673196 -398.83039)
			(xy 104.653273 -398.778299) (xy 104.641147 -398.723862) (xy 104.637076 -398.66824) (xy 104.384602 -398.66824)
			(xy 104.384093 -398.696126) (xy 104.375973 -398.751302) (xy 104.359905 -398.804709) (xy 104.336233 -398.855206)
			(xy 104.30546 -398.901719) (xy 104.268243 -398.943256) (xy 104.225375 -398.978931) (xy 104.177769 -399.007985)
			(xy 104.12644 -399.029797) (xy 104.072483 -399.043903) (xy 104.017046 -399.050003) (xy 103.961312 -399.047966)
			(xy 103.906469 -399.037836) (xy 103.853685 -399.019829) (xy 103.804085 -398.994328) (xy 103.758727 -398.961877)
			(xy 103.718578 -398.923168) (xy 103.684492 -398.879025) (xy 103.657196 -398.83039) (xy 103.637273 -398.778299)
			(xy 103.625147 -398.723862) (xy 103.621076 -398.66824) (xy 103.368602 -398.66824) (xy 103.368093 -398.696126)
			(xy 103.359973 -398.751302) (xy 103.343905 -398.804709) (xy 103.320233 -398.855206) (xy 103.28946 -398.901719)
			(xy 103.252243 -398.943256) (xy 103.209375 -398.978931) (xy 103.161769 -399.007985) (xy 103.11044 -399.029797)
			(xy 103.056483 -399.043903) (xy 103.001046 -399.050003) (xy 102.945312 -399.047966) (xy 102.890469 -399.037836)
			(xy 102.837685 -399.019829) (xy 102.788085 -398.994328) (xy 102.742727 -398.961877) (xy 102.702578 -398.923168)
			(xy 102.668492 -398.879025) (xy 102.641196 -398.83039) (xy 102.621273 -398.778299) (xy 102.609147 -398.723862)
			(xy 102.605076 -398.66824) (xy 97.563178 -398.66824) (xy 98.464116 -399.569178) (xy 98.471514 -399.576024)
			(xy 98.490113 -399.583756) (xy 98.500184 -399.584164)
		)
		(stroke
			(width 0)
			(type solid)
		)
		(fill yes)
		(layer "In5.Cu")
		(net "P3V3_AUX")
	)
	(gr_poly
		(pts
			(xy 101.319076 -337.69554) (xy 101.329139 -337.695101) (xy 101.347717 -337.687361) (xy 101.355144 -337.680554)
			(xy 101.975412 -337.060286) (xy 101.982266 -337.052891) (xy 101.990009 -337.034292) (xy 101.990398 -337.024218)
			(xy 101.990398 -335.349596) (xy 101.988366 -335.34223) (xy 101.98083 -335.315554) (xy 101.972676 -335.260725)
			(xy 101.97211 -335.23301) (xy 101.972682 -335.205296) (xy 101.980839 -335.150468) (xy 101.988366 -335.12379)
			(xy 101.990398 -335.116424) (xy 101.990398 -333.12735) (xy 101.989966 -333.117284) (xy 101.982238 -333.098693)
			(xy 101.975412 -333.091282) (xy 100.503482 -331.619352) (xy 100.478082 -331.611986) (xy 100.465382 -331.615034)
			(xy 100.444155 -331.619651) (xy 100.400997 -331.624614) (xy 100.379276 -331.62494) (xy 100.378768 -331.62494)
			(xy 100.351517 -331.624452) (xy 100.297571 -331.616692) (xy 100.245279 -331.601334) (xy 100.195703 -331.578692)
			(xy 100.149855 -331.549225) (xy 100.108666 -331.513534) (xy 100.072975 -331.472345) (xy 100.043508 -331.426497)
			(xy 100.020866 -331.376921) (xy 100.005508 -331.324629) (xy 99.997748 -331.270683) (xy 99.99726 -331.243432)
			(xy 99.99726 -331.242924) (xy 99.997583 -331.221203) (xy 100.002552 -331.178046) (xy 100.007166 -331.156818)
			(xy 100.010214 -331.144118) (xy 100.002848 -331.118718) (xy 99.476052 -330.591922) (xy 99.469212 -330.584522)
			(xy 99.461498 -330.565923) (xy 99.461066 -330.555854) (xy 99.461066 -293.294054) (xy 99.461066 -293.29126)
			(xy 99.460241 -293.282373) (xy 99.453224 -293.265974) (xy 99.44735 -293.259256) (xy 99.445064 -293.25697)
			(xy 99.383342 -293.199058) (xy 99.364038 -293.191946) (xy 99.35337 -293.192708) (xy 99.302873 -293.195559)
			(xy 99.201763 -293.198607) (xy 99.151186 -293.198804) (xy 99.149916 -293.198804) (xy 99.068262 -293.198319)
			(xy 98.905143 -293.190429) (xy 98.742597 -293.174669) (xy 98.581001 -293.151073) (xy 98.420734 -293.119698)
			(xy 98.262171 -293.080616) (xy 98.10568 -293.033919) (xy 97.951629 -292.979716) (xy 97.800376 -292.918133)
			(xy 97.652275 -292.849315) (xy 97.507672 -292.773422) (xy 97.366904 -292.690632) (xy 97.230301 -292.601137)
			(xy 97.098181 -292.505147) (xy 96.970853 -292.402885) (xy 96.848614 -292.294592) (xy 96.73175 -292.180519)
			(xy 96.620534 -292.060933) (xy 96.515225 -291.936114) (xy 96.416069 -291.806352) (xy 96.323299 -291.671952)
			(xy 96.237131 -291.533226) (xy 96.157765 -291.390499) (xy 96.085387 -291.244105) (xy 96.020167 -291.094384)
			(xy 95.962257 -290.941688) (xy 95.911792 -290.786372) (xy 95.868889 -290.628799) (xy 95.83365 -290.469337)
			(xy 95.806155 -290.30836) (xy 95.78647 -290.146241) (xy 95.774641 -289.983361) (xy 95.770695 -289.8201)
			(xy 95.774641 -289.656839) (xy 95.78647 -289.493959) (xy 95.806155 -289.33184) (xy 95.83365 -289.170863)
			(xy 95.868889 -289.011401) (xy 95.911792 -288.853828) (xy 95.962257 -288.698512) (xy 96.020167 -288.545816)
			(xy 96.085387 -288.396095) (xy 96.157765 -288.249701) (xy 96.237131 -288.106974) (xy 96.323299 -287.968248)
			(xy 96.416069 -287.833848) (xy 96.515225 -287.704086) (xy 96.620534 -287.579267) (xy 96.73175 -287.459681)
			(xy 96.848614 -287.345608) (xy 96.970853 -287.237315) (xy 97.098181 -287.135053) (xy 97.230301 -287.039063)
			(xy 97.366904 -286.949568) (xy 97.507672 -286.866778) (xy 97.652275 -286.790885) (xy 97.800376 -286.722067)
			(xy 97.951629 -286.660484) (xy 98.10568 -286.606281) (xy 98.262171 -286.559584) (xy 98.420734 -286.520502)
			(xy 98.581001 -286.489127) (xy 98.742597 -286.465531) (xy 98.905143 -286.449771) (xy 99.068262 -286.441881)
			(xy 99.149916 -286.441388) (xy 99.151186 -286.441388) (xy 99.201763 -286.44159) (xy 99.302872 -286.444639)
			(xy 99.35337 -286.447484) (xy 99.364038 -286.448246) (xy 99.383342 -286.441134) (xy 99.445064 -286.383222)
			(xy 99.44735 -286.380936) (xy 99.453165 -286.374177) (xy 99.460191 -286.357805) (xy 99.461066 -286.348932)
			(xy 99.461066 -286.346138) (xy 99.461066 -284.598872) (xy 99.460637 -284.588805) (xy 99.452912 -284.570211)
			(xy 99.44608 -284.562804) (xy 99.095052 -284.211776) (xy 95.245936 -284.211776) (xy 94.682564 -284.775148)
			(xy 94.682564 -285.043118) (xy 94.710277 -285.048648) (xy 94.763793 -285.066794) (xy 94.814047 -285.092637)
			(xy 94.859938 -285.125611) (xy 94.900463 -285.164994) (xy 94.934735 -285.209925) (xy 94.962003 -285.25942)
			(xy 94.981671 -285.312396) (xy 94.993308 -285.367694) (xy 94.996661 -285.424103) (xy 94.991655 -285.480391)
			(xy 94.9784 -285.535323) (xy 94.957187 -285.5877) (xy 94.928478 -285.636373) (xy 94.892904 -285.680279)
			(xy 94.851241 -285.718457) (xy 94.804402 -285.75007) (xy 94.753412 -285.774428) (xy 94.699387 -285.790997)
			(xy 94.643508 -285.799414) (xy 94.615254 -285.800038) (xy 94.615 -285.800038) (xy 94.588389 -285.79955)
			(xy 94.53569 -285.792112) (xy 94.484531 -285.777434) (xy 94.435904 -285.7558) (xy 94.41307 -285.742126)
			(xy 94.412816 -285.741872) (xy 94.404947 -285.737514) (xy 94.387309 -285.734041) (xy 94.369549 -285.736822)
			(xy 94.361508 -285.740856) (xy 94.283784 -285.783782) (xy 94.276048 -285.788487) (xy 94.264258 -285.802214)
			(xy 94.257977 -285.819184) (xy 94.257622 -285.828232) (xy 94.257622 -288.849816) (xy 94.257197 -288.859885)
			(xy 94.249481 -288.878488) (xy 94.242636 -288.885884) (xy 93.35389 -289.77463) (xy 93.346524 -289.781742)
			(xy 93.338904 -289.800538) (xy 93.338904 -290.870894) (xy 93.33952 -290.883312) (xy 93.351101 -290.905283)
			(xy 93.361002 -290.912804) (xy 93.440504 -290.967414) (xy 93.465142 -290.970462) (xy 93.47708 -290.96589)
			(xy 93.498916 -290.957866) (xy 93.544047 -290.946577) (xy 93.590217 -290.940864) (xy 93.613478 -290.94049)
			(xy 93.620844 -290.94049) (xy 93.623892 -290.94049) (xy 93.638878 -290.940236) (xy 93.66615 -290.940698)
			(xy 93.720139 -290.948458) (xy 93.772475 -290.963822) (xy 93.822091 -290.986478) (xy 93.867977 -291.015965)
			(xy 93.9092 -291.051683) (xy 93.94492 -291.092903) (xy 93.97441 -291.138788) (xy 93.99707 -291.188403)
			(xy 94.012437 -291.240737) (xy 94.0202 -291.294726) (xy 94.02064 -291.321998) (xy 94.020121 -291.350727)
			(xy 94.011512 -291.407538) (xy 93.994489 -291.462417) (xy 93.969434 -291.514125) (xy 93.936915 -291.561497)
			(xy 93.897665 -291.60346) (xy 93.852571 -291.63907) (xy 93.827854 -291.653722) (xy 93.821716 -291.657498)
			(xy 93.811652 -291.667805) (xy 93.808042 -291.674042) (xy 93.804994 -291.679884) (xy 93.804994 -291.751512)
			(xy 93.8052 -291.757744) (xy 93.808274 -291.769825) (xy 93.81109 -291.775388) (xy 93.815408 -291.783516)
			(xy 93.838273 -291.795951) (xy 93.880713 -291.826081) (xy 93.918672 -291.861692) (xy 93.951446 -291.902125)
			(xy 93.978431 -291.946631) (xy 93.999126 -291.994388) (xy 94.013148 -292.044512) (xy 94.020239 -292.096074)
			(xy 94.02064 -292.122098) (xy 94.020125 -292.150523) (xy 94.011711 -292.206748) (xy 93.995054 -292.261103)
			(xy 93.970522 -292.312388) (xy 93.938657 -292.359469) (xy 93.900164 -292.401305) (xy 93.855894 -292.436972)
			(xy 93.806824 -292.465681) (xy 93.78061 -292.476682) (xy 93.768164 -292.481508) (xy 93.7514 -292.502336)
			(xy 93.737684 -292.584632) (xy 93.736366 -292.596765) (xy 93.743781 -292.619979) (xy 93.751908 -292.629082)
			(xy 94.856808 -293.733982) (xy 94.86364 -293.741386) (xy 94.871344 -293.759984) (xy 94.871794 -293.77005)
			(xy 94.871794 -296.509948) (xy 94.872225 -296.520015) (xy 94.879951 -296.538607) (xy 94.88678 -296.546016)
			(xy 96.359726 -298.018962) (xy 96.366571 -298.02636) (xy 96.374294 -298.044959) (xy 96.374712 -298.05503)
			(xy 96.374712 -307.09743) (xy 96.374284 -307.107498) (xy 96.366563 -307.126096) (xy 96.359726 -307.133498)
			(xy 94.88678 -308.606444) (xy 94.879932 -308.613841) (xy 94.872201 -308.63244) (xy 94.871794 -308.642512)
			(xy 94.871794 -330.416662) (xy 97.355152 -330.416662) (xy 97.355152 -329.553062) (xy 97.355593 -329.523076)
			(xy 97.363425 -329.463618) (xy 97.378951 -329.405691) (xy 97.401905 -329.350287) (xy 97.431894 -329.298352)
			(xy 97.468406 -329.250775) (xy 97.510814 -329.208371) (xy 97.558395 -329.171865) (xy 97.610333 -329.141882)
			(xy 97.665741 -329.118934) (xy 97.723669 -329.103415) (xy 97.783128 -329.095589) (xy 97.813114 -329.0951)
			(xy 97.842756 -329.095621) (xy 97.901537 -329.103334) (xy 97.958836 -329.118554) (xy 98.013697 -329.141027)
			(xy 98.039682 -329.155298) (xy 98.048094 -329.159547) (xy 98.066725 -329.162278) (xy 98.076004 -329.160632)
			(xy 98.115628 -329.151742) (xy 98.130868 -329.141328) (xy 98.136456 -329.133708) (xy 98.151877 -329.112882)
			(xy 98.187416 -329.075169) (xy 98.227736 -329.042616) (xy 98.272093 -329.015825) (xy 98.31967 -328.995289)
			(xy 98.369591 -328.981387) (xy 98.420934 -328.974374) (xy 98.446844 -328.973942) (xy 98.447098 -328.973942)
			(xy 98.474355 -328.974305) (xy 98.528313 -328.982063) (xy 98.580618 -328.99742) (xy 98.630205 -329.020066)
			(xy 98.676064 -329.049538) (xy 98.717263 -329.085236) (xy 98.752961 -329.126434) (xy 98.782433 -329.172293)
			(xy 98.805079 -329.22188) (xy 98.820437 -329.274185) (xy 98.828195 -329.328143) (xy 98.828195 -329.382657)
			(xy 98.820437 -329.436615) (xy 98.805079 -329.48892) (xy 98.782433 -329.538507) (xy 98.752961 -329.584366)
			(xy 98.717263 -329.625564) (xy 98.676064 -329.661262) (xy 98.630205 -329.690734) (xy 98.580618 -329.71338)
			(xy 98.528313 -329.728737) (xy 98.474355 -329.736495) (xy 98.447098 -329.736958) (xy 98.432305 -329.736825)
			(xy 98.402807 -329.734535) (xy 98.38817 -329.732386) (xy 98.377248 -329.730608) (xy 98.355912 -329.736704)
			(xy 98.28022 -329.80122) (xy 98.271076 -329.821286) (xy 98.271076 -329.832716) (xy 98.271076 -330.137008)
			(xy 98.271076 -330.148438) (xy 98.28022 -330.168504) (xy 98.355912 -330.23302) (xy 98.377248 -330.239116)
			(xy 98.38817 -330.237338) (xy 98.402807 -330.235194) (xy 98.432305 -330.232908) (xy 98.447098 -330.232766)
			(xy 98.474336 -330.233279) (xy 98.52826 -330.241028) (xy 98.580532 -330.256368) (xy 98.630091 -330.278989)
			(xy 98.675927 -330.308429) (xy 98.71711 -330.34409) (xy 98.752802 -330.385247) (xy 98.782276 -330.431062)
			(xy 98.804933 -330.480604) (xy 98.820312 -330.532865) (xy 98.828101 -330.586782) (xy 98.828606 -330.61402)
			(xy 98.828606 -330.614528) (xy 98.828606 -330.61783) (xy 98.830384 -330.6318) (xy 98.836466 -330.656046)
			(xy 98.842965 -330.705611) (xy 98.843338 -330.730606) (xy 98.842904 -330.757878) (xy 98.83514 -330.811867)
			(xy 98.819772 -330.864202) (xy 98.797112 -330.913817) (xy 98.767622 -330.959702) (xy 98.731901 -331.000922)
			(xy 98.690678 -331.03664) (xy 98.644791 -331.066127) (xy 98.595174 -331.088783) (xy 98.542838 -331.104147)
			(xy 98.488848 -331.111906) (xy 98.461576 -331.112368) (xy 98.434498 -331.111875) (xy 98.380887 -331.104206)
			(xy 98.328898 -331.08904) (xy 98.279573 -331.06668) (xy 98.233902 -331.037575) (xy 98.192802 -331.00231)
			(xy 98.157096 -330.961592) (xy 98.127501 -330.916237) (xy 98.115628 -330.891896) (xy 98.108625 -330.878079)
			(xy 98.087722 -330.855235) (xy 98.060934 -330.839705) (xy 98.030723 -330.832917) (xy 97.999866 -330.835495)
			(xy 97.985326 -330.840842) (xy 97.957881 -330.851508) (xy 97.900944 -330.866523) (xy 97.842555 -330.874133)
			(xy 97.813114 -330.874624) (xy 97.783127 -330.87418) (xy 97.723666 -330.866353) (xy 97.665736 -330.850831)
			(xy 97.610327 -330.82788) (xy 97.558388 -330.797893) (xy 97.510809 -330.761382) (xy 97.468402 -330.718973)
			(xy 97.431894 -330.671392) (xy 97.401909 -330.619451) (xy 97.378961 -330.564042) (xy 97.363443 -330.50611)
			(xy 97.355619 -330.446649) (xy 97.355152 -330.416662) (xy 94.871794 -330.416662) (xy 94.871794 -332.038452)
			(xy 99.003864 -332.038452) (xy 99.007937 -331.982793) (xy 99.020072 -331.92832) (xy 99.040008 -331.876194)
			(xy 99.067322 -331.827526) (xy 99.10143 -331.783354) (xy 99.141607 -331.744619) (xy 99.186995 -331.712147)
			(xy 99.236627 -331.686629) (xy 99.289447 -331.66861) (xy 99.344326 -331.658473) (xy 99.400097 -331.656435)
			(xy 99.455571 -331.662538) (xy 99.509564 -331.676654) (xy 99.560927 -331.698481) (xy 99.608565 -331.727554)
			(xy 99.651461 -331.763253) (xy 99.688703 -331.804817) (xy 99.719497 -331.851361) (xy 99.743185 -331.901892)
			(xy 99.759263 -331.955334) (xy 99.767389 -332.010548) (xy 99.767898 -332.038452) (xy 99.767389 -332.066356)
			(xy 99.759263 -332.12157) (xy 99.743185 -332.175012) (xy 99.719497 -332.225543) (xy 99.688703 -332.272087)
			(xy 99.651461 -332.313651) (xy 99.608565 -332.34935) (xy 99.560927 -332.378423) (xy 99.509564 -332.40025)
			(xy 99.455571 -332.414366) (xy 99.400097 -332.420469) (xy 99.344326 -332.418431) (xy 99.289447 -332.408294)
			(xy 99.236627 -332.390275) (xy 99.186995 -332.364757) (xy 99.141607 -332.332285) (xy 99.10143 -332.29355)
			(xy 99.067322 -332.249378) (xy 99.040008 -332.20071) (xy 99.020072 -332.148584) (xy 99.007937 -332.094111)
			(xy 99.003864 -332.038452) (xy 94.871794 -332.038452) (xy 94.871794 -336.30108) (xy 94.872231 -336.311144)
			(xy 94.879965 -336.329728) (xy 94.88678 -336.337148) (xy 96.230186 -337.680554) (xy 96.237587 -337.687392)
			(xy 96.256186 -337.695102) (xy 96.266254 -337.69554)
		)
		(stroke
			(width 0)
			(type solid)
		)
		(fill yes)
		(layer "In5.Cu")
		(net "P3V3")
	)
	(gr_poly
		(pts
			(xy 71.392034 -116.202968) (xy 71.396445 -116.202881) (xy 71.405133 -116.201351) (xy 71.409306 -116.19992)
			(xy 71.435214 -116.190014) (xy 71.441564 -116.18468) (xy 71.465419 -116.16553) (xy 71.517997 -116.134269)
			(xy 71.546212 -116.12245) (xy 71.573121 -116.11237) (xy 71.629122 -116.099498) (xy 71.68642 -116.095175)
			(xy 71.743718 -116.099498) (xy 71.799719 -116.11237) (xy 71.826628 -116.12245) (xy 71.854855 -116.134245)
			(xy 71.907431 -116.165515) (xy 71.931276 -116.18468) (xy 71.937626 -116.190014) (xy 71.963534 -116.19992)
			(xy 71.967713 -116.201331) (xy 71.976397 -116.202867) (xy 71.980806 -116.202968) (xy 73.910444 -116.202968)
			(xy 73.915948 -116.202849) (xy 73.926712 -116.200547) (xy 73.93178 -116.198396) (xy 73.958958 -116.185696)
			(xy 73.96607 -116.178076) (xy 73.985908 -116.157067) (xy 74.030796 -116.120684) (xy 74.080657 -116.091485)
			(xy 74.13435 -116.070139) (xy 74.190648 -116.057132) (xy 74.248264 -116.052763) (xy 74.30588 -116.057132)
			(xy 74.362178 -116.070139) (xy 74.415871 -116.091485) (xy 74.465732 -116.120684) (xy 74.51062 -116.157067)
			(xy 74.530458 -116.178076) (xy 74.53757 -116.185696) (xy 74.564748 -116.198396) (xy 74.569813 -116.200557)
			(xy 74.580578 -116.202867) (xy 74.586084 -116.202968) (xy 75.71105 -116.202968) (xy 75.719178 -116.202206)
			(xy 75.719686 -116.202206) (xy 75.727208 -116.200611) (xy 75.740905 -116.193644) (xy 75.74661 -116.18849)
			(xy 76.0222 -115.9129) (xy 76.027191 -115.907403) (xy 76.034041 -115.894237) (xy 76.035662 -115.886992)
			(xy 76.036678 -115.87734) (xy 76.036678 -113.730024) (xy 76.036424 -113.726214) (xy 76.03527 -113.716131)
			(xy 76.026099 -113.698047) (xy 76.018644 -113.691162) (xy 75.985878 -113.665254) (xy 75.954382 -113.640616)
			(xy 75.949837 -113.637206) (xy 75.939578 -113.632328) (xy 75.934062 -113.630964) (xy 75.922378 -113.628424)
			(xy 75.917044 -113.629694) (xy 75.893398 -113.635481) (xy 75.845118 -113.641727) (xy 75.820778 -113.64214)
			(xy 75.793525 -113.641653) (xy 75.739576 -113.633893) (xy 75.687279 -113.618535) (xy 75.637701 -113.59589)
			(xy 75.591849 -113.566421) (xy 75.550658 -113.530726) (xy 75.514966 -113.489533) (xy 75.485499 -113.44368)
			(xy 75.462858 -113.3941) (xy 75.447502 -113.341803) (xy 75.439746 -113.287853) (xy 75.439746 -113.233347)
			(xy 75.447502 -113.179397) (xy 75.462858 -113.1271) (xy 75.485499 -113.07752) (xy 75.514966 -113.031667)
			(xy 75.550658 -112.990474) (xy 75.591849 -112.954779) (xy 75.637701 -112.92531) (xy 75.687279 -112.902665)
			(xy 75.739576 -112.887307) (xy 75.793525 -112.879547) (xy 75.820778 -112.879124) (xy 75.843546 -112.879487)
			(xy 75.888751 -112.884967) (xy 75.910948 -112.890046) (xy 75.911202 -112.890046) (xy 75.916848 -112.891254)
			(xy 75.928391 -112.891386) (xy 75.934062 -112.8903) (xy 75.945238 -112.88776) (xy 76.000356 -112.844326)
			(xy 76.000864 -112.843818) (xy 76.018644 -112.830102) (xy 76.026073 -112.823199) (xy 76.035227 -112.805121)
			(xy 76.036424 -112.79505) (xy 76.036678 -112.79124) (xy 76.036678 -112.597438) (xy 76.036581 -112.592561)
			(xy 76.034792 -112.582972) (xy 76.033122 -112.578388) (xy 76.029312 -112.569244) (xy 75.527154 -112.067086)
			(xy 75.5243 -112.064384) (xy 75.517917 -112.0598) (xy 75.514454 -112.057942) (xy 75.502024 -112.051296)
			(xy 75.478244 -112.036158) (xy 75.466956 -112.027716) (xy 75.455018 -112.021112) (xy 75.451716 -112.019588)
			(xy 75.447143 -112.017882) (xy 75.437547 -112.0161) (xy 75.432666 -112.016032) (xy 75.416664 -112.016032)
			(xy 75.414378 -112.015778) (xy 75.405996 -112.017048) (xy 75.379834 -112.017048) (xy 75.374246 -112.021874)
			(xy 75.371198 -112.040416) (xy 75.371198 -112.04067) (xy 75.366494 -112.067239) (xy 75.35059 -112.118799)
			(xy 75.327585 -112.167606) (xy 75.297939 -112.212689) (xy 75.262242 -112.25315) (xy 75.221205 -112.288183)
			(xy 75.175645 -112.31709) (xy 75.126469 -112.339295) (xy 75.074657 -112.354357) (xy 75.02124 -112.361975)
			(xy 74.994262 -112.362488) (xy 74.991214 -112.362488) (xy 74.983086 -112.362234) (xy 74.953673 -112.360802)
			(xy 74.895785 -112.350014) (xy 74.840239 -112.330468) (xy 74.788351 -112.302628) (xy 74.741352 -112.267153)
			(xy 74.72045 -112.24641) (xy 74.713084 -112.239044) (xy 74.683874 -112.22609) (xy 74.679411 -112.22446)
			(xy 74.670081 -112.222663) (xy 74.665332 -112.222534) (xy 74.611992 -112.222534) (xy 74.607239 -112.222634)
			(xy 74.597905 -112.22443) (xy 74.59345 -112.22609) (xy 74.56424 -112.239044) (xy 74.556874 -112.24641)
			(xy 74.537363 -112.265843) (xy 74.493749 -112.299461) (xy 74.445757 -112.326465) (xy 74.394384 -112.346292)
			(xy 74.340694 -112.358531) (xy 74.313288 -112.361218) (xy 74.297286 -112.362488) (xy 74.283062 -112.362488)
			(xy 74.256078 -112.362026) (xy 74.202647 -112.354431) (xy 74.150819 -112.339383) (xy 74.101629 -112.317183)
			(xy 74.056057 -112.288273) (xy 74.015013 -112.253231) (xy 73.979315 -112.212756) (xy 73.949677 -112.167655)
			(xy 73.926689 -112.118828) (xy 73.91081 -112.067248) (xy 73.906126 -112.04067) (xy 73.906126 -112.040416)
			(xy 73.903078 -112.021874) (xy 73.897236 -112.017048) (xy 73.872344 -112.017048) (xy 73.863454 -112.015778)
			(xy 73.86066 -112.016032) (xy 72.493378 -112.016032) (xy 72.489771 -112.01611) (xy 72.482725 -112.017659)
			(xy 72.479408 -112.01908) (xy 72.46341 -112.036422) (xy 72.428013 -112.067621) (xy 72.408796 -112.08131)
			(xy 72.401782 -112.086699) (xy 72.391612 -112.101153) (xy 72.386911 -112.11819) (xy 72.387206 -112.12703)
			(xy 72.391778 -112.188752) (xy 72.392464 -112.194951) (xy 72.396453 -112.206765) (xy 72.399652 -112.21212)
			(xy 72.402954 -112.217454) (xy 72.41286 -112.226344) (xy 72.418956 -112.229646) (xy 72.441747 -112.242093)
			(xy 72.484042 -112.272223) (xy 72.521863 -112.307807) (xy 72.554513 -112.348188) (xy 72.581389 -112.392622)
			(xy 72.601995 -112.440288) (xy 72.615951 -112.490307) (xy 72.623 -112.541755) (xy 72.623426 -112.56772)
			(xy 72.62294 -112.594971) (xy 72.615184 -112.648919) (xy 72.599829 -112.701214) (xy 72.577187 -112.750791)
			(xy 72.547721 -112.796641) (xy 72.51203 -112.837832) (xy 72.470839 -112.873523) (xy 72.424989 -112.902989)
			(xy 72.375412 -112.925631) (xy 72.323117 -112.940986) (xy 72.269169 -112.948742) (xy 72.214667 -112.948742)
			(xy 72.160719 -112.940986) (xy 72.108424 -112.925631) (xy 72.058847 -112.902989) (xy 72.012997 -112.873523)
			(xy 71.971806 -112.837832) (xy 71.936115 -112.796641) (xy 71.906649 -112.750791) (xy 71.884007 -112.701214)
			(xy 71.868652 -112.648919) (xy 71.860896 -112.594971) (xy 71.86041 -112.56772) (xy 71.860982 -112.537925)
			(xy 71.870241 -112.47906) (xy 71.888539 -112.42235) (xy 71.915429 -112.369173) (xy 71.950259 -112.320822)
			(xy 71.992181 -112.278474) (xy 72.015858 -112.26038) (xy 72.016112 -112.260126) (xy 72.021122 -112.256233)
			(xy 72.029208 -112.246463) (xy 72.032114 -112.240822) (xy 72.034654 -112.235234) (xy 72.03694 -112.222534)
			(xy 72.03186 -112.153954) (xy 72.030823 -112.145146) (xy 72.023556 -112.128985) (xy 72.011206 -112.116278)
			(xy 72.003412 -112.112044) (xy 71.980358 -112.100326) (xy 71.93719 -112.071847) (xy 71.89802 -112.03808)
			(xy 71.880476 -112.01908) (xy 71.87717 -112.017626) (xy 71.870117 -112.016081) (xy 71.866506 -112.016032)
			(xy 71.13651 -112.016032) (xy 71.108316 -112.014508) (xy 71.102474 -112.021874) (xy 71.099426 -112.028986)
			(xy 71.088247 -112.054867) (xy 71.059388 -112.103296) (xy 71.02372 -112.146954) (xy 70.982018 -112.18489)
			(xy 70.935189 -112.216279) (xy 70.884252 -112.240439) (xy 70.830316 -112.256843) (xy 70.774554 -112.265135)
			(xy 70.718178 -112.265135) (xy 70.662416 -112.256843) (xy 70.60848 -112.240439) (xy 70.557543 -112.216279)
			(xy 70.510714 -112.18489) (xy 70.469012 -112.146954) (xy 70.433344 -112.103296) (xy 70.404485 -112.054867)
			(xy 70.393306 -112.028986) (xy 70.390258 -112.021874) (xy 70.383654 -112.013746) (xy 70.374291 -112.014791)
			(xy 70.355483 -112.015937) (xy 70.346062 -112.016032) (xy 68.987416 -112.016032) (xy 68.982377 -112.016193)
			(xy 68.972789 -112.019293) (xy 68.96862 -112.022128) (xy 68.934584 -112.048036) (xy 68.931368 -112.050361)
			(xy 68.924349 -112.054063) (xy 68.920614 -112.055402) (xy 68.91274 -112.058196) (xy 68.907347 -112.06024)
			(xy 68.897598 -112.066396) (xy 68.893436 -112.070388) (xy 68.49364 -112.470184) (xy 68.490933 -112.473034)
			(xy 68.486338 -112.479412) (xy 68.484496 -112.482884) (xy 68.481917 -112.488312) (xy 68.479103 -112.499991)
			(xy 68.478908 -112.505998) (xy 68.478908 -112.989614) (xy 70.44004 -112.989614) (xy 70.444111 -112.933992)
			(xy 70.456237 -112.879555) (xy 70.47616 -112.827464) (xy 70.503456 -112.778829) (xy 70.537542 -112.734686)
			(xy 70.577691 -112.695977) (xy 70.623049 -112.663526) (xy 70.672649 -112.638025) (xy 70.725433 -112.620018)
			(xy 70.780276 -112.609888) (xy 70.83601 -112.607851) (xy 70.891447 -112.613951) (xy 70.945404 -112.628057)
			(xy 70.996733 -112.649869) (xy 71.044339 -112.678923) (xy 71.087207 -112.714598) (xy 71.124424 -112.756135)
			(xy 71.155197 -112.802648) (xy 71.178869 -112.853145) (xy 71.194937 -112.906552) (xy 71.203057 -112.961728)
			(xy 71.203566 -112.989614) (xy 71.203057 -113.0175) (xy 71.194937 -113.072676) (xy 71.178869 -113.126083)
			(xy 71.155197 -113.17658) (xy 71.124424 -113.223093) (xy 71.087207 -113.26463) (xy 71.044339 -113.300305)
			(xy 70.996733 -113.329359) (xy 70.945404 -113.351171) (xy 70.891447 -113.365277) (xy 70.83601 -113.371377)
			(xy 70.780276 -113.36934) (xy 70.725433 -113.35921) (xy 70.672649 -113.341203) (xy 70.623049 -113.315702)
			(xy 70.577691 -113.283251) (xy 70.537542 -113.244542) (xy 70.503456 -113.200399) (xy 70.47616 -113.151764)
			(xy 70.456237 -113.099673) (xy 70.444111 -113.045236) (xy 70.44004 -112.989614) (xy 68.478908 -112.989614)
			(xy 68.478908 -113.917222) (xy 70.793862 -113.917222) (xy 70.797933 -113.8616) (xy 70.810059 -113.807163)
			(xy 70.829982 -113.755072) (xy 70.857278 -113.706437) (xy 70.891364 -113.662294) (xy 70.931513 -113.623585)
			(xy 70.976871 -113.591134) (xy 71.026471 -113.565633) (xy 71.079255 -113.547626) (xy 71.134098 -113.537496)
			(xy 71.189832 -113.535459) (xy 71.245269 -113.541559) (xy 71.299226 -113.555665) (xy 71.350555 -113.577477)
			(xy 71.398161 -113.606531) (xy 71.441029 -113.642206) (xy 71.478246 -113.683743) (xy 71.509019 -113.730256)
			(xy 71.532691 -113.780753) (xy 71.548759 -113.83416) (xy 71.556879 -113.889336) (xy 71.557388 -113.917222)
			(xy 71.556879 -113.945108) (xy 71.548759 -114.000284) (xy 71.532691 -114.053691) (xy 71.509019 -114.104188)
			(xy 71.478246 -114.150701) (xy 71.441029 -114.192238) (xy 71.398161 -114.227913) (xy 71.350555 -114.256967)
			(xy 71.299226 -114.278779) (xy 71.245269 -114.292885) (xy 71.189832 -114.298985) (xy 71.134098 -114.296948)
			(xy 71.079255 -114.286818) (xy 71.026471 -114.268811) (xy 70.976871 -114.24331) (xy 70.931513 -114.210859)
			(xy 70.891364 -114.17215) (xy 70.857278 -114.128007) (xy 70.829982 -114.079372) (xy 70.810059 -114.027281)
			(xy 70.797933 -113.972844) (xy 70.793862 -113.917222) (xy 68.478908 -113.917222) (xy 68.478908 -114.812572)
			(xy 71.850758 -114.812572) (xy 71.851244 -114.785321) (xy 71.859 -114.731373) (xy 71.874355 -114.679078)
			(xy 71.896997 -114.629501) (xy 71.926463 -114.583651) (xy 71.962154 -114.54246) (xy 72.003345 -114.506769)
			(xy 72.049195 -114.477303) (xy 72.098772 -114.454661) (xy 72.151067 -114.439306) (xy 72.205015 -114.43155)
			(xy 72.259517 -114.43155) (xy 72.313465 -114.439306) (xy 72.36576 -114.454661) (xy 72.415337 -114.477303)
			(xy 72.461187 -114.506769) (xy 72.502378 -114.54246) (xy 72.538069 -114.583651) (xy 72.567535 -114.629501)
			(xy 72.590177 -114.679078) (xy 72.605532 -114.731373) (xy 72.613288 -114.785321) (xy 72.613774 -114.812572)
			(xy 72.613219 -114.842264) (xy 72.604009 -114.900929) (xy 72.585822 -114.957459) (xy 72.559097 -115.010489)
			(xy 72.52448 -115.058739) (xy 72.504046 -115.080288) (xy 72.49668 -115.087654) (xy 72.489314 -115.10645)
			(xy 72.491092 -115.200176) (xy 72.499474 -115.218972) (xy 72.507094 -115.22583) (xy 72.525906 -115.243934)
			(xy 72.558883 -115.28441) (xy 72.586035 -115.329003) (xy 72.606857 -115.376881) (xy 72.620959 -115.42715)
			(xy 72.628078 -115.478871) (xy 72.628506 -115.504976) (xy 72.62802 -115.532227) (xy 72.620264 -115.586175)
			(xy 72.604909 -115.63847) (xy 72.582267 -115.688047) (xy 72.552801 -115.733897) (xy 72.51711 -115.775088)
			(xy 72.475919 -115.810779) (xy 72.430069 -115.840245) (xy 72.380492 -115.862887) (xy 72.328197 -115.878242)
			(xy 72.274249 -115.885998) (xy 72.219747 -115.885998) (xy 72.165799 -115.878242) (xy 72.113504 -115.862887)
			(xy 72.063927 -115.840245) (xy 72.018077 -115.810779) (xy 71.976886 -115.775088) (xy 71.941195 -115.733897)
			(xy 71.911729 -115.688047) (xy 71.889087 -115.63847) (xy 71.873732 -115.586175) (xy 71.865976 -115.532227)
			(xy 71.86549 -115.504976) (xy 71.866085 -115.475286) (xy 71.875287 -115.416623) (xy 71.893465 -115.360094)
			(xy 71.920181 -115.307063) (xy 71.954788 -115.258811) (xy 71.975218 -115.23726) (xy 71.982584 -115.229894)
			(xy 71.98995 -115.211098) (xy 71.988172 -115.117372) (xy 71.97979 -115.098576) (xy 71.97217 -115.091718)
			(xy 71.953375 -115.073598) (xy 71.920398 -115.033124) (xy 71.893244 -114.988534) (xy 71.87242 -114.94066)
			(xy 71.858314 -114.890395) (xy 71.851189 -114.838676) (xy 71.850758 -114.812572) (xy 68.478908 -114.812572)
			(xy 68.478908 -116.15166) (xy 68.479924 -116.161312) (xy 68.481546 -116.168559) (xy 68.48838 -116.181736)
			(xy 68.493386 -116.18722) (xy 68.494656 -116.18849) (xy 68.500156 -116.193475) (xy 68.513324 -116.200313)
			(xy 68.520564 -116.201952) (xy 68.530216 -116.202968)
		)
		(stroke
			(width 0)
			(type solid)
		)
		(fill yes)
		(layer "In5.Cu")
		(net "P3V3_NIC1")
	)
	(gr_poly
		(pts
			(xy 254.826262 -290.753292) (xy 254.836327 -290.752857) (xy 254.854914 -290.745126) (xy 254.86233 -290.738306)
			(xy 255.227582 -290.373054) (xy 255.234423 -290.365654) (xy 255.242144 -290.347056) (xy 255.242568 -290.336986)
			(xy 255.242568 -269.460726) (xy 255.242131 -269.450662) (xy 255.234394 -269.43208) (xy 255.227582 -269.424658)
			(xy 247.832626 -262.029702) (xy 247.825223 -262.022867) (xy 247.806625 -262.015159) (xy 247.796558 -262.014716)
			(xy 247.742964 -262.014716) (xy 247.732896 -262.014287) (xy 247.7143 -262.006565) (xy 247.706896 -261.99973)
			(xy 247.05564 -261.348474) (xy 247.048793 -261.341076) (xy 247.041062 -261.322478) (xy 247.040654 -261.312406)
			(xy 247.040654 -257.936492) (xy 247.040228 -257.926423) (xy 247.032506 -257.907826) (xy 247.025668 -257.900424)
			(xy 246.232934 -257.10769) (xy 246.225536 -257.100844) (xy 246.206937 -257.09312) (xy 246.196866 -257.092704)
			(xy 234.893358 -257.092704) (xy 234.883291 -257.093135) (xy 234.864698 -257.100861) (xy 234.85729 -257.10769)
			(xy 234.424474 -257.540506) (xy 234.417108 -257.547618) (xy 234.409488 -257.566414) (xy 234.409488 -271.027398)
			(xy 234.40991 -271.037469) (xy 234.417623 -271.056075) (xy 234.424474 -271.063466) (xy 234.997752 -271.636744)
			(xy 235.005151 -271.643588) (xy 235.023749 -271.651313) (xy 235.03382 -271.65173) (xy 244.189758 -271.65173)
			(xy 244.199823 -271.652164) (xy 244.218409 -271.659897) (xy 244.225826 -271.666716) (xy 246.030496 -273.471386)
			(xy 248.784108 -273.471386) (xy 248.788179 -273.415764) (xy 248.800305 -273.361327) (xy 248.820228 -273.309236)
			(xy 248.847524 -273.260601) (xy 248.88161 -273.216458) (xy 248.921759 -273.177749) (xy 248.967117 -273.145298)
			(xy 249.016717 -273.119797) (xy 249.069501 -273.10179) (xy 249.124344 -273.09166) (xy 249.180078 -273.089623)
			(xy 249.235515 -273.095723) (xy 249.289472 -273.109829) (xy 249.340801 -273.131641) (xy 249.388407 -273.160695)
			(xy 249.431275 -273.19637) (xy 249.468492 -273.237907) (xy 249.499265 -273.28442) (xy 249.522937 -273.334917)
			(xy 249.539005 -273.388324) (xy 249.547125 -273.4435) (xy 249.547634 -273.471386) (xy 249.547125 -273.499272)
			(xy 249.539005 -273.554448) (xy 249.522937 -273.607855) (xy 249.499265 -273.658352) (xy 249.468492 -273.704865)
			(xy 249.431275 -273.746402) (xy 249.388407 -273.782077) (xy 249.340801 -273.811131) (xy 249.289472 -273.832943)
			(xy 249.235515 -273.847049) (xy 249.180078 -273.853149) (xy 249.124344 -273.851112) (xy 249.069501 -273.840982)
			(xy 249.016717 -273.822975) (xy 248.967117 -273.797474) (xy 248.921759 -273.765023) (xy 248.88161 -273.726314)
			(xy 248.847524 -273.682171) (xy 248.820228 -273.633536) (xy 248.800305 -273.581445) (xy 248.788179 -273.527008)
			(xy 248.784108 -273.471386) (xy 246.030496 -273.471386) (xy 246.54256 -273.98345) (xy 249.491246 -273.98345)
			(xy 249.491732 -273.956199) (xy 249.499488 -273.902251) (xy 249.514843 -273.849956) (xy 249.537485 -273.800379)
			(xy 249.566951 -273.754529) (xy 249.602642 -273.713338) (xy 249.643833 -273.677647) (xy 249.689683 -273.648181)
			(xy 249.73926 -273.625539) (xy 249.791555 -273.610184) (xy 249.845503 -273.602428) (xy 249.900005 -273.602428)
			(xy 249.953953 -273.610184) (xy 250.006248 -273.625539) (xy 250.055825 -273.648181) (xy 250.101675 -273.677647)
			(xy 250.142866 -273.713338) (xy 250.178557 -273.754529) (xy 250.208023 -273.800379) (xy 250.230665 -273.849956)
			(xy 250.24602 -273.902251) (xy 250.253776 -273.956199) (xy 250.254262 -273.98345) (xy 250.253689 -274.014423)
			(xy 250.243735 -274.075562) (xy 250.23445 -274.105116) (xy 250.231148 -274.114768) (xy 250.232418 -274.134326)
			(xy 250.272042 -274.216368) (xy 250.286774 -274.229576) (xy 250.296172 -274.233132) (xy 250.323475 -274.243568)
			(xy 250.374805 -274.271521) (xy 250.421269 -274.306979) (xy 250.461779 -274.349111) (xy 250.495386 -274.39693)
			(xy 250.521304 -274.449317) (xy 250.538925 -274.505046) (xy 250.547838 -274.56281) (xy 250.548394 -274.592034)
			(xy 250.547908 -274.619285) (xy 250.540152 -274.673233) (xy 250.524797 -274.725528) (xy 250.502155 -274.775105)
			(xy 250.472689 -274.820955) (xy 250.436998 -274.862146) (xy 250.395807 -274.897837) (xy 250.349957 -274.927303)
			(xy 250.30038 -274.949945) (xy 250.248085 -274.9653) (xy 250.194137 -274.973056) (xy 250.139635 -274.973056)
			(xy 250.085687 -274.9653) (xy 250.033392 -274.949945) (xy 249.983815 -274.927303) (xy 249.937965 -274.897837)
			(xy 249.896774 -274.862146) (xy 249.861083 -274.820955) (xy 249.831617 -274.775105) (xy 249.808975 -274.725528)
			(xy 249.79362 -274.673233) (xy 249.785864 -274.619285) (xy 249.785378 -274.592034) (xy 249.785945 -274.561061)
			(xy 249.795903 -274.499922) (xy 249.80519 -274.470368) (xy 249.808492 -274.460716) (xy 249.807222 -274.441158)
			(xy 249.767598 -274.359116) (xy 249.752866 -274.345908) (xy 249.743468 -274.342352) (xy 249.716146 -274.331963)
			(xy 249.664817 -274.304001) (xy 249.618355 -274.268534) (xy 249.577848 -274.226395) (xy 249.544243 -274.17857)
			(xy 249.518329 -274.126177) (xy 249.50071 -274.070444) (xy 249.4918 -274.012676) (xy 249.491246 -273.98345)
			(xy 246.54256 -273.98345) (xy 247.046496 -274.487386) (xy 248.722386 -274.487386) (xy 248.726457 -274.431764)
			(xy 248.738583 -274.377327) (xy 248.758506 -274.325236) (xy 248.785802 -274.276601) (xy 248.819888 -274.232458)
			(xy 248.860037 -274.193749) (xy 248.905395 -274.161298) (xy 248.954995 -274.135797) (xy 249.007779 -274.11779)
			(xy 249.062622 -274.10766) (xy 249.118356 -274.105623) (xy 249.173793 -274.111723) (xy 249.22775 -274.125829)
			(xy 249.279079 -274.147641) (xy 249.326685 -274.176695) (xy 249.369553 -274.21237) (xy 249.40677 -274.253907)
			(xy 249.437543 -274.30042) (xy 249.461215 -274.350917) (xy 249.477283 -274.404324) (xy 249.485403 -274.4595)
			(xy 249.485912 -274.487386) (xy 249.485403 -274.515272) (xy 249.477283 -274.570448) (xy 249.461215 -274.623855)
			(xy 249.437543 -274.674352) (xy 249.40677 -274.720865) (xy 249.369553 -274.762402) (xy 249.326685 -274.798077)
			(xy 249.279079 -274.827131) (xy 249.22775 -274.848943) (xy 249.173793 -274.863049) (xy 249.118356 -274.869149)
			(xy 249.062622 -274.867112) (xy 249.007779 -274.856982) (xy 248.954995 -274.838975) (xy 248.905395 -274.813474)
			(xy 248.860037 -274.781023) (xy 248.819888 -274.742314) (xy 248.785802 -274.698171) (xy 248.758506 -274.649536)
			(xy 248.738583 -274.597445) (xy 248.726457 -274.543008) (xy 248.722386 -274.487386) (xy 247.046496 -274.487386)
			(xy 248.062496 -275.503386) (xy 248.722386 -275.503386) (xy 248.726457 -275.447764) (xy 248.738583 -275.393327)
			(xy 248.758506 -275.341236) (xy 248.785802 -275.292601) (xy 248.819888 -275.248458) (xy 248.860037 -275.209749)
			(xy 248.905395 -275.177298) (xy 248.954995 -275.151797) (xy 249.007779 -275.13379) (xy 249.062622 -275.12366)
			(xy 249.118356 -275.121623) (xy 249.173793 -275.127723) (xy 249.22775 -275.141829) (xy 249.279079 -275.163641)
			(xy 249.326685 -275.192695) (xy 249.369553 -275.22837) (xy 249.40677 -275.269907) (xy 249.437543 -275.31642)
			(xy 249.461215 -275.366917) (xy 249.477283 -275.420324) (xy 249.485403 -275.4755) (xy 249.485912 -275.503386)
			(xy 249.485403 -275.531272) (xy 249.477283 -275.586448) (xy 249.461215 -275.639855) (xy 249.437543 -275.690352)
			(xy 249.40677 -275.736865) (xy 249.369553 -275.778402) (xy 249.326685 -275.814077) (xy 249.279079 -275.843131)
			(xy 249.22775 -275.864943) (xy 249.173793 -275.879049) (xy 249.118356 -275.885149) (xy 249.062622 -275.883112)
			(xy 249.007779 -275.872982) (xy 248.954995 -275.854975) (xy 248.905395 -275.829474) (xy 248.860037 -275.797023)
			(xy 248.819888 -275.758314) (xy 248.785802 -275.714171) (xy 248.758506 -275.665536) (xy 248.738583 -275.613445)
			(xy 248.726457 -275.559008) (xy 248.722386 -275.503386) (xy 248.062496 -275.503386) (xy 248.772426 -276.213316)
			(xy 248.779446 -276.219805) (xy 248.796936 -276.227486) (xy 248.806462 -276.228302) (xy 248.836434 -276.229318)
			(xy 248.845385 -276.229321) (xy 248.862415 -276.223842) (xy 248.869708 -276.21865) (xy 248.889894 -276.203407)
			(xy 248.933525 -276.177818) (xy 248.980159 -276.158226) (xy 249.028974 -276.144975) (xy 249.079113 -276.138297)
			(xy 249.104404 -276.137878) (xy 249.131655 -276.138364) (xy 249.185603 -276.146121) (xy 249.237899 -276.161476)
			(xy 249.287476 -276.184117) (xy 249.333327 -276.213584) (xy 249.374518 -276.249275) (xy 249.41021 -276.290465)
			(xy 249.439678 -276.336315) (xy 249.46232 -276.385892) (xy 249.477677 -276.438187) (xy 249.485435 -276.492135)
			(xy 249.485912 -276.519386) (xy 249.485458 -276.545895) (xy 249.478121 -276.598403) (xy 249.463586 -276.649389)
			(xy 249.442133 -276.697873) (xy 249.414175 -276.74292) (xy 249.380251 -276.783663) (xy 249.360944 -276.801834)
			(xy 249.356372 -276.805898) (xy 249.335371 -276.823709) (xy 249.289212 -276.853737) (xy 249.23922 -276.876824)
			(xy 249.18643 -276.892492) (xy 249.131937 -276.900415) (xy 249.104404 -276.900894) (xy 249.093482 -276.90064)
			(xy 249.083322 -276.900386) (xy 249.064018 -276.908006) (xy 249.004582 -276.965918) (xy 248.99756 -276.973314)
			(xy 248.989553 -276.992053) (xy 248.989088 -277.00224) (xy 248.989088 -277.053548) (xy 248.989537 -277.063704)
			(xy 248.997397 -277.082434) (xy 249.004328 -277.08987) (xy 249.064018 -277.148036) (xy 249.083322 -277.155656)
			(xy 249.093482 -277.155402) (xy 249.104404 -277.155148) (xy 249.131656 -277.155634) (xy 249.185606 -277.163391)
			(xy 249.237903 -277.178746) (xy 249.287482 -277.201387) (xy 249.333335 -277.230852) (xy 249.374529 -277.266543)
			(xy 249.410224 -277.307733) (xy 249.439694 -277.353583) (xy 249.46234 -277.40316) (xy 249.477701 -277.455455)
			(xy 249.485463 -277.509404) (xy 249.485912 -277.536656) (xy 249.485623 -277.557855) (xy 249.480908 -277.599989)
			(xy 249.476514 -277.62073) (xy 249.473974 -277.63216) (xy 249.479054 -277.654512) (xy 249.53595 -277.725632)
			(xy 249.543476 -277.73431) (xy 249.564102 -277.744368) (xy 249.575574 -277.744936) (xy 250.85548 -277.744936)
			(xy 250.888355 -277.745362) (xy 250.953694 -277.752691) (xy 251.017801 -277.767293) (xy 251.079869 -277.788984)
			(xy 251.139116 -277.817491) (xy 251.194797 -277.852455) (xy 251.246212 -277.893437) (xy 251.269754 -277.916386)
			(xy 251.750576 -278.397208) (xy 251.773524 -278.420762) (xy 251.814549 -278.47216) (xy 251.849558 -278.52783)
			(xy 251.878109 -278.587072) (xy 251.899844 -278.64914) (xy 251.914488 -278.713252) (xy 251.921858 -278.7786)
			(xy 251.92228 -278.811482) (xy 251.921768 -278.846897) (xy 251.913232 -278.91721) (xy 251.896284 -278.985982)
			(xy 251.871169 -279.05221) (xy 251.838254 -279.114927) (xy 251.798019 -279.17322) (xy 251.751051 -279.226237)
			(xy 251.698035 -279.273207) (xy 251.639744 -279.313443) (xy 251.577028 -279.34636) (xy 251.510801 -279.371478)
			(xy 251.44203 -279.388429) (xy 251.371717 -279.396967) (xy 251.336302 -279.39746) (xy 251.303426 -279.396978)
			(xy 251.238091 -279.389579) (xy 251.173993 -279.374919) (xy 251.111938 -279.35318) (xy 251.052704 -279.324638)
			(xy 250.997033 -279.289648) (xy 250.945626 -279.248652) (xy 250.922028 -279.225756) (xy 250.627642 -278.93137)
			(xy 250.620297 -278.924561) (xy 250.601834 -278.916838) (xy 250.591828 -278.916384) (xy 249.617992 -278.916384)
			(xy 249.60752 -278.917004) (xy 249.58837 -278.925522) (xy 249.580908 -278.932894) (xy 249.522742 -278.995378)
			(xy 249.515884 -279.01519) (xy 249.5169 -279.025858) (xy 249.517916 -279.055322) (xy 249.517481 -279.081534)
			(xy 249.510306 -279.133465) (xy 249.496093 -279.183925) (xy 249.475111 -279.231967) (xy 249.447753 -279.276686)
			(xy 249.414535 -279.317242) (xy 249.37608 -279.352872) (xy 249.354848 -279.36825) (xy 249.343672 -279.376124)
			(xy 249.332242 -279.4) (xy 249.34037 -279.514046) (xy 249.355102 -279.536144) (xy 249.367294 -279.54224)
			(xy 249.390651 -279.554475) (xy 249.434057 -279.58441) (xy 249.472929 -279.620034) (xy 249.506528 -279.66067)
			(xy 249.534214 -279.705544) (xy 249.55546 -279.753801) (xy 249.569863 -279.804523) (xy 249.577146 -279.856745)
			(xy 249.577606 -279.883108) (xy 249.577527 -279.895846) (xy 249.575873 -279.921267) (xy 249.574304 -279.933908)
			(xy 249.574558 -279.933908) (xy 249.570638 -279.959629) (xy 249.556737 -280.009767) (xy 249.536163 -280.057556)
			(xy 249.509296 -280.102112) (xy 249.476633 -280.142612) (xy 249.438778 -280.178306) (xy 249.41784 -280.19375)
			(xy 249.409629 -280.200265) (xy 249.398873 -280.218232) (xy 249.397012 -280.228548) (xy 249.38609 -280.312368)
			(xy 249.391932 -280.332434) (xy 249.39879 -280.340816) (xy 249.415183 -280.361391) (xy 249.442753 -280.406193)
			(xy 249.463903 -280.45436) (xy 249.478231 -280.504977) (xy 249.485464 -280.557083) (xy 249.485912 -280.583386)
			(xy 249.485912 -280.587196) (xy 249.485658 -280.593546) (xy 249.484487 -280.620307) (xy 249.475574 -280.673127)
			(xy 249.459362 -280.72418) (xy 249.43617 -280.772465) (xy 249.406453 -280.817032) (xy 249.370795 -280.857005)
			(xy 249.329897 -280.891599) (xy 249.284564 -280.920133) (xy 249.235685 -280.942047) (xy 249.184222 -280.956909)
			(xy 249.131187 -280.964429) (xy 249.104404 -280.964894) (xy 249.093482 -280.96464) (xy 249.083322 -280.964386)
			(xy 249.064018 -280.972006) (xy 249.035824 -280.999438) (xy 249.028881 -281.006865) (xy 249.021034 -281.025602)
			(xy 249.020584 -281.03576) (xy 249.020584 -282.18638) (xy 249.021077 -282.196378) (xy 249.028707 -282.214864)
			(xy 249.042791 -282.229062) (xy 249.051826 -282.23337) (xy 249.066304 -282.239212) (xy 249.096022 -282.23337)
			(xy 250.193556 -281.135836) (xy 250.21711 -281.112889) (xy 250.268509 -281.071868) (xy 250.32418 -281.036863)
			(xy 250.383422 -281.008316) (xy 250.44549 -280.986586) (xy 250.509601 -280.971946) (xy 250.574949 -280.964582)
			(xy 250.60783 -280.964132) (xy 250.643241 -280.964668) (xy 250.713547 -280.973208) (xy 250.782312 -280.990161)
			(xy 250.848531 -281.015278) (xy 250.91124 -281.048193) (xy 250.969525 -281.088427) (xy 251.022535 -281.135394)
			(xy 251.069497 -281.188407) (xy 251.109727 -281.246694) (xy 251.142639 -281.309405) (xy 251.167751 -281.375627)
			(xy 251.184699 -281.444392) (xy 251.193234 -281.514699) (xy 251.193808 -281.55011) (xy 251.193331 -281.582988)
			(xy 251.185942 -281.648329) (xy 251.17129 -281.712432) (xy 251.14956 -281.774495) (xy 251.121025 -281.833738)
			(xy 251.086042 -281.889417) (xy 251.045051 -281.940834) (xy 251.022104 -281.964384) (xy 249.495056 -283.491432)
			(xy 249.488382 -283.498845) (xy 249.480818 -283.517281) (xy 249.480324 -283.527246) (xy 249.480324 -290.702492)
			(xy 249.480743 -290.712513) (xy 249.488412 -290.731028) (xy 249.502585 -290.745197) (xy 249.521103 -290.75286)
			(xy 249.531124 -290.753292)
		)
		(stroke
			(width 0)
			(type solid)
		)
		(fill yes)
		(layer "In5.Cu")
		(net "P1V25_SERDES_VDDPLL_PEX2")
	)
	(gr_poly
		(pts
			(xy 93.70695 -128.126744) (xy 95.429832 -126.403862) (xy 95.437996 -126.39456) (xy 95.445268 -126.370943)
			(xy 95.443802 -126.35865) (xy 95.42653 -126.263908) (xy 95.41129 -126.244604) (xy 95.399606 -126.23927)
			(xy 95.374869 -126.227583) (xy 95.328735 -126.198175) (xy 95.287275 -126.162478) (xy 95.25134 -126.121224)
			(xy 95.221667 -126.07526) (xy 95.198865 -126.025528) (xy 95.183402 -125.973049) (xy 95.175594 -125.918899)
			(xy 95.17507 -125.891544) (xy 95.175489 -125.865224) (xy 95.182686 -125.81308) (xy 95.19699 -125.762422)
			(xy 95.21813 -125.714215) (xy 95.245702 -125.669375) (xy 95.279182 -125.628757) (xy 95.29826 -125.61062)
			(xy 95.30571 -125.603129) (xy 95.314254 -125.583833) (xy 95.31477 -125.573282) (xy 95.31477 -125.498606)
			(xy 95.314179 -125.488073) (xy 95.305643 -125.468805) (xy 95.29826 -125.461268) (xy 95.2792 -125.443117)
			(xy 95.245748 -125.402485) (xy 95.218193 -125.357643) (xy 95.197059 -125.309441) (xy 95.182745 -125.258794)
			(xy 95.175524 -125.20666) (xy 95.17507 -125.180344) (xy 95.175556 -125.153093) (xy 95.183312 -125.099145)
			(xy 95.198667 -125.04685) (xy 95.221309 -124.997273) (xy 95.250775 -124.951423) (xy 95.286466 -124.910232)
			(xy 95.327657 -124.874541) (xy 95.373507 -124.845075) (xy 95.423084 -124.822433) (xy 95.475379 -124.807078)
			(xy 95.529327 -124.799322) (xy 95.583829 -124.799322) (xy 95.637777 -124.807078) (xy 95.690072 -124.822433)
			(xy 95.739649 -124.845075) (xy 95.785499 -124.874541) (xy 95.82669 -124.910232) (xy 95.862381 -124.951423)
			(xy 95.891847 -124.997273) (xy 95.914489 -125.04685) (xy 95.929844 -125.099145) (xy 95.9376 -125.153093)
			(xy 95.938086 -125.180344) (xy 95.937667 -125.206664) (xy 95.930473 -125.258811) (xy 95.916172 -125.309471)
			(xy 95.895036 -125.357681) (xy 95.867467 -125.402525) (xy 95.83399 -125.443148) (xy 95.814896 -125.461268)
			(xy 95.807449 -125.468761) (xy 95.798909 -125.488056) (xy 95.798386 -125.498606) (xy 95.798386 -125.573282)
			(xy 95.798973 -125.583817) (xy 95.807501 -125.603093) (xy 95.814896 -125.61062) (xy 95.833483 -125.62831)
			(xy 95.866225 -125.667817) (xy 95.893385 -125.711352) (xy 95.904304 -125.734572) (xy 95.909638 -125.746256)
			(xy 95.928942 -125.761496) (xy 96.023684 -125.778768) (xy 96.035988 -125.780463) (xy 96.059692 -125.773138)
			(xy 96.068896 -125.764798) (xy 97.591118 -124.242322) (xy 97.598343 -124.234417) (xy 97.605964 -124.214423)
			(xy 97.60585 -124.203714) (xy 97.601532 -124.117354) (xy 97.591626 -124.098558) (xy 97.583244 -124.091446)
			(xy 97.561738 -124.073388) (xy 97.52375 -124.032035) (xy 97.492229 -123.985562) (xy 97.467857 -123.934973)
			(xy 97.459038 -123.908312) (xy 97.457006 -123.90247) (xy 97.450656 -123.891802) (xy 94.579694 -121.02084)
			(xy 94.572324 -121.014095) (xy 94.553863 -121.006498) (xy 94.54388 -121.006108) (xy 93.52153 -121.006108)
			(xy 93.509137 -121.006652) (xy 93.487165 -121.018105) (xy 93.47962 -121.027952) (xy 93.42501 -121.107708)
			(xy 93.421962 -121.132092) (xy 93.426534 -121.14403) (xy 93.434639 -121.166024) (xy 93.446043 -121.211489)
			(xy 93.45181 -121.258007) (xy 93.452188 -121.281444) (xy 93.451713 -121.308813) (xy 93.443883 -121.362988)
			(xy 93.428391 -121.415488) (xy 93.405554 -121.465234) (xy 93.375842 -121.511206) (xy 93.358208 -121.532142)
			(xy 93.352112 -121.539254) (xy 93.345762 -121.556272) (xy 93.345762 -121.641616) (xy 93.352112 -121.658634)
			(xy 93.358208 -121.665746) (xy 93.375847 -121.686678) (xy 93.405567 -121.732646) (xy 93.428404 -121.782393)
			(xy 93.443887 -121.834896) (xy 93.451699 -121.889075) (xy 93.452188 -121.916444) (xy 93.451699 -121.943693)
			(xy 93.443937 -121.997634) (xy 93.428578 -122.049923) (xy 93.405934 -122.099493) (xy 93.376466 -122.145336)
			(xy 93.340774 -122.18652) (xy 93.299585 -122.222205) (xy 93.253737 -122.251665) (xy 93.204163 -122.2743)
			(xy 93.151872 -122.289651) (xy 93.097929 -122.297403) (xy 93.07068 -122.297952) (xy 93.04156 -122.297401)
			(xy 92.983996 -122.288549) (xy 92.928445 -122.271054) (xy 92.876197 -122.245322) (xy 92.828465 -122.211951)
			(xy 92.786358 -122.171714) (xy 92.750852 -122.125548) (xy 92.722774 -122.074523) (xy 92.702773 -122.019824)
			(xy 92.696538 -121.991374) (xy 92.694252 -121.97969) (xy 92.679774 -121.960894) (xy 92.585032 -121.915174)
			(xy 92.56141 -121.915428) (xy 92.550488 -121.921016) (xy 92.523379 -121.934284) (xy 92.466018 -121.953053)
			(xy 92.40642 -121.962575) (xy 92.376244 -121.96318) (xy 92.34899 -121.96272) (xy 92.295036 -121.954968)
			(xy 92.242734 -121.939615) (xy 92.19315 -121.916975) (xy 92.147294 -121.887507) (xy 92.106098 -121.851813)
			(xy 92.070402 -121.810619) (xy 92.040933 -121.764764) (xy 92.018291 -121.715181) (xy 92.002936 -121.66288)
			(xy 91.995181 -121.608926) (xy 91.994736 -121.581672) (xy 91.99521 -121.554303) (xy 92.003038 -121.500127)
			(xy 92.018529 -121.447627) (xy 92.041366 -121.397879) (xy 92.071078 -121.351907) (xy 92.088716 -121.330974)
			(xy 92.094812 -121.323862) (xy 92.101162 -121.306844) (xy 92.101162 -121.2215) (xy 92.094812 -121.204482)
			(xy 92.088716 -121.19737) (xy 92.071075 -121.176438) (xy 92.041351 -121.130472) (xy 92.018511 -121.080725)
			(xy 92.003024 -121.028221) (xy 91.99521 -120.974042) (xy 91.994736 -120.946672) (xy 91.995287 -120.917181)
			(xy 92.004363 -120.8589) (xy 92.022295 -120.802709) (xy 92.048656 -120.749944) (xy 92.082818 -120.701862)
			(xy 92.12397 -120.659606) (xy 92.17113 -120.624182) (xy 92.19692 -120.609868) (xy 92.207588 -120.60428)
			(xy 92.221558 -120.584722) (xy 92.235274 -120.491758) (xy 92.23644 -120.479875) (xy 92.229023 -120.457212)
			(xy 92.22105 -120.448324) (xy 88.773 -117.000274) (xy 88.765558 -116.993576) (xy 88.747059 -116.985971)
			(xy 88.727058 -116.985988) (xy 88.717628 -116.989352) (xy 88.70315 -116.995448) (xy 88.686132 -117.020594)
			(xy 88.686132 -117.633242) (xy 88.686678 -117.643225) (xy 88.694405 -117.661643) (xy 88.701118 -117.669056)
			(xy 89.411556 -118.379494) (xy 89.429642 -118.398286) (xy 89.460271 -118.440497) (xy 89.483917 -118.486982)
			(xy 89.499997 -118.536595) (xy 89.508114 -118.588113) (xy 89.508584 -118.61419) (xy 89.508584 -119.27205)
			(xy 89.509112 -119.282042) (xy 89.516811 -119.300488) (xy 89.52357 -119.307864) (xy 90.024712 -119.809006)
			(xy 90.031567 -119.816401) (xy 90.039313 -119.835) (xy 90.039698 -119.845074) (xy 90.039698 -119.940324)
			(xy 90.040268 -119.952238) (xy 90.050861 -119.973576) (xy 90.060018 -119.981218) (xy 90.083426 -119.999333)
			(xy 90.124878 -120.04158) (xy 90.159304 -120.089724) (xy 90.185877 -120.14261) (xy 90.203959 -120.198967)
			(xy 90.213115 -120.257441) (xy 90.213688 -120.287034) (xy 90.213214 -120.314403) (xy 90.205385 -120.368579)
			(xy 90.189894 -120.421079) (xy 90.167058 -120.470827) (xy 90.137347 -120.5168) (xy 90.119708 -120.537732)
			(xy 90.113612 -120.544844) (xy 90.107262 -120.561862) (xy 90.107262 -120.647206) (xy 90.113612 -120.664224)
			(xy 90.119708 -120.671336) (xy 90.137345 -120.692269) (xy 90.167062 -120.738237) (xy 90.189901 -120.787982)
			(xy 90.205391 -120.840482) (xy 90.213215 -120.894657) (xy 90.213211 -120.949394) (xy 90.20538 -121.003568)
			(xy 90.189883 -121.056066) (xy 90.167037 -121.105808) (xy 90.137314 -121.151772) (xy 90.119708 -121.172732)
			(xy 90.113612 -121.179844) (xy 90.107262 -121.196862) (xy 90.107262 -121.198753) (xy 90.48544 -121.198753)
			(xy 90.48544 -121.144247) (xy 90.493196 -121.090297) (xy 90.508551 -121.038) (xy 90.531192 -120.98842)
			(xy 90.560659 -120.942566) (xy 90.59635 -120.901373) (xy 90.637541 -120.865678) (xy 90.683392 -120.836208)
			(xy 90.73297 -120.813562) (xy 90.785266 -120.798203) (xy 90.839216 -120.790442) (xy 90.866468 -120.789954)
			(xy 90.893838 -120.790426) (xy 90.948018 -120.79824) (xy 91.000521 -120.813727) (xy 91.050268 -120.836568)
			(xy 91.096235 -120.866293) (xy 91.117166 -120.883934) (xy 91.124278 -120.89003) (xy 91.141296 -120.89638)
			(xy 91.22664 -120.89638) (xy 91.243658 -120.89003) (xy 91.25077 -120.883934) (xy 91.271707 -120.866301)
			(xy 91.317678 -120.836587) (xy 91.367424 -120.813749) (xy 91.419924 -120.798257) (xy 91.474099 -120.790428)
			(xy 91.501468 -120.789954) (xy 91.52872 -120.790491) (xy 91.582669 -120.798244) (xy 91.634965 -120.813595)
			(xy 91.684544 -120.836234) (xy 91.730397 -120.865698) (xy 91.771589 -120.901388) (xy 91.807283 -120.942577)
			(xy 91.836751 -120.988428) (xy 91.859394 -121.038005) (xy 91.87475 -121.0903) (xy 91.882507 -121.144248)
			(xy 91.882507 -121.198752) (xy 91.87475 -121.2527) (xy 91.859394 -121.304995) (xy 91.836751 -121.354572)
			(xy 91.807283 -121.400423) (xy 91.771589 -121.441612) (xy 91.730397 -121.477302) (xy 91.684544 -121.506766)
			(xy 91.634965 -121.529405) (xy 91.582669 -121.544756) (xy 91.52872 -121.552509) (xy 91.501468 -121.55297)
			(xy 91.474097 -121.55253) (xy 91.419916 -121.544707) (xy 91.367413 -121.529212) (xy 91.317666 -121.506365)
			(xy 91.271701 -121.476634) (xy 91.25077 -121.45899) (xy 91.243658 -121.452894) (xy 91.22664 -121.446544)
			(xy 91.141296 -121.446544) (xy 91.124278 -121.452894) (xy 91.117166 -121.45899) (xy 91.096219 -121.47661)
			(xy 91.05025 -121.506325) (xy 91.000507 -121.529165) (xy 90.948009 -121.54466) (xy 90.893836 -121.552493)
			(xy 90.866468 -121.55297) (xy 90.839216 -121.552558) (xy 90.785266 -121.544797) (xy 90.73297 -121.529438)
			(xy 90.683392 -121.506792) (xy 90.637541 -121.477322) (xy 90.59635 -121.441627) (xy 90.560659 -121.400434)
			(xy 90.531192 -121.35458) (xy 90.508551 -121.305) (xy 90.493196 -121.252703) (xy 90.48544 -121.198753)
			(xy 90.107262 -121.198753) (xy 90.107262 -121.282206) (xy 90.113612 -121.299224) (xy 90.119708 -121.306336)
			(xy 90.137345 -121.327269) (xy 90.167062 -121.373237) (xy 90.189901 -121.422982) (xy 90.205391 -121.475482)
			(xy 90.213215 -121.529657) (xy 90.213211 -121.584394) (xy 90.20538 -121.638568) (xy 90.189883 -121.691066)
			(xy 90.167037 -121.740808) (xy 90.137314 -121.786772) (xy 90.119708 -121.807732) (xy 90.113612 -121.814844)
			(xy 90.107262 -121.831862) (xy 90.107262 -121.917206) (xy 90.113612 -121.934224) (xy 90.119708 -121.941336)
			(xy 90.137348 -121.962268) (xy 90.167069 -122.008236) (xy 90.189907 -122.057983) (xy 90.205392 -122.110486)
			(xy 90.213205 -122.164664) (xy 90.213688 -122.192034) (xy 90.213106 -122.221624) (xy 90.203923 -122.280088)
			(xy 90.185828 -122.336435) (xy 90.159256 -122.389315) (xy 90.124842 -122.437461) (xy 90.083411 -122.47972)
			(xy 90.060018 -122.49785) (xy 90.05087 -122.505502) (xy 90.040268 -122.526831) (xy 90.039698 -122.538744)
			(xy 90.039698 -122.665998) (xy 90.040186 -122.676006) (xy 90.047845 -122.694499) (xy 90.061998 -122.708653)
			(xy 90.08049 -122.716313) (xy 90.090498 -122.716798) (xy 90.527124 -122.716798) (xy 90.537192 -122.717226)
			(xy 90.555791 -122.724946) (xy 90.563192 -122.731784) (xy 91.195961 -123.364553) (xy 94.064275 -123.364553)
			(xy 94.064275 -123.310047) (xy 94.072033 -123.256097) (xy 94.087389 -123.203799) (xy 94.110033 -123.15422)
			(xy 94.139502 -123.108368) (xy 94.175197 -123.067177) (xy 94.21639 -123.031485) (xy 94.262245 -123.002019)
			(xy 94.311826 -122.97938) (xy 94.364124 -122.964027) (xy 94.418075 -122.956273) (xy 94.445328 -122.955812)
			(xy 94.472699 -122.956259) (xy 94.526879 -122.964081) (xy 94.579382 -122.979574) (xy 94.629129 -123.00242)
			(xy 94.675095 -123.032149) (xy 94.696026 -123.049792) (xy 94.703138 -123.055888) (xy 94.720156 -123.062238)
			(xy 94.8055 -123.062238) (xy 94.822518 -123.055888) (xy 94.82963 -123.049792) (xy 94.850563 -123.032151)
			(xy 94.896531 -123.002427) (xy 94.946277 -122.979581) (xy 94.998779 -122.964085) (xy 95.052957 -122.956256)
			(xy 95.107699 -122.956256) (xy 95.161877 -122.964085) (xy 95.214379 -122.979581) (xy 95.264125 -123.002427)
			(xy 95.310093 -123.032151) (xy 95.331026 -123.049792) (xy 95.338138 -123.055888) (xy 95.355156 -123.062238)
			(xy 95.4405 -123.062238) (xy 95.457518 -123.055888) (xy 95.46463 -123.049792) (xy 95.485577 -123.032171)
			(xy 95.531546 -123.002457) (xy 95.581289 -122.979617) (xy 95.633787 -122.964122) (xy 95.68796 -122.956289)
			(xy 95.715328 -122.955812) (xy 95.742579 -122.95626) (xy 95.796527 -122.96402) (xy 95.848821 -122.979378)
			(xy 95.898397 -123.002022) (xy 95.944247 -123.031491) (xy 95.985436 -123.067184) (xy 96.021126 -123.108376)
			(xy 96.050591 -123.154227) (xy 96.073232 -123.203805) (xy 96.088586 -123.256101) (xy 96.096342 -123.310049)
			(xy 96.096342 -123.364551) (xy 96.088586 -123.4185) (xy 96.073232 -123.470795) (xy 96.050591 -123.520373)
			(xy 96.021126 -123.566224) (xy 95.985436 -123.607416) (xy 95.944247 -123.643109) (xy 95.898397 -123.672578)
			(xy 95.848821 -123.695222) (xy 95.796527 -123.71058) (xy 95.742579 -123.71834) (xy 95.715328 -123.718828)
			(xy 95.687958 -123.718363) (xy 95.633778 -123.710548) (xy 95.581274 -123.695059) (xy 95.531527 -123.672217)
			(xy 95.485561 -123.64249) (xy 95.46463 -123.624848) (xy 95.457518 -123.618752) (xy 95.4405 -123.612402)
			(xy 95.355156 -123.612402) (xy 95.338138 -123.618752) (xy 95.331026 -123.624848) (xy 95.310093 -123.642489)
			(xy 95.264125 -123.672213) (xy 95.214379 -123.695059) (xy 95.161877 -123.710555) (xy 95.107699 -123.718384)
			(xy 95.052957 -123.718384) (xy 94.998779 -123.710555) (xy 94.946277 -123.695059) (xy 94.896531 -123.672213)
			(xy 94.850563 -123.642489) (xy 94.82963 -123.624848) (xy 94.822518 -123.618752) (xy 94.8055 -123.612402)
			(xy 94.720156 -123.612402) (xy 94.703138 -123.618752) (xy 94.696026 -123.624848) (xy 94.675088 -123.64248)
			(xy 94.629118 -123.672195) (xy 94.579372 -123.695033) (xy 94.526872 -123.710525) (xy 94.472697 -123.718354)
			(xy 94.445328 -123.718828) (xy 94.418075 -123.718327) (xy 94.364124 -123.710573) (xy 94.311826 -123.69522)
			(xy 94.262245 -123.672581) (xy 94.21639 -123.643115) (xy 94.175197 -123.607423) (xy 94.139502 -123.566232)
			(xy 94.110033 -123.52038) (xy 94.087389 -123.470801) (xy 94.072033 -123.418503) (xy 94.064275 -123.364553)
			(xy 91.195961 -123.364553) (xy 92.046552 -124.215144) (xy 94.606616 -124.215144) (xy 94.610687 -124.159522)
			(xy 94.622813 -124.105085) (xy 94.642736 -124.052994) (xy 94.670032 -124.004359) (xy 94.704118 -123.960216)
			(xy 94.744267 -123.921507) (xy 94.789625 -123.889056) (xy 94.839225 -123.863555) (xy 94.892009 -123.845548)
			(xy 94.946852 -123.835418) (xy 95.002586 -123.833381) (xy 95.058023 -123.839481) (xy 95.11198 -123.853587)
			(xy 95.163309 -123.875399) (xy 95.210915 -123.904453) (xy 95.253783 -123.940128) (xy 95.291 -123.981665)
			(xy 95.321773 -124.028178) (xy 95.345445 -124.078675) (xy 95.361513 -124.132082) (xy 95.369633 -124.187258)
			(xy 95.370142 -124.215144) (xy 95.369633 -124.24303) (xy 95.361513 -124.298206) (xy 95.345445 -124.351613)
			(xy 95.321773 -124.40211) (xy 95.291 -124.448623) (xy 95.253783 -124.49016) (xy 95.210915 -124.525835)
			(xy 95.163309 -124.554889) (xy 95.11198 -124.576701) (xy 95.058023 -124.590807) (xy 95.002586 -124.596907)
			(xy 94.946852 -124.59487) (xy 94.892009 -124.58474) (xy 94.839225 -124.566733) (xy 94.789625 -124.541232)
			(xy 94.744267 -124.508781) (xy 94.704118 -124.470072) (xy 94.670032 -124.425929) (xy 94.642736 -124.377294)
			(xy 94.622813 -124.325203) (xy 94.610687 -124.270766) (xy 94.606616 -124.215144) (xy 92.046552 -124.215144)
			(xy 93.616272 -125.784864) (xy 93.623111 -125.792265) (xy 93.630827 -125.810863) (xy 93.631258 -125.820932)
			(xy 93.631258 -128.079754) (xy 93.631797 -128.089703) (xy 93.639466 -128.10807) (xy 93.653523 -128.122162)
			(xy 93.6625 -128.12649) (xy 93.676978 -128.132586)
		)
		(stroke
			(width 0)
			(type solid)
		)
		(fill yes)
		(layer "In5.Cu")
		(net "GND")
	)
	(gr_poly
		(pts
			(xy 6.30936 -34.677858) (xy 6.316036 -34.683967) (xy 6.332497 -34.691456) (xy 6.350533 -34.692774)
			(xy 6.367907 -34.687758) (xy 6.3754 -34.682684) (xy 6.400086 -34.665304) (xy 6.453787 -34.637722)
			(xy 6.511157 -34.618926) (xy 6.570767 -34.609381) (xy 6.600952 -34.60877) (xy 6.601206 -34.60877)
			(xy 6.624165 -34.609098) (xy 6.669754 -34.614575) (xy 6.692138 -34.619692) (xy 6.701653 -34.621599)
			(xy 6.720858 -34.61892) (xy 6.737693 -34.609301) (xy 6.749752 -34.594116) (xy 6.755309 -34.575539)
			(xy 6.754876 -34.565844) (xy 6.753929 -34.555201) (xy 6.752914 -34.533856) (xy 6.752844 -34.523172)
			(xy 6.752844 -33.65881) (xy 6.753334 -33.628842) (xy 6.761157 -33.56942) (xy 6.77667 -33.511527)
			(xy 6.799606 -33.456154) (xy 6.829573 -33.404248) (xy 6.86606 -33.356698) (xy 6.90844 -33.314318)
			(xy 6.95599 -33.277831) (xy 7.007896 -33.247864) (xy 7.063269 -33.224928) (xy 7.121162 -33.209415)
			(xy 7.180584 -33.201592) (xy 7.24052 -33.201592) (xy 7.299942 -33.209415) (xy 7.357835 -33.224928)
			(xy 7.413208 -33.247864) (xy 7.465114 -33.277831) (xy 7.512664 -33.314318) (xy 7.555044 -33.356698)
			(xy 7.591531 -33.404248) (xy 7.621498 -33.456154) (xy 7.644434 -33.511527) (xy 7.659947 -33.56942)
			(xy 7.66777 -33.628842) (xy 7.66826 -33.65881) (xy 7.66826 -34.523172) (xy 7.666228 -34.565844) (xy 7.665784 -34.57554)
			(xy 7.671342 -34.59412) (xy 7.683404 -34.609307) (xy 7.700243 -34.618927) (xy 7.719451 -34.621606)
			(xy 7.728966 -34.619692) (xy 7.751408 -34.614543) (xy 7.797128 -34.609069) (xy 7.820152 -34.60877)
			(xy 7.850374 -34.609322) (xy 7.910067 -34.618818) (xy 7.96751 -34.637626) (xy 7.99465 -34.650934)
			(xy 8.004402 -34.655448) (xy 8.025837 -34.656679) (xy 8.045904 -34.649043) (xy 8.053832 -34.64179)
			(xy 9.291066 -33.404556) (xy 9.298049 -33.396962) (xy 9.305769 -33.377852) (xy 9.305294 -33.357248)
			(xy 9.30148 -33.34766) (xy 9.290741 -33.32281) (xy 9.275592 -33.270838) (xy 9.267935 -33.217247)
			(xy 9.267444 -33.19018) (xy 9.267608 -33.175128) (xy 9.27002 -33.14512) (xy 9.27227 -33.130236) (xy 9.248091 -33.142104)
			(xy 9.197551 -33.160732) (xy 9.145174 -33.173297) (xy 9.091684 -33.179626) (xy 9.064752 -33.18002)
			(xy 9.034786 -33.179527) (xy 8.975368 -33.171699) (xy 8.917479 -33.156182) (xy 8.862111 -33.133243)
			(xy 8.81021 -33.103274) (xy 8.762665 -33.066788) (xy 8.720288 -33.024408) (xy 8.683806 -32.97686)
			(xy 8.653841 -32.924957) (xy 8.630906 -32.869587) (xy 8.615394 -32.811697) (xy 8.607571 -32.752278)
			(xy 8.607044 -32.722312) (xy 8.607044 -31.858712) (xy 8.607534 -31.828744) (xy 8.615357 -31.769322)
			(xy 8.63087 -31.711429) (xy 8.653806 -31.656056) (xy 8.683773 -31.60415) (xy 8.72026 -31.5566) (xy 8.76264 -31.51422)
			(xy 8.81019 -31.477733) (xy 8.862096 -31.447766) (xy 8.917469 -31.42483) (xy 8.975362 -31.409317)
			(xy 9.034784 -31.401494) (xy 9.09472 -31.401494) (xy 9.154142 -31.409317) (xy 9.212035 -31.42483)
			(xy 9.267408 -31.447766) (xy 9.319314 -31.477733) (xy 9.366864 -31.51422) (xy 9.409244 -31.5566)
			(xy 9.445731 -31.60415) (xy 9.475698 -31.656056) (xy 9.498634 -31.711429) (xy 9.514147 -31.769322)
			(xy 9.52197 -31.828744) (xy 9.52246 -31.858712) (xy 9.52246 -32.722566) (xy 9.520936 -32.760666)
			(xy 9.520626 -32.769987) (xy 9.52591 -32.787855) (xy 9.537221 -32.802663) (xy 9.553072 -32.81246)
			(xy 9.571374 -32.815956) (xy 9.580626 -32.814768) (xy 9.597373 -32.811931) (xy 9.631205 -32.80888)
			(xy 9.64819 -32.808672) (xy 9.648952 -32.808672) (xy 9.676021 -32.809143) (xy 9.729615 -32.816795)
			(xy 9.781588 -32.831952) (xy 9.806432 -32.842708) (xy 9.816017 -32.846489) (xy 9.836599 -32.846893)
			(xy 9.855703 -32.839224) (xy 9.863328 -32.832294) (xy 10.278618 -32.417004) (xy 10.285474 -32.40961)
			(xy 10.293223 -32.391011) (xy 10.293604 -32.380936) (xy 10.293604 -30.854904) (xy 10.294064 -30.82205)
			(xy 10.30142 -30.756756) (xy 10.31604 -30.692696) (xy 10.337741 -30.630675) (xy 10.366249 -30.571474)
			(xy 10.401206 -30.515838) (xy 10.442172 -30.464464) (xy 10.465054 -30.440884) (xy 10.939018 -29.96692)
			(xy 10.962572 -29.943972) (xy 11.01397 -29.902948) (xy 11.069641 -29.867941) (xy 11.128883 -29.839391)
			(xy 11.19095 -29.817658) (xy 11.255062 -29.803014) (xy 11.320411 -29.795646) (xy 11.353292 -29.795216)
			(xy 11.8364 -29.795216) (xy 11.846471 -29.794793) (xy 11.865077 -29.787081) (xy 11.872468 -29.78023)
			(xy 13.665962 -27.986736) (xy 13.689516 -27.96379) (xy 13.740915 -27.922769) (xy 13.796586 -27.887764)
			(xy 13.855828 -27.859218) (xy 13.917896 -27.837488) (xy 13.982007 -27.82285) (xy 14.047355 -27.815486)
			(xy 14.080236 -27.815032) (xy 16.572738 -27.815032) (xy 16.582806 -27.814603) (xy 16.601403 -27.806882)
			(xy 16.608806 -27.800046) (xy 16.629126 -27.779726) (xy 16.635621 -27.772708) (xy 16.643318 -27.755219)
			(xy 16.644112 -27.74569) (xy 16.64716 -27.666696) (xy 16.64081 -27.648916) (xy 16.63446 -27.64155)
			(xy 16.613683 -27.616518) (xy 16.578669 -27.561691) (xy 16.551765 -27.502462) (xy 16.533514 -27.440021)
			(xy 16.52428 -27.375626) (xy 16.523716 -27.3431) (xy 16.523716 -26.479246) (xy 16.524206 -26.449278)
			(xy 16.532029 -26.389856) (xy 16.547542 -26.331963) (xy 16.570478 -26.27659) (xy 16.600445 -26.224684)
			(xy 16.636932 -26.177134) (xy 16.679312 -26.134754) (xy 16.726862 -26.098267) (xy 16.778768 -26.0683)
			(xy 16.834141 -26.045364) (xy 16.892034 -26.029851) (xy 16.951456 -26.022028) (xy 17.011392 -26.022028)
			(xy 17.070814 -26.029851) (xy 17.128707 -26.045364) (xy 17.18408 -26.0683) (xy 17.235986 -26.098267)
			(xy 17.283536 -26.134754) (xy 17.325916 -26.177134) (xy 17.362403 -26.224684) (xy 17.39237 -26.27659)
			(xy 17.415306 -26.331963) (xy 17.430819 -26.389856) (xy 17.438642 -26.449278) (xy 17.439132 -26.479246)
			(xy 17.439132 -26.847038) (xy 17.439564 -26.857078) (xy 17.447281 -26.875617) (xy 17.46152 -26.889777)
			(xy 17.470628 -26.894028) (xy 17.484852 -26.900124) (xy 17.514824 -26.894028) (xy 17.899126 -26.509726)
			(xy 17.921478 -26.488644) (xy 17.921732 -26.48839) (xy 17.929034 -26.481107) (xy 17.937576 -26.462358)
			(xy 17.938242 -26.452068) (xy 17.940274 -26.378408) (xy 17.940031 -26.368019) (xy 17.932282 -26.348758)
			(xy 17.925288 -26.34107) (xy 17.4371 -25.852882) (xy 17.429705 -25.846027) (xy 17.411106 -25.838279)
			(xy 17.401032 -25.837896) (xy 15.766034 -25.837896) (xy 15.755969 -25.838331) (xy 15.737382 -25.846062)
			(xy 15.729966 -25.852882) (xy 14.281912 -27.30119) (xy 14.263133 -27.319307) (xy 14.220938 -27.349999)
			(xy 14.174457 -27.373707) (xy 14.124838 -27.389846) (xy 14.073305 -27.398018) (xy 14.047216 -27.398472)
			(xy 9.143238 -27.398472) (xy 9.137371 -27.398624) (xy 9.125951 -27.401323) (xy 9.120632 -27.403806)
			(xy 9.120124 -27.40406) (xy 9.092597 -27.417898) (xy 9.034184 -27.437481) (xy 8.973382 -27.447417)
			(xy 8.942578 -27.448002) (xy 8.911873 -27.447369) (xy 8.851259 -27.437499) (xy 8.793009 -27.418049)
			(xy 8.76554 -27.404314) (xy 8.764524 -27.403806) (xy 8.75919 -27.401012) (xy 8.748014 -27.398472)
			(xy 7.704836 -27.398472) (xy 7.694784 -27.398975) (xy 7.676219 -27.406692) (xy 7.668768 -27.413458)
			(xy 6.252718 -28.829508) (xy 6.233946 -28.847539) (xy 6.191829 -28.878116) (xy 6.145452 -28.901741)
			(xy 6.095956 -28.917832) (xy 6.044553 -28.925996) (xy 6.01853 -28.926536) (xy 4.199636 -28.926536)
			(xy 4.189797 -28.92699) (xy 4.171577 -28.934418) (xy 4.157517 -28.948184) (xy 4.153154 -28.957016)
			(xy 4.11607 -29.042614) (xy 4.112542 -29.051829) (xy 4.112063 -29.071535) (xy 4.119083 -29.089955)
			(xy 4.125468 -29.097478) (xy 4.144616 -29.118775) (xy 4.147076 -29.12237) (xy 8.607044 -29.12237)
			(xy 8.607044 -28.25877) (xy 8.607534 -28.228802) (xy 8.615357 -28.16938) (xy 8.63087 -28.111487)
			(xy 8.653806 -28.056114) (xy 8.683773 -28.004208) (xy 8.72026 -27.956658) (xy 8.76264 -27.914278)
			(xy 8.81019 -27.877791) (xy 8.862096 -27.847824) (xy 8.917469 -27.824888) (xy 8.975362 -27.809375)
			(xy 9.034784 -27.801552) (xy 9.09472 -27.801552) (xy 9.154142 -27.809375) (xy 9.212035 -27.824888)
			(xy 9.267408 -27.847824) (xy 9.319314 -27.877791) (xy 9.366864 -27.914278) (xy 9.409244 -27.956658)
			(xy 9.445731 -28.004208) (xy 9.475698 -28.056114) (xy 9.498634 -28.111487) (xy 9.514147 -28.16938)
			(xy 9.52197 -28.228802) (xy 9.52246 -28.25877) (xy 9.52246 -29.12237) (xy 9.52197 -29.152338) (xy 9.514147 -29.21176)
			(xy 9.498634 -29.269653) (xy 9.475698 -29.325026) (xy 9.445731 -29.376932) (xy 9.409244 -29.424482)
			(xy 9.366864 -29.466862) (xy 9.319314 -29.503349) (xy 9.267408 -29.533316) (xy 9.212035 -29.556252)
			(xy 9.154142 -29.571765) (xy 9.09472 -29.579588) (xy 9.034784 -29.579588) (xy 8.975362 -29.571765)
			(xy 8.917469 -29.556252) (xy 8.862096 -29.533316) (xy 8.81019 -29.503349) (xy 8.76264 -29.466862)
			(xy 8.72026 -29.424482) (xy 8.683773 -29.376932) (xy 8.653806 -29.325026) (xy 8.63087 -29.269653)
			(xy 8.615357 -29.21176) (xy 8.607534 -29.152338) (xy 8.607044 -29.12237) (xy 4.147076 -29.12237)
			(xy 4.17696 -29.166035) (xy 4.201875 -29.217601) (xy 4.218798 -29.272313) (xy 4.22735 -29.328939)
			(xy 4.22783 -29.357574) (xy 4.227344 -29.384825) (xy 4.219588 -29.438773) (xy 4.204233 -29.491068)
			(xy 4.181591 -29.540645) (xy 4.152125 -29.586495) (xy 4.116434 -29.627686) (xy 4.075243 -29.663377)
			(xy 4.029393 -29.692843) (xy 3.979816 -29.715485) (xy 3.927521 -29.73084) (xy 3.873573 -29.738596)
			(xy 3.819071 -29.738596) (xy 3.765123 -29.73084) (xy 3.712828 -29.715485) (xy 3.663251 -29.692843)
			(xy 3.617401 -29.663377) (xy 3.57621 -29.627686) (xy 3.540519 -29.586495) (xy 3.511053 -29.540645)
			(xy 3.488411 -29.491068) (xy 3.473056 -29.438773) (xy 3.4653 -29.384825) (xy 3.464814 -29.357574)
			(xy 3.465328 -29.328941) (xy 3.473884 -29.272318) (xy 3.490802 -29.217609) (xy 3.515701 -29.166039)
			(xy 3.548022 -29.118767) (xy 3.567176 -29.097478) (xy 3.573549 -29.089954) (xy 3.580536 -29.071534)
			(xy 3.580061 -29.051839) (xy 3.576574 -29.042614) (xy 3.53949 -28.957016) (xy 3.535128 -28.94819)
			(xy 3.521046 -28.934455) (xy 3.502841 -28.927003) (xy 3.493008 -28.926536) (xy 2.950464 -28.926536)
			(xy 2.940934 -28.92692) (xy 2.923184 -28.93386) (xy 2.909195 -28.946805) (xy 2.904744 -28.955238)
			(xy 2.858516 -29.05125) (xy 2.862072 -29.080206) (xy 2.871216 -29.091636) (xy 2.886949 -29.111985)
			(xy 2.913384 -29.156109) (xy 2.933654 -29.203384) (xy 2.947392 -29.252952) (xy 2.954349 -29.303916)
			(xy 2.954782 -29.329634) (xy 2.954782 -29.330142) (xy 2.954296 -29.357393) (xy 2.946539 -29.411341)
			(xy 2.931184 -29.463636) (xy 2.908543 -29.513213) (xy 2.879077 -29.559063) (xy 2.843385 -29.600254)
			(xy 2.802195 -29.635945) (xy 2.756345 -29.665412) (xy 2.706768 -29.688053) (xy 2.654473 -29.703409)
			(xy 2.600525 -29.711166) (xy 2.573274 -29.71165) (xy 2.562069 -29.711521) (xy 2.539703 -29.710125)
			(xy 2.52857 -29.708856) (xy 2.527808 -29.708856) (xy 2.517149 -29.708243) (xy 2.496819 -29.714685)
			(xy 2.488438 -29.721302) (xy 2.431542 -29.771848) (xy 2.423827 -29.77942) (xy 2.415036 -29.799148)
			(xy 2.414524 -29.809948) (xy 2.414524 -30.922468) (xy 6.752844 -30.922468) (xy 6.752844 -30.058868)
			(xy 6.753334 -30.0289) (xy 6.761157 -29.969478) (xy 6.77667 -29.911585) (xy 6.799606 -29.856212)
			(xy 6.829573 -29.804306) (xy 6.86606 -29.756756) (xy 6.90844 -29.714376) (xy 6.95599 -29.677889)
			(xy 7.007896 -29.647922) (xy 7.063269 -29.624986) (xy 7.121162 -29.609473) (xy 7.180584 -29.60165)
			(xy 7.24052 -29.60165) (xy 7.299942 -29.609473) (xy 7.357835 -29.624986) (xy 7.413208 -29.647922)
			(xy 7.465114 -29.677889) (xy 7.512664 -29.714376) (xy 7.555044 -29.756756) (xy 7.591531 -29.804306)
			(xy 7.621498 -29.856212) (xy 7.644434 -29.911585) (xy 7.659947 -29.969478) (xy 7.66777 -30.0289)
			(xy 7.66826 -30.058868) (xy 7.66826 -30.922468) (xy 7.66777 -30.952436) (xy 7.659947 -31.011858)
			(xy 7.644434 -31.069751) (xy 7.621498 -31.125124) (xy 7.591531 -31.17703) (xy 7.555044 -31.22458)
			(xy 7.512664 -31.26696) (xy 7.465114 -31.303447) (xy 7.413208 -31.333414) (xy 7.357835 -31.35635)
			(xy 7.299942 -31.371863) (xy 7.24052 -31.379686) (xy 7.180584 -31.379686) (xy 7.121162 -31.371863)
			(xy 7.063269 -31.35635) (xy 7.007896 -31.333414) (xy 6.95599 -31.303447) (xy 6.90844 -31.26696) (xy 6.86606 -31.22458)
			(xy 6.829573 -31.17703) (xy 6.799606 -31.125124) (xy 6.77667 -31.069751) (xy 6.761157 -31.011858)
			(xy 6.753334 -30.952436) (xy 6.752844 -30.922468) (xy 2.414524 -30.922468) (xy 2.414524 -33.14446)
			(xy 2.414916 -33.153695) (xy 2.421454 -33.17097) (xy 2.433695 -33.184802) (xy 2.441702 -33.189418)
			(xy 2.534158 -33.237932) (xy 2.562098 -33.236408) (xy 2.573782 -33.22828) (xy 2.6032 -33.208633)
			(xy 2.665844 -33.175767) (xy 2.731989 -33.150683) (xy 2.800673 -33.133744) (xy 2.870897 -33.125199)
			(xy 2.906268 -33.124648) (xy 2.9337 -33.124648) (xy 2.966577 -33.125127) (xy 3.031915 -33.132521)
			(xy 3.096015 -33.147177) (xy 3.158074 -33.168912) (xy 3.217312 -33.197451) (xy 3.272987 -33.232438)
			(xy 3.324398 -33.273433) (xy 3.347974 -33.296352) (xy 3.378708 -33.327086) (xy 3.38555 -33.33331)
			(xy 3.402434 -33.340826) (xy 3.420886 -33.341867) (xy 3.438508 -33.336297) (xy 3.446018 -33.330896)
			(xy 3.471911 -33.311036) (xy 3.527316 -33.276556) (xy 3.586207 -33.248443) (xy 3.647857 -33.227044)
			(xy 3.711502 -33.212625) (xy 3.776355 -33.205365) (xy 3.808984 -33.204912) (xy 3.809238 -33.204912)
			(xy 3.842094 -33.205352) (xy 3.907393 -33.212703) (xy 3.971458 -33.227318) (xy 4.033485 -33.249015)
			(xy 4.092692 -33.277521) (xy 4.148335 -33.312476) (xy 4.199714 -33.353441) (xy 4.223258 -33.376362)
			(xy 4.52247 -33.675574) (xy 4.531919 -33.684019) (xy 4.556178 -33.691237) (xy 4.568698 -33.68929)
			(xy 4.651756 -33.672272) (xy 4.66398 -33.669036) (xy 4.683302 -33.652773) (xy 4.688586 -33.641284)
			(xy 4.699574 -33.615027) (xy 4.728197 -33.565831) (xy 4.76381 -33.521432) (xy 4.805624 -33.482817)
			(xy 4.852711 -33.450842) (xy 4.904024 -33.426216) (xy 4.958427 -33.409486) (xy 5.014712 -33.401024)
			(xy 5.04317 -33.400492) (xy 5.070424 -33.400953) (xy 5.124378 -33.408707) (xy 5.17668 -33.42406)
			(xy 5.226264 -33.446701) (xy 5.272121 -33.476168) (xy 5.313317 -33.511862) (xy 5.349014 -33.553055)
			(xy 5.378485 -33.59891) (xy 5.401129 -33.648492) (xy 5.416487 -33.700792) (xy 5.424245 -33.754746)
			(xy 5.424678 -33.782) (xy 5.424678 -33.782508) (xy 5.424137 -33.810937) (xy 5.41566 -33.867161) (xy 5.398926 -33.921502)
			(xy 5.387086 -33.947354) (xy 5.387086 -33.947608) (xy 5.383698 -33.955437) (xy 5.381805 -33.97238)
			(xy 5.385593 -33.989003) (xy 5.38988 -33.996376) (xy 5.435346 -34.06902) (xy 5.44018 -34.076165)
			(xy 5.453629 -34.086949) (xy 5.469905 -34.092627) (xy 5.478526 -34.092896) (xy 5.482082 -34.092896)
			(xy 5.514959 -34.093377) (xy 5.580295 -34.100774) (xy 5.644394 -34.115432) (xy 5.706452 -34.137168)
			(xy 5.765689 -34.165708) (xy 5.821362 -34.200694) (xy 5.872773 -34.241688) (xy 5.896356 -34.2646)
		)
		(stroke
			(width 0)
			(type solid)
		)
		(fill yes)
		(layer "In5.Cu")
		(net "GND")
	)
	(gr_poly
		(pts
			(xy 22.604222 -415.589974) (xy 22.61429 -415.589546) (xy 22.632886 -415.581823) (xy 22.64029 -415.574988)
			(xy 23.348188 -414.86709) (xy 23.355034 -414.859691) (xy 23.362767 -414.841093) (xy 23.363174 -414.831022)
			(xy 23.363174 -405.167592) (xy 23.362749 -405.157523) (xy 23.355029 -405.138923) (xy 23.348188 -405.131524)
			(xy 21.084286 -402.867622) (xy 21.076888 -402.860775) (xy 21.05829 -402.853043) (xy 21.048218 -402.852636)
			(xy 19.240754 -402.852636) (xy 19.230689 -402.852203) (xy 19.212103 -402.844469) (xy 19.204686 -402.83765)
			(xy 18.667222 -402.300186) (xy 18.660375 -402.292788) (xy 18.652643 -402.27419) (xy 18.652236 -402.264118)
			(xy 18.652236 -401.314666) (xy 18.651805 -401.3046) (xy 18.644075 -401.28601) (xy 18.63725 -401.278598)
			(xy 17.887696 -400.529044) (xy 17.880299 -400.522193) (xy 17.861701 -400.514453) (xy 17.851628 -400.514058)
			(xy 11.254486 -400.514058) (xy 11.244418 -400.514485) (xy 11.225823 -400.52221) (xy 11.218418 -400.529044)
			(xy 10.947908 -400.799554) (xy 10.941069 -400.806955) (xy 10.933353 -400.825553) (xy 10.932922 -400.835622)
			(xy 10.932922 -402.208492) (xy 17.05408 -402.208492) (xy 17.058037 -402.151898) (xy 17.069833 -402.096406)
			(xy 17.089236 -402.043096) (xy 17.11587 -401.993005) (xy 17.149216 -401.947108) (xy 17.188625 -401.906298)
			(xy 17.233331 -401.871371) (xy 17.282462 -401.843005) (xy 17.335063 -401.821752) (xy 17.390109 -401.808028)
			(xy 17.44653 -401.802098) (xy 17.503228 -401.804078) (xy 17.559098 -401.813929) (xy 17.613053 -401.83146)
			(xy 17.664043 -401.85633) (xy 17.711076 -401.888054) (xy 17.753236 -401.926015) (xy 17.789702 -401.969474)
			(xy 17.819766 -402.017585) (xy 17.84284 -402.069412) (xy 17.858478 -402.123946) (xy 17.866373 -402.180126)
			(xy 17.866868 -402.208492) (xy 17.866373 -402.236858) (xy 17.858478 -402.293038) (xy 17.84284 -402.347572)
			(xy 17.819766 -402.399399) (xy 17.789702 -402.44751) (xy 17.753236 -402.490969) (xy 17.711076 -402.52893)
			(xy 17.664043 -402.560654) (xy 17.613053 -402.585524) (xy 17.559098 -402.603055) (xy 17.503228 -402.612906)
			(xy 17.44653 -402.614886) (xy 17.390109 -402.608956) (xy 17.335063 -402.595232) (xy 17.282462 -402.573979)
			(xy 17.233331 -402.545613) (xy 17.188625 -402.510686) (xy 17.149216 -402.469876) (xy 17.11587 -402.423979)
			(xy 17.089236 -402.373888) (xy 17.069833 -402.320578) (xy 17.058037 -402.265086) (xy 17.05408 -402.208492)
			(xy 10.932922 -402.208492) (xy 10.932922 -404.501858) (xy 17.351246 -404.501858) (xy 17.355317 -404.446236)
			(xy 17.367443 -404.391799) (xy 17.387366 -404.339708) (xy 17.414662 -404.291073) (xy 17.448748 -404.24693)
			(xy 17.488897 -404.208221) (xy 17.534255 -404.17577) (xy 17.583855 -404.150269) (xy 17.636639 -404.132262)
			(xy 17.691482 -404.122132) (xy 17.747216 -404.120095) (xy 17.802653 -404.126195) (xy 17.85661 -404.140301)
			(xy 17.907939 -404.162113) (xy 17.955545 -404.191167) (xy 17.998413 -404.226842) (xy 18.03563 -404.268379)
			(xy 18.066403 -404.314892) (xy 18.090075 -404.365389) (xy 18.106143 -404.418796) (xy 18.114263 -404.473972)
			(xy 18.114772 -404.501858) (xy 18.114263 -404.529744) (xy 18.106143 -404.58492) (xy 18.094299 -404.624286)
			(xy 18.644868 -404.624286) (xy 18.648939 -404.568664) (xy 18.661065 -404.514227) (xy 18.680988 -404.462136)
			(xy 18.708284 -404.413501) (xy 18.74237 -404.369358) (xy 18.782519 -404.330649) (xy 18.827877 -404.298198)
			(xy 18.877477 -404.272697) (xy 18.930261 -404.25469) (xy 18.985104 -404.24456) (xy 19.040838 -404.242523)
			(xy 19.096275 -404.248623) (xy 19.150232 -404.262729) (xy 19.201561 -404.284541) (xy 19.249167 -404.313595)
			(xy 19.292035 -404.34927) (xy 19.329252 -404.390807) (xy 19.360025 -404.43732) (xy 19.383697 -404.487817)
			(xy 19.399765 -404.541224) (xy 19.407885 -404.5964) (xy 19.408394 -404.624286) (xy 19.407885 -404.652172)
			(xy 19.399765 -404.707348) (xy 19.383697 -404.760755) (xy 19.360025 -404.811252) (xy 19.329252 -404.857765)
			(xy 19.292035 -404.899302) (xy 19.249167 -404.934977) (xy 19.201561 -404.964031) (xy 19.150232 -404.985843)
			(xy 19.096275 -404.999949) (xy 19.040838 -405.006049) (xy 18.985104 -405.004012) (xy 18.930261 -404.993882)
			(xy 18.877477 -404.975875) (xy 18.827877 -404.950374) (xy 18.782519 -404.917923) (xy 18.74237 -404.879214)
			(xy 18.708284 -404.835071) (xy 18.680988 -404.786436) (xy 18.661065 -404.734345) (xy 18.648939 -404.679908)
			(xy 18.644868 -404.624286) (xy 18.094299 -404.624286) (xy 18.090075 -404.638327) (xy 18.066403 -404.688824)
			(xy 18.03563 -404.735337) (xy 17.998413 -404.776874) (xy 17.955545 -404.812549) (xy 17.907939 -404.841603)
			(xy 17.85661 -404.863415) (xy 17.802653 -404.877521) (xy 17.747216 -404.883621) (xy 17.691482 -404.881584)
			(xy 17.636639 -404.871454) (xy 17.583855 -404.853447) (xy 17.534255 -404.827946) (xy 17.488897 -404.795495)
			(xy 17.448748 -404.756786) (xy 17.414662 -404.712643) (xy 17.387366 -404.664008) (xy 17.367443 -404.611917)
			(xy 17.355317 -404.55748) (xy 17.351246 -404.501858) (xy 10.932922 -404.501858) (xy 10.932922 -405.769572)
			(xy 10.932991 -405.774047) (xy 10.93452 -405.782864) (xy 10.93597 -405.787098) (xy 10.960598 -405.85517)
			(xy 21.715982 -405.85517) (xy 21.720053 -405.799548) (xy 21.732179 -405.745111) (xy 21.752102 -405.69302)
			(xy 21.779398 -405.644385) (xy 21.813484 -405.600242) (xy 21.853633 -405.561533) (xy 21.898991 -405.529082)
			(xy 21.948591 -405.503581) (xy 22.001375 -405.485574) (xy 22.056218 -405.475444) (xy 22.111952 -405.473407)
			(xy 22.167389 -405.479507) (xy 22.221346 -405.493613) (xy 22.272675 -405.515425) (xy 22.320281 -405.544479)
			(xy 22.363149 -405.580154) (xy 22.400366 -405.621691) (xy 22.431139 -405.668204) (xy 22.454811 -405.718701)
			(xy 22.470879 -405.772108) (xy 22.478999 -405.827284) (xy 22.479508 -405.85517) (xy 22.478999 -405.883056)
			(xy 22.470879 -405.938232) (xy 22.454811 -405.991639) (xy 22.431139 -406.042136) (xy 22.400366 -406.088649)
			(xy 22.363149 -406.130186) (xy 22.320281 -406.165861) (xy 22.272675 -406.194915) (xy 22.221346 -406.216727)
			(xy 22.167389 -406.230833) (xy 22.111952 -406.236933) (xy 22.056218 -406.234896) (xy 22.001375 -406.224766)
			(xy 21.948591 -406.206759) (xy 21.898991 -406.181258) (xy 21.853633 -406.148807) (xy 21.813484 -406.110098)
			(xy 21.779398 -406.065955) (xy 21.752102 -406.01732) (xy 21.732179 -405.965229) (xy 21.720053 -405.910792)
			(xy 21.715982 -405.85517) (xy 10.960598 -405.85517) (xy 10.970952 -405.88379) (xy 11.034248 -406.079455)
			(xy 11.089844 -406.277445) (xy 11.137655 -406.477458) (xy 11.177607 -406.679188) (xy 11.209641 -406.882326)
			(xy 11.233706 -407.086561) (xy 11.249766 -407.291581) (xy 11.257797 -407.497072) (xy 11.258296 -407.599896)
			(xy 11.257796 -407.70272) (xy 11.249754 -407.90821) (xy 11.233685 -408.113228) (xy 11.209614 -408.317462)
			(xy 11.177578 -408.520599) (xy 11.137627 -408.722328) (xy 11.08982 -408.922341) (xy 11.034231 -409.120333)
			(xy 10.970945 -409.316) (xy 10.93597 -409.412694) (xy 10.934548 -409.416935) (xy 10.933023 -409.425748)
			(xy 10.932922 -409.43022) (xy 10.932922 -409.448508) (xy 14.998698 -409.448508) (xy 15.002769 -409.392886)
			(xy 15.014895 -409.338449) (xy 15.034818 -409.286358) (xy 15.062114 -409.237723) (xy 15.0962 -409.19358)
			(xy 15.136349 -409.154871) (xy 15.181707 -409.12242) (xy 15.231307 -409.096919) (xy 15.284091 -409.078912)
			(xy 15.338934 -409.068782) (xy 15.394668 -409.066745) (xy 15.450105 -409.072845) (xy 15.504062 -409.086951)
			(xy 15.555391 -409.108763) (xy 15.602997 -409.137817) (xy 15.645865 -409.173492) (xy 15.683082 -409.215029)
			(xy 15.713855 -409.261542) (xy 15.737527 -409.312039) (xy 15.753595 -409.365446) (xy 15.761715 -409.420622)
			(xy 15.762224 -409.448508) (xy 15.761715 -409.476394) (xy 15.753595 -409.53157) (xy 15.737527 -409.584977)
			(xy 15.713855 -409.635474) (xy 15.683082 -409.681987) (xy 15.645865 -409.723524) (xy 15.602997 -409.759199)
			(xy 15.555391 -409.788253) (xy 15.504062 -409.810065) (xy 15.450105 -409.824171) (xy 15.394668 -409.830271)
			(xy 15.338934 -409.828234) (xy 15.284091 -409.818104) (xy 15.231307 -409.800097) (xy 15.181707 -409.774596)
			(xy 15.136349 -409.742145) (xy 15.0962 -409.703436) (xy 15.062114 -409.659293) (xy 15.034818 -409.610658)
			(xy 15.014895 -409.558567) (xy 15.002769 -409.50413) (xy 14.998698 -409.448508) (xy 10.932922 -409.448508)
			(xy 10.932922 -412.752286) (xy 17.883122 -412.752286) (xy 17.887193 -412.696664) (xy 17.899319 -412.642227)
			(xy 17.919242 -412.590136) (xy 17.946538 -412.541501) (xy 17.980624 -412.497358) (xy 18.020773 -412.458649)
			(xy 18.066131 -412.426198) (xy 18.115731 -412.400697) (xy 18.168515 -412.38269) (xy 18.223358 -412.37256)
			(xy 18.279092 -412.370523) (xy 18.334529 -412.376623) (xy 18.388486 -412.390729) (xy 18.439815 -412.412541)
			(xy 18.487421 -412.441595) (xy 18.530289 -412.47727) (xy 18.567506 -412.518807) (xy 18.598279 -412.56532)
			(xy 18.621951 -412.615817) (xy 18.638019 -412.669224) (xy 18.646139 -412.7244) (xy 18.646648 -412.752286)
			(xy 18.646139 -412.780172) (xy 18.638019 -412.835348) (xy 18.621951 -412.888755) (xy 18.598527 -412.938722)
			(xy 19.503896 -412.938722) (xy 19.507967 -412.8831) (xy 19.520093 -412.828663) (xy 19.540016 -412.776572)
			(xy 19.567312 -412.727937) (xy 19.601398 -412.683794) (xy 19.641547 -412.645085) (xy 19.686905 -412.612634)
			(xy 19.736505 -412.587133) (xy 19.789289 -412.569126) (xy 19.844132 -412.558996) (xy 19.899866 -412.556959)
			(xy 19.955303 -412.563059) (xy 20.00926 -412.577165) (xy 20.060589 -412.598977) (xy 20.108195 -412.628031)
			(xy 20.151063 -412.663706) (xy 20.1683 -412.682944) (xy 20.874988 -412.682944) (xy 20.879059 -412.627322)
			(xy 20.891185 -412.572885) (xy 20.911108 -412.520794) (xy 20.938404 -412.472159) (xy 20.97249 -412.428016)
			(xy 21.012639 -412.389307) (xy 21.057997 -412.356856) (xy 21.107597 -412.331355) (xy 21.160381 -412.313348)
			(xy 21.215224 -412.303218) (xy 21.270958 -412.301181) (xy 21.326395 -412.307281) (xy 21.380352 -412.321387)
			(xy 21.431681 -412.343199) (xy 21.479287 -412.372253) (xy 21.522155 -412.407928) (xy 21.559372 -412.449465)
			(xy 21.590145 -412.495978) (xy 21.613817 -412.546475) (xy 21.629885 -412.599882) (xy 21.638005 -412.655058)
			(xy 21.638514 -412.682944) (xy 21.638005 -412.71083) (xy 21.629885 -412.766006) (xy 21.613817 -412.819413)
			(xy 21.590145 -412.86991) (xy 21.559372 -412.916423) (xy 21.522155 -412.95796) (xy 21.479287 -412.993635)
			(xy 21.431681 -413.022689) (xy 21.380352 -413.044501) (xy 21.326395 -413.058607) (xy 21.270958 -413.064707)
			(xy 21.215224 -413.06267) (xy 21.160381 -413.05254) (xy 21.107597 -413.034533) (xy 21.057997 -413.009032)
			(xy 21.012639 -412.976581) (xy 20.97249 -412.937872) (xy 20.938404 -412.893729) (xy 20.911108 -412.845094)
			(xy 20.891185 -412.793003) (xy 20.879059 -412.738566) (xy 20.874988 -412.682944) (xy 20.1683 -412.682944)
			(xy 20.18828 -412.705243) (xy 20.219053 -412.751756) (xy 20.242725 -412.802253) (xy 20.258793 -412.85566)
			(xy 20.266913 -412.910836) (xy 20.267422 -412.938722) (xy 20.266913 -412.966608) (xy 20.258793 -413.021784)
			(xy 20.242725 -413.075191) (xy 20.219053 -413.125688) (xy 20.18828 -413.172201) (xy 20.151063 -413.213738)
			(xy 20.108195 -413.249413) (xy 20.060589 -413.278467) (xy 20.00926 -413.300279) (xy 19.955303 -413.314385)
			(xy 19.899866 -413.320485) (xy 19.844132 -413.318448) (xy 19.789289 -413.308318) (xy 19.736505 -413.290311)
			(xy 19.686905 -413.26481) (xy 19.641547 -413.232359) (xy 19.601398 -413.19365) (xy 19.567312 -413.149507)
			(xy 19.540016 -413.100872) (xy 19.520093 -413.048781) (xy 19.507967 -412.994344) (xy 19.503896 -412.938722)
			(xy 18.598527 -412.938722) (xy 18.598279 -412.939252) (xy 18.567506 -412.985765) (xy 18.530289 -413.027302)
			(xy 18.487421 -413.062977) (xy 18.439815 -413.092031) (xy 18.388486 -413.113843) (xy 18.334529 -413.127949)
			(xy 18.279092 -413.134049) (xy 18.223358 -413.132012) (xy 18.168515 -413.121882) (xy 18.115731 -413.103875)
			(xy 18.066131 -413.078374) (xy 18.020773 -413.045923) (xy 17.980624 -413.007214) (xy 17.946538 -412.963071)
			(xy 17.919242 -412.914436) (xy 17.899319 -412.862345) (xy 17.887193 -412.807908) (xy 17.883122 -412.752286)
			(xy 10.932922 -412.752286) (xy 10.932922 -413.752538) (xy 10.933353 -413.762605) (xy 10.941079 -413.781197)
			(xy 10.947908 -413.788606) (xy 12.144756 -414.985454) (xy 16.455896 -414.985454) (xy 16.459967 -414.929832)
			(xy 16.472093 -414.875395) (xy 16.492016 -414.823304) (xy 16.519312 -414.774669) (xy 16.553398 -414.730526)
			(xy 16.593547 -414.691817) (xy 16.638905 -414.659366) (xy 16.688505 -414.633865) (xy 16.741289 -414.615858)
			(xy 16.796132 -414.605728) (xy 16.851866 -414.603691) (xy 16.907303 -414.609791) (xy 16.96126 -414.623897)
			(xy 17.012589 -414.645709) (xy 17.060195 -414.674763) (xy 17.103063 -414.710438) (xy 17.14028 -414.751975)
			(xy 17.171053 -414.798488) (xy 17.194725 -414.848985) (xy 17.210793 -414.902392) (xy 17.218913 -414.957568)
			(xy 17.219422 -414.985454) (xy 18.487896 -414.985454) (xy 18.491967 -414.929832) (xy 18.504093 -414.875395)
			(xy 18.524016 -414.823304) (xy 18.551312 -414.774669) (xy 18.585398 -414.730526) (xy 18.625547 -414.691817)
			(xy 18.670905 -414.659366) (xy 18.720505 -414.633865) (xy 18.773289 -414.615858) (xy 18.828132 -414.605728)
			(xy 18.883866 -414.603691) (xy 18.939303 -414.609791) (xy 18.99326 -414.623897) (xy 19.044589 -414.645709)
			(xy 19.092195 -414.674763) (xy 19.135063 -414.710438) (xy 19.17228 -414.751975) (xy 19.203053 -414.798488)
			(xy 19.226725 -414.848985) (xy 19.242793 -414.902392) (xy 19.250913 -414.957568) (xy 19.251422 -414.985454)
			(xy 21.535896 -414.985454) (xy 21.539967 -414.929832) (xy 21.552093 -414.875395) (xy 21.572016 -414.823304)
			(xy 21.599312 -414.774669) (xy 21.633398 -414.730526) (xy 21.673547 -414.691817) (xy 21.718905 -414.659366)
			(xy 21.768505 -414.633865) (xy 21.821289 -414.615858) (xy 21.876132 -414.605728) (xy 21.931866 -414.603691)
			(xy 21.987303 -414.609791) (xy 22.04126 -414.623897) (xy 22.092589 -414.645709) (xy 22.140195 -414.674763)
			(xy 22.183063 -414.710438) (xy 22.22028 -414.751975) (xy 22.251053 -414.798488) (xy 22.274725 -414.848985)
			(xy 22.290793 -414.902392) (xy 22.298913 -414.957568) (xy 22.299422 -414.985454) (xy 22.298913 -415.01334)
			(xy 22.290793 -415.068516) (xy 22.274725 -415.121923) (xy 22.251053 -415.17242) (xy 22.22028 -415.218933)
			(xy 22.183063 -415.26047) (xy 22.140195 -415.296145) (xy 22.092589 -415.325199) (xy 22.04126 -415.347011)
			(xy 21.987303 -415.361117) (xy 21.931866 -415.367217) (xy 21.876132 -415.36518) (xy 21.821289 -415.35505)
			(xy 21.768505 -415.337043) (xy 21.718905 -415.311542) (xy 21.673547 -415.279091) (xy 21.633398 -415.240382)
			(xy 21.599312 -415.196239) (xy 21.572016 -415.147604) (xy 21.552093 -415.095513) (xy 21.539967 -415.041076)
			(xy 21.535896 -414.985454) (xy 19.251422 -414.985454) (xy 19.250913 -415.01334) (xy 19.242793 -415.068516)
			(xy 19.226725 -415.121923) (xy 19.203053 -415.17242) (xy 19.17228 -415.218933) (xy 19.135063 -415.26047)
			(xy 19.092195 -415.296145) (xy 19.044589 -415.325199) (xy 18.99326 -415.347011) (xy 18.939303 -415.361117)
			(xy 18.883866 -415.367217) (xy 18.828132 -415.36518) (xy 18.773289 -415.35505) (xy 18.720505 -415.337043)
			(xy 18.670905 -415.311542) (xy 18.625547 -415.279091) (xy 18.585398 -415.240382) (xy 18.551312 -415.196239)
			(xy 18.524016 -415.147604) (xy 18.504093 -415.095513) (xy 18.491967 -415.041076) (xy 18.487896 -414.985454)
			(xy 17.219422 -414.985454) (xy 17.218913 -415.01334) (xy 17.210793 -415.068516) (xy 17.194725 -415.121923)
			(xy 17.171053 -415.17242) (xy 17.14028 -415.218933) (xy 17.103063 -415.26047) (xy 17.060195 -415.296145)
			(xy 17.012589 -415.325199) (xy 16.96126 -415.347011) (xy 16.907303 -415.361117) (xy 16.851866 -415.367217)
			(xy 16.796132 -415.36518) (xy 16.741289 -415.35505) (xy 16.688505 -415.337043) (xy 16.638905 -415.311542)
			(xy 16.593547 -415.279091) (xy 16.553398 -415.240382) (xy 16.519312 -415.196239) (xy 16.492016 -415.147604)
			(xy 16.472093 -415.095513) (xy 16.459967 -415.041076) (xy 16.455896 -414.985454) (xy 12.144756 -414.985454)
			(xy 12.73429 -415.574988) (xy 12.741687 -415.581837) (xy 12.760285 -415.589577) (xy 12.770358 -415.589974)
		)
		(stroke
			(width 0)
			(type solid)
		)
		(fill yes)
		(layer "In5.Cu")
		(net "P3V3_AUX")
	)
	(gr_poly
		(pts
			(xy 9.936226 -363.648244) (xy 9.946293 -363.647815) (xy 9.964885 -363.640087) (xy 9.972294 -363.633258)
			(xy 11.200638 -362.404914) (xy 11.207478 -362.397514) (xy 11.21519 -362.378915) (xy 11.215624 -362.368846)
			(xy 11.215624 -328.712068) (xy 11.215768 -328.70732) (xy 11.217567 -328.697994) (xy 11.21918 -328.693526)
			(xy 14.332712 -320.805048) (xy 14.334399 -320.800535) (xy 14.336191 -320.791069) (xy 14.336268 -320.786252)
			(xy 14.336268 -320.098674) (xy 14.336771 -320.065387) (xy 14.345426 -319.999378) (xy 14.362623 -319.935064)
			(xy 14.374876 -319.90411) (xy 16.333978 -315.174122) (xy 16.335779 -315.169436) (xy 16.337702 -315.159584)
			(xy 16.337788 -315.154564) (xy 16.337788 -309.368698) (xy 16.33829 -309.336425) (xy 16.346463 -309.272397)
			(xy 16.362678 -309.20992) (xy 16.386673 -309.149999) (xy 16.418062 -309.093599) (xy 16.456341 -309.041627)
			(xy 16.47825 -309.017924) (xy 16.484605 -309.010659) (xy 16.491805 -308.992768) (xy 16.49222 -308.983126)
			(xy 16.49222 -307.637942) (xy 16.491769 -307.627279) (xy 16.4831 -307.607796) (xy 16.475456 -307.60035)
			(xy 16.411702 -307.542692) (xy 16.391382 -307.535834) (xy 16.38046 -307.537104) (xy 16.370456 -307.538078)
			(xy 16.350379 -307.539095) (xy 16.340328 -307.539136) (xy 16.30854 -307.538481) (xy 16.245852 -307.527881)
			(xy 16.215614 -307.518054) (xy 16.21536 -307.518054) (xy 16.214598 -307.5178) (xy 16.209154 -307.515744)
			(xy 16.199279 -307.509594) (xy 16.19504 -307.505608) (xy 15.45209 -306.762658) (xy 15.44524 -306.755262)
			(xy 15.437507 -306.736662) (xy 15.437104 -306.72659) (xy 15.437104 -304.982626) (xy 15.436569 -304.972264)
			(xy 15.428321 -304.953247) (xy 15.421102 -304.945796) (xy 15.359888 -304.88763) (xy 15.340584 -304.880518)
			(xy 15.329916 -304.88128) (xy 15.308326 -304.881788) (xy 15.281073 -304.881326) (xy 15.227122 -304.873573)
			(xy 15.174824 -304.85822) (xy 15.125243 -304.83558) (xy 15.079389 -304.806114) (xy 15.038196 -304.770423)
			(xy 15.002501 -304.729231) (xy 14.973032 -304.683379) (xy 14.950389 -304.6338) (xy 14.935033 -304.581503)
			(xy 14.927275 -304.527553) (xy 14.927275 -304.473047) (xy 14.935033 -304.419097) (xy 14.950389 -304.3668)
			(xy 14.973032 -304.317221) (xy 15.002501 -304.271369) (xy 15.038196 -304.230177) (xy 15.079389 -304.194486)
			(xy 15.125243 -304.16502) (xy 15.174824 -304.14238) (xy 15.227122 -304.127027) (xy 15.281073 -304.119274)
			(xy 15.308326 -304.118772) (xy 15.329916 -304.11928) (xy 15.340584 -304.120042) (xy 15.359888 -304.11293)
			(xy 15.421102 -304.054764) (xy 15.428329 -304.047316) (xy 15.436585 -304.028299) (xy 15.437104 -304.017934)
			(xy 15.437104 -299.711618) (xy 15.437581 -299.686338) (xy 15.445446 -299.636396) (xy 15.461019 -299.588295)
			(xy 15.483915 -299.543218) (xy 15.513573 -299.502272) (xy 15.531084 -299.484034) (xy 17.037304 -297.977814)
			(xy 17.044116 -297.970469) (xy 17.051853 -297.952007) (xy 17.05229 -297.942) (xy 17.05229 -292.339522)
			(xy 17.051852 -292.329458) (xy 17.044117 -292.310875) (xy 17.037304 -292.303454) (xy 16.682212 -291.948362)
			(xy 16.6751 -291.940996) (xy 16.656304 -291.933376) (xy 0.737362 -291.933376) (xy 0.727294 -291.933805)
			(xy 0.708698 -291.941527) (xy 0.701294 -291.948362) (xy 0.594106 -292.05555) (xy 0.587267 -292.062951)
			(xy 0.57955 -292.081549) (xy 0.57912 -292.091618) (xy 0.57912 -304.457354) (xy 7.652256 -304.457354)
			(xy 7.656327 -304.401732) (xy 7.668453 -304.347295) (xy 7.688376 -304.295204) (xy 7.715672 -304.246569)
			(xy 7.749758 -304.202426) (xy 7.789907 -304.163717) (xy 7.835265 -304.131266) (xy 7.884865 -304.105765)
			(xy 7.937649 -304.087758) (xy 7.992492 -304.077628) (xy 8.048226 -304.075591) (xy 8.103663 -304.081691)
			(xy 8.15762 -304.095797) (xy 8.208949 -304.117609) (xy 8.256555 -304.146663) (xy 8.299423 -304.182338)
			(xy 8.33664 -304.223875) (xy 8.367413 -304.270388) (xy 8.391085 -304.320885) (xy 8.407153 -304.374292)
			(xy 8.415273 -304.429468) (xy 8.415782 -304.457354) (xy 8.415273 -304.48524) (xy 8.407153 -304.540416)
			(xy 8.391085 -304.593823) (xy 8.367413 -304.64432) (xy 8.33664 -304.690833) (xy 8.299423 -304.73237)
			(xy 8.256555 -304.768045) (xy 8.208949 -304.797099) (xy 8.15762 -304.818911) (xy 8.103663 -304.833017)
			(xy 8.048226 -304.839117) (xy 7.992492 -304.83708) (xy 7.937649 -304.82695) (xy 7.884865 -304.808943)
			(xy 7.835265 -304.783442) (xy 7.789907 -304.750991) (xy 7.749758 -304.712282) (xy 7.715672 -304.668139)
			(xy 7.688376 -304.619504) (xy 7.668453 -304.567413) (xy 7.656327 -304.512976) (xy 7.652256 -304.457354)
			(xy 0.57912 -304.457354) (xy 0.57912 -305.159664) (xy 12.577824 -305.159664) (xy 12.581895 -305.104042)
			(xy 12.594021 -305.049605) (xy 12.613944 -304.997514) (xy 12.64124 -304.948879) (xy 12.675326 -304.904736)
			(xy 12.715475 -304.866027) (xy 12.760833 -304.833576) (xy 12.810433 -304.808075) (xy 12.863217 -304.790068)
			(xy 12.91806 -304.779938) (xy 12.973794 -304.777901) (xy 13.029231 -304.784001) (xy 13.083188 -304.798107)
			(xy 13.134517 -304.819919) (xy 13.182123 -304.848973) (xy 13.224991 -304.884648) (xy 13.262208 -304.926185)
			(xy 13.292981 -304.972698) (xy 13.316653 -305.023195) (xy 13.332721 -305.076602) (xy 13.340841 -305.131778)
			(xy 13.34135 -305.159664) (xy 13.340841 -305.18755) (xy 13.332721 -305.242726) (xy 13.316653 -305.296133)
			(xy 13.292981 -305.34663) (xy 13.262208 -305.393143) (xy 13.224991 -305.43468) (xy 13.182123 -305.470355)
			(xy 13.134517 -305.499409) (xy 13.083188 -305.521221) (xy 13.029231 -305.535327) (xy 12.973794 -305.541427)
			(xy 12.91806 -305.53939) (xy 12.863217 -305.52926) (xy 12.810433 -305.511253) (xy 12.760833 -305.485752)
			(xy 12.715475 -305.453301) (xy 12.675326 -305.414592) (xy 12.64124 -305.370449) (xy 12.613944 -305.321814)
			(xy 12.594021 -305.269723) (xy 12.581895 -305.215286) (xy 12.577824 -305.159664) (xy 0.57912 -305.159664)
			(xy 0.57912 -306.115466) (xy 13.635734 -306.115466) (xy 13.639805 -306.059844) (xy 13.651931 -306.005407)
			(xy 13.671854 -305.953316) (xy 13.69915 -305.904681) (xy 13.733236 -305.860538) (xy 13.773385 -305.821829)
			(xy 13.818743 -305.789378) (xy 13.868343 -305.763877) (xy 13.921127 -305.74587) (xy 13.97597 -305.73574)
			(xy 14.031704 -305.733703) (xy 14.087141 -305.739803) (xy 14.141098 -305.753909) (xy 14.192427 -305.775721)
			(xy 14.240033 -305.804775) (xy 14.282901 -305.84045) (xy 14.320118 -305.881987) (xy 14.350891 -305.9285)
			(xy 14.374563 -305.978997) (xy 14.390631 -306.032404) (xy 14.398751 -306.08758) (xy 14.39926 -306.115466)
			(xy 14.398751 -306.143352) (xy 14.390631 -306.198528) (xy 14.374563 -306.251935) (xy 14.350891 -306.302432)
			(xy 14.320118 -306.348945) (xy 14.282901 -306.390482) (xy 14.240033 -306.426157) (xy 14.192427 -306.455211)
			(xy 14.141098 -306.477023) (xy 14.087141 -306.491129) (xy 14.031704 -306.497229) (xy 13.97597 -306.495192)
			(xy 13.921127 -306.485062) (xy 13.868343 -306.467055) (xy 13.818743 -306.441554) (xy 13.773385 -306.409103)
			(xy 13.733236 -306.370394) (xy 13.69915 -306.326251) (xy 13.671854 -306.277616) (xy 13.651931 -306.225525)
			(xy 13.639805 -306.171088) (xy 13.635734 -306.115466) (xy 0.57912 -306.115466) (xy 0.57912 -307.621686)
			(xy 12.02385 -307.621686) (xy 12.027921 -307.566064) (xy 12.040047 -307.511627) (xy 12.05997 -307.459536)
			(xy 12.087266 -307.410901) (xy 12.121352 -307.366758) (xy 12.161501 -307.328049) (xy 12.206859 -307.295598)
			(xy 12.256459 -307.270097) (xy 12.309243 -307.25209) (xy 12.364086 -307.24196) (xy 12.41982 -307.239923)
			(xy 12.475257 -307.246023) (xy 12.529214 -307.260129) (xy 12.580543 -307.281941) (xy 12.628149 -307.310995)
			(xy 12.671017 -307.34667) (xy 12.708234 -307.388207) (xy 12.739007 -307.43472) (xy 12.750091 -307.458364)
			(xy 13.739366 -307.458364) (xy 13.743437 -307.402742) (xy 13.755563 -307.348305) (xy 13.775486 -307.296214)
			(xy 13.802782 -307.247579) (xy 13.836868 -307.203436) (xy 13.877017 -307.164727) (xy 13.922375 -307.132276)
			(xy 13.971975 -307.106775) (xy 14.024759 -307.088768) (xy 14.079602 -307.078638) (xy 14.135336 -307.076601)
			(xy 14.190773 -307.082701) (xy 14.24473 -307.096807) (xy 14.296059 -307.118619) (xy 14.343665 -307.147673)
			(xy 14.386533 -307.183348) (xy 14.42375 -307.224885) (xy 14.454523 -307.271398) (xy 14.478195 -307.321895)
			(xy 14.494263 -307.375302) (xy 14.502383 -307.430478) (xy 14.502892 -307.458364) (xy 14.502383 -307.48625)
			(xy 14.494263 -307.541426) (xy 14.478195 -307.594833) (xy 14.454523 -307.64533) (xy 14.42375 -307.691843)
			(xy 14.386533 -307.73338) (xy 14.343665 -307.769055) (xy 14.296059 -307.798109) (xy 14.24473 -307.819921)
			(xy 14.190773 -307.834027) (xy 14.135336 -307.840127) (xy 14.079602 -307.83809) (xy 14.024759 -307.82796)
			(xy 13.971975 -307.809953) (xy 13.922375 -307.784452) (xy 13.877017 -307.752001) (xy 13.836868 -307.713292)
			(xy 13.802782 -307.669149) (xy 13.775486 -307.620514) (xy 13.755563 -307.568423) (xy 13.743437 -307.513986)
			(xy 13.739366 -307.458364) (xy 12.750091 -307.458364) (xy 12.762679 -307.485217) (xy 12.778747 -307.538624)
			(xy 12.786867 -307.5938) (xy 12.787376 -307.621686) (xy 12.786867 -307.649572) (xy 12.778747 -307.704748)
			(xy 12.762679 -307.758155) (xy 12.739007 -307.808652) (xy 12.708234 -307.855165) (xy 12.671017 -307.896702)
			(xy 12.628149 -307.932377) (xy 12.580543 -307.961431) (xy 12.529214 -307.983243) (xy 12.475257 -307.997349)
			(xy 12.41982 -308.003449) (xy 12.364086 -308.001412) (xy 12.309243 -307.991282) (xy 12.256459 -307.973275)
			(xy 12.206859 -307.947774) (xy 12.161501 -307.915323) (xy 12.121352 -307.876614) (xy 12.087266 -307.832471)
			(xy 12.05997 -307.783836) (xy 12.040047 -307.731745) (xy 12.027921 -307.677308) (xy 12.02385 -307.621686)
			(xy 0.57912 -307.621686) (xy 0.57912 -308.929024) (xy 13.201648 -308.929024) (xy 13.205719 -308.873402)
			(xy 13.217845 -308.818965) (xy 13.237768 -308.766874) (xy 13.265064 -308.718239) (xy 13.29915 -308.674096)
			(xy 13.339299 -308.635387) (xy 13.384657 -308.602936) (xy 13.434257 -308.577435) (xy 13.487041 -308.559428)
			(xy 13.541884 -308.549298) (xy 13.597618 -308.547261) (xy 13.653055 -308.553361) (xy 13.707012 -308.567467)
			(xy 13.758341 -308.589279) (xy 13.805947 -308.618333) (xy 13.848815 -308.654008) (xy 13.886032 -308.695545)
			(xy 13.916805 -308.742058) (xy 13.940477 -308.792555) (xy 13.956545 -308.845962) (xy 13.964665 -308.901138)
			(xy 13.965174 -308.929024) (xy 13.964665 -308.95691) (xy 13.956545 -309.012086) (xy 13.940477 -309.065493)
			(xy 13.916805 -309.11599) (xy 13.886032 -309.162503) (xy 13.848815 -309.20404) (xy 13.805947 -309.239715)
			(xy 13.758341 -309.268769) (xy 13.707012 -309.290581) (xy 13.653055 -309.304687) (xy 13.597618 -309.310787)
			(xy 13.541884 -309.30875) (xy 13.487041 -309.29862) (xy 13.434257 -309.280613) (xy 13.384657 -309.255112)
			(xy 13.339299 -309.222661) (xy 13.29915 -309.183952) (xy 13.265064 -309.139809) (xy 13.237768 -309.091174)
			(xy 13.217845 -309.039083) (xy 13.205719 -308.984646) (xy 13.201648 -308.929024) (xy 0.57912 -308.929024)
			(xy 0.57912 -318.52997) (xy 10.590784 -318.52997) (xy 10.591212 -318.502598) (xy 10.599036 -318.448417)
			(xy 10.614533 -318.395912) (xy 10.637383 -318.346166) (xy 10.667118 -318.300202) (xy 10.684764 -318.279272)
			(xy 10.69086 -318.27216) (xy 10.69721 -318.255142) (xy 10.69721 -318.169798) (xy 10.69086 -318.15278)
			(xy 10.684764 -318.145668) (xy 10.667138 -318.124726) (xy 10.637425 -318.078755) (xy 10.614587 -318.02901)
			(xy 10.599093 -317.976512) (xy 10.591261 -317.922338) (xy 10.590784 -317.89497) (xy 10.59125 -317.867718)
			(xy 10.59901 -317.81377) (xy 10.614369 -317.761476) (xy 10.637013 -317.711899) (xy 10.666482 -317.666049)
			(xy 10.702175 -317.624859) (xy 10.743367 -317.589168) (xy 10.789218 -317.559702) (xy 10.838796 -317.537061)
			(xy 10.891092 -317.521706) (xy 10.94504 -317.513948) (xy 10.972292 -317.513462) (xy 10.999663 -317.513918)
			(xy 11.053843 -317.521736) (xy 11.106347 -317.537226) (xy 11.156093 -317.560071) (xy 11.202059 -317.589799)
			(xy 11.22299 -317.607442) (xy 11.230102 -317.613538) (xy 11.24712 -317.619888) (xy 11.332464 -317.619888)
			(xy 11.349482 -317.613538) (xy 11.356594 -317.607442) (xy 11.377527 -317.589801) (xy 11.423495 -317.560077)
			(xy 11.473241 -317.537231) (xy 11.525743 -317.521735) (xy 11.579921 -317.513906) (xy 11.634663 -317.513906)
			(xy 11.688841 -317.521735) (xy 11.741343 -317.537231) (xy 11.791089 -317.560077) (xy 11.837057 -317.589801)
			(xy 11.85799 -317.607442) (xy 11.865102 -317.613538) (xy 11.88212 -317.619888) (xy 11.967464 -317.619888)
			(xy 11.984482 -317.613538) (xy 11.991594 -317.607442) (xy 12.012523 -317.589799) (xy 12.058496 -317.560086)
			(xy 12.108244 -317.53725) (xy 12.160746 -317.52176) (xy 12.214922 -317.513934) (xy 12.242292 -317.513462)
			(xy 12.269542 -317.513985) (xy 12.323487 -317.52174) (xy 12.375779 -317.537092) (xy 12.425354 -317.55973)
			(xy 12.471203 -317.589193) (xy 12.512393 -317.624881) (xy 12.548084 -317.666067) (xy 12.577551 -317.711913)
			(xy 12.600194 -317.761486) (xy 12.615552 -317.813776) (xy 12.623312 -317.86772) (xy 12.6238 -317.89497)
			(xy 12.623316 -317.92234) (xy 12.615503 -317.976518) (xy 12.600018 -318.029021) (xy 12.57718 -318.078768)
			(xy 12.547459 -318.124736) (xy 12.52982 -318.145668) (xy 12.523724 -318.15278) (xy 12.517374 -318.169798)
			(xy 12.517374 -318.255142) (xy 12.523724 -318.27216) (xy 12.52982 -318.279272) (xy 12.547463 -318.300201)
			(xy 12.577173 -318.346175) (xy 12.600008 -318.395923) (xy 12.615498 -318.448425) (xy 12.623326 -318.502601)
			(xy 12.6238 -318.52997) (xy 12.623317 -318.557222) (xy 12.615564 -318.611173) (xy 12.600211 -318.663471)
			(xy 12.577571 -318.713052) (xy 12.548106 -318.758905) (xy 12.512414 -318.800099) (xy 12.471223 -318.835793)
			(xy 12.425371 -318.865261) (xy 12.375792 -318.887903) (xy 12.323495 -318.903259) (xy 12.269544 -318.911015)
			(xy 12.242292 -318.911478) (xy 12.214921 -318.911022) (xy 12.160742 -318.903203) (xy 12.108238 -318.887711)
			(xy 12.058491 -318.864867) (xy 12.012525 -318.83514) (xy 11.991594 -318.817498) (xy 11.984482 -318.811402)
			(xy 11.967464 -318.805052) (xy 11.88212 -318.805052) (xy 11.865102 -318.811402) (xy 11.85799 -318.817498)
			(xy 11.837057 -318.835139) (xy 11.791089 -318.864863) (xy 11.741343 -318.887709) (xy 11.688841 -318.903205)
			(xy 11.634663 -318.911034) (xy 11.579921 -318.911034) (xy 11.525743 -318.903205) (xy 11.473241 -318.887709)
			(xy 11.423495 -318.864863) (xy 11.377527 -318.835139) (xy 11.356594 -318.817498) (xy 11.349482 -318.811402)
			(xy 11.332464 -318.805052) (xy 11.24712 -318.805052) (xy 11.230102 -318.811402) (xy 11.22299 -318.817498)
			(xy 11.202072 -318.835155) (xy 11.156096 -318.864864) (xy 11.106344 -318.887697) (xy 11.053841 -318.903184)
			(xy 10.999662 -318.911007) (xy 10.972292 -318.911478) (xy 10.945038 -318.911052) (xy 10.891084 -318.903293)
			(xy 10.838783 -318.887935) (xy 10.789201 -318.865289) (xy 10.743347 -318.835817) (xy 10.702153 -318.80012)
			(xy 10.66646 -318.758923) (xy 10.636993 -318.713065) (xy 10.614352 -318.663481) (xy 10.598999 -318.611179)
			(xy 10.591245 -318.557224) (xy 10.590784 -318.52997) (xy 0.57912 -318.52997) (xy 0.57912 -348.976496)
			(xy 4.708641 -348.976496) (xy 4.708641 -348.847356) (xy 4.716591 -348.718461) (xy 4.732461 -348.590301)
			(xy 4.75619 -348.46336) (xy 4.787689 -348.338121) (xy 4.826838 -348.215058) (xy 4.873489 -348.094639)
			(xy 4.927464 -347.97732) (xy 4.988559 -347.863546) (xy 5.056542 -347.753749) (xy 5.131156 -347.648346)
			(xy 5.212117 -347.547736) (xy 5.299117 -347.452301) (xy 5.391828 -347.362402) (xy 5.489898 -347.278381)
			(xy 5.592953 -347.200557) (xy 5.700604 -347.129225) (xy 5.812443 -347.064655) (xy 5.928044 -347.007093)
			(xy 6.046969 -346.956756) (xy 6.168768 -346.913836) (xy 6.292978 -346.878495) (xy 6.419127 -346.850868)
			(xy 6.546739 -346.831059) (xy 6.675328 -346.819143) (xy 6.804406 -346.815167) (xy 6.933484 -346.819143)
			(xy 7.062073 -346.831059) (xy 7.189685 -346.850868) (xy 7.315834 -346.878495) (xy 7.440044 -346.913836)
			(xy 7.561843 -346.956756) (xy 7.680768 -347.007093) (xy 7.796369 -347.064655) (xy 7.908208 -347.129225)
			(xy 8.015859 -347.200557) (xy 8.118914 -347.278381) (xy 8.216984 -347.362402) (xy 8.309695 -347.452301)
			(xy 8.396695 -347.547736) (xy 8.477656 -347.648346) (xy 8.55227 -347.753749) (xy 8.620253 -347.863546)
			(xy 8.681348 -347.97732) (xy 8.735323 -348.094639) (xy 8.781974 -348.215058) (xy 8.821123 -348.338121)
			(xy 8.852622 -348.46336) (xy 8.876351 -348.590301) (xy 8.892221 -348.718461) (xy 8.900171 -348.847356)
			(xy 8.900668 -348.911926) (xy 8.900171 -348.976496) (xy 8.892221 -349.105391) (xy 8.876351 -349.233551)
			(xy 8.852622 -349.360492) (xy 8.821123 -349.485731) (xy 8.781974 -349.608794) (xy 8.735323 -349.729213)
			(xy 8.681348 -349.846532) (xy 8.620253 -349.960306) (xy 8.55227 -350.070103) (xy 8.477656 -350.175506)
			(xy 8.396695 -350.276116) (xy 8.309695 -350.371551) (xy 8.216984 -350.46145) (xy 8.118914 -350.545471)
			(xy 8.015859 -350.623295) (xy 7.908208 -350.694627) (xy 7.796369 -350.759197) (xy 7.680768 -350.816759)
			(xy 7.561843 -350.867096) (xy 7.440044 -350.910016) (xy 7.315834 -350.945357) (xy 7.189685 -350.972984)
			(xy 7.062073 -350.992793) (xy 6.933484 -351.004709) (xy 6.804406 -351.008686) (xy 6.675328 -351.004709)
			(xy 6.546739 -350.992793) (xy 6.419127 -350.972984) (xy 6.292978 -350.945357) (xy 6.168768 -350.910016)
			(xy 6.046969 -350.867096) (xy 5.928044 -350.816759) (xy 5.812443 -350.759197) (xy 5.700604 -350.694627)
			(xy 5.592953 -350.623295) (xy 5.489898 -350.545471) (xy 5.391828 -350.46145) (xy 5.299117 -350.371551)
			(xy 5.212117 -350.276116) (xy 5.131156 -350.175506) (xy 5.056542 -350.070103) (xy 4.988559 -349.960306)
			(xy 4.927464 -349.846532) (xy 4.873489 -349.729213) (xy 4.826838 -349.608794) (xy 4.787689 -349.485731)
			(xy 4.75619 -349.360492) (xy 4.732461 -349.233551) (xy 4.716591 -349.105391) (xy 4.708641 -348.976496)
			(xy 0.57912 -348.976496) (xy 0.57912 -363.031786) (xy 0.57955 -363.041853) (xy 0.587276 -363.060446)
			(xy 0.594106 -363.067854) (xy 1.15951 -363.633258) (xy 1.166907 -363.640107) (xy 1.185505 -363.647845)
			(xy 1.195578 -363.648244)
		)
		(stroke
			(width 0)
			(type solid)
		)
		(fill yes)
		(layer "In5.Cu")
		(net "GND")
	)
	(gr_poly
		(pts
			(xy 259.946648 -301.257462) (xy 259.951667 -301.25737) (xy 259.961519 -301.255449) (xy 259.966206 -301.253652)
			(xy 260.037072 -301.224188) (xy 260.041635 -301.22218) (xy 260.04995 -301.216681) (xy 260.053582 -301.213266)
			(xy 260.398514 -300.868334) (xy 260.405359 -300.860936) (xy 260.413083 -300.842337) (xy 260.4135 -300.832266)
			(xy 260.4135 -300.564804) (xy 260.420311 -300.557459) (xy 260.428045 -300.538997) (xy 260.428486 -300.52899)
			(xy 260.428486 -299.345604) (xy 260.426962 -299.333158) (xy 260.422644 -299.315886) (xy 260.41985 -299.310552)
			(xy 260.406134 -299.283074) (xy 260.386683 -299.224827) (xy 260.376797 -299.164218) (xy 260.376162 -299.133514)
			(xy 260.376793 -299.102809) (xy 260.386664 -299.042196) (xy 260.406122 -298.983949) (xy 260.41985 -298.956476)
			(xy 260.422644 -298.951142) (xy 260.426962 -298.93387) (xy 260.428486 -298.921424) (xy 260.428486 -296.145204)
			(xy 260.426962 -296.132758) (xy 260.422644 -296.115486) (xy 260.41985 -296.110152) (xy 260.406134 -296.082674)
			(xy 260.386683 -296.024427) (xy 260.376797 -295.963818) (xy 260.376162 -295.933114) (xy 260.376793 -295.902409)
			(xy 260.386664 -295.841796) (xy 260.406122 -295.783549) (xy 260.41985 -295.756076) (xy 260.422644 -295.750742)
			(xy 260.426962 -295.73347) (xy 260.428486 -295.721024) (xy 260.428486 -292.944804) (xy 260.426962 -292.932358)
			(xy 260.422644 -292.915086) (xy 260.41985 -292.909752) (xy 260.406134 -292.882274) (xy 260.386683 -292.824027)
			(xy 260.376797 -292.763418) (xy 260.376162 -292.732714) (xy 260.376793 -292.702009) (xy 260.386664 -292.641396)
			(xy 260.406122 -292.583149) (xy 260.41985 -292.555676) (xy 260.422644 -292.550342) (xy 260.426962 -292.53307)
			(xy 260.428486 -292.520624) (xy 260.428486 -289.744404) (xy 260.426962 -289.731958) (xy 260.422644 -289.714686)
			(xy 260.41985 -289.709352) (xy 260.406134 -289.681874) (xy 260.386683 -289.623627) (xy 260.376797 -289.563018)
			(xy 260.376162 -289.532314) (xy 260.376793 -289.501609) (xy 260.386664 -289.440996) (xy 260.406122 -289.382749)
			(xy 260.41985 -289.355276) (xy 260.422644 -289.349942) (xy 260.426962 -289.33267) (xy 260.428486 -289.320224)
			(xy 260.428486 -286.544004) (xy 260.426962 -286.531558) (xy 260.422644 -286.514286) (xy 260.41985 -286.508952)
			(xy 260.406134 -286.481474) (xy 260.386683 -286.423227) (xy 260.376797 -286.362618) (xy 260.376162 -286.331914)
			(xy 260.376793 -286.301209) (xy 260.386664 -286.240596) (xy 260.406122 -286.182349) (xy 260.41985 -286.154876)
			(xy 260.422644 -286.149542) (xy 260.426962 -286.13227) (xy 260.428486 -286.119824) (xy 260.428486 -283.575252)
			(xy 260.428133 -283.566563) (xy 260.422279 -283.550202) (xy 260.417056 -283.543248) (xy 260.413754 -283.539438)
			(xy 260.27888 -283.404564) (xy 260.271521 -283.397922) (xy 260.25322 -283.390355) (xy 260.24332 -283.389832)
			(xy 260.207252 -283.389578) (xy 260.169914 -283.389324) (xy 260.160469 -283.39008) (xy 260.14311 -283.397646)
			(xy 260.136132 -283.404056) (xy 260.114801 -283.424195) (xy 260.067104 -283.458344) (xy 260.014743 -283.484792)
			(xy 259.958952 -283.502917) (xy 259.901044 -283.512291) (xy 259.871718 -283.513022) (xy 259.869432 -283.513022)
			(xy 259.8424 -283.512583) (xy 259.78887 -283.505016) (xy 259.736944 -283.489972) (xy 259.687659 -283.467752)
			(xy 259.642002 -283.4388) (xy 259.600887 -283.403697) (xy 259.565136 -283.363143) (xy 259.5499 -283.34081)
			(xy 259.54262 -283.330714) (xy 259.520912 -283.318595) (xy 259.508498 -283.317696) (xy 258.755134 -283.317696)
			(xy 258.75488 -283.317696) (xy 258.747073 -283.318025) (xy 258.732209 -283.322815) (xy 258.72567 -283.327094)
			(xy 258.710712 -283.351505) (xy 258.674717 -283.396021) (xy 258.632532 -283.434722) (xy 258.585086 -283.466758)
			(xy 258.533423 -283.491422) (xy 258.478681 -283.508173) (xy 258.422062 -283.516641) (xy 258.364814 -283.516641)
			(xy 258.308195 -283.508173) (xy 258.253453 -283.491422) (xy 258.20179 -283.466758) (xy 258.154344 -283.434722)
			(xy 258.112159 -283.396021) (xy 258.076164 -283.351505) (xy 258.061206 -283.327094) (xy 258.054677 -283.322797)
			(xy 258.039806 -283.318012) (xy 258.031996 -283.317696) (xy 257.966464 -283.317696) (xy 257.956461 -283.31819)
			(xy 257.937981 -283.325856) (xy 257.923838 -283.340008) (xy 257.916184 -283.358493) (xy 257.915664 -283.368496)
			(xy 257.915664 -286.028638) (xy 257.916184 -286.039138) (xy 257.924581 -286.058386) (xy 257.939963 -286.072682)
			(xy 257.9497 -286.076644) (xy 258.040124 -286.108394) (xy 258.050157 -286.111354) (xy 258.071 -286.109836)
			(xy 258.089539 -286.100189) (xy 258.096512 -286.092392) (xy 258.114731 -286.070637) (xy 258.156507 -286.032239)
			(xy 258.203509 -286.000449) (xy 258.2547 -285.975971) (xy 258.308951 -285.959342) (xy 258.365067 -285.95093)
			(xy 258.393438 -285.950406) (xy 258.420686 -285.950895) (xy 258.474628 -285.958655) (xy 258.526916 -285.974013)
			(xy 258.576487 -285.996656) (xy 258.622331 -286.026122) (xy 258.663515 -286.061812) (xy 258.699201 -286.103)
			(xy 258.728663 -286.148847) (xy 258.7513 -286.198419) (xy 258.766653 -286.250709) (xy 258.774408 -286.304652)
			(xy 258.774408 -286.331914) (xy 259.486906 -286.331914) (xy 259.490977 -286.276292) (xy 259.503103 -286.221855)
			(xy 259.523026 -286.169764) (xy 259.550322 -286.121129) (xy 259.584408 -286.076986) (xy 259.624557 -286.038277)
			(xy 259.669915 -286.005826) (xy 259.719515 -285.980325) (xy 259.772299 -285.962318) (xy 259.827142 -285.952188)
			(xy 259.882876 -285.950151) (xy 259.938313 -285.956251) (xy 259.99227 -285.970357) (xy 260.043599 -285.992169)
			(xy 260.091205 -286.021223) (xy 260.134073 -286.056898) (xy 260.17129 -286.098435) (xy 260.202063 -286.144948)
			(xy 260.225735 -286.195445) (xy 260.241803 -286.248852) (xy 260.249923 -286.304028) (xy 260.250432 -286.331914)
			(xy 260.249923 -286.3598) (xy 260.241803 -286.414976) (xy 260.225735 -286.468383) (xy 260.202063 -286.51888)
			(xy 260.17129 -286.565393) (xy 260.134073 -286.60693) (xy 260.091205 -286.642605) (xy 260.043599 -286.671659)
			(xy 259.99227 -286.693471) (xy 259.938313 -286.707577) (xy 259.882876 -286.713677) (xy 259.827142 -286.71164)
			(xy 259.772299 -286.70151) (xy 259.719515 -286.683503) (xy 259.669915 -286.658002) (xy 259.624557 -286.625551)
			(xy 259.584408 -286.586842) (xy 259.550322 -286.542699) (xy 259.523026 -286.494064) (xy 259.503103 -286.441973)
			(xy 259.490977 -286.387536) (xy 259.486906 -286.331914) (xy 258.774408 -286.331914) (xy 258.774408 -286.359148)
			(xy 258.766653 -286.413091) (xy 258.7513 -286.465381) (xy 258.728663 -286.514953) (xy 258.699201 -286.5608)
			(xy 258.663515 -286.601988) (xy 258.622331 -286.637678) (xy 258.576487 -286.667144) (xy 258.526916 -286.689787)
			(xy 258.474628 -286.705145) (xy 258.420686 -286.712905) (xy 258.393438 -286.713422) (xy 258.365065 -286.712905)
			(xy 258.308945 -286.704503) (xy 258.254689 -286.68788) (xy 258.203495 -286.663402) (xy 258.156492 -286.631609)
			(xy 258.114718 -286.593204) (xy 258.096512 -286.571436) (xy 258.089557 -286.563602) (xy 258.07102 -286.553891)
			(xy 258.050148 -286.552397) (xy 258.040124 -286.555434) (xy 257.9497 -286.587184) (xy 257.939951 -286.591132)
			(xy 257.924546 -286.60542) (xy 257.916159 -286.624684) (xy 257.915664 -286.63519) (xy 257.915664 -289.229038)
			(xy 257.916184 -289.239538) (xy 257.924581 -289.258786) (xy 257.939963 -289.273082) (xy 257.9497 -289.277044)
			(xy 258.040124 -289.308794) (xy 258.050157 -289.311754) (xy 258.071 -289.310236) (xy 258.089539 -289.300589)
			(xy 258.096512 -289.292792) (xy 258.114731 -289.271037) (xy 258.156507 -289.232639) (xy 258.203509 -289.200849)
			(xy 258.2547 -289.176371) (xy 258.308951 -289.159742) (xy 258.365067 -289.15133) (xy 258.393438 -289.150806)
			(xy 258.420686 -289.151295) (xy 258.474628 -289.159055) (xy 258.526916 -289.174413) (xy 258.576487 -289.197056)
			(xy 258.622331 -289.226522) (xy 258.663515 -289.262212) (xy 258.699201 -289.3034) (xy 258.728663 -289.349247)
			(xy 258.7513 -289.398819) (xy 258.766653 -289.451109) (xy 258.774408 -289.505052) (xy 258.774408 -289.532314)
			(xy 259.486906 -289.532314) (xy 259.490977 -289.476692) (xy 259.503103 -289.422255) (xy 259.523026 -289.370164)
			(xy 259.550322 -289.321529) (xy 259.584408 -289.277386) (xy 259.624557 -289.238677) (xy 259.669915 -289.206226)
			(xy 259.719515 -289.180725) (xy 259.772299 -289.162718) (xy 259.827142 -289.152588) (xy 259.882876 -289.150551)
			(xy 259.938313 -289.156651) (xy 259.99227 -289.170757) (xy 260.043599 -289.192569) (xy 260.091205 -289.221623)
			(xy 260.134073 -289.257298) (xy 260.17129 -289.298835) (xy 260.202063 -289.345348) (xy 260.225735 -289.395845)
			(xy 260.241803 -289.449252) (xy 260.249923 -289.504428) (xy 260.250432 -289.532314) (xy 260.249923 -289.5602)
			(xy 260.241803 -289.615376) (xy 260.225735 -289.668783) (xy 260.202063 -289.71928) (xy 260.17129 -289.765793)
			(xy 260.134073 -289.80733) (xy 260.091205 -289.843005) (xy 260.043599 -289.872059) (xy 259.99227 -289.893871)
			(xy 259.938313 -289.907977) (xy 259.882876 -289.914077) (xy 259.827142 -289.91204) (xy 259.772299 -289.90191)
			(xy 259.719515 -289.883903) (xy 259.669915 -289.858402) (xy 259.624557 -289.825951) (xy 259.584408 -289.787242)
			(xy 259.550322 -289.743099) (xy 259.523026 -289.694464) (xy 259.503103 -289.642373) (xy 259.490977 -289.587936)
			(xy 259.486906 -289.532314) (xy 258.774408 -289.532314) (xy 258.774408 -289.559548) (xy 258.766653 -289.613491)
			(xy 258.7513 -289.665781) (xy 258.728663 -289.715353) (xy 258.699201 -289.7612) (xy 258.663515 -289.802388)
			(xy 258.622331 -289.838078) (xy 258.576487 -289.867544) (xy 258.526916 -289.890187) (xy 258.474628 -289.905545)
			(xy 258.420686 -289.913305) (xy 258.393438 -289.913822) (xy 258.365065 -289.913305) (xy 258.308945 -289.904903)
			(xy 258.254689 -289.88828) (xy 258.203495 -289.863802) (xy 258.156492 -289.832009) (xy 258.114718 -289.793604)
			(xy 258.096512 -289.771836) (xy 258.089557 -289.764002) (xy 258.07102 -289.754291) (xy 258.050148 -289.752797)
			(xy 258.040124 -289.755834) (xy 257.9497 -289.787584) (xy 257.939951 -289.791532) (xy 257.924546 -289.80582)
			(xy 257.916159 -289.825084) (xy 257.915664 -289.83559) (xy 257.915664 -292.429438) (xy 257.916184 -292.439938)
			(xy 257.924581 -292.459186) (xy 257.939963 -292.473482) (xy 257.9497 -292.477444) (xy 258.040124 -292.509194)
			(xy 258.050157 -292.512154) (xy 258.071 -292.510636) (xy 258.089539 -292.500989) (xy 258.096512 -292.493192)
			(xy 258.114731 -292.471437) (xy 258.156507 -292.433039) (xy 258.203509 -292.401249) (xy 258.2547 -292.376771)
			(xy 258.308951 -292.360142) (xy 258.365067 -292.35173) (xy 258.393438 -292.351206) (xy 258.420686 -292.351695)
			(xy 258.474628 -292.359455) (xy 258.526916 -292.374813) (xy 258.576487 -292.397456) (xy 258.622331 -292.426922)
			(xy 258.663515 -292.462612) (xy 258.699201 -292.5038) (xy 258.728663 -292.549647) (xy 258.7513 -292.599219)
			(xy 258.766653 -292.651509) (xy 258.774408 -292.705452) (xy 258.774408 -292.732714) (xy 259.486906 -292.732714)
			(xy 259.490977 -292.677092) (xy 259.503103 -292.622655) (xy 259.523026 -292.570564) (xy 259.550322 -292.521929)
			(xy 259.584408 -292.477786) (xy 259.624557 -292.439077) (xy 259.669915 -292.406626) (xy 259.719515 -292.381125)
			(xy 259.772299 -292.363118) (xy 259.827142 -292.352988) (xy 259.882876 -292.350951) (xy 259.938313 -292.357051)
			(xy 259.99227 -292.371157) (xy 260.043599 -292.392969) (xy 260.091205 -292.422023) (xy 260.134073 -292.457698)
			(xy 260.17129 -292.499235) (xy 260.202063 -292.545748) (xy 260.225735 -292.596245) (xy 260.241803 -292.649652)
			(xy 260.249923 -292.704828) (xy 260.250432 -292.732714) (xy 260.249923 -292.7606) (xy 260.241803 -292.815776)
			(xy 260.225735 -292.869183) (xy 260.202063 -292.91968) (xy 260.17129 -292.966193) (xy 260.134073 -293.00773)
			(xy 260.091205 -293.043405) (xy 260.043599 -293.072459) (xy 259.99227 -293.094271) (xy 259.938313 -293.108377)
			(xy 259.882876 -293.114477) (xy 259.827142 -293.11244) (xy 259.772299 -293.10231) (xy 259.719515 -293.084303)
			(xy 259.669915 -293.058802) (xy 259.624557 -293.026351) (xy 259.584408 -292.987642) (xy 259.550322 -292.943499)
			(xy 259.523026 -292.894864) (xy 259.503103 -292.842773) (xy 259.490977 -292.788336) (xy 259.486906 -292.732714)
			(xy 258.774408 -292.732714) (xy 258.774408 -292.759948) (xy 258.766653 -292.813891) (xy 258.7513 -292.866181)
			(xy 258.728663 -292.915753) (xy 258.699201 -292.9616) (xy 258.663515 -293.002788) (xy 258.622331 -293.038478)
			(xy 258.576487 -293.067944) (xy 258.526916 -293.090587) (xy 258.474628 -293.105945) (xy 258.420686 -293.113705)
			(xy 258.393438 -293.114222) (xy 258.365065 -293.113705) (xy 258.308945 -293.105303) (xy 258.254689 -293.08868)
			(xy 258.203495 -293.064202) (xy 258.156492 -293.032409) (xy 258.114718 -292.994004) (xy 258.096512 -292.972236)
			(xy 258.089557 -292.964402) (xy 258.07102 -292.954691) (xy 258.050148 -292.953197) (xy 258.040124 -292.956234)
			(xy 257.9497 -292.987984) (xy 257.939951 -292.991932) (xy 257.924546 -293.00622) (xy 257.916159 -293.025484)
			(xy 257.915664 -293.03599) (xy 257.915664 -295.629838) (xy 257.916184 -295.640338) (xy 257.924581 -295.659586)
			(xy 257.939963 -295.673882) (xy 257.9497 -295.677844) (xy 258.040124 -295.709594) (xy 258.050157 -295.712554)
			(xy 258.071 -295.711036) (xy 258.089539 -295.701389) (xy 258.096512 -295.693592) (xy 258.114731 -295.671837)
			(xy 258.156507 -295.633439) (xy 258.203509 -295.601649) (xy 258.2547 -295.577171) (xy 258.308951 -295.560542)
			(xy 258.365067 -295.55213) (xy 258.393438 -295.551606) (xy 258.420686 -295.552095) (xy 258.474628 -295.559855)
			(xy 258.526916 -295.575213) (xy 258.576487 -295.597856) (xy 258.622331 -295.627322) (xy 258.663515 -295.663012)
			(xy 258.699201 -295.7042) (xy 258.728663 -295.750047) (xy 258.7513 -295.799619) (xy 258.766653 -295.851909)
			(xy 258.774408 -295.905852) (xy 258.774408 -295.933114) (xy 259.486906 -295.933114) (xy 259.490977 -295.877492)
			(xy 259.503103 -295.823055) (xy 259.523026 -295.770964) (xy 259.550322 -295.722329) (xy 259.584408 -295.678186)
			(xy 259.624557 -295.639477) (xy 259.669915 -295.607026) (xy 259.719515 -295.581525) (xy 259.772299 -295.563518)
			(xy 259.827142 -295.553388) (xy 259.882876 -295.551351) (xy 259.938313 -295.557451) (xy 259.99227 -295.571557)
			(xy 260.043599 -295.593369) (xy 260.091205 -295.622423) (xy 260.134073 -295.658098) (xy 260.17129 -295.699635)
			(xy 260.202063 -295.746148) (xy 260.225735 -295.796645) (xy 260.241803 -295.850052) (xy 260.249923 -295.905228)
			(xy 260.250432 -295.933114) (xy 260.249923 -295.961) (xy 260.241803 -296.016176) (xy 260.225735 -296.069583)
			(xy 260.202063 -296.12008) (xy 260.17129 -296.166593) (xy 260.134073 -296.20813) (xy 260.091205 -296.243805)
			(xy 260.043599 -296.272859) (xy 259.99227 -296.294671) (xy 259.938313 -296.308777) (xy 259.882876 -296.314877)
			(xy 259.827142 -296.31284) (xy 259.772299 -296.30271) (xy 259.719515 -296.284703) (xy 259.669915 -296.259202)
			(xy 259.624557 -296.226751) (xy 259.584408 -296.188042) (xy 259.550322 -296.143899) (xy 259.523026 -296.095264)
			(xy 259.503103 -296.043173) (xy 259.490977 -295.988736) (xy 259.486906 -295.933114) (xy 258.774408 -295.933114)
			(xy 258.774408 -295.960348) (xy 258.766653 -296.014291) (xy 258.7513 -296.066581) (xy 258.728663 -296.116153)
			(xy 258.699201 -296.162) (xy 258.663515 -296.203188) (xy 258.622331 -296.238878) (xy 258.576487 -296.268344)
			(xy 258.526916 -296.290987) (xy 258.474628 -296.306345) (xy 258.420686 -296.314105) (xy 258.393438 -296.314622)
			(xy 258.365065 -296.314105) (xy 258.308945 -296.305703) (xy 258.254689 -296.28908) (xy 258.203495 -296.264602)
			(xy 258.156492 -296.232809) (xy 258.114718 -296.194404) (xy 258.096512 -296.172636) (xy 258.089557 -296.164802)
			(xy 258.07102 -296.155091) (xy 258.050148 -296.153597) (xy 258.040124 -296.156634) (xy 257.9497 -296.188384)
			(xy 257.939951 -296.192332) (xy 257.924546 -296.20662) (xy 257.916159 -296.225884) (xy 257.915664 -296.23639)
			(xy 257.915664 -298.400978) (xy 257.915298 -298.422618) (xy 257.909642 -298.465527) (xy 257.898463 -298.507338)
			(xy 257.890518 -298.52747) (xy 257.800094 -298.745656) (xy 257.798292 -298.750342) (xy 257.796365 -298.760194)
			(xy 257.796284 -298.765214) (xy 257.796284 -299.133514) (xy 258.01142 -299.133514) (xy 258.015491 -299.077892)
			(xy 258.027617 -299.023455) (xy 258.04754 -298.971364) (xy 258.074836 -298.922729) (xy 258.108922 -298.878586)
			(xy 258.149071 -298.839877) (xy 258.194429 -298.807426) (xy 258.244029 -298.781925) (xy 258.296813 -298.763918)
			(xy 258.351656 -298.753788) (xy 258.40739 -298.751751) (xy 258.462827 -298.757851) (xy 258.516784 -298.771957)
			(xy 258.568113 -298.793769) (xy 258.615719 -298.822823) (xy 258.658587 -298.858498) (xy 258.695804 -298.900035)
			(xy 258.726577 -298.946548) (xy 258.750249 -298.997045) (xy 258.766317 -299.050452) (xy 258.774437 -299.105628)
			(xy 258.774946 -299.133514) (xy 259.486906 -299.133514) (xy 259.490977 -299.077892) (xy 259.503103 -299.023455)
			(xy 259.523026 -298.971364) (xy 259.550322 -298.922729) (xy 259.584408 -298.878586) (xy 259.624557 -298.839877)
			(xy 259.669915 -298.807426) (xy 259.719515 -298.781925) (xy 259.772299 -298.763918) (xy 259.827142 -298.753788)
			(xy 259.882876 -298.751751) (xy 259.938313 -298.757851) (xy 259.99227 -298.771957) (xy 260.043599 -298.793769)
			(xy 260.091205 -298.822823) (xy 260.134073 -298.858498) (xy 260.17129 -298.900035) (xy 260.202063 -298.946548)
			(xy 260.225735 -298.997045) (xy 260.241803 -299.050452) (xy 260.249923 -299.105628) (xy 260.250432 -299.133514)
			(xy 260.249923 -299.1614) (xy 260.241803 -299.216576) (xy 260.225735 -299.269983) (xy 260.202063 -299.32048)
			(xy 260.17129 -299.366993) (xy 260.134073 -299.40853) (xy 260.091205 -299.444205) (xy 260.043599 -299.473259)
			(xy 259.99227 -299.495071) (xy 259.938313 -299.509177) (xy 259.882876 -299.515277) (xy 259.827142 -299.51324)
			(xy 259.772299 -299.50311) (xy 259.719515 -299.485103) (xy 259.669915 -299.459602) (xy 259.624557 -299.427151)
			(xy 259.584408 -299.388442) (xy 259.550322 -299.344299) (xy 259.523026 -299.295664) (xy 259.503103 -299.243573)
			(xy 259.490977 -299.189136) (xy 259.486906 -299.133514) (xy 258.774946 -299.133514) (xy 258.774437 -299.1614)
			(xy 258.766317 -299.216576) (xy 258.750249 -299.269983) (xy 258.726577 -299.32048) (xy 258.695804 -299.366993)
			(xy 258.658587 -299.40853) (xy 258.615719 -299.444205) (xy 258.568113 -299.473259) (xy 258.516784 -299.495071)
			(xy 258.462827 -299.509177) (xy 258.40739 -299.515277) (xy 258.351656 -299.51324) (xy 258.296813 -299.50311)
			(xy 258.244029 -299.485103) (xy 258.194429 -299.459602) (xy 258.149071 -299.427151) (xy 258.108922 -299.388442)
			(xy 258.074836 -299.344299) (xy 258.04754 -299.295664) (xy 258.027617 -299.243573) (xy 258.015491 -299.189136)
			(xy 258.01142 -299.133514) (xy 257.796284 -299.133514) (xy 257.796284 -301.062644) (xy 257.7973 -301.072296)
			(xy 257.798932 -301.079538) (xy 257.805779 -301.092701) (xy 257.810762 -301.098204) (xy 257.955034 -301.242476)
			(xy 257.962433 -301.24932) (xy 257.981032 -301.257046) (xy 257.991102 -301.257462)
		)
		(stroke
			(width 0)
			(type solid)
		)
		(fill yes)
		(layer "In5.Cu")
		(net "P1V8_PLL0_PEX2")
	)
	(gr_poly
		(pts
			(arc
				(start 200.481692 -418.081968)
				(mid 201.086106 -417.953924)
				(end 201.586846 -417.592002)
			)
			(arc
				(start 201.586846 -417.592002)
				(mid 202.42889 -416.98332)
				(end 203.445364 -416.768026)
			)
			(arc
				(start 271.794732 -416.768026)
				(mid 272.811071 -416.983322)
				(end 273.652996 -417.592002)
			)
			(arc
				(start 273.652996 -417.592002)
				(mid 274.153727 -417.953921)
				(end 274.75815 -418.081968)
			)
			(arc
				(start 465.600034 -418.081968)
				(mid 466.655034 -417.644972)
				(end 467.09203 -416.589972)
			)
			(arc
				(start 467.09203 -246.488204)
				(mid 466.978493 -245.917325)
				(end 466.65515 -245.433342)
			)
			(arc
				(start 464.026504 -242.80495)
				(mid 463.482885 -241.991412)
				(end 463.291936 -241.031776)
			)
			(arc
				(start 463.291936 -87.588344)
				(mid 463.482826 -86.628673)
				(end 464.026504 -85.81517)
			)
			(arc
				(start 466.65515 -83.186524)
				(mid 466.978483 -82.702667)
				(end 467.09203 -82.131916)
			)
			(arc
				(start 467.09203 -1.999996)
				(mid 466.655034 -0.944996)
				(end 465.600034 -0.508)
			)
			(arc
				(start 446.265046 -0.508)
				(mid 445.210046 -0.944996)
				(end 444.77305 -1.999996)
			)
			(arc
				(start 444.77305 -11.850116)
				(mid 444.676277 -12.381671)
				(end 444.3984 -12.845034)
			)
			(xy 444.3984 -12.869164) (xy 444.399924 -12.870688)
			(arc
				(start 445.002666 -12.870688)
				(mid 445.20965 -12.378943)
				(end 445.280288 -11.850116)
			)
			(arc
				(start 445.280288 -1.999996)
				(mid 445.568553 -1.303936)
				(end 446.264538 -1.015492)
			)
			(arc
				(start 465.600034 -1.015492)
				(mid 466.296273 -1.303831)
				(end 466.584792 -1.999996)
			)
			(arc
				(start 466.584792 -82.131916)
				(mid 466.509885 -82.508586)
				(end 466.296502 -82.827876)
			)
			(arc
				(start 463.667856 -85.456522)
				(mid 463.014235 -86.434595)
				(end 462.784698 -87.588344)
			)
			(xy 462.784444 -87.588344) (xy 462.784444 -241.031776)
			(arc
				(start 462.784698 -241.031776)
				(mid 463.014268 -242.185519)
				(end 463.667856 -243.163598)
			)
			(arc
				(start 466.296502 -245.79199)
				(mid 466.509882 -246.11143)
				(end 466.584792 -246.488204)
			)
			(arc
				(start 466.584792 -416.589972)
				(mid 466.296527 -417.286032)
				(end 465.600542 -417.574476)
			)
			(xy 414.915604 -417.574476) (xy 414.915604 -417.797742) (xy 400.95424 -417.797742) (xy 400.95424 -417.730432)
			(xy 400.899884 -417.730432) (xy 400.743928 -417.574476) (xy 326.621648 -417.574476) (xy 326.621648 -417.747958)
			(xy 313.065922 -417.747958) (xy 313.065922 -417.61791) (xy 313.022488 -417.574476)
			(arc
				(start 274.757896 -417.574476)
				(mid 274.359217 -417.490052)
				(end 274.028916 -417.251388)
			)
			(arc
				(start 274.028916 -417.251388)
				(mid 273.01669 -416.519565)
				(end 271.794732 -416.260788)
			)
			(arc
				(start 203.445364 -416.260788)
				(mid 202.223266 -416.519531)
				(end 201.210926 -417.251388)
			)
			(arc
				(start 201.210926 -417.251388)
				(mid 200.880626 -417.490098)
				(end 200.481946 -417.574476)
			)
			(xy 154.845512 -417.574476) (xy 154.688794 -417.731194) (xy 141.03223 -417.731194) (xy 140.875512 -417.574476)
			(xy 66.745104 -417.574476) (xy 66.745104 -417.671758) (xy 53.039772 -417.671758) (xy 53.039772 -417.574476)
			(arc
				(start 1.999996 -417.574476)
				(mid 1.303847 -417.286121)
				(end 1.015492 -416.589972)
			)
			(arc
				(start 1.015492 -246.48795)
				(mid 1.090466 -246.111319)
				(end 1.303782 -245.79199)
			)
			(arc
				(start 3.93192 -243.163852)
				(mid 4.58575 -242.18556)
				(end 4.815332 -241.031522)
			)
			(arc
				(start 4.815332 -87.588344)
				(mid 4.585694 -86.434435)
				(end 3.93192 -85.456268)
			)
			(arc
				(start 1.303528 -82.827876)
				(mid 1.090411 -82.508641)
				(end 1.015492 -82.13217)
			)
			(arc
				(start 1.015492 -1.999996)
				(mid 1.303847 -1.303847)
				(end 1.999996 -1.015492)
			)
			(arc
				(start 5.964936 -1.015492)
				(mid 6.661085 -1.303847)
				(end 6.94944 -1.999996)
			)
			(arc
				(start 6.94944 -11.850116)
				(mid 7.539853 -13.275118)
				(end 8.96493 -13.865352)
			)
			(xy 16.2814 -13.865352) (xy 16.371316 -13.775436) (xy 16.371316 -13.44803) (xy 16.2814 -13.358114)
			(arc
				(start 8.96493 -13.358114)
				(mid 7.898614 -12.916432)
				(end 7.456932 -11.850116)
			)
			(arc
				(start 7.456932 -1.999996)
				(mid 7.019936 -0.944996)
				(end 5.964936 -0.508)
			)
			(arc
				(start 1.999996 -0.508)
				(mid 0.944996 -0.944996)
				(end 0.508 -1.999996)
			)
			(arc
				(start 0.508 -82.131916)
				(mid 0.621601 -82.702644)
				(end 0.94488 -83.186524)
			)
			(arc
				(start 3.573272 -85.81517)
				(mid 4.117081 -86.628665)
				(end 4.308094 -87.588344)
			)
			(arc
				(start 4.308094 -241.031522)
				(mid 4.117082 -241.991334)
				(end 3.573272 -242.80495)
			)
			(arc
				(start 0.94488 -245.433342)
				(mid 0.621552 -245.917331)
				(end 0.508 -246.488204)
			)
			(arc
				(start 0.508 -416.589972)
				(mid 0.944996 -417.644972)
				(end 1.999996 -418.081968)
			)
		)
		(stroke
			(width 0)
			(type solid)
		)
		(fill yes)
		(layer "In5.Cu")
		(net "GND")
	)
	(gr_poly
		(pts
			(xy 4.147058 -396.324836) (xy 4.1656 -396.319756) (xy 4.171442 -396.316454) (xy 4.171696 -396.316454)
			(xy 4.18338 -396.30985) (xy 4.241401 -396.277516) (xy 4.360907 -396.219509) (xy 4.483905 -396.169327)
			(xy 4.609882 -396.127179) (xy 4.738314 -396.093241) (xy 4.868667 -396.067654) (xy 5.000398 -396.050524)
			(xy 5.13296 -396.041923) (xy 5.19938 -396.041372) (xy 6.800596 -396.041372) (xy 6.867016 -396.04192)
			(xy 6.999579 -396.050517) (xy 7.131311 -396.067645) (xy 7.261664 -396.093231) (xy 7.390097 -396.12717)
			(xy 7.516074 -396.169319) (xy 7.63907 -396.219504) (xy 7.758575 -396.277515) (xy 7.816596 -396.30985)
			(xy 7.82828 -396.316454) (xy 7.828534 -396.316454) (xy 7.834376 -396.319756) (xy 7.852918 -396.324836)
			(xy 7.866126 -396.326614) (xy 18.08353 -396.326614) (xy 18.093406 -396.326152) (xy 18.111703 -396.318707)
			(xy 18.11909 -396.312136) (xy 18.119344 -396.311882) (xy 19.042888 -395.388338) (xy 19.049726 -395.380937)
			(xy 19.057439 -395.362338) (xy 19.057874 -395.35227) (xy 19.057874 -388.62127) (xy 19.057761 -388.616924)
			(xy 19.056221 -388.608369) (xy 19.054826 -388.604252) (xy 18.621248 -387.391402) (xy 18.610326 -387.357366)
			(xy 16.801592 -380.821692) (xy 16.793464 -380.787148) (xy 16.676624 -380.1999) (xy 16.673753 -380.188552)
			(xy 16.659502 -380.170014) (xy 16.638531 -380.159674) (xy 16.62684 -380.159006) (xy 13.836142 -380.159006)
			(xy 13.826077 -380.15944) (xy 13.807488 -380.16717) (xy 13.800074 -380.173992) (xy 13.340588 -380.633478)
			(xy 13.333902 -380.640887) (xy 13.326314 -380.659323) (xy 13.325856 -380.669292) (xy 13.325856 -382.69926)
			(xy 13.326322 -382.709135) (xy 13.333772 -382.727426) (xy 13.340334 -382.73482) (xy 13.340588 -382.735074)
			(xy 14.162278 -383.556764) (xy 14.169679 -383.563602) (xy 14.188278 -383.571314) (xy 14.198346 -383.57175)
			(xy 15.643098 -383.57175) (xy 15.653167 -383.572174) (xy 15.671767 -383.579894) (xy 15.679166 -383.586736)
			(xy 16.354806 -384.262376) (xy 16.36164 -384.269779) (xy 16.369346 -384.288377) (xy 16.369792 -384.298444)
			(xy 16.369792 -390.414256) (xy 16.369358 -390.424321) (xy 16.361629 -390.44291) (xy 16.354806 -390.450324)
			(xy 15.974822 -390.830308) (xy 15.967419 -390.837141) (xy 15.948821 -390.844846) (xy 15.938754 -390.845294)
			(xy 4.703826 -390.845294) (xy 4.695308 -390.844978) (xy 4.679208 -390.839406) (xy 4.67233 -390.834372)
			(xy 4.671822 -390.833864) (xy 4.664982 -390.828915) (xy 4.649018 -390.82345) (xy 4.64058 -390.823196)
			(xy 4.617212 -390.823196) (xy 4.607224 -390.822661) (xy 4.588789 -390.81495) (xy 4.581398 -390.80821)
			(xy 3.890264 -390.117076) (xy 3.883623 -390.109717) (xy 3.876057 -390.091416) (xy 3.875532 -390.081516)
			(xy 3.875532 -389.473694) (xy 3.876053 -389.463797) (xy 3.883639 -389.445506) (xy 3.890264 -389.438134)
			(xy 4.352798 -388.9756) (xy 4.360154 -388.968951) (xy 4.378455 -388.96137) (xy 4.388358 -388.960868)
			(xy 5.719064 -388.960868) (xy 5.729128 -388.960433) (xy 5.747713 -388.952698) (xy 5.755132 -388.945882)
			(xy 5.84962 -388.85114) (xy 5.85643 -388.843795) (xy 5.864153 -388.825332) (xy 5.864606 -388.815326)
			(xy 5.864606 -387.42493) (xy 5.864171 -387.414865) (xy 5.856439 -387.396279) (xy 5.84962 -387.388862)
			(xy 5.612638 -387.15188) (xy 5.60524 -387.145035) (xy 5.586641 -387.13731) (xy 5.57657 -387.136894)
			(xy 4.284218 -387.136894) (xy 4.274155 -387.136456) (xy 4.255572 -387.12872) (xy 4.24815 -387.121908)
			(xy 3.92557 -386.799328) (xy 3.920658 -386.794116) (xy 3.913686 -386.781613) (xy 3.911854 -386.77469)
			(xy 3.909997 -386.767833) (xy 3.903028 -386.755461) (xy 3.898138 -386.750306) (xy 3.890264 -386.742432)
			(xy 3.883614 -386.735076) (xy 3.876028 -386.716776) (xy 3.875532 -386.706872) (xy 3.875532 -384.726434)
			(xy 3.876046 -384.716533) (xy 3.883621 -384.698233) (xy 3.890264 -384.690874) (xy 4.390898 -384.19024)
			(xy 4.398257 -384.183597) (xy 4.416557 -384.176026) (xy 4.426458 -384.175508) (xy 5.870956 -384.175508)
			(xy 5.878348 -384.175291) (xy 5.892542 -384.171163) (xy 5.898896 -384.16738) (xy 5.904484 -384.16357)
			(xy 5.99567 -384.072384) (xy 5.999691 -384.068099) (xy 6.00585 -384.058093) (xy 6.007862 -384.052572)
			(xy 6.010656 -384.04419) (xy 6.010656 -382.005586) (xy 6.001512 -381.991616) (xy 5.994908 -381.983488)
			(xy 5.869686 -381.858266) (xy 5.862574 -381.8509) (xy 5.843778 -381.84328) (xy 3.282696 -381.84328)
			(xy 3.272709 -381.842741) (xy 3.25428 -381.835025) (xy 3.246882 -381.828294) (xy 3.212592 -381.794258)
			(xy 3.20518 -381.78758) (xy 3.186744 -381.780007) (xy 3.176778 -381.779526) (xy 2.14884 -381.779526)
			(xy 2.138775 -381.779961) (xy 2.120189 -381.787693) (xy 2.112772 -381.794512) (xy 1.399286 -382.507998)
			(xy 1.39243 -382.515392) (xy 1.384681 -382.533991) (xy 1.3843 -382.544066) (xy 1.3843 -385.877308)
			(xy 2.74904 -385.877308) (xy 2.753111 -385.821686) (xy 2.765237 -385.767249) (xy 2.78516 -385.715158)
			(xy 2.812456 -385.666523) (xy 2.846542 -385.62238) (xy 2.886691 -385.583671) (xy 2.932049 -385.55122)
			(xy 2.981649 -385.525719) (xy 3.034433 -385.507712) (xy 3.089276 -385.497582) (xy 3.14501 -385.495545)
			(xy 3.200447 -385.501645) (xy 3.254404 -385.515751) (xy 3.305733 -385.537563) (xy 3.353339 -385.566617)
			(xy 3.396207 -385.602292) (xy 3.433424 -385.643829) (xy 3.464197 -385.690342) (xy 3.487869 -385.740839)
			(xy 3.503937 -385.794246) (xy 3.512057 -385.849422) (xy 3.512566 -385.877308) (xy 3.512057 -385.905194)
			(xy 3.503937 -385.96037) (xy 3.487869 -386.013777) (xy 3.464197 -386.064274) (xy 3.433424 -386.110787)
			(xy 3.396207 -386.152324) (xy 3.353339 -386.187999) (xy 3.305733 -386.217053) (xy 3.254404 -386.238865)
			(xy 3.200447 -386.252971) (xy 3.14501 -386.259071) (xy 3.089276 -386.257034) (xy 3.034433 -386.246904)
			(xy 2.981649 -386.228897) (xy 2.932049 -386.203396) (xy 2.886691 -386.170945) (xy 2.846542 -386.132236)
			(xy 2.812456 -386.088093) (xy 2.78516 -386.039458) (xy 2.765237 -385.987367) (xy 2.753111 -385.93293)
			(xy 2.74904 -385.877308) (xy 1.3843 -385.877308) (xy 1.3843 -388.37489) (xy 1.56972 -388.37489) (xy 1.56972 -387.51129)
			(xy 1.570189 -387.481068) (xy 1.578113 -387.421145) (xy 1.593854 -387.362786) (xy 1.61714 -387.307007)
			(xy 1.647565 -387.254779) (xy 1.6846 -387.207009) (xy 1.7276 -387.16453) (xy 1.775818 -387.12808)
			(xy 1.801876 -387.112764) (xy 1.813306 -387.106414) (xy 1.826768 -387.084824) (xy 1.834134 -386.97408)
			(xy 1.823466 -386.950966) (xy 1.813052 -386.943346) (xy 1.789883 -386.925187) (xy 1.748883 -386.88295)
			(xy 1.714853 -386.834919) (xy 1.688598 -386.782235) (xy 1.670741 -386.726145) (xy 1.661704 -386.667978)
			(xy 1.66116 -386.638546) (xy 1.661646 -386.611295) (xy 1.669402 -386.557347) (xy 1.684757 -386.505052)
			(xy 1.707399 -386.455475) (xy 1.736865 -386.409625) (xy 1.772556 -386.368434) (xy 1.813747 -386.332743)
			(xy 1.859597 -386.303277) (xy 1.909174 -386.280635) (xy 1.961469 -386.26528) (xy 2.015417 -386.257524)
			(xy 2.069919 -386.257524) (xy 2.123867 -386.26528) (xy 2.176162 -386.280635) (xy 2.225739 -386.303277)
			(xy 2.271589 -386.332743) (xy 2.31278 -386.368434) (xy 2.348471 -386.409625) (xy 2.377937 -386.455475)
			(xy 2.400579 -386.505052) (xy 2.415934 -386.557347) (xy 2.42369 -386.611295) (xy 2.424176 -386.638546)
			(xy 2.423759 -386.664716) (xy 2.416582 -386.716561) (xy 2.402383 -386.766938) (xy 2.381429 -386.8149)
			(xy 2.354114 -386.859546) (xy 2.32095 -386.900038) (xy 2.282561 -386.935615) (xy 2.261362 -386.950966)
			(xy 2.250948 -386.958586) (xy 2.239518 -386.981192) (xy 2.24282 -387.09219) (xy 2.25552 -387.114034)
			(xy 2.266696 -387.120892) (xy 2.291364 -387.136568) (xy 2.3369 -387.173207) (xy 2.3774 -387.215347)
			(xy 2.412203 -387.262302) (xy 2.440744 -387.313307) (xy 2.462556 -387.367531) (xy 2.477286 -387.424091)
			(xy 2.484692 -387.482066) (xy 2.485136 -387.51129) (xy 2.485136 -388.37489) (xy 2.484639 -388.405377)
			(xy 2.476548 -388.465812) (xy 2.46051 -388.524639) (xy 2.436806 -388.580817) (xy 2.405857 -388.633352)
			(xy 2.36821 -388.681316) (xy 2.324531 -388.72386) (xy 2.275593 -388.760231) (xy 2.24917 -388.775448)
			(xy 2.23774 -388.781798) (xy 2.224024 -388.803642) (xy 2.216912 -388.914894) (xy 2.227834 -388.938516)
			(xy 2.238248 -388.946136) (xy 2.261906 -388.964254) (xy 2.303829 -389.006598) (xy 2.33866 -389.054944)
			(xy 2.365554 -389.108116) (xy 2.383856 -389.164821) (xy 2.393121 -389.223683) (xy 2.393696 -389.253476)
			(xy 2.39321 -389.280727) (xy 2.385454 -389.334675) (xy 2.370099 -389.38697) (xy 2.347457 -389.436547)
			(xy 2.317991 -389.482397) (xy 2.2823 -389.523588) (xy 2.241109 -389.559279) (xy 2.195259 -389.588745)
			(xy 2.145682 -389.611387) (xy 2.093387 -389.626742) (xy 2.039439 -389.634498) (xy 1.984937 -389.634498)
			(xy 1.930989 -389.626742) (xy 1.878694 -389.611387) (xy 1.829117 -389.588745) (xy 1.783267 -389.559279)
			(xy 1.742076 -389.523588) (xy 1.706385 -389.482397) (xy 1.676919 -389.436547) (xy 1.654277 -389.38697)
			(xy 1.638922 -389.334675) (xy 1.631166 -389.280727) (xy 1.63068 -389.253476) (xy 1.631124 -389.226991)
			(xy 1.638448 -389.17453) (xy 1.652966 -389.123589) (xy 1.674396 -389.075148) (xy 1.702328 -389.030142)
			(xy 1.736223 -388.989436) (xy 1.775427 -388.953816) (xy 1.79705 -388.938516) (xy 1.807718 -388.93115)
			(xy 1.819402 -388.908036) (xy 1.8161 -388.79653) (xy 1.803146 -388.774178) (xy 1.79197 -388.767574)
			(xy 1.766919 -388.751993) (xy 1.72066 -388.715377) (xy 1.679484 -388.673126) (xy 1.644074 -388.625938)
			(xy 1.615015 -388.574595) (xy 1.592787 -388.519946) (xy 1.57776 -388.462896) (xy 1.570181 -388.404388)
			(xy 1.56972 -388.37489) (xy 1.3843 -388.37489) (xy 1.3843 -389.924036) (xy 2.664712 -389.924036)
			(xy 2.668783 -389.868414) (xy 2.680909 -389.813977) (xy 2.700832 -389.761886) (xy 2.728128 -389.713251)
			(xy 2.762214 -389.669108) (xy 2.802363 -389.630399) (xy 2.847721 -389.597948) (xy 2.897321 -389.572447)
			(xy 2.950105 -389.55444) (xy 3.004948 -389.54431) (xy 3.060682 -389.542273) (xy 3.116119 -389.548373)
			(xy 3.170076 -389.562479) (xy 3.221405 -389.584291) (xy 3.269011 -389.613345) (xy 3.311879 -389.64902)
			(xy 3.349096 -389.690557) (xy 3.379869 -389.73707) (xy 3.403541 -389.787567) (xy 3.419609 -389.840974)
			(xy 3.427729 -389.89615) (xy 3.428238 -389.924036) (xy 3.427729 -389.951922) (xy 3.419609 -390.007098)
			(xy 3.403541 -390.060505) (xy 3.379869 -390.111002) (xy 3.349096 -390.157515) (xy 3.311879 -390.199052)
			(xy 3.269011 -390.234727) (xy 3.221405 -390.263781) (xy 3.170076 -390.285593) (xy 3.116119 -390.299699)
			(xy 3.060682 -390.305799) (xy 3.004948 -390.303762) (xy 2.950105 -390.293632) (xy 2.897321 -390.275625)
			(xy 2.847721 -390.250124) (xy 2.802363 -390.217673) (xy 2.762214 -390.178964) (xy 2.728128 -390.134821)
			(xy 2.700832 -390.086186) (xy 2.680909 -390.034095) (xy 2.668783 -389.979658) (xy 2.664712 -389.924036)
			(xy 1.3843 -389.924036) (xy 1.3843 -390.396984) (xy 1.384717 -390.406276) (xy 1.391337 -390.423641)
			(xy 1.403686 -390.43753) (xy 1.411732 -390.442196) (xy 1.489964 -390.482836) (xy 1.495298 -390.485122)
			(xy 1.496568 -390.48563) (xy 1.506578 -390.488883) (xy 1.527578 -390.487843) (xy 1.537208 -390.483598)
			(xy 1.544828 -390.479788) (xy 1.547876 -390.477756) (xy 1.571962 -390.461634) (xy 1.623988 -390.436093)
			(xy 1.679285 -390.418738) (xy 1.736575 -390.409971) (xy 1.765554 -390.40943) (xy 1.792805 -390.409916)
			(xy 1.846753 -390.417672) (xy 1.899048 -390.433027) (xy 1.948625 -390.455669) (xy 1.994475 -390.485135)
			(xy 2.035666 -390.520826) (xy 2.071357 -390.562017) (xy 2.100823 -390.607867) (xy 2.123465 -390.657444)
			(xy 2.13882 -390.709739) (xy 2.146576 -390.763687) (xy 2.146576 -390.818189) (xy 2.13882 -390.872137)
			(xy 2.123465 -390.924432) (xy 2.100823 -390.974009) (xy 2.071357 -391.019859) (xy 2.035666 -391.06105)
			(xy 1.994475 -391.096741) (xy 1.948625 -391.126207) (xy 1.899048 -391.148849) (xy 1.846753 -391.164204)
			(xy 1.792805 -391.17196) (xy 1.765554 -391.172446) (xy 1.736579 -391.171884) (xy 1.679299 -391.163082)
			(xy 1.624005 -391.145732) (xy 1.571965 -391.120232) (xy 1.547876 -391.10412) (xy 1.544828 -391.102088)
			(xy 1.537208 -391.098278) (xy 1.527568 -391.094075) (xy 1.506586 -391.093043) (xy 1.496568 -391.096246)
			(xy 1.492504 -391.09777) (xy 1.411732 -391.13968) (xy 1.40331 -391.144558) (xy 1.390655 -391.159323)
			(xy 1.387094 -391.168382) (xy 1.3843 -391.17651) (xy 1.3843 -394.323062) (xy 1.384941 -394.335572)
			(xy 1.396653 -394.357682) (xy 1.406652 -394.365226) (xy 1.476756 -394.41247) (xy 1.487519 -394.418895)
			(xy 1.512426 -394.421441) (xy 1.524254 -394.417296) (xy 1.547159 -394.408371) (xy 1.594689 -394.395823)
			(xy 1.643439 -394.389498) (xy 1.668018 -394.389102) (xy 1.695271 -394.389565) (xy 1.749222 -394.397322)
			(xy 1.80152 -394.412678) (xy 1.851101 -394.43532) (xy 1.896954 -394.464788) (xy 1.929205 -394.492734)
			(xy 3.269232 -394.492734) (xy 3.273303 -394.437112) (xy 3.285429 -394.382675) (xy 3.305352 -394.330584)
			(xy 3.332648 -394.281949) (xy 3.366734 -394.237806) (xy 3.406883 -394.199097) (xy 3.452241 -394.166646)
			(xy 3.501841 -394.141145) (xy 3.554625 -394.123138) (xy 3.609468 -394.113008) (xy 3.665202 -394.110971)
			(xy 3.720639 -394.117071) (xy 3.774596 -394.131177) (xy 3.825925 -394.152989) (xy 3.873531 -394.182043)
			(xy 3.916399 -394.217718) (xy 3.953616 -394.259255) (xy 3.984389 -394.305768) (xy 4.008061 -394.356265)
			(xy 4.024129 -394.409672) (xy 4.032249 -394.464848) (xy 4.032758 -394.492734) (xy 4.032249 -394.52062)
			(xy 4.024129 -394.575796) (xy 4.008061 -394.629203) (xy 3.984389 -394.6797) (xy 3.953616 -394.726213)
			(xy 3.916795 -394.767308) (xy 4.293868 -394.767308) (xy 4.297939 -394.711686) (xy 4.310065 -394.657249)
			(xy 4.329988 -394.605158) (xy 4.357284 -394.556523) (xy 4.39137 -394.51238) (xy 4.431519 -394.473671)
			(xy 4.476877 -394.44122) (xy 4.526477 -394.415719) (xy 4.579261 -394.397712) (xy 4.634104 -394.387582)
			(xy 4.689838 -394.385545) (xy 4.745275 -394.391645) (xy 4.799232 -394.405751) (xy 4.850561 -394.427563)
			(xy 4.898167 -394.456617) (xy 4.941035 -394.492292) (xy 4.978252 -394.533829) (xy 5.009025 -394.580342)
			(xy 5.032697 -394.630839) (xy 5.048765 -394.684246) (xy 5.056885 -394.739422) (xy 5.057162 -394.754608)
			(xy 5.302756 -394.754608) (xy 5.306827 -394.698986) (xy 5.318953 -394.644549) (xy 5.338876 -394.592458)
			(xy 5.366172 -394.543823) (xy 5.400258 -394.49968) (xy 5.440407 -394.460971) (xy 5.485765 -394.42852)
			(xy 5.535365 -394.403019) (xy 5.588149 -394.385012) (xy 5.642992 -394.374882) (xy 5.698726 -394.372845)
			(xy 5.754163 -394.378945) (xy 5.80812 -394.393051) (xy 5.859449 -394.414863) (xy 5.907055 -394.443917)
			(xy 5.949923 -394.479592) (xy 5.98714 -394.521129) (xy 6.017913 -394.567642) (xy 6.041585 -394.618139)
			(xy 6.057653 -394.671546) (xy 6.065773 -394.726722) (xy 6.066282 -394.754608) (xy 6.065773 -394.782494)
			(xy 6.057653 -394.83767) (xy 6.041585 -394.891077) (xy 6.017913 -394.941574) (xy 5.98714 -394.988087)
			(xy 5.949923 -395.029624) (xy 5.907055 -395.065299) (xy 5.859449 -395.094353) (xy 5.80812 -395.116165)
			(xy 5.754163 -395.130271) (xy 5.698726 -395.136371) (xy 5.642992 -395.134334) (xy 5.588149 -395.124204)
			(xy 5.535365 -395.106197) (xy 5.485765 -395.080696) (xy 5.440407 -395.048245) (xy 5.400258 -395.009536)
			(xy 5.366172 -394.965393) (xy 5.338876 -394.916758) (xy 5.318953 -394.864667) (xy 5.306827 -394.81023)
			(xy 5.302756 -394.754608) (xy 5.057162 -394.754608) (xy 5.057394 -394.767308) (xy 5.056885 -394.795194)
			(xy 5.048765 -394.85037) (xy 5.032697 -394.903777) (xy 5.009025 -394.954274) (xy 4.978252 -395.000787)
			(xy 4.941035 -395.042324) (xy 4.898167 -395.077999) (xy 4.850561 -395.107053) (xy 4.799232 -395.128865)
			(xy 4.745275 -395.142971) (xy 4.689838 -395.149071) (xy 4.634104 -395.147034) (xy 4.579261 -395.136904)
			(xy 4.526477 -395.118897) (xy 4.476877 -395.093396) (xy 4.431519 -395.060945) (xy 4.39137 -395.022236)
			(xy 4.357284 -394.978093) (xy 4.329988 -394.929458) (xy 4.310065 -394.877367) (xy 4.297939 -394.82293)
			(xy 4.293868 -394.767308) (xy 3.916795 -394.767308) (xy 3.916399 -394.76775) (xy 3.873531 -394.803425)
			(xy 3.825925 -394.832479) (xy 3.774596 -394.854291) (xy 3.720639 -394.868397) (xy 3.665202 -394.874497)
			(xy 3.609468 -394.87246) (xy 3.554625 -394.86233) (xy 3.501841 -394.844323) (xy 3.452241 -394.818822)
			(xy 3.406883 -394.786371) (xy 3.366734 -394.747662) (xy 3.332648 -394.703519) (xy 3.305352 -394.654884)
			(xy 3.285429 -394.602793) (xy 3.273303 -394.548356) (xy 3.269232 -394.492734) (xy 1.929205 -394.492734)
			(xy 1.938147 -394.500482) (xy 1.973841 -394.541674) (xy 2.003309 -394.587528) (xy 2.025952 -394.637108)
			(xy 2.041308 -394.689406) (xy 2.049065 -394.743357) (xy 2.049526 -394.77061) (xy 2.048999 -394.799077)
			(xy 2.040538 -394.855377) (xy 2.023805 -394.909796) (xy 1.99917 -394.961123) (xy 1.967181 -395.00822)
			(xy 1.928548 -395.050039) (xy 1.884129 -395.085653) (xy 1.834911 -395.114271) (xy 1.781987 -395.135256)
			(xy 1.754378 -395.142212) (xy 1.741932 -395.146784) (xy 1.736344 -395.149832) (xy 1.713484 -395.17066)
			(xy 1.708546 -395.175428) (xy 1.701195 -395.187015) (xy 1.699006 -395.19352) (xy 1.682199 -395.248384)
			(xy 8.723882 -395.248384) (xy 8.727953 -395.192762) (xy 8.740079 -395.138325) (xy 8.760002 -395.086234)
			(xy 8.787298 -395.037599) (xy 8.821384 -394.993456) (xy 8.861533 -394.954747) (xy 8.906891 -394.922296)
			(xy 8.956491 -394.896795) (xy 9.009275 -394.878788) (xy 9.064118 -394.868658) (xy 9.119852 -394.866621)
			(xy 9.175289 -394.872721) (xy 9.229246 -394.886827) (xy 9.280575 -394.908639) (xy 9.328181 -394.937693)
			(xy 9.371049 -394.973368) (xy 9.408266 -395.014905) (xy 9.439039 -395.061418) (xy 9.462711 -395.111915)
			(xy 9.478779 -395.165322) (xy 9.486899 -395.220498) (xy 9.48725 -395.239748) (xy 12.838174 -395.239748)
			(xy 12.842245 -395.184126) (xy 12.854371 -395.129689) (xy 12.874294 -395.077598) (xy 12.90159 -395.028963)
			(xy 12.935676 -394.98482) (xy 12.975825 -394.946111) (xy 13.021183 -394.91366) (xy 13.070783 -394.888159)
			(xy 13.123567 -394.870152) (xy 13.17841 -394.860022) (xy 13.234144 -394.857985) (xy 13.289581 -394.864085)
			(xy 13.343538 -394.878191) (xy 13.394867 -394.900003) (xy 13.442473 -394.929057) (xy 13.485341 -394.964732)
			(xy 13.522558 -395.006269) (xy 13.553331 -395.052782) (xy 13.577003 -395.103279) (xy 13.593071 -395.156686)
			(xy 13.601191 -395.211862) (xy 13.601695 -395.239494) (xy 13.870938 -395.239494) (xy 13.875009 -395.183872)
			(xy 13.887135 -395.129435) (xy 13.907058 -395.077344) (xy 13.934354 -395.028709) (xy 13.96844 -394.984566)
			(xy 14.008589 -394.945857) (xy 14.053947 -394.913406) (xy 14.103547 -394.887905) (xy 14.156331 -394.869898)
			(xy 14.211174 -394.859768) (xy 14.266908 -394.857731) (xy 14.322345 -394.863831) (xy 14.376302 -394.877937)
			(xy 14.427631 -394.899749) (xy 14.475237 -394.928803) (xy 14.518105 -394.964478) (xy 14.555322 -395.006015)
			(xy 14.586095 -395.052528) (xy 14.609767 -395.103025) (xy 14.625835 -395.156432) (xy 14.631667 -395.19606)
			(xy 15.04772 -395.19606) (xy 15.051791 -395.140438) (xy 15.063917 -395.086001) (xy 15.08384 -395.03391)
			(xy 15.111136 -394.985275) (xy 15.145222 -394.941132) (xy 15.185371 -394.902423) (xy 15.230729 -394.869972)
			(xy 15.280329 -394.844471) (xy 15.333113 -394.826464) (xy 15.387956 -394.816334) (xy 15.44369 -394.814297)
			(xy 15.499127 -394.820397) (xy 15.553084 -394.834503) (xy 15.604413 -394.856315) (xy 15.652019 -394.885369)
			(xy 15.694887 -394.921044) (xy 15.732104 -394.962581) (xy 15.762877 -395.009094) (xy 15.786549 -395.059591)
			(xy 15.802617 -395.112998) (xy 15.810737 -395.168174) (xy 15.811246 -395.19606) (xy 15.810737 -395.223946)
			(xy 15.802617 -395.279122) (xy 15.786549 -395.332529) (xy 15.762877 -395.383026) (xy 15.732104 -395.429539)
			(xy 15.694887 -395.471076) (xy 15.652019 -395.506751) (xy 15.604413 -395.535805) (xy 15.553084 -395.557617)
			(xy 15.499127 -395.571723) (xy 15.44369 -395.577823) (xy 15.387956 -395.575786) (xy 15.333113 -395.565656)
			(xy 15.280329 -395.547649) (xy 15.230729 -395.522148) (xy 15.185371 -395.489697) (xy 15.145222 -395.450988)
			(xy 15.111136 -395.406845) (xy 15.08384 -395.35821) (xy 15.063917 -395.306119) (xy 15.051791 -395.251682)
			(xy 15.04772 -395.19606) (xy 14.631667 -395.19606) (xy 14.633955 -395.211608) (xy 14.634464 -395.239494)
			(xy 14.633955 -395.26738) (xy 14.625835 -395.322556) (xy 14.609767 -395.375963) (xy 14.586095 -395.42646)
			(xy 14.555322 -395.472973) (xy 14.518105 -395.51451) (xy 14.475237 -395.550185) (xy 14.427631 -395.579239)
			(xy 14.376302 -395.601051) (xy 14.322345 -395.615157) (xy 14.266908 -395.621257) (xy 14.211174 -395.61922)
			(xy 14.156331 -395.60909) (xy 14.103547 -395.591083) (xy 14.053947 -395.565582) (xy 14.008589 -395.533131)
			(xy 13.96844 -395.494422) (xy 13.934354 -395.450279) (xy 13.907058 -395.401644) (xy 13.887135 -395.349553)
			(xy 13.875009 -395.295116) (xy 13.870938 -395.239494) (xy 13.601695 -395.239494) (xy 13.6017 -395.239748)
			(xy 13.601191 -395.267634) (xy 13.593071 -395.32281) (xy 13.577003 -395.376217) (xy 13.553331 -395.426714)
			(xy 13.522558 -395.473227) (xy 13.485341 -395.514764) (xy 13.442473 -395.550439) (xy 13.394867 -395.579493)
			(xy 13.343538 -395.601305) (xy 13.289581 -395.615411) (xy 13.234144 -395.621511) (xy 13.17841 -395.619474)
			(xy 13.123567 -395.609344) (xy 13.070783 -395.591337) (xy 13.021183 -395.565836) (xy 12.975825 -395.533385)
			(xy 12.935676 -395.494676) (xy 12.90159 -395.450533) (xy 12.874294 -395.401898) (xy 12.854371 -395.349807)
			(xy 12.842245 -395.29537) (xy 12.838174 -395.239748) (xy 9.48725 -395.239748) (xy 9.487408 -395.248384)
			(xy 9.486899 -395.27627) (xy 9.478779 -395.331446) (xy 9.462711 -395.384853) (xy 9.439039 -395.43535)
			(xy 9.408266 -395.481863) (xy 9.371049 -395.5234) (xy 9.328181 -395.559075) (xy 9.280575 -395.588129)
			(xy 9.229246 -395.609941) (xy 9.175289 -395.624047) (xy 9.119852 -395.630147) (xy 9.064118 -395.62811)
			(xy 9.009275 -395.61798) (xy 8.956491 -395.599973) (xy 8.906891 -395.574472) (xy 8.861533 -395.542021)
			(xy 8.821384 -395.503312) (xy 8.787298 -395.459169) (xy 8.760002 -395.410534) (xy 8.740079 -395.358443)
			(xy 8.727953 -395.304006) (xy 8.723882 -395.248384) (xy 1.682199 -395.248384) (xy 1.676908 -395.265656)
			(xy 1.674625 -395.274568) (xy 1.675834 -395.292913) (xy 1.683397 -395.309669) (xy 1.689608 -395.316456)
			(xy 2.68478 -396.311628) (xy 2.692179 -396.31847) (xy 2.710779 -396.326186) (xy 2.720848 -396.326614)
			(xy 4.13385 -396.326614)
		)
		(stroke
			(width 0)
			(type solid)
		)
		(fill yes)
		(layer "In5.Cu")
		(net "P3V3_USB_8042")
	)
	(gr_poly
		(pts
			(xy 240.273586 -161.345626) (xy 240.283636 -161.345119) (xy 240.302195 -161.337396) (xy 240.309654 -161.33064)
			(xy 240.366042 -161.274252) (xy 240.372887 -161.266854) (xy 240.380613 -161.248255) (xy 240.381028 -161.238184)
			(xy 240.381028 -160.88487) (xy 240.3806 -160.874802) (xy 240.372881 -160.856202) (xy 240.366042 -160.848802)
			(xy 240.332514 -160.815274) (xy 240.32567 -160.807875) (xy 240.317943 -160.789277) (xy 240.317528 -160.779206)
			(xy 240.317528 -155.528772) (xy 240.317057 -155.518466) (xy 240.30894 -155.49952) (xy 240.293998 -155.485323)
			(xy 240.284508 -155.481274) (xy 240.180368 -155.442412) (xy 240.149634 -155.450032) (xy 240.13922 -155.462224)
			(xy 240.12101 -155.482455) (xy 240.079842 -155.518061) (xy 240.034031 -155.547454) (xy 239.984507 -155.570036)
			(xy 239.932276 -155.585351) (xy 239.878399 -155.593085) (xy 239.851184 -155.593542) (xy 239.823931 -155.593055)
			(xy 239.76998 -155.585296) (xy 239.717683 -155.569938) (xy 239.668103 -155.547294) (xy 239.622251 -155.517825)
			(xy 239.581059 -155.48213) (xy 239.545366 -155.440937) (xy 239.515898 -155.395083) (xy 239.493256 -155.345502)
			(xy 239.477901 -155.293204) (xy 239.470144 -155.239253) (xy 239.470144 -155.184747) (xy 239.477901 -155.130796)
			(xy 239.493256 -155.078498) (xy 239.515898 -155.028917) (xy 239.545366 -154.983064) (xy 239.581059 -154.94187)
			(xy 239.622251 -154.906175) (xy 239.668103 -154.876706) (xy 239.717683 -154.854062) (xy 239.76998 -154.838704)
			(xy 239.823931 -154.830945) (xy 239.851184 -154.830526) (xy 239.878398 -154.831008) (xy 239.932275 -154.83874)
			(xy 239.984506 -154.854049) (xy 240.034031 -154.876625) (xy 240.079846 -154.906009) (xy 240.121021 -154.941605)
			(xy 240.13922 -154.961844) (xy 240.149634 -154.974036) (xy 240.180368 -154.981656) (xy 240.284508 -154.942794)
			(xy 240.293985 -154.938732) (xy 240.30889 -154.924515) (xy 240.317034 -154.905594) (xy 240.317528 -154.895296)
			(xy 240.317528 -150.54834) (xy 240.301272 -150.523194) (xy 240.287302 -150.517098) (xy 240.263791 -150.506128)
			(xy 240.219707 -150.478771) (xy 240.179722 -150.445712) (xy 240.161826 -150.426928) (xy 240.154335 -150.419478)
			(xy 240.135039 -150.410935) (xy 240.124488 -150.410418) (xy 240.049812 -150.410418) (xy 240.039278 -150.411007)
			(xy 240.020007 -150.41954) (xy 240.012474 -150.426928) (xy 239.994324 -150.445988) (xy 239.953692 -150.479443)
			(xy 239.90885 -150.506999) (xy 239.860648 -150.528135) (xy 239.81 -150.54245) (xy 239.757866 -150.549672)
			(xy 239.73155 -150.550118) (xy 239.7043 -150.549629) (xy 239.650357 -150.541866) (xy 239.598067 -150.526506)
			(xy 239.548494 -150.503862) (xy 239.502649 -150.474393) (xy 239.461464 -150.438701) (xy 239.425777 -150.397511)
			(xy 239.396314 -150.351662) (xy 239.373676 -150.302087) (xy 239.358323 -150.249794) (xy 239.350568 -150.19585)
			(xy 239.350568 -150.14135) (xy 239.358323 -150.087406) (xy 239.373676 -150.035113) (xy 239.396314 -149.985538)
			(xy 239.425777 -149.939689) (xy 239.461464 -149.898499) (xy 239.502649 -149.862807) (xy 239.548494 -149.833338)
			(xy 239.598067 -149.810694) (xy 239.650357 -149.795334) (xy 239.7043 -149.787571) (xy 239.73155 -149.787102)
			(xy 239.75787 -149.787521) (xy 239.810016 -149.794716) (xy 239.860676 -149.809018) (xy 239.908886 -149.830154)
			(xy 239.95373 -149.857722) (xy 239.994354 -149.891198) (xy 240.012474 -149.910292) (xy 240.019966 -149.917739)
			(xy 240.039262 -149.926279) (xy 240.049812 -149.926802) (xy 240.124488 -149.926802) (xy 240.135022 -149.926214)
			(xy 240.154296 -149.917683) (xy 240.161826 -149.910292) (xy 240.179705 -149.891489) (xy 240.219682 -149.858414)
			(xy 240.263783 -149.83108) (xy 240.287302 -149.820122) (xy 240.301272 -149.814026) (xy 240.317528 -149.78888)
			(xy 240.317528 -148.010118) (xy 240.301272 -147.984972) (xy 240.287302 -147.978876) (xy 240.263791 -147.967905)
			(xy 240.219709 -147.940548) (xy 240.179725 -147.907487) (xy 240.161826 -147.888706) (xy 240.154333 -147.881259)
			(xy 240.135038 -147.872719) (xy 240.124488 -147.872196) (xy 240.049812 -147.872196) (xy 240.039278 -147.872784)
			(xy 240.020004 -147.881315) (xy 240.012474 -147.888706) (xy 239.994324 -147.907767) (xy 239.953693 -147.941224)
			(xy 239.908852 -147.968782) (xy 239.86065 -147.989919) (xy 239.810001 -148.004234) (xy 239.757866 -148.011457)
			(xy 239.73155 -148.011896) (xy 239.704302 -148.011406) (xy 239.650361 -148.003644) (xy 239.598074 -147.988285)
			(xy 239.548505 -147.965642) (xy 239.502662 -147.936175) (xy 239.46148 -147.900485) (xy 239.425795 -147.859297)
			(xy 239.396334 -147.813451) (xy 239.373697 -147.763879) (xy 239.358345 -147.71159) (xy 239.35059 -147.657648)
			(xy 239.35059 -147.603152) (xy 239.358345 -147.54921) (xy 239.373697 -147.496921) (xy 239.396334 -147.447349)
			(xy 239.425795 -147.401503) (xy 239.46148 -147.360315) (xy 239.502662 -147.324625) (xy 239.548505 -147.295158)
			(xy 239.598074 -147.272515) (xy 239.650361 -147.257156) (xy 239.704302 -147.249394) (xy 239.73155 -147.24888)
			(xy 239.75787 -147.249299) (xy 239.810014 -147.256495) (xy 239.860672 -147.270799) (xy 239.90888 -147.291938)
			(xy 239.95372 -147.319511) (xy 239.994338 -147.352991) (xy 240.012474 -147.37207) (xy 240.019965 -147.37952)
			(xy 240.039261 -147.388064) (xy 240.049812 -147.38858) (xy 240.124488 -147.38858) (xy 240.135022 -147.387991)
			(xy 240.154293 -147.379458) (xy 240.161826 -147.37207) (xy 240.179706 -147.353268) (xy 240.219683 -147.320195)
			(xy 240.263785 -147.292862) (xy 240.287302 -147.2819) (xy 240.301272 -147.275804) (xy 240.317528 -147.250658)
			(xy 240.317528 -133.419342) (xy 240.317095 -133.409276) (xy 240.309369 -133.390684) (xy 240.302542 -133.383274)
			(xy 239.242092 -132.322824) (xy 239.234694 -132.315976) (xy 239.216096 -132.308241) (xy 239.206024 -132.307838)
			(xy 239.140492 -132.307838) (xy 239.130475 -132.30826) (xy 239.111967 -132.315932) (xy 239.097806 -132.330106)
			(xy 239.090151 -132.34862) (xy 239.089692 -132.358638) (xy 239.089692 -133.847332) (xy 239.09274 -133.85927)
			(xy 239.095534 -133.864858) (xy 239.109366 -133.892387) (xy 239.128938 -133.9508) (xy 239.138861 -134.011601)
			(xy 239.139476 -134.042404) (xy 239.13901 -134.069688) (xy 239.131232 -134.123698) (xy 239.115836 -134.176049)
			(xy 239.093136 -134.22567) (xy 239.063595 -134.27155) (xy 239.027817 -134.312751) (xy 238.986531 -134.348433)
			(xy 238.940582 -134.377866) (xy 238.915956 -134.389622) (xy 238.902748 -134.395718) (xy 238.886746 -134.419086)
			(xy 238.880904 -134.538212) (xy 238.89462 -134.56285) (xy 238.907066 -134.570216) (xy 238.931486 -134.584964)
			(xy 238.976054 -134.620571) (xy 239.014826 -134.662416) (xy 239.046936 -134.709566) (xy 239.07167 -134.760971)
			(xy 239.088476 -134.815485) (xy 239.09698 -134.871893) (xy 239.097566 -134.900416) (xy 239.09708 -134.927667)
			(xy 239.089324 -134.981615) (xy 239.073969 -135.03391) (xy 239.051327 -135.083487) (xy 239.021861 -135.129337)
			(xy 238.98617 -135.170528) (xy 238.944979 -135.206219) (xy 238.899129 -135.235685) (xy 238.849552 -135.258327)
			(xy 238.797257 -135.273682) (xy 238.743309 -135.281438) (xy 238.688807 -135.281438) (xy 238.634859 -135.273682)
			(xy 238.582564 -135.258327) (xy 238.532987 -135.235685) (xy 238.487137 -135.206219) (xy 238.445946 -135.170528)
			(xy 238.410255 -135.129337) (xy 238.380789 -135.083487) (xy 238.358147 -135.03391) (xy 238.342792 -134.981615)
			(xy 238.335036 -134.927667) (xy 238.33455 -134.900416) (xy 238.335015 -134.873132) (xy 238.342791 -134.81912)
			(xy 238.358185 -134.766769) (xy 238.380885 -134.717146) (xy 238.410426 -134.671265) (xy 238.446205 -134.630064)
			(xy 238.487491 -134.594383) (xy 238.533442 -134.564951) (xy 238.55807 -134.553198) (xy 238.571278 -134.547102)
			(xy 238.58728 -134.523734) (xy 238.593122 -134.404608) (xy 238.579406 -134.37997) (xy 238.56696 -134.372604)
			(xy 238.542538 -134.357858) (xy 238.497965 -134.322252) (xy 238.459188 -134.280409) (xy 238.427073 -134.233259)
			(xy 238.402335 -134.181853) (xy 238.385525 -134.127338) (xy 238.377017 -134.070928) (xy 238.37646 -134.042404)
			(xy 238.377072 -134.011602) (xy 238.387009 -133.950804) (xy 238.406577 -133.89239) (xy 238.420402 -133.864858)
			(xy 238.423196 -133.85927) (xy 238.426244 -133.847332) (xy 238.426244 -132.358638) (xy 238.425763 -132.348622)
			(xy 238.418112 -132.33011) (xy 238.403959 -132.315934) (xy 238.385459 -132.308253) (xy 238.375444 -132.307838)
			(xy 237.431072 -132.307838) (xy 237.421005 -132.308267) (xy 237.402411 -132.315993) (xy 237.395004 -132.322824)
			(xy 236.916214 -132.801614) (xy 236.909368 -132.809013) (xy 236.901637 -132.827611) (xy 236.901228 -132.837682)
			(xy 236.901228 -136.328404) (xy 238.37595 -136.328404) (xy 238.380021 -136.272782) (xy 238.392147 -136.218345)
			(xy 238.41207 -136.166254) (xy 238.439366 -136.117619) (xy 238.473452 -136.073476) (xy 238.513601 -136.034767)
			(xy 238.558959 -136.002316) (xy 238.608559 -135.976815) (xy 238.661343 -135.958808) (xy 238.716186 -135.948678)
			(xy 238.77192 -135.946641) (xy 238.827357 -135.952741) (xy 238.881314 -135.966847) (xy 238.932643 -135.988659)
			(xy 238.980249 -136.017713) (xy 239.023117 -136.053388) (xy 239.060334 -136.094925) (xy 239.091107 -136.141438)
			(xy 239.114779 -136.191935) (xy 239.130847 -136.245342) (xy 239.138967 -136.300518) (xy 239.139476 -136.328404)
			(xy 239.138967 -136.35629) (xy 239.130847 -136.411466) (xy 239.114779 -136.464873) (xy 239.091107 -136.51537)
			(xy 239.060334 -136.561883) (xy 239.023117 -136.60342) (xy 238.980249 -136.639095) (xy 238.932643 -136.668149)
			(xy 238.881314 -136.689961) (xy 238.827357 -136.704067) (xy 238.77192 -136.710167) (xy 238.716186 -136.70813)
			(xy 238.661343 -136.698) (xy 238.608559 -136.679993) (xy 238.558959 -136.654492) (xy 238.513601 -136.622041)
			(xy 238.473452 -136.583332) (xy 238.439366 -136.539189) (xy 238.41207 -136.490554) (xy 238.392147 -136.438463)
			(xy 238.380021 -136.384026) (xy 238.37595 -136.328404) (xy 236.901228 -136.328404) (xy 236.901228 -137.344404)
			(xy 238.37595 -137.344404) (xy 238.380021 -137.288782) (xy 238.392147 -137.234345) (xy 238.41207 -137.182254)
			(xy 238.439366 -137.133619) (xy 238.473452 -137.089476) (xy 238.513601 -137.050767) (xy 238.558959 -137.018316)
			(xy 238.608559 -136.992815) (xy 238.661343 -136.974808) (xy 238.716186 -136.964678) (xy 238.77192 -136.962641)
			(xy 238.827357 -136.968741) (xy 238.881314 -136.982847) (xy 238.932643 -137.004659) (xy 238.980249 -137.033713)
			(xy 239.023117 -137.069388) (xy 239.060334 -137.110925) (xy 239.091107 -137.157438) (xy 239.114779 -137.207935)
			(xy 239.130847 -137.261342) (xy 239.138967 -137.316518) (xy 239.139476 -137.344404) (xy 239.138967 -137.37229)
			(xy 239.130847 -137.427466) (xy 239.114779 -137.480873) (xy 239.091107 -137.53137) (xy 239.060334 -137.577883)
			(xy 239.023117 -137.61942) (xy 238.980249 -137.655095) (xy 238.932643 -137.684149) (xy 238.881314 -137.705961)
			(xy 238.827357 -137.720067) (xy 238.77192 -137.726167) (xy 238.716186 -137.72413) (xy 238.661343 -137.714)
			(xy 238.608559 -137.695993) (xy 238.558959 -137.670492) (xy 238.513601 -137.638041) (xy 238.473452 -137.599332)
			(xy 238.439366 -137.555189) (xy 238.41207 -137.506554) (xy 238.392147 -137.454463) (xy 238.380021 -137.400026)
			(xy 238.37595 -137.344404) (xy 236.901228 -137.344404) (xy 236.901228 -138.360404) (xy 238.37595 -138.360404)
			(xy 238.380021 -138.304782) (xy 238.392147 -138.250345) (xy 238.41207 -138.198254) (xy 238.439366 -138.149619)
			(xy 238.473452 -138.105476) (xy 238.513601 -138.066767) (xy 238.558959 -138.034316) (xy 238.608559 -138.008815)
			(xy 238.661343 -137.990808) (xy 238.716186 -137.980678) (xy 238.77192 -137.978641) (xy 238.827357 -137.984741)
			(xy 238.881314 -137.998847) (xy 238.932643 -138.020659) (xy 238.980249 -138.049713) (xy 239.023117 -138.085388)
			(xy 239.060334 -138.126925) (xy 239.091107 -138.173438) (xy 239.114779 -138.223935) (xy 239.130847 -138.277342)
			(xy 239.138967 -138.332518) (xy 239.139476 -138.360404) (xy 239.138967 -138.38829) (xy 239.130847 -138.443466)
			(xy 239.114779 -138.496873) (xy 239.091107 -138.54737) (xy 239.060334 -138.593883) (xy 239.023117 -138.63542)
			(xy 238.980249 -138.671095) (xy 238.932643 -138.700149) (xy 238.881314 -138.721961) (xy 238.827357 -138.736067)
			(xy 238.77192 -138.742167) (xy 238.716186 -138.74013) (xy 238.661343 -138.73) (xy 238.608559 -138.711993)
			(xy 238.558959 -138.686492) (xy 238.513601 -138.654041) (xy 238.473452 -138.615332) (xy 238.439366 -138.571189)
			(xy 238.41207 -138.522554) (xy 238.392147 -138.470463) (xy 238.380021 -138.416026) (xy 238.37595 -138.360404)
			(xy 236.901228 -138.360404) (xy 236.901228 -139.376404) (xy 238.37595 -139.376404) (xy 238.380021 -139.320782)
			(xy 238.392147 -139.266345) (xy 238.41207 -139.214254) (xy 238.439366 -139.165619) (xy 238.473452 -139.121476)
			(xy 238.513601 -139.082767) (xy 238.558959 -139.050316) (xy 238.608559 -139.024815) (xy 238.661343 -139.006808)
			(xy 238.716186 -138.996678) (xy 238.77192 -138.994641) (xy 238.827357 -139.000741) (xy 238.881314 -139.014847)
			(xy 238.932643 -139.036659) (xy 238.980249 -139.065713) (xy 239.023117 -139.101388) (xy 239.060334 -139.142925)
			(xy 239.091107 -139.189438) (xy 239.114779 -139.239935) (xy 239.130847 -139.293342) (xy 239.138967 -139.348518)
			(xy 239.139476 -139.376404) (xy 239.138967 -139.40429) (xy 239.130847 -139.459466) (xy 239.114779 -139.512873)
			(xy 239.091107 -139.56337) (xy 239.060334 -139.609883) (xy 239.023117 -139.65142) (xy 238.980249 -139.687095)
			(xy 238.932643 -139.716149) (xy 238.881314 -139.737961) (xy 238.827357 -139.752067) (xy 238.77192 -139.758167)
			(xy 238.716186 -139.75613) (xy 238.661343 -139.746) (xy 238.608559 -139.727993) (xy 238.558959 -139.702492)
			(xy 238.513601 -139.670041) (xy 238.473452 -139.631332) (xy 238.439366 -139.587189) (xy 238.41207 -139.538554)
			(xy 238.392147 -139.486463) (xy 238.380021 -139.432026) (xy 238.37595 -139.376404) (xy 236.901228 -139.376404)
			(xy 236.901228 -140.392404) (xy 238.37595 -140.392404) (xy 238.380021 -140.336782) (xy 238.392147 -140.282345)
			(xy 238.41207 -140.230254) (xy 238.439366 -140.181619) (xy 238.473452 -140.137476) (xy 238.513601 -140.098767)
			(xy 238.558959 -140.066316) (xy 238.608559 -140.040815) (xy 238.661343 -140.022808) (xy 238.716186 -140.012678)
			(xy 238.77192 -140.010641) (xy 238.827357 -140.016741) (xy 238.881314 -140.030847) (xy 238.932643 -140.052659)
			(xy 238.980249 -140.081713) (xy 239.023117 -140.117388) (xy 239.060334 -140.158925) (xy 239.091107 -140.205438)
			(xy 239.114779 -140.255935) (xy 239.130847 -140.309342) (xy 239.138967 -140.364518) (xy 239.139476 -140.392404)
			(xy 239.138967 -140.42029) (xy 239.130847 -140.475466) (xy 239.114779 -140.528873) (xy 239.091107 -140.57937)
			(xy 239.060334 -140.625883) (xy 239.023117 -140.66742) (xy 238.980249 -140.703095) (xy 238.932643 -140.732149)
			(xy 238.881314 -140.753961) (xy 238.827357 -140.768067) (xy 238.77192 -140.774167) (xy 238.716186 -140.77213)
			(xy 238.661343 -140.762) (xy 238.608559 -140.743993) (xy 238.558959 -140.718492) (xy 238.513601 -140.686041)
			(xy 238.473452 -140.647332) (xy 238.439366 -140.603189) (xy 238.41207 -140.554554) (xy 238.392147 -140.502463)
			(xy 238.380021 -140.448026) (xy 238.37595 -140.392404) (xy 236.901228 -140.392404) (xy 236.901228 -141.348714)
			(xy 236.901713 -141.358161) (xy 236.908611 -141.375757) (xy 236.91469 -141.383004) (xy 236.933424 -141.404239)
			(xy 236.965059 -141.451205) (xy 236.989405 -141.50233) (xy 237.005929 -141.556492) (xy 237.014266 -141.612501)
			(xy 237.014766 -141.640814) (xy 237.014271 -141.669129) (xy 237.005942 -141.725141) (xy 236.989423 -141.779307)
			(xy 236.965078 -141.830436) (xy 236.933442 -141.877404) (xy 236.91469 -141.898624) (xy 236.908539 -141.905828)
			(xy 236.901622 -141.923449) (xy 236.901228 -141.932914) (xy 236.901228 -142.348712) (xy 236.901712 -142.358159)
			(xy 236.90861 -142.375756) (xy 236.91469 -142.383002) (xy 236.933424 -142.404237) (xy 236.965059 -142.451203)
			(xy 236.989406 -142.502328) (xy 237.00593 -142.556489) (xy 237.014267 -142.612499) (xy 237.014766 -142.640812)
			(xy 237.014272 -142.669127) (xy 237.005942 -142.72514) (xy 236.989424 -142.779306) (xy 236.965079 -142.830435)
			(xy 236.933443 -142.877403) (xy 236.91469 -142.898622) (xy 236.908538 -142.905826) (xy 236.901621 -142.923447)
			(xy 236.901228 -142.932912) (xy 236.901228 -143.364712) (xy 236.901712 -143.374159) (xy 236.90861 -143.391756)
			(xy 236.91469 -143.399002) (xy 236.933424 -143.420237) (xy 236.965059 -143.467203) (xy 236.989406 -143.518328)
			(xy 237.00593 -143.572489) (xy 237.014267 -143.628499) (xy 237.014766 -143.656812) (xy 237.014272 -143.685127)
			(xy 237.005942 -143.74114) (xy 236.989424 -143.795306) (xy 236.965079 -143.846435) (xy 236.933443 -143.893403)
			(xy 236.91469 -143.914622) (xy 236.908538 -143.921826) (xy 236.901621 -143.939447) (xy 236.901228 -143.948912)
			(xy 236.901228 -144.380712) (xy 236.901712 -144.390159) (xy 236.90861 -144.407756) (xy 236.91469 -144.415002)
			(xy 236.933424 -144.436237) (xy 236.965059 -144.483203) (xy 236.989406 -144.534328) (xy 237.00593 -144.588489)
			(xy 237.014267 -144.644499) (xy 237.014766 -144.672812) (xy 237.014272 -144.701127) (xy 237.005942 -144.75714)
			(xy 236.989424 -144.811306) (xy 236.965079 -144.862435) (xy 236.933443 -144.909403) (xy 236.91469 -144.930622)
			(xy 236.908538 -144.937826) (xy 236.901621 -144.955447) (xy 236.901228 -144.964912) (xy 236.901228 -145.396712)
			(xy 236.901712 -145.406159) (xy 236.90861 -145.423756) (xy 236.91469 -145.431002) (xy 236.933424 -145.452237)
			(xy 236.965059 -145.499203) (xy 236.989406 -145.550328) (xy 237.00593 -145.604489) (xy 237.014267 -145.660499)
			(xy 237.014766 -145.688812) (xy 237.014272 -145.717127) (xy 237.005942 -145.77314) (xy 236.989424 -145.827306)
			(xy 236.965079 -145.878435) (xy 236.933443 -145.925403) (xy 236.91469 -145.946622) (xy 236.908538 -145.953826)
			(xy 236.901621 -145.971447) (xy 236.901228 -145.980912) (xy 236.901228 -146.412712) (xy 236.901712 -146.422159)
			(xy 236.90861 -146.439756) (xy 236.91469 -146.447002) (xy 236.933424 -146.468237) (xy 236.965059 -146.515203)
			(xy 236.989406 -146.566328) (xy 237.00593 -146.620489) (xy 237.014267 -146.676499) (xy 237.014766 -146.704812)
			(xy 237.014272 -146.733127) (xy 237.005942 -146.78914) (xy 236.989424 -146.843306) (xy 236.965079 -146.894435)
			(xy 236.933443 -146.941403) (xy 236.91469 -146.962622) (xy 236.908538 -146.969826) (xy 236.901621 -146.987447)
			(xy 236.901228 -146.996912) (xy 236.901228 -147.428712) (xy 236.901712 -147.438159) (xy 236.90861 -147.455756)
			(xy 236.91469 -147.463002) (xy 236.933424 -147.484237) (xy 236.965059 -147.531203) (xy 236.989406 -147.582328)
			(xy 237.00593 -147.636489) (xy 237.014267 -147.692499) (xy 237.014766 -147.720812) (xy 237.014272 -147.749127)
			(xy 237.005942 -147.80514) (xy 236.989424 -147.859306) (xy 236.965079 -147.910435) (xy 236.933443 -147.957403)
			(xy 236.91469 -147.978622) (xy 236.908538 -147.985826) (xy 236.901621 -148.003447) (xy 236.901228 -148.012912)
			(xy 236.901228 -148.15185) (xy 236.901585 -148.161232) (xy 236.908361 -148.178729) (xy 236.914436 -148.185886)
			(xy 236.932465 -148.20652) (xy 236.963033 -148.251994) (xy 236.986776 -148.301376) (xy 236.995462 -148.327364)
			(xy 236.998566 -148.33607) (xy 237.009886 -148.350662) (xy 237.01756 -148.355812) (xy 237.04423 -148.371814)
			(xy 237.052444 -148.376246) (xy 237.070807 -148.379501) (xy 237.080044 -148.378164) (xy 237.101366 -148.374349)
			(xy 237.144491 -148.370275) (xy 237.16615 -148.370036) (xy 237.196122 -148.370529) (xy 237.255552 -148.378356)
			(xy 237.313453 -148.39387) (xy 237.368834 -148.416806) (xy 237.42075 -148.446772) (xy 237.468313 -148.483255)
			(xy 237.510709 -148.525632) (xy 237.547213 -148.573178) (xy 237.577202 -148.625081) (xy 237.600163 -148.680452)
			(xy 237.615704 -148.738346) (xy 237.623558 -148.797773) (xy 237.624112 -148.827744) (xy 237.624112 -149.691344)
			(xy 237.623639 -149.721322) (xy 237.615806 -149.780764) (xy 237.600278 -149.838674) (xy 237.577323 -149.894061)
			(xy 237.547332 -149.945977) (xy 237.51082 -149.993532) (xy 237.468411 -150.035914) (xy 237.420832 -150.072395)
			(xy 237.368897 -150.102353) (xy 237.313495 -150.125273) (xy 237.255575 -150.140763) (xy 237.196128 -150.148559)
			(xy 237.16615 -150.149052) (xy 237.138769 -150.148664) (xy 237.084394 -150.142168) (xy 237.057692 -150.136098)
			(xy 237.048886 -150.134333) (xy 237.03106 -150.136422) (xy 237.022894 -150.140162) (xy 236.995716 -150.153878)
			(xy 236.987867 -150.158248) (xy 236.975639 -150.171391) (xy 236.97184 -150.179532) (xy 236.960318 -150.205206)
			(xy 236.930854 -150.253149) (xy 236.913166 -150.275036) (xy 236.907324 -150.282148) (xy 236.901228 -150.298658)
			(xy 236.901228 -150.3934) (xy 236.901692 -150.403033) (xy 236.908872 -150.420918) (xy 236.915198 -150.428198)
			(xy 236.932214 -150.446746) (xy 236.961727 -150.48752) (xy 236.985625 -150.53182) (xy 236.994954 -150.555198)
			(xy 236.998452 -150.56344) (xy 237.010155 -150.576977) (xy 237.017814 -150.581614) (xy 237.044484 -150.596346)
			(xy 237.052545 -150.600407) (xy 237.070375 -150.603144) (xy 237.079282 -150.60168) (xy 237.101774 -150.597418)
			(xy 237.147324 -150.592838) (xy 237.170214 -150.592536) (xy 237.200198 -150.593027) (xy 237.259652 -150.600856)
			(xy 237.317576 -150.616378) (xy 237.372978 -150.639328) (xy 237.424911 -150.669313) (xy 237.472486 -150.705819)
			(xy 237.514889 -150.748223) (xy 237.551394 -150.795799) (xy 237.581377 -150.847733) (xy 237.604326 -150.903136)
			(xy 237.619846 -150.96106) (xy 237.627674 -151.020514) (xy 237.628176 -151.050498) (xy 237.628176 -151.914098)
			(xy 237.627686 -151.944083) (xy 237.619859 -152.003539) (xy 237.604338 -152.061465) (xy 237.581389 -152.11687)
			(xy 237.551405 -152.168805) (xy 237.514899 -152.216383) (xy 237.472495 -152.258789) (xy 237.424919 -152.295297)
			(xy 237.372984 -152.325282) (xy 237.31758 -152.348233) (xy 237.259655 -152.363756) (xy 237.200199 -152.371585)
			(xy 237.170214 -152.37206) (xy 237.142826 -152.371614) (xy 237.088451 -152.364992) (xy 237.061756 -152.358852)
			(xy 237.052948 -152.357076) (xy 237.035111 -152.359143) (xy 237.026958 -152.362916) (xy 236.99978 -152.376632)
			(xy 236.991929 -152.380999) (xy 236.979699 -152.394143) (xy 236.975904 -152.402286) (xy 236.963813 -152.429245)
			(xy 236.932559 -152.479385) (xy 236.913674 -152.502108) (xy 236.907992 -152.50923) (xy 236.901609 -152.52628)
			(xy 236.901228 -152.535382) (xy 236.901228 -157.812994) (xy 238.850168 -157.812994) (xy 238.854239 -157.757372)
			(xy 238.866365 -157.702935) (xy 238.886288 -157.650844) (xy 238.913584 -157.602209) (xy 238.94767 -157.558066)
			(xy 238.987819 -157.519357) (xy 239.033177 -157.486906) (xy 239.082777 -157.461405) (xy 239.135561 -157.443398)
			(xy 239.190404 -157.433268) (xy 239.246138 -157.431231) (xy 239.301575 -157.437331) (xy 239.355532 -157.451437)
			(xy 239.406861 -157.473249) (xy 239.454467 -157.502303) (xy 239.497335 -157.537978) (xy 239.534552 -157.579515)
			(xy 239.565325 -157.626028) (xy 239.588997 -157.676525) (xy 239.605065 -157.729932) (xy 239.613185 -157.785108)
			(xy 239.613694 -157.812994) (xy 239.613185 -157.84088) (xy 239.605065 -157.896056) (xy 239.588997 -157.949463)
			(xy 239.565325 -157.99996) (xy 239.534552 -158.046473) (xy 239.497335 -158.08801) (xy 239.454467 -158.123685)
			(xy 239.406861 -158.152739) (xy 239.355532 -158.174551) (xy 239.301575 -158.188657) (xy 239.246138 -158.194757)
			(xy 239.190404 -158.19272) (xy 239.135561 -158.18259) (xy 239.082777 -158.164583) (xy 239.033177 -158.139082)
			(xy 238.987819 -158.106631) (xy 238.94767 -158.067922) (xy 238.913584 -158.023779) (xy 238.886288 -157.975144)
			(xy 238.866365 -157.923053) (xy 238.854239 -157.868616) (xy 238.850168 -157.812994) (xy 236.901228 -157.812994)
			(xy 236.901228 -158.828994) (xy 238.850168 -158.828994) (xy 238.854239 -158.773372) (xy 238.866365 -158.718935)
			(xy 238.886288 -158.666844) (xy 238.913584 -158.618209) (xy 238.94767 -158.574066) (xy 238.987819 -158.535357)
			(xy 239.033177 -158.502906) (xy 239.082777 -158.477405) (xy 239.135561 -158.459398) (xy 239.190404 -158.449268)
			(xy 239.246138 -158.447231) (xy 239.301575 -158.453331) (xy 239.355532 -158.467437) (xy 239.406861 -158.489249)
			(xy 239.454467 -158.518303) (xy 239.497335 -158.553978) (xy 239.534552 -158.595515) (xy 239.565325 -158.642028)
			(xy 239.588997 -158.692525) (xy 239.605065 -158.745932) (xy 239.613185 -158.801108) (xy 239.613694 -158.828994)
			(xy 239.613185 -158.85688) (xy 239.605065 -158.912056) (xy 239.588997 -158.965463) (xy 239.565325 -159.01596)
			(xy 239.534552 -159.062473) (xy 239.497335 -159.10401) (xy 239.454467 -159.139685) (xy 239.406861 -159.168739)
			(xy 239.355532 -159.190551) (xy 239.301575 -159.204657) (xy 239.246138 -159.210757) (xy 239.190404 -159.20872)
			(xy 239.135561 -159.19859) (xy 239.082777 -159.180583) (xy 239.033177 -159.155082) (xy 238.987819 -159.122631)
			(xy 238.94767 -159.083922) (xy 238.913584 -159.039779) (xy 238.886288 -158.991144) (xy 238.866365 -158.939053)
			(xy 238.854239 -158.884616) (xy 238.850168 -158.828994) (xy 236.901228 -158.828994) (xy 236.901228 -159.844994)
			(xy 238.850168 -159.844994) (xy 238.854239 -159.789372) (xy 238.866365 -159.734935) (xy 238.886288 -159.682844)
			(xy 238.913584 -159.634209) (xy 238.94767 -159.590066) (xy 238.987819 -159.551357) (xy 239.033177 -159.518906)
			(xy 239.082777 -159.493405) (xy 239.135561 -159.475398) (xy 239.190404 -159.465268) (xy 239.246138 -159.463231)
			(xy 239.301575 -159.469331) (xy 239.355532 -159.483437) (xy 239.406861 -159.505249) (xy 239.454467 -159.534303)
			(xy 239.497335 -159.569978) (xy 239.534552 -159.611515) (xy 239.565325 -159.658028) (xy 239.588997 -159.708525)
			(xy 239.605065 -159.761932) (xy 239.613185 -159.817108) (xy 239.613694 -159.844994) (xy 239.613185 -159.87288)
			(xy 239.605065 -159.928056) (xy 239.588997 -159.981463) (xy 239.565325 -160.03196) (xy 239.534552 -160.078473)
			(xy 239.497335 -160.12001) (xy 239.454467 -160.155685) (xy 239.406861 -160.184739) (xy 239.355532 -160.206551)
			(xy 239.301575 -160.220657) (xy 239.246138 -160.226757) (xy 239.190404 -160.22472) (xy 239.135561 -160.21459)
			(xy 239.082777 -160.196583) (xy 239.033177 -160.171082) (xy 238.987819 -160.138631) (xy 238.94767 -160.099922)
			(xy 238.913584 -160.055779) (xy 238.886288 -160.007144) (xy 238.866365 -159.955053) (xy 238.854239 -159.900616)
			(xy 238.850168 -159.844994) (xy 236.901228 -159.844994) (xy 236.901228 -160.997392) (xy 236.90165 -161.007462)
			(xy 236.909366 -161.026066) (xy 236.916214 -161.03346) (xy 237.213394 -161.33064) (xy 237.220789 -161.337494)
			(xy 237.239388 -161.34524) (xy 237.249462 -161.345626)
		)
		(stroke
			(width 0)
			(type solid)
		)
		(fill yes)
		(layer "In5.Cu")
		(net "P5V_AUX")
	)
	(gr_poly
		(pts
			(xy 414.309052 -84.852764) (xy 414.317376 -84.854235) (xy 414.334147 -84.852198) (xy 414.349332 -84.844793)
			(xy 414.355534 -84.839048) (xy 414.685226 -84.509356) (xy 414.704994 -84.490429) (xy 414.749547 -84.458652)
			(xy 414.773872 -84.44611) (xy 414.777936 -84.443824) (xy 414.803254 -84.429218) (xy 414.85787 -84.408415)
			(xy 414.915339 -84.397783) (xy 414.94456 -84.397088) (xy 418.141658 -84.397088) (xy 418.1602 -84.389214)
			(xy 418.167312 -84.382102) (xy 427.043342 -75.506072) (xy 427.050154 -75.498728) (xy 427.057886 -75.480265)
			(xy 427.058328 -75.470258) (xy 427.058328 -66.312034) (xy 427.057798 -66.302043) (xy 427.050096 -66.283599)
			(xy 427.043342 -66.27622) (xy 426.423582 -65.65646) (xy 426.41647 -65.649094) (xy 426.397674 -65.641474)
			(xy 420.920926 -65.641474) (xy 420.910862 -65.641037) (xy 420.89228 -65.633301) (xy 420.884858 -65.626488)
			(xy 420.737284 -65.47866) (xy 420.725854 -65.472056) (xy 420.718996 -65.470278) (xy 420.692071 -65.462805)
			(xy 420.640596 -65.441064) (xy 420.592844 -65.412048) (xy 420.549833 -65.376377) (xy 420.512486 -65.334814)
			(xy 420.4816 -65.288249) (xy 420.457835 -65.237677) (xy 420.441701 -65.184179) (xy 420.433543 -65.128901)
			(xy 420.432992 -65.100962) (xy 420.433246 -65.087246) (xy 420.433246 -65.083944) (xy 420.432236 -65.068244)
			(xy 420.42187 -65.038559) (xy 420.402971 -65.013429) (xy 420.377328 -64.995233) (xy 420.347368 -64.985692)
			(xy 420.331646 -64.985138) (xy 419.779196 -64.985138) (xy 419.769127 -64.985563) (xy 419.750527 -64.993282)
			(xy 419.743128 -65.000124) (xy 418.760402 -65.983104) (xy 418.742217 -66.000563) (xy 418.701421 -66.030174)
			(xy 418.656504 -66.053057) (xy 418.608567 -66.068652) (xy 418.558784 -66.076576) (xy 418.53358 -66.077084)
			(xy 418.389562 -66.077084) (xy 418.38372 -66.078354) (xy 418.36488 -66.082509) (xy 418.326557 -66.086961)
			(xy 418.307266 -66.087244) (xy 415.223706 -66.087244) (xy 415.211768 -66.090292) (xy 415.20618 -66.093086)
			(xy 415.178652 -66.10692) (xy 415.120238 -66.126495) (xy 415.059437 -66.136423) (xy 415.028634 -66.137028)
			(xy 414.997832 -66.136419) (xy 414.937032 -66.126486) (xy 414.878615 -66.106921) (xy 414.851088 -66.093086)
			(xy 414.8455 -66.090292) (xy 414.833562 -66.087244) (xy 414.362138 -66.087244) (xy 414.352148 -66.087776)
			(xy 414.333711 -66.095485) (xy 414.326324 -66.10223) (xy 413.388048 -67.040506) (xy 413.38137 -67.047918)
			(xy 413.373798 -67.066354) (xy 413.373316 -67.07632) (xy 413.373316 -67.128949) (xy 414.666698 -67.128949)
			(xy 414.666698 -67.074451) (xy 414.674454 -67.020508) (xy 414.689807 -66.968217) (xy 414.712446 -66.918643)
			(xy 414.741909 -66.872796) (xy 414.777597 -66.831609) (xy 414.818783 -66.795919) (xy 414.864629 -66.766454)
			(xy 414.914202 -66.743813) (xy 414.966492 -66.728457) (xy 415.020435 -66.720699) (xy 415.047684 -66.720212)
			(xy 415.075054 -66.720685) (xy 415.129233 -66.7285) (xy 415.181736 -66.743988) (xy 415.231483 -66.766828)
			(xy 415.27745 -66.796551) (xy 415.298382 -66.814192) (xy 415.305494 -66.820288) (xy 415.322512 -66.826638)
			(xy 415.407856 -66.826638) (xy 415.424874 -66.820288) (xy 415.431986 -66.814192) (xy 415.452911 -66.796545)
			(xy 415.498886 -66.766834) (xy 415.548635 -66.744) (xy 415.601138 -66.728511) (xy 415.655314 -66.720685)
			(xy 415.682684 -66.720212) (xy 415.709939 -66.720634) (xy 415.763895 -66.728389) (xy 415.816197 -66.743745)
			(xy 415.865782 -66.766388) (xy 415.91164 -66.795857) (xy 415.952836 -66.831552) (xy 415.988534 -66.872748)
			(xy 416.018005 -66.918604) (xy 416.04065 -66.968188) (xy 416.056007 -67.02049) (xy 416.063765 -67.074445)
			(xy 416.063765 -67.128955) (xy 416.056007 -67.18291) (xy 416.04065 -67.235212) (xy 416.018005 -67.284796)
			(xy 415.988534 -67.330652) (xy 415.952836 -67.371848) (xy 415.91164 -67.407543) (xy 415.865782 -67.437012)
			(xy 415.816197 -67.459655) (xy 415.763895 -67.475011) (xy 415.709939 -67.482766) (xy 415.682684 -67.483228)
			(xy 415.655313 -67.482789) (xy 415.601132 -67.474967) (xy 415.548628 -67.459473) (xy 415.498881 -67.436625)
			(xy 415.452916 -67.406893) (xy 415.431986 -67.389248) (xy 415.424874 -67.383152) (xy 415.407856 -67.376802)
			(xy 415.322512 -67.376802) (xy 415.305494 -67.383152) (xy 415.298382 -67.389248) (xy 415.277423 -67.406854)
			(xy 415.231459 -67.436573) (xy 415.181718 -67.459416) (xy 415.129223 -67.474914) (xy 415.075051 -67.48275)
			(xy 415.047684 -67.483228) (xy 415.020435 -67.482701) (xy 414.966492 -67.474943) (xy 414.914202 -67.459587)
			(xy 414.864629 -67.436946) (xy 414.818783 -67.407481) (xy 414.777597 -67.371791) (xy 414.741909 -67.330604)
			(xy 414.712446 -67.284757) (xy 414.689807 -67.235183) (xy 414.674454 -67.182892) (xy 414.666698 -67.128949)
			(xy 413.373316 -67.128949) (xy 413.373316 -67.488054) (xy 419.07917 -67.488054) (xy 419.083241 -67.432432)
			(xy 419.095367 -67.377995) (xy 419.11529 -67.325904) (xy 419.142586 -67.277269) (xy 419.176672 -67.233126)
			(xy 419.216821 -67.194417) (xy 419.262179 -67.161966) (xy 419.311779 -67.136465) (xy 419.364563 -67.118458)
			(xy 419.419406 -67.108328) (xy 419.47514 -67.106291) (xy 419.530577 -67.112391) (xy 419.584534 -67.126497)
			(xy 419.635863 -67.148309) (xy 419.683469 -67.177363) (xy 419.726337 -67.213038) (xy 419.763554 -67.254575)
			(xy 419.794327 -67.301088) (xy 419.817999 -67.351585) (xy 419.834067 -67.404992) (xy 419.842187 -67.460168)
			(xy 419.842696 -67.488054) (xy 419.842187 -67.51594) (xy 419.839002 -67.537584) (xy 420.371268 -67.537584)
			(xy 420.375339 -67.481962) (xy 420.387465 -67.427525) (xy 420.407388 -67.375434) (xy 420.434684 -67.326799)
			(xy 420.46877 -67.282656) (xy 420.508919 -67.243947) (xy 420.554277 -67.211496) (xy 420.603877 -67.185995)
			(xy 420.656661 -67.167988) (xy 420.711504 -67.157858) (xy 420.767238 -67.155821) (xy 420.822675 -67.161921)
			(xy 420.876632 -67.176027) (xy 420.927961 -67.197839) (xy 420.975567 -67.226893) (xy 421.018435 -67.262568)
			(xy 421.055652 -67.304105) (xy 421.086425 -67.350618) (xy 421.110097 -67.401115) (xy 421.126165 -67.454522)
			(xy 421.134285 -67.509698) (xy 421.134794 -67.537584) (xy 421.134285 -67.56547) (xy 421.13024 -67.592956)
			(xy 421.645332 -67.592956) (xy 421.649403 -67.537334) (xy 421.661529 -67.482897) (xy 421.681452 -67.430806)
			(xy 421.708748 -67.382171) (xy 421.742834 -67.338028) (xy 421.782983 -67.299319) (xy 421.828341 -67.266868)
			(xy 421.877941 -67.241367) (xy 421.930725 -67.22336) (xy 421.985568 -67.21323) (xy 422.041302 -67.211193)
			(xy 422.096739 -67.217293) (xy 422.150696 -67.231399) (xy 422.202025 -67.253211) (xy 422.249631 -67.282265)
			(xy 422.292499 -67.31794) (xy 422.329716 -67.359477) (xy 422.360489 -67.40599) (xy 422.384161 -67.456487)
			(xy 422.400229 -67.509894) (xy 422.408346 -67.565047) (xy 424.746716 -67.565047) (xy 424.746716 -67.510553)
			(xy 424.754471 -67.456613) (xy 424.769823 -67.404325) (xy 424.79246 -67.354755) (xy 424.821921 -67.30891)
			(xy 424.857606 -67.267725) (xy 424.898789 -67.232037) (xy 424.944632 -67.202573) (xy 424.994201 -67.179933)
			(xy 425.046487 -67.164577) (xy 425.100427 -67.156818) (xy 425.127674 -67.15633) (xy 425.155044 -67.156804)
			(xy 425.209223 -67.164619) (xy 425.261726 -67.180106) (xy 425.311473 -67.202946) (xy 425.35744 -67.232669)
			(xy 425.378372 -67.25031) (xy 425.385484 -67.256406) (xy 425.402502 -67.262756) (xy 425.487846 -67.262756)
			(xy 425.504864 -67.256406) (xy 425.511976 -67.25031) (xy 425.532908 -67.23267) (xy 425.57888 -67.202958)
			(xy 425.628628 -67.180122) (xy 425.681129 -67.164631) (xy 425.735305 -67.156804) (xy 425.762674 -67.15633)
			(xy 425.789931 -67.156715) (xy 425.84389 -67.16447) (xy 425.896196 -67.179825) (xy 425.945785 -67.202469)
			(xy 425.991646 -67.231939) (xy 426.032846 -67.267636) (xy 426.068546 -67.308834) (xy 426.098019 -67.354693)
			(xy 426.120666 -67.404279) (xy 426.136025 -67.456585) (xy 426.143783 -67.510543) (xy 426.143783 -67.565057)
			(xy 426.136025 -67.619015) (xy 426.120666 -67.671321) (xy 426.098019 -67.720907) (xy 426.068546 -67.766766)
			(xy 426.032846 -67.807964) (xy 425.991646 -67.843661) (xy 425.945785 -67.873131) (xy 425.896196 -67.895775)
			(xy 425.84389 -67.91113) (xy 425.789931 -67.918885) (xy 425.762674 -67.919346) (xy 425.735303 -67.918908)
			(xy 425.681122 -67.911086) (xy 425.628618 -67.895591) (xy 425.578871 -67.872742) (xy 425.532906 -67.843011)
			(xy 425.511976 -67.825366) (xy 425.504864 -67.81927) (xy 425.487846 -67.81292) (xy 425.402502 -67.81292)
			(xy 425.385484 -67.81927) (xy 425.378372 -67.825366) (xy 425.357419 -67.84298) (xy 425.311453 -67.872696)
			(xy 425.26171 -67.895538) (xy 425.209214 -67.911035) (xy 425.155042 -67.918869) (xy 425.127674 -67.919346)
			(xy 425.100427 -67.918782) (xy 425.046487 -67.911023) (xy 424.994201 -67.895667) (xy 424.944632 -67.873027)
			(xy 424.898789 -67.843563) (xy 424.857606 -67.807875) (xy 424.821921 -67.76669) (xy 424.79246 -67.720845)
			(xy 424.769823 -67.671275) (xy 424.754471 -67.618987) (xy 424.746716 -67.565047) (xy 422.408346 -67.565047)
			(xy 422.408349 -67.56507) (xy 422.408858 -67.592956) (xy 422.408349 -67.620842) (xy 422.400229 -67.676018)
			(xy 422.384161 -67.729425) (xy 422.360489 -67.779922) (xy 422.329716 -67.826435) (xy 422.292499 -67.867972)
			(xy 422.249631 -67.903647) (xy 422.202025 -67.932701) (xy 422.150696 -67.954513) (xy 422.096739 -67.968619)
			(xy 422.041302 -67.974719) (xy 421.985568 -67.972682) (xy 421.930725 -67.962552) (xy 421.877941 -67.944545)
			(xy 421.828341 -67.919044) (xy 421.782983 -67.886593) (xy 421.742834 -67.847884) (xy 421.708748 -67.803741)
			(xy 421.681452 -67.755106) (xy 421.661529 -67.703015) (xy 421.649403 -67.648578) (xy 421.645332 -67.592956)
			(xy 421.13024 -67.592956) (xy 421.126165 -67.620646) (xy 421.110097 -67.674053) (xy 421.086425 -67.72455)
			(xy 421.055652 -67.771063) (xy 421.018435 -67.8126) (xy 420.975567 -67.848275) (xy 420.927961 -67.877329)
			(xy 420.876632 -67.899141) (xy 420.822675 -67.913247) (xy 420.767238 -67.919347) (xy 420.711504 -67.91731)
			(xy 420.656661 -67.90718) (xy 420.603877 -67.889173) (xy 420.554277 -67.863672) (xy 420.508919 -67.831221)
			(xy 420.46877 -67.792512) (xy 420.434684 -67.748369) (xy 420.407388 -67.699734) (xy 420.387465 -67.647643)
			(xy 420.375339 -67.593206) (xy 420.371268 -67.537584) (xy 419.839002 -67.537584) (xy 419.834067 -67.571116)
			(xy 419.817999 -67.624523) (xy 419.794327 -67.67502) (xy 419.763554 -67.721533) (xy 419.726337 -67.76307)
			(xy 419.683469 -67.798745) (xy 419.635863 -67.827799) (xy 419.584534 -67.849611) (xy 419.530577 -67.863717)
			(xy 419.47514 -67.869817) (xy 419.419406 -67.86778) (xy 419.364563 -67.85765) (xy 419.311779 -67.839643)
			(xy 419.262179 -67.814142) (xy 419.216821 -67.781691) (xy 419.176672 -67.742982) (xy 419.142586 -67.698839)
			(xy 419.11529 -67.650204) (xy 419.095367 -67.598113) (xy 419.083241 -67.543676) (xy 419.07917 -67.488054)
			(xy 413.373316 -67.488054) (xy 413.373316 -68.586604) (xy 416.925252 -68.586604) (xy 416.925708 -68.559233)
			(xy 416.933526 -68.505053) (xy 416.949017 -68.45255) (xy 416.971861 -68.402803) (xy 417.001589 -68.356837)
			(xy 417.019232 -68.335906) (xy 417.025328 -68.328794) (xy 417.031678 -68.311776) (xy 417.031678 -68.226432)
			(xy 417.025328 -68.209414) (xy 417.019232 -68.202302) (xy 417.001585 -68.181376) (xy 416.971874 -68.135402)
			(xy 416.949039 -68.085653) (xy 416.933549 -68.033151) (xy 416.925724 -67.978974) (xy 416.925252 -67.951604)
			(xy 416.925781 -67.924355) (xy 416.933536 -67.870411) (xy 416.948889 -67.818119) (xy 416.971527 -67.768545)
			(xy 417.000989 -67.722696) (xy 417.036676 -67.681507) (xy 417.077861 -67.645815) (xy 417.123706 -67.616348)
			(xy 417.173278 -67.593704) (xy 417.225568 -67.578346) (xy 417.279511 -67.570585) (xy 417.30676 -67.570096)
			(xy 417.333077 -67.570531) (xy 417.385211 -67.577755) (xy 417.43586 -67.592071) (xy 417.484062 -67.613209)
			(xy 417.528903 -67.640768) (xy 417.569534 -67.674224) (xy 417.587684 -67.693286) (xy 417.595212 -67.70068)
			(xy 417.614487 -67.709209) (xy 417.625022 -67.709796) (xy 417.699698 -67.709796) (xy 417.710249 -67.70928)
			(xy 417.729544 -67.700736) (xy 417.737036 -67.693286) (xy 417.75515 -67.674186) (xy 417.795776 -67.640711)
			(xy 417.84062 -67.613143) (xy 417.888832 -67.592008) (xy 417.939493 -67.577708) (xy 417.991639 -67.570514)
			(xy 418.01796 -67.570096) (xy 418.045329 -67.570586) (xy 418.099507 -67.578399) (xy 418.15201 -67.593882)
			(xy 418.201757 -67.616718) (xy 418.247725 -67.646437) (xy 418.268658 -67.664076) (xy 418.27577 -67.670172)
			(xy 418.292788 -67.676522) (xy 418.378132 -67.676522) (xy 418.39515 -67.670172) (xy 418.402262 -67.664076)
			(xy 418.423194 -67.646438) (xy 418.469168 -67.616726) (xy 418.518915 -67.593891) (xy 418.571415 -67.578399)
			(xy 418.625591 -67.570571) (xy 418.65296 -67.570096) (xy 418.680212 -67.570593) (xy 418.734162 -67.578344)
			(xy 418.786459 -67.593695) (xy 418.83604 -67.616333) (xy 418.881893 -67.645798) (xy 418.923086 -67.681488)
			(xy 418.958781 -67.722678) (xy 418.988249 -67.768529) (xy 419.010892 -67.818107) (xy 419.026248 -67.870403)
			(xy 419.034005 -67.924352) (xy 419.034468 -67.951604) (xy 419.034012 -67.978975) (xy 419.026193 -68.033155)
			(xy 419.010702 -68.085658) (xy 418.987858 -68.135405) (xy 418.958131 -68.181371) (xy 418.940488 -68.202302)
			(xy 418.934392 -68.209414) (xy 418.928042 -68.226432) (xy 418.928042 -68.311776) (xy 418.934392 -68.328794)
			(xy 418.940488 -68.335906) (xy 418.958141 -68.356827) (xy 418.987852 -68.402802) (xy 419.010685 -68.452553)
			(xy 419.026173 -68.505056) (xy 419.033996 -68.559234) (xy 419.034468 -68.586604) (xy 419.034048 -68.613859)
			(xy 419.02629 -68.667813) (xy 419.010931 -68.720114) (xy 418.994299 -68.75653) (xy 422.470326 -68.75653)
			(xy 422.470803 -68.72916) (xy 422.478617 -68.674981) (xy 422.494104 -68.622478) (xy 422.516943 -68.572731)
			(xy 422.546666 -68.526764) (xy 422.564306 -68.505832) (xy 422.570402 -68.49872) (xy 422.576752 -68.481702)
			(xy 422.576752 -68.396358) (xy 422.570402 -68.37934) (xy 422.564306 -68.372228) (xy 422.546668 -68.351295)
			(xy 422.516955 -68.305323) (xy 422.494119 -68.255575) (xy 422.478628 -68.203075) (xy 422.4708 -68.148899)
			(xy 422.470326 -68.12153) (xy 422.470783 -68.094276) (xy 422.478537 -68.040323) (xy 422.493891 -67.988023)
			(xy 422.516533 -67.938441) (xy 422.546001 -67.892586) (xy 422.581695 -67.851392) (xy 422.622889 -67.815698)
			(xy 422.668745 -67.786231) (xy 422.718327 -67.76359) (xy 422.770627 -67.748236) (xy 422.82458 -67.740483)
			(xy 422.851834 -67.740022) (xy 422.879205 -67.740463) (xy 422.933386 -67.748286) (xy 422.985889 -67.763781)
			(xy 423.035636 -67.786628) (xy 423.081601 -67.816358) (xy 423.102532 -67.834002) (xy 423.109644 -67.840098)
			(xy 423.126662 -67.846448) (xy 423.212006 -67.846448) (xy 423.229024 -67.840098) (xy 423.236136 -67.834002)
			(xy 423.257082 -67.81638) (xy 423.303051 -67.786665) (xy 423.352795 -67.763826) (xy 423.405292 -67.748331)
			(xy 423.459466 -67.740498) (xy 423.486834 -67.740022) (xy 423.51315 -67.740466) (xy 423.565285 -67.747687)
			(xy 423.615934 -67.762001) (xy 423.664136 -67.783137) (xy 423.708978 -67.810695) (xy 423.749609 -67.844151)
			(xy 423.767758 -67.863212) (xy 423.775292 -67.870599) (xy 423.794563 -67.879131) (xy 423.805096 -67.879722)
			(xy 423.879772 -67.879722) (xy 423.890321 -67.879185) (xy 423.909615 -67.870654) (xy 423.91711 -67.863212)
			(xy 423.935242 -67.84413) (xy 423.975863 -67.810652) (xy 424.020704 -67.783081) (xy 424.068912 -67.761943)
			(xy 424.11957 -67.747639) (xy 424.171714 -67.740442) (xy 424.198034 -67.740022) (xy 424.225287 -67.740446)
			(xy 424.279239 -67.748208) (xy 424.331537 -67.763569) (xy 424.381116 -67.786216) (xy 424.426968 -67.815689)
			(xy 424.468158 -67.851387) (xy 424.503849 -67.892584) (xy 424.533314 -67.93844) (xy 424.555953 -67.988023)
			(xy 424.571305 -68.040324) (xy 424.579058 -68.094276) (xy 424.579542 -68.12153) (xy 424.579108 -68.148902)
			(xy 424.571284 -68.203083) (xy 424.555789 -68.255587) (xy 424.532939 -68.305333) (xy 424.503207 -68.351298)
			(xy 424.485562 -68.372228) (xy 424.479466 -68.37934) (xy 424.473116 -68.396358) (xy 424.473116 -68.481702)
			(xy 424.479466 -68.49872) (xy 424.485562 -68.505832) (xy 424.503177 -68.526784) (xy 424.532894 -68.572751)
			(xy 424.555735 -68.622493) (xy 424.571231 -68.67499) (xy 424.579065 -68.729162) (xy 424.579542 -68.75653)
			(xy 424.57905 -68.78378) (xy 424.57129 -68.837726) (xy 424.555933 -68.890019) (xy 424.533291 -68.939594)
			(xy 424.503825 -68.985442) (xy 424.468134 -69.026631) (xy 424.426946 -69.062322) (xy 424.381097 -69.091789)
			(xy 424.331522 -69.114432) (xy 424.27923 -69.12979) (xy 424.225284 -69.13755) (xy 424.198034 -69.138038)
			(xy 424.171718 -69.137597) (xy 424.119584 -69.130372) (xy 424.068936 -69.116056) (xy 424.020734 -69.094919)
			(xy 423.975892 -69.067363) (xy 423.93526 -69.033908) (xy 423.91711 -69.014848) (xy 423.90958 -69.007456)
			(xy 423.890307 -68.998925) (xy 423.879772 -68.998338) (xy 423.805096 -68.998338) (xy 423.794543 -68.99884)
			(xy 423.775247 -69.007393) (xy 423.767758 -69.014848) (xy 423.749634 -69.033938) (xy 423.709012 -69.067417)
			(xy 423.66417 -69.094987) (xy 423.61596 -69.116124) (xy 423.5653 -69.130426) (xy 423.513154 -69.13762)
			(xy 423.486834 -69.138038) (xy 423.459464 -69.137567) (xy 423.405284 -69.129753) (xy 423.352781 -69.114266)
			(xy 423.303034 -69.091425) (xy 423.257067 -69.0617) (xy 423.236136 -69.044058) (xy 423.229024 -69.037962)
			(xy 423.212006 -69.031612) (xy 423.126662 -69.031612) (xy 423.109644 -69.037962) (xy 423.102532 -69.044058)
			(xy 423.081593 -69.061689) (xy 423.035623 -69.091404) (xy 422.985877 -69.114242) (xy 422.933378 -69.129734)
			(xy 422.879203 -69.137564) (xy 422.851834 -69.138038) (xy 422.824583 -69.137513) (xy 422.770636 -69.129762)
			(xy 422.718341 -69.114411) (xy 422.668763 -69.091775) (xy 422.622911 -69.062313) (xy 422.581719 -69.026626)
			(xy 422.546025 -68.98544) (xy 422.516556 -68.939593) (xy 422.493911 -68.890019) (xy 422.478552 -68.837726)
			(xy 422.470791 -68.783781) (xy 422.470326 -68.75653) (xy 418.994299 -68.75653) (xy 418.988285 -68.769697)
			(xy 418.958813 -68.815552) (xy 418.923115 -68.856746) (xy 418.881917 -68.89244) (xy 418.836059 -68.921906)
			(xy 418.786473 -68.944547) (xy 418.73417 -68.959899) (xy 418.680215 -68.967651) (xy 418.65296 -68.968112)
			(xy 418.625591 -68.967608) (xy 418.571414 -68.959799) (xy 418.518911 -68.944318) (xy 418.469164 -68.921485)
			(xy 418.423195 -68.891769) (xy 418.402262 -68.874132) (xy 418.39515 -68.868036) (xy 418.378132 -68.861686)
			(xy 418.292788 -68.861686) (xy 418.27577 -68.868036) (xy 418.268658 -68.874132) (xy 418.247719 -68.891762)
			(xy 418.201748 -68.921474) (xy 418.152002 -68.944312) (xy 418.099503 -68.959805) (xy 418.045329 -68.967636)
			(xy 418.01796 -68.968112) (xy 417.991644 -68.967662) (xy 417.93951 -68.96044) (xy 417.888862 -68.946127)
			(xy 417.84066 -68.924992) (xy 417.795818 -68.897436) (xy 417.755186 -68.863982) (xy 417.737036 -68.844922)
			(xy 417.7295 -68.837537) (xy 417.710231 -68.829003) (xy 417.699698 -68.828412) (xy 417.625022 -68.828412)
			(xy 417.614472 -68.828936) (xy 417.595176 -68.837474) (xy 417.587684 -68.844922) (xy 417.569542 -68.863994)
			(xy 417.528925 -68.897476) (xy 417.484086 -68.925049) (xy 417.43588 -68.94619) (xy 417.385223 -68.960495)
			(xy 417.333079 -68.967692) (xy 417.30676 -68.968112) (xy 417.279508 -68.967659) (xy 417.225559 -68.959898)
			(xy 417.173264 -68.944538) (xy 417.123687 -68.921892) (xy 417.077837 -68.892422) (xy 417.036647 -68.856727)
			(xy 417.000956 -68.815534) (xy 416.971491 -68.769681) (xy 416.94885 -68.720102) (xy 416.933495 -68.667806)
			(xy 416.925738 -68.613856) (xy 416.925252 -68.586604) (xy 413.373316 -68.586604) (xy 413.373316 -71.555864)
			(xy 419.49446 -71.555864) (xy 419.498531 -71.500242) (xy 419.510657 -71.445805) (xy 419.53058 -71.393714)
			(xy 419.557876 -71.345079) (xy 419.591962 -71.300936) (xy 419.632111 -71.262227) (xy 419.677469 -71.229776)
			(xy 419.727069 -71.204275) (xy 419.779853 -71.186268) (xy 419.834696 -71.176138) (xy 419.89043 -71.174101)
			(xy 419.945867 -71.180201) (xy 419.999824 -71.194307) (xy 420.051153 -71.216119) (xy 420.098759 -71.245173)
			(xy 420.141627 -71.280848) (xy 420.178844 -71.322385) (xy 420.209617 -71.368898) (xy 420.233289 -71.419395)
			(xy 420.249357 -71.472802) (xy 420.257477 -71.527978) (xy 420.257986 -71.555864) (xy 420.257477 -71.58375)
			(xy 420.251638 -71.623428) (xy 421.003474 -71.623428) (xy 421.007545 -71.567806) (xy 421.019671 -71.513369)
			(xy 421.039594 -71.461278) (xy 421.06689 -71.412643) (xy 421.100976 -71.3685) (xy 421.141125 -71.329791)
			(xy 421.186483 -71.29734) (xy 421.236083 -71.271839) (xy 421.288867 -71.253832) (xy 421.34371 -71.243702)
			(xy 421.399444 -71.241665) (xy 421.454881 -71.247765) (xy 421.508838 -71.261871) (xy 421.560167 -71.283683)
			(xy 421.607773 -71.312737) (xy 421.650641 -71.348412) (xy 421.687858 -71.389949) (xy 421.718631 -71.436462)
			(xy 421.742303 -71.486959) (xy 421.758371 -71.540366) (xy 421.766491 -71.595542) (xy 421.767 -71.623428)
			(xy 421.766491 -71.651314) (xy 421.758371 -71.70649) (xy 421.742303 -71.759897) (xy 421.718631 -71.810394)
			(xy 421.687858 -71.856907) (xy 421.650641 -71.898444) (xy 421.607773 -71.934119) (xy 421.560167 -71.963173)
			(xy 421.508838 -71.984985) (xy 421.454881 -71.999091) (xy 421.399444 -72.005191) (xy 421.34371 -72.003154)
			(xy 421.288867 -71.993024) (xy 421.236083 -71.975017) (xy 421.186483 -71.949516) (xy 421.141125 -71.917065)
			(xy 421.100976 -71.878356) (xy 421.06689 -71.834213) (xy 421.039594 -71.785578) (xy 421.019671 -71.733487)
			(xy 421.007545 -71.67905) (xy 421.003474 -71.623428) (xy 420.251638 -71.623428) (xy 420.249357 -71.638926)
			(xy 420.233289 -71.692333) (xy 420.209617 -71.74283) (xy 420.178844 -71.789343) (xy 420.141627 -71.83088)
			(xy 420.098759 -71.866555) (xy 420.051153 -71.895609) (xy 419.999824 -71.917421) (xy 419.945867 -71.931527)
			(xy 419.89043 -71.937627) (xy 419.834696 -71.93559) (xy 419.779853 -71.92546) (xy 419.727069 -71.907453)
			(xy 419.677469 -71.881952) (xy 419.632111 -71.849501) (xy 419.591962 -71.810792) (xy 419.557876 -71.766649)
			(xy 419.53058 -71.718014) (xy 419.510657 -71.665923) (xy 419.498531 -71.611486) (xy 419.49446 -71.555864)
			(xy 413.373316 -71.555864) (xy 413.373316 -80.019906) (xy 420.800782 -80.019906) (xy 420.804853 -79.964284)
			(xy 420.816979 -79.909847) (xy 420.836902 -79.857756) (xy 420.864198 -79.809121) (xy 420.898284 -79.764978)
			(xy 420.938433 -79.726269) (xy 420.983791 -79.693818) (xy 421.033391 -79.668317) (xy 421.086175 -79.65031)
			(xy 421.141018 -79.64018) (xy 421.196752 -79.638143) (xy 421.252189 -79.644243) (xy 421.306146 -79.658349)
			(xy 421.357475 -79.680161) (xy 421.405081 -79.709215) (xy 421.447949 -79.74489) (xy 421.485166 -79.786427)
			(xy 421.515939 -79.83294) (xy 421.539611 -79.883437) (xy 421.555679 -79.936844) (xy 421.563799 -79.99202)
			(xy 421.564308 -80.019906) (xy 421.563799 -80.047792) (xy 421.555679 -80.102968) (xy 421.539611 -80.156375)
			(xy 421.515939 -80.206872) (xy 421.485166 -80.253385) (xy 421.447949 -80.294922) (xy 421.405081 -80.330597)
			(xy 421.357475 -80.359651) (xy 421.306146 -80.381463) (xy 421.252189 -80.395569) (xy 421.196752 -80.401669)
			(xy 421.141018 -80.399632) (xy 421.086175 -80.389502) (xy 421.033391 -80.371495) (xy 420.983791 -80.345994)
			(xy 420.938433 -80.313543) (xy 420.898284 -80.274834) (xy 420.864198 -80.230691) (xy 420.836902 -80.182056)
			(xy 420.816979 -80.129965) (xy 420.804853 -80.075528) (xy 420.800782 -80.019906) (xy 413.373316 -80.019906)
			(xy 413.373316 -84.640928) (xy 413.373836 -84.651426) (xy 413.382234 -84.67067) (xy 413.397622 -84.684956)
			(xy 413.407352 -84.688934) (xy 413.487616 -84.716874) (xy 413.497672 -84.719858) (xy 413.518568 -84.718303)
			(xy 413.537092 -84.708507) (xy 413.544004 -84.700618) (xy 413.553458 -84.689) (xy 413.573929 -84.66713)
			(xy 413.584898 -84.65693) (xy 413.594296 -84.648548) (xy 413.601916 -84.641944) (xy 413.61106 -84.624418)
			(xy 413.618426 -84.53247) (xy 413.61233 -84.51342) (xy 413.605726 -84.505546) (xy 413.588693 -84.484768)
			(xy 413.560017 -84.439334) (xy 413.537996 -84.390327) (xy 413.523067 -84.338716) (xy 413.515523 -84.285521)
			(xy 413.515048 -84.258658) (xy 413.515613 -84.228533) (xy 413.525078 -84.16903) (xy 413.543782 -84.111756)
			(xy 413.571259 -84.058135) (xy 413.606826 -84.009502) (xy 413.627824 -83.987894) (xy 413.634936 -83.980782)
			(xy 413.642556 -83.962748) (xy 413.64408 -83.871816) (xy 413.636968 -83.853274) (xy 413.629856 -83.845908)
			(xy 413.61027 -83.824498) (xy 413.577144 -83.77686) (xy 413.55161 -83.724756) (xy 413.534258 -83.669387)
			(xy 413.525487 -83.61203) (xy 413.524954 -83.583018) (xy 413.52544 -83.555767) (xy 413.533196 -83.501819)
			(xy 413.548551 -83.449524) (xy 413.571193 -83.399947) (xy 413.600659 -83.354097) (xy 413.63635 -83.312906)
			(xy 413.677541 -83.277215) (xy 413.723391 -83.247749) (xy 413.772968 -83.225107) (xy 413.825263 -83.209752)
			(xy 413.879211 -83.201996) (xy 413.933713 -83.201996) (xy 413.987661 -83.209752) (xy 414.039956 -83.225107)
			(xy 414.089533 -83.247749) (xy 414.135383 -83.277215) (xy 414.176574 -83.312906) (xy 414.212265 -83.354097)
			(xy 414.241731 -83.399947) (xy 414.264373 -83.449524) (xy 414.279728 -83.501819) (xy 414.287484 -83.555767)
			(xy 414.28797 -83.583018) (xy 414.287399 -83.613141) (xy 414.277924 -83.672638) (xy 414.259213 -83.729905)
			(xy 414.23173 -83.783518) (xy 414.196159 -83.832143) (xy 414.175194 -83.853782) (xy 414.168082 -83.860894)
			(xy 414.160462 -83.878928) (xy 414.158938 -83.96986) (xy 414.16605 -83.988402) (xy 414.173162 -83.995768)
			(xy 414.19127 -84.015483) (xy 414.222353 -84.059065) (xy 414.247042 -84.106562) (xy 414.264849 -84.157044)
			(xy 414.275427 -84.209519) (xy 414.278568 -84.262957) (xy 414.274209 -84.31631) (xy 414.262437 -84.36853)
			(xy 414.243483 -84.418593) (xy 414.217718 -84.465515) (xy 414.185648 -84.508376) (xy 414.167066 -84.527644)
			(xy 414.144968 -84.548218) (xy 414.137348 -84.555076) (xy 414.128204 -84.572602) (xy 414.120838 -84.664296)
			(xy 414.126934 -84.683346) (xy 414.133538 -84.69122) (xy 414.154495 -84.717019) (xy 414.188087 -84.774368)
			(xy 414.20034 -84.805266) (xy 414.204912 -84.817712) (xy 414.22447 -84.834476)
		)
		(stroke
			(width 0)
			(type solid)
		)
		(fill yes)
		(layer "In5.Cu")
		(net "GND")
	)
	(gr_poly
		(pts
			(xy 243.411502 -321.442842) (xy 243.421571 -321.442417) (xy 243.440169 -321.434696) (xy 243.44757 -321.427856)
			(xy 243.70538 -321.170046) (xy 243.708873 -321.166436) (xy 243.714505 -321.158121) (xy 243.716556 -321.153536)
			(xy 246.921528 -313.415172) (xy 246.923368 -313.41049) (xy 246.925406 -313.400641) (xy 246.925592 -313.395614)
			(xy 246.925592 -309.431182) (xy 246.925245 -309.422197) (xy 246.919033 -309.405337) (xy 246.907351 -309.391683)
			(xy 246.899684 -309.386986) (xy 246.810276 -309.336694) (xy 246.783098 -309.337202) (xy 246.77116 -309.344314)
			(xy 246.748693 -309.357436) (xy 246.70096 -309.378138) (xy 246.650855 -309.392156) (xy 246.599309 -309.399231)
			(xy 246.573294 -309.399686) (xy 246.546045 -309.399199) (xy 246.492101 -309.391443) (xy 246.43981 -309.376088)
			(xy 246.390236 -309.353448) (xy 246.344389 -309.323983) (xy 246.303202 -309.288294) (xy 246.267513 -309.247106)
			(xy 246.238049 -309.201258) (xy 246.21541 -309.151685) (xy 246.200056 -309.099393) (xy 246.1923 -309.045449)
			(xy 246.1923 -308.990951) (xy 246.200056 -308.937007) (xy 246.21541 -308.884715) (xy 246.238049 -308.835142)
			(xy 246.267513 -308.789294) (xy 246.303202 -308.748106) (xy 246.344389 -308.712417) (xy 246.390236 -308.682952)
			(xy 246.43981 -308.660312) (xy 246.492101 -308.644957) (xy 246.546045 -308.637201) (xy 246.573294 -308.63667)
			(xy 246.599309 -308.637112) (xy 246.650857 -308.644187) (xy 246.700963 -308.658208) (xy 246.748696 -308.678913)
			(xy 246.77116 -308.692042) (xy 246.783098 -308.699154) (xy 246.810276 -308.699662) (xy 246.899684 -308.64937)
			(xy 246.907326 -308.64465) (xy 246.918962 -308.630983) (xy 246.925191 -308.614148) (xy 246.925592 -308.605174)
			(xy 246.925592 -307.205634) (xy 246.926018 -307.172759) (xy 246.933346 -307.10742) (xy 246.947948 -307.043313)
			(xy 246.96964 -306.981246) (xy 246.998148 -306.921999) (xy 247.033113 -306.866319) (xy 247.074096 -306.814906)
			(xy 247.097042 -306.79136) (xy 247.833896 -306.054506) (xy 247.840582 -306.047097) (xy 247.848167 -306.028661)
			(xy 247.848628 -306.018692) (xy 247.848628 -278.877014) (xy 247.849109 -278.844138) (xy 247.856507 -278.778802)
			(xy 247.871166 -278.714703) (xy 247.892903 -278.652647) (xy 247.921444 -278.593411) (xy 247.956433 -278.53774)
			(xy 247.997428 -278.486331) (xy 248.020332 -278.46274) (xy 248.27103 -278.212042) (xy 248.277724 -278.204632)
			(xy 248.285337 -278.186194) (xy 248.285345 -278.166246) (xy 248.277746 -278.147801) (xy 248.27103 -278.140414)
			(xy 247.033034 -276.902418) (xy 247.019826 -276.895306) (xy 247.012206 -276.893782) (xy 246.986891 -276.888403)
			(xy 246.937898 -276.871721) (xy 246.891606 -276.848579) (xy 246.848862 -276.8194) (xy 246.810448 -276.784717)
			(xy 246.777068 -276.745166) (xy 246.749333 -276.701472) (xy 246.73814 -276.678136) (xy 246.73179 -276.66442)
			(xy 246.707152 -276.648418) (xy 244.11305 -276.648418) (xy 244.102984 -276.648851) (xy 244.084395 -276.65658)
			(xy 244.076982 -276.663404) (xy 243.909596 -276.83079) (xy 243.902748 -276.838188) (xy 243.895011 -276.856786)
			(xy 243.89461 -276.866858) (xy 243.89461 -278.484076) (xy 243.895047 -278.49414) (xy 243.902782 -278.512723)
			(xy 243.909596 -278.520144) (xy 243.940838 -278.551386) (xy 246.703596 -278.551386) (xy 246.70414 -278.52247)
			(xy 246.712858 -278.465298) (xy 246.730109 -278.410098) (xy 246.755496 -278.358135) (xy 246.788437 -278.310601)
			(xy 246.828177 -278.268585) (xy 246.850662 -278.250396) (xy 246.859432 -278.242842) (xy 246.869608 -278.222077)
			(xy 246.87022 -278.210518) (xy 246.87022 -278.130254) (xy 246.869612 -278.118691) (xy 246.859443 -278.09792)
			(xy 246.850662 -278.090376) (xy 246.828159 -278.072208) (xy 246.788427 -278.030182) (xy 246.755491 -277.982642)
			(xy 246.730107 -277.930677) (xy 246.712854 -277.875476) (xy 246.704129 -277.818303) (xy 246.703596 -277.789386)
			(xy 246.704082 -277.762135) (xy 246.711838 -277.708187) (xy 246.727193 -277.655892) (xy 246.749835 -277.606315)
			(xy 246.779301 -277.560465) (xy 246.814992 -277.519274) (xy 246.856183 -277.483583) (xy 246.902033 -277.454117)
			(xy 246.95161 -277.431475) (xy 247.003905 -277.41612) (xy 247.057853 -277.408364) (xy 247.112355 -277.408364)
			(xy 247.166303 -277.41612) (xy 247.218598 -277.431475) (xy 247.268175 -277.454117) (xy 247.314025 -277.483583)
			(xy 247.355216 -277.519274) (xy 247.390907 -277.560465) (xy 247.420373 -277.606315) (xy 247.443015 -277.655892)
			(xy 247.45837 -277.708187) (xy 247.466126 -277.762135) (xy 247.466612 -277.789386) (xy 247.466117 -277.818304)
			(xy 247.457388 -277.875478) (xy 247.440128 -277.930679) (xy 247.414732 -277.982641) (xy 247.381782 -278.030174)
			(xy 247.342035 -278.072188) (xy 247.319546 -278.090376) (xy 247.31079 -278.097943) (xy 247.300606 -278.118698)
			(xy 247.299988 -278.130254) (xy 247.299988 -278.210518) (xy 247.300553 -278.222086) (xy 247.310752 -278.242857)
			(xy 247.319546 -278.250396) (xy 247.342037 -278.268578) (xy 247.38177 -278.310601) (xy 247.414707 -278.358138)
			(xy 247.440093 -278.410101) (xy 247.457348 -278.465299) (xy 247.466077 -278.52247) (xy 247.466612 -278.551386)
			(xy 247.466126 -278.578637) (xy 247.45837 -278.632585) (xy 247.443015 -278.68488) (xy 247.420373 -278.734457)
			(xy 247.390907 -278.780307) (xy 247.355216 -278.821498) (xy 247.314025 -278.857189) (xy 247.268175 -278.886655)
			(xy 247.218598 -278.909297) (xy 247.166303 -278.924652) (xy 247.112355 -278.932408) (xy 247.057853 -278.932408)
			(xy 247.003905 -278.924652) (xy 246.95161 -278.909297) (xy 246.902033 -278.886655) (xy 246.856183 -278.857189)
			(xy 246.814992 -278.821498) (xy 246.779301 -278.780307) (xy 246.749835 -278.734457) (xy 246.727193 -278.68488)
			(xy 246.711838 -278.632585) (xy 246.704082 -278.578637) (xy 246.703596 -278.551386) (xy 243.940838 -278.551386)
			(xy 244.709442 -279.31999) (xy 244.716296 -279.327385) (xy 244.724044 -279.345984) (xy 244.724428 -279.356058)
			(xy 244.724428 -279.567386) (xy 246.703086 -279.567386) (xy 246.707157 -279.511764) (xy 246.719283 -279.457327)
			(xy 246.739206 -279.405236) (xy 246.766502 -279.356601) (xy 246.800588 -279.312458) (xy 246.840737 -279.273749)
			(xy 246.886095 -279.241298) (xy 246.935695 -279.215797) (xy 246.988479 -279.19779) (xy 247.043322 -279.18766)
			(xy 247.099056 -279.185623) (xy 247.154493 -279.191723) (xy 247.20845 -279.205829) (xy 247.259779 -279.227641)
			(xy 247.307385 -279.256695) (xy 247.350253 -279.29237) (xy 247.38747 -279.333907) (xy 247.418243 -279.38042)
			(xy 247.441915 -279.430917) (xy 247.457983 -279.484324) (xy 247.466103 -279.5395) (xy 247.466612 -279.567386)
			(xy 247.466103 -279.595272) (xy 247.457983 -279.650448) (xy 247.441915 -279.703855) (xy 247.418243 -279.754352)
			(xy 247.38747 -279.800865) (xy 247.350253 -279.842402) (xy 247.307385 -279.878077) (xy 247.259779 -279.907131)
			(xy 247.20845 -279.928943) (xy 247.154493 -279.943049) (xy 247.099056 -279.949149) (xy 247.043322 -279.947112)
			(xy 246.988479 -279.936982) (xy 246.935695 -279.918975) (xy 246.886095 -279.893474) (xy 246.840737 -279.861023)
			(xy 246.800588 -279.822314) (xy 246.766502 -279.778171) (xy 246.739206 -279.729536) (xy 246.719283 -279.677445)
			(xy 246.707157 -279.623008) (xy 246.703086 -279.567386) (xy 244.724428 -279.567386) (xy 244.724428 -280.500582)
			(xy 245.065802 -280.500582) (xy 245.069873 -280.44496) (xy 245.081999 -280.390523) (xy 245.101922 -280.338432)
			(xy 245.129218 -280.289797) (xy 245.163304 -280.245654) (xy 245.203453 -280.206945) (xy 245.248811 -280.174494)
			(xy 245.298411 -280.148993) (xy 245.351195 -280.130986) (xy 245.406038 -280.120856) (xy 245.461772 -280.118819)
			(xy 245.517209 -280.124919) (xy 245.571166 -280.139025) (xy 245.622495 -280.160837) (xy 245.670101 -280.189891)
			(xy 245.712969 -280.225566) (xy 245.750186 -280.267103) (xy 245.780959 -280.313616) (xy 245.804631 -280.364113)
			(xy 245.820699 -280.41752) (xy 245.828819 -280.472696) (xy 245.829328 -280.500582) (xy 245.828819 -280.528468)
			(xy 245.820699 -280.583644) (xy 245.804631 -280.637051) (xy 245.780959 -280.687548) (xy 245.750186 -280.734061)
			(xy 245.712969 -280.775598) (xy 245.670101 -280.811273) (xy 245.622495 -280.840327) (xy 245.571166 -280.862139)
			(xy 245.517209 -280.876245) (xy 245.461772 -280.882345) (xy 245.406038 -280.880308) (xy 245.351195 -280.870178)
			(xy 245.298411 -280.852171) (xy 245.248811 -280.82667) (xy 245.203453 -280.794219) (xy 245.163304 -280.75551)
			(xy 245.129218 -280.711367) (xy 245.101922 -280.662732) (xy 245.081999 -280.610641) (xy 245.069873 -280.556204)
			(xy 245.065802 -280.500582) (xy 244.724428 -280.500582) (xy 244.724428 -287.45307) (xy 244.724865 -287.463134)
			(xy 244.7326 -287.481717) (xy 244.739414 -287.489138) (xy 245.025418 -287.775142) (xy 245.032267 -287.782539)
			(xy 245.039999 -287.801138) (xy 245.040404 -287.81121) (xy 245.040404 -290.297616) (xy 245.039978 -290.307685)
			(xy 245.03226 -290.326285) (xy 245.025418 -290.333684) (xy 244.696742 -290.66236) (xy 244.691408 -290.693856)
			(xy 244.69852 -290.708588) (xy 244.710234 -290.734382) (xy 244.726762 -290.788567) (xy 244.735094 -290.844601)
			(xy 244.735604 -290.872926) (xy 244.735116 -290.900176) (xy 244.727357 -290.954121) (xy 244.711999 -291.006412)
			(xy 244.689357 -291.055986) (xy 244.65989 -291.101833) (xy 244.624198 -291.143019) (xy 244.583009 -291.178708)
			(xy 244.537159 -291.208171) (xy 244.487584 -291.23081) (xy 244.435291 -291.246163) (xy 244.381346 -291.253919)
			(xy 244.354096 -291.254434) (xy 244.326726 -291.253962) (xy 244.272549 -291.246136) (xy 244.220048 -291.230647)
			(xy 244.170299 -291.207811) (xy 244.124326 -291.178098) (xy 244.103398 -291.160454) (xy 244.096286 -291.154358)
			(xy 244.079268 -291.148008) (xy 243.993924 -291.148008) (xy 243.976906 -291.154358) (xy 243.969794 -291.160454)
			(xy 243.948863 -291.178098) (xy 243.902898 -291.207826) (xy 243.853151 -291.230672) (xy 243.800647 -291.246163)
			(xy 243.746467 -291.253982) (xy 243.719096 -291.254434) (xy 243.692195 -291.253973) (xy 243.638927 -291.246414)
			(xy 243.58725 -291.231447) (xy 243.538187 -291.209368) (xy 243.492713 -291.180616) (xy 243.451729 -291.145761)
			(xy 243.416047 -291.105493) (xy 243.386377 -291.060612) (xy 243.363306 -291.012009) (xy 243.35486 -290.986464)
			(xy 243.34978 -290.970462) (xy 243.32311 -290.950904) (xy 235.737146 -290.950904) (xy 235.72708 -290.951337)
			(xy 235.70849 -290.959066) (xy 235.701078 -290.96589) (xy 235.331 -291.335968) (xy 235.32465 -291.365432)
			(xy 235.330238 -291.379656) (xy 235.33845 -291.401756) (xy 235.349985 -291.447471) (xy 235.355801 -291.494258)
			(xy 235.356146 -291.517832) (xy 235.355659 -291.545049) (xy 236.34701 -291.545049) (xy 236.34701 -291.490551)
			(xy 236.354766 -291.436608) (xy 236.37012 -291.384318) (xy 236.392759 -291.334745) (xy 236.422223 -291.288898)
			(xy 236.457911 -291.247711) (xy 236.499098 -291.212023) (xy 236.544945 -291.182559) (xy 236.594518 -291.15992)
			(xy 236.646808 -291.144566) (xy 236.700751 -291.13681) (xy 236.728 -291.136324) (xy 236.755371 -291.136784)
			(xy 236.80955 -291.144603) (xy 236.862053 -291.160093) (xy 236.9118 -291.182936) (xy 236.957767 -291.212662)
			(xy 236.978698 -291.230304) (xy 236.98581 -291.2364) (xy 237.002828 -291.24275) (xy 237.088172 -291.24275)
			(xy 237.10519 -291.2364) (xy 237.112302 -291.230304) (xy 237.133223 -291.212651) (xy 237.179199 -291.182941)
			(xy 237.228949 -291.160108) (xy 237.281452 -291.14462) (xy 237.33563 -291.136796) (xy 237.363 -291.136324)
			(xy 237.390254 -291.136746) (xy 237.444206 -291.144503) (xy 237.496505 -291.159859) (xy 237.546086 -291.182502)
			(xy 237.591941 -291.211971) (xy 237.633134 -291.247666) (xy 237.668829 -291.288859) (xy 237.698298 -291.334714)
			(xy 237.720941 -291.384295) (xy 237.736297 -291.436594) (xy 237.744054 -291.490546) (xy 237.744054 -291.545054)
			(xy 237.736297 -291.599006) (xy 237.720941 -291.651305) (xy 237.698298 -291.700886) (xy 237.668829 -291.746741)
			(xy 237.633134 -291.787934) (xy 237.591941 -291.823629) (xy 237.546086 -291.853098) (xy 237.496505 -291.875741)
			(xy 237.444206 -291.891097) (xy 237.390254 -291.898854) (xy 237.363 -291.89934) (xy 237.335629 -291.898889)
			(xy 237.281449 -291.891069) (xy 237.228945 -291.875578) (xy 237.179198 -291.852732) (xy 237.133233 -291.823004)
			(xy 237.112302 -291.80536) (xy 237.10519 -291.799264) (xy 237.088172 -291.792914) (xy 237.002828 -291.792914)
			(xy 236.98581 -291.799264) (xy 236.978698 -291.80536) (xy 236.957772 -291.823007) (xy 236.911798 -291.852719)
			(xy 236.862049 -291.875554) (xy 236.809547 -291.891043) (xy 236.75537 -291.898868) (xy 236.728 -291.89934)
			(xy 236.700751 -291.89879) (xy 236.646808 -291.891034) (xy 236.594518 -291.87568) (xy 236.544945 -291.853041)
			(xy 236.499098 -291.823577) (xy 236.457911 -291.787889) (xy 236.422223 -291.746702) (xy 236.392759 -291.700855)
			(xy 236.37012 -291.651282) (xy 236.354766 -291.598992) (xy 236.34701 -291.545049) (xy 235.355659 -291.545049)
			(xy 235.355658 -291.545083) (xy 235.347898 -291.599029) (xy 235.332541 -291.651322) (xy 235.309898 -291.700898)
			(xy 235.280432 -291.746747) (xy 235.244741 -291.787936) (xy 235.203552 -291.823628) (xy 235.157703 -291.853095)
			(xy 235.108128 -291.875738) (xy 235.055835 -291.891097) (xy 235.001889 -291.898858) (xy 234.974638 -291.89934)
			(xy 234.951064 -291.898991) (xy 234.904275 -291.893183) (xy 234.858559 -291.881652) (xy 234.836462 -291.873432)
			(xy 234.822238 -291.867844) (xy 234.792774 -291.874194) (xy 234.682538 -291.98443) (xy 234.675692 -291.991828)
			(xy 234.667962 -292.010427) (xy 234.667552 -292.020498) (xy 234.667552 -306.744116) (xy 238.199674 -306.744116)
			(xy 238.203745 -306.688494) (xy 238.215871 -306.634057) (xy 238.235794 -306.581966) (xy 238.26309 -306.533331)
			(xy 238.297176 -306.489188) (xy 238.337325 -306.450479) (xy 238.382683 -306.418028) (xy 238.432283 -306.392527)
			(xy 238.485067 -306.37452) (xy 238.53991 -306.36439) (xy 238.595644 -306.362353) (xy 238.651081 -306.368453)
			(xy 238.705038 -306.382559) (xy 238.756367 -306.404371) (xy 238.803973 -306.433425) (xy 238.846841 -306.4691)
			(xy 238.884058 -306.510637) (xy 238.914831 -306.55715) (xy 238.938503 -306.607647) (xy 238.954571 -306.661054)
			(xy 238.962691 -306.71623) (xy 238.9632 -306.744116) (xy 238.962691 -306.772002) (xy 238.960478 -306.787042)
			(xy 245.473726 -306.787042) (xy 245.477797 -306.73142) (xy 245.489923 -306.676983) (xy 245.509846 -306.624892)
			(xy 245.537142 -306.576257) (xy 245.571228 -306.532114) (xy 245.611377 -306.493405) (xy 245.656735 -306.460954)
			(xy 245.706335 -306.435453) (xy 245.759119 -306.417446) (xy 245.813962 -306.407316) (xy 245.869696 -306.405279)
			(xy 245.925133 -306.411379) (xy 245.97909 -306.425485) (xy 246.030419 -306.447297) (xy 246.078025 -306.476351)
			(xy 246.120893 -306.512026) (xy 246.15811 -306.553563) (xy 246.188883 -306.600076) (xy 246.212555 -306.650573)
			(xy 246.228623 -306.70398) (xy 246.236743 -306.759156) (xy 246.237252 -306.787042) (xy 246.236743 -306.814928)
			(xy 246.228623 -306.870104) (xy 246.212555 -306.923511) (xy 246.188883 -306.974008) (xy 246.15811 -307.020521)
			(xy 246.120893 -307.062058) (xy 246.078025 -307.097733) (xy 246.030419 -307.126787) (xy 245.97909 -307.148599)
			(xy 245.925133 -307.162705) (xy 245.869696 -307.168805) (xy 245.813962 -307.166768) (xy 245.759119 -307.156638)
			(xy 245.706335 -307.138631) (xy 245.656735 -307.11313) (xy 245.611377 -307.080679) (xy 245.571228 -307.04197)
			(xy 245.537142 -306.997827) (xy 245.509846 -306.949192) (xy 245.489923 -306.897101) (xy 245.477797 -306.842664)
			(xy 245.473726 -306.787042) (xy 238.960478 -306.787042) (xy 238.954571 -306.827178) (xy 238.938503 -306.880585)
			(xy 238.914831 -306.931082) (xy 238.884058 -306.977595) (xy 238.846841 -307.019132) (xy 238.803973 -307.054807)
			(xy 238.756367 -307.083861) (xy 238.705038 -307.105673) (xy 238.651081 -307.119779) (xy 238.595644 -307.125879)
			(xy 238.53991 -307.123842) (xy 238.485067 -307.113712) (xy 238.432283 -307.095705) (xy 238.382683 -307.070204)
			(xy 238.337325 -307.037753) (xy 238.297176 -306.999044) (xy 238.26309 -306.954901) (xy 238.235794 -306.906266)
			(xy 238.215871 -306.854175) (xy 238.203745 -306.799738) (xy 238.199674 -306.744116) (xy 234.667552 -306.744116)
			(xy 234.667552 -307.446426) (xy 243.125242 -307.446426) (xy 243.129313 -307.390804) (xy 243.141439 -307.336367)
			(xy 243.161362 -307.284276) (xy 243.188658 -307.235641) (xy 243.222744 -307.191498) (xy 243.262893 -307.152789)
			(xy 243.308251 -307.120338) (xy 243.357851 -307.094837) (xy 243.410635 -307.07683) (xy 243.465478 -307.0667)
			(xy 243.521212 -307.064663) (xy 243.576649 -307.070763) (xy 243.630606 -307.084869) (xy 243.681935 -307.106681)
			(xy 243.729541 -307.135735) (xy 243.772409 -307.17141) (xy 243.809626 -307.212947) (xy 243.840399 -307.25946)
			(xy 243.864071 -307.309957) (xy 243.880139 -307.363364) (xy 243.888259 -307.41854) (xy 243.888768 -307.446426)
			(xy 243.888259 -307.474312) (xy 243.880139 -307.529488) (xy 243.864071 -307.582895) (xy 243.840399 -307.633392)
			(xy 243.809626 -307.679905) (xy 243.772409 -307.721442) (xy 243.729541 -307.757117) (xy 243.681935 -307.786171)
			(xy 243.630606 -307.807983) (xy 243.576649 -307.822089) (xy 243.521212 -307.828189) (xy 243.465478 -307.826152)
			(xy 243.410635 -307.816022) (xy 243.357851 -307.798015) (xy 243.308251 -307.772514) (xy 243.262893 -307.740063)
			(xy 243.222744 -307.701354) (xy 243.188658 -307.657211) (xy 243.161362 -307.608576) (xy 243.141439 -307.556485)
			(xy 243.129313 -307.502048) (xy 243.125242 -307.446426) (xy 234.667552 -307.446426) (xy 234.667552 -308.402228)
			(xy 244.183152 -308.402228) (xy 244.187223 -308.346606) (xy 244.199349 -308.292169) (xy 244.219272 -308.240078)
			(xy 244.246568 -308.191443) (xy 244.280654 -308.1473) (xy 244.320803 -308.108591) (xy 244.366161 -308.07614)
			(xy 244.415761 -308.050639) (xy 244.468545 -308.032632) (xy 244.523388 -308.022502) (xy 244.579122 -308.020465)
			(xy 244.634559 -308.026565) (xy 244.688516 -308.040671) (xy 244.739845 -308.062483) (xy 244.787451 -308.091537)
			(xy 244.830319 -308.127212) (xy 244.867536 -308.168749) (xy 244.898309 -308.215262) (xy 244.921981 -308.265759)
			(xy 244.938049 -308.319166) (xy 244.946169 -308.374342) (xy 244.946678 -308.402228) (xy 244.946169 -308.430114)
			(xy 244.938049 -308.48529) (xy 244.921981 -308.538697) (xy 244.898309 -308.589194) (xy 244.867536 -308.635707)
			(xy 244.830319 -308.677244) (xy 244.787451 -308.712919) (xy 244.739845 -308.741973) (xy 244.688516 -308.763785)
			(xy 244.634559 -308.777891) (xy 244.579122 -308.783991) (xy 244.523388 -308.781954) (xy 244.468545 -308.771824)
			(xy 244.415761 -308.753817) (xy 244.366161 -308.728316) (xy 244.320803 -308.695865) (xy 244.280654 -308.657156)
			(xy 244.246568 -308.613013) (xy 244.219272 -308.564378) (xy 244.199349 -308.512287) (xy 244.187223 -308.45785)
			(xy 244.183152 -308.402228) (xy 234.667552 -308.402228) (xy 234.667552 -309.908448) (xy 242.571268 -309.908448)
			(xy 242.575339 -309.852826) (xy 242.587465 -309.798389) (xy 242.607388 -309.746298) (xy 242.634684 -309.697663)
			(xy 242.66877 -309.65352) (xy 242.708919 -309.614811) (xy 242.754277 -309.58236) (xy 242.803877 -309.556859)
			(xy 242.856661 -309.538852) (xy 242.911504 -309.528722) (xy 242.967238 -309.526685) (xy 243.022675 -309.532785)
			(xy 243.076632 -309.546891) (xy 243.127961 -309.568703) (xy 243.175567 -309.597757) (xy 243.218435 -309.633432)
			(xy 243.255652 -309.674969) (xy 243.286425 -309.721482) (xy 243.297509 -309.745126) (xy 244.286784 -309.745126)
			(xy 244.290855 -309.689504) (xy 244.302981 -309.635067) (xy 244.322904 -309.582976) (xy 244.3502 -309.534341)
			(xy 244.384286 -309.490198) (xy 244.424435 -309.451489) (xy 244.469793 -309.419038) (xy 244.519393 -309.393537)
			(xy 244.572177 -309.37553) (xy 244.62702 -309.3654) (xy 244.682754 -309.363363) (xy 244.738191 -309.369463)
			(xy 244.792148 -309.383569) (xy 244.843477 -309.405381) (xy 244.891083 -309.434435) (xy 244.933951 -309.47011)
			(xy 244.971168 -309.511647) (xy 245.001941 -309.55816) (xy 245.025613 -309.608657) (xy 245.041681 -309.662064)
			(xy 245.049801 -309.71724) (xy 245.05031 -309.745126) (xy 245.049801 -309.773012) (xy 245.041681 -309.828188)
			(xy 245.025613 -309.881595) (xy 245.001941 -309.932092) (xy 244.971168 -309.978605) (xy 244.933951 -310.020142)
			(xy 244.891083 -310.055817) (xy 244.843477 -310.084871) (xy 244.792148 -310.106683) (xy 244.738191 -310.120789)
			(xy 244.682754 -310.126889) (xy 244.62702 -310.124852) (xy 244.572177 -310.114722) (xy 244.519393 -310.096715)
			(xy 244.469793 -310.071214) (xy 244.424435 -310.038763) (xy 244.384286 -310.000054) (xy 244.3502 -309.955911)
			(xy 244.322904 -309.907276) (xy 244.302981 -309.855185) (xy 244.290855 -309.800748) (xy 244.286784 -309.745126)
			(xy 243.297509 -309.745126) (xy 243.310097 -309.771979) (xy 243.326165 -309.825386) (xy 243.334285 -309.880562)
			(xy 243.334794 -309.908448) (xy 243.334285 -309.936334) (xy 243.326165 -309.99151) (xy 243.310097 -310.044917)
			(xy 243.286425 -310.095414) (xy 243.255652 -310.141927) (xy 243.218435 -310.183464) (xy 243.175567 -310.219139)
			(xy 243.127961 -310.248193) (xy 243.076632 -310.270005) (xy 243.022675 -310.284111) (xy 242.967238 -310.290211)
			(xy 242.911504 -310.288174) (xy 242.856661 -310.278044) (xy 242.803877 -310.260037) (xy 242.754277 -310.234536)
			(xy 242.708919 -310.202085) (xy 242.66877 -310.163376) (xy 242.634684 -310.119233) (xy 242.607388 -310.070598)
			(xy 242.587465 -310.018507) (xy 242.575339 -309.96407) (xy 242.571268 -309.908448) (xy 234.667552 -309.908448)
			(xy 234.667552 -311.215786) (xy 243.749066 -311.215786) (xy 243.753137 -311.160164) (xy 243.765263 -311.105727)
			(xy 243.785186 -311.053636) (xy 243.812482 -311.005001) (xy 243.846568 -310.960858) (xy 243.886717 -310.922149)
			(xy 243.932075 -310.889698) (xy 243.981675 -310.864197) (xy 244.034459 -310.84619) (xy 244.089302 -310.83606)
			(xy 244.145036 -310.834023) (xy 244.200473 -310.840123) (xy 244.25443 -310.854229) (xy 244.305759 -310.876041)
			(xy 244.353365 -310.905095) (xy 244.396233 -310.94077) (xy 244.43345 -310.982307) (xy 244.464223 -311.02882)
			(xy 244.487895 -311.079317) (xy 244.503963 -311.132724) (xy 244.512083 -311.1879) (xy 244.512592 -311.215786)
			(xy 244.512083 -311.243672) (xy 244.503963 -311.298848) (xy 244.487895 -311.352255) (xy 244.464223 -311.402752)
			(xy 244.43345 -311.449265) (xy 244.396233 -311.490802) (xy 244.353365 -311.526477) (xy 244.305759 -311.555531)
			(xy 244.25443 -311.577343) (xy 244.200473 -311.591449) (xy 244.145036 -311.597549) (xy 244.089302 -311.595512)
			(xy 244.034459 -311.585382) (xy 243.981675 -311.567375) (xy 243.932075 -311.541874) (xy 243.886717 -311.509423)
			(xy 243.846568 -311.470714) (xy 243.812482 -311.426571) (xy 243.785186 -311.377936) (xy 243.765263 -311.325845)
			(xy 243.753137 -311.271408) (xy 243.749066 -311.215786) (xy 234.667552 -311.215786) (xy 234.667552 -314.823094)
			(xy 234.667169 -314.844567) (xy 234.661502 -314.887139) (xy 234.65033 -314.928609) (xy 234.642406 -314.94857)
			(xy 234.479084 -315.342524) (xy 234.477288 -315.347211) (xy 234.475376 -315.357063) (xy 234.475274 -315.362082)
			(xy 234.475274 -320.816732) (xy 241.138202 -320.816732) (xy 241.138686 -320.789362) (xy 241.1465 -320.735184)
			(xy 241.161984 -320.682681) (xy 241.184822 -320.632934) (xy 241.214543 -320.586966) (xy 241.232182 -320.566034)
			(xy 241.238278 -320.558922) (xy 241.244628 -320.541904) (xy 241.244628 -320.45656) (xy 241.238278 -320.439542)
			(xy 241.232182 -320.43243) (xy 241.214541 -320.4115) (xy 241.18483 -320.365526) (xy 241.161995 -320.315778)
			(xy 241.146504 -320.263277) (xy 241.138676 -320.209101) (xy 241.138202 -320.181732) (xy 241.138685 -320.154479)
			(xy 241.146438 -320.100529) (xy 241.16179 -320.048231) (xy 241.18443 -319.99865) (xy 241.213896 -319.952796)
			(xy 241.249587 -319.911603) (xy 241.290779 -319.875909) (xy 241.336631 -319.846441) (xy 241.38621 -319.823798)
			(xy 241.438507 -319.808443) (xy 241.492458 -319.800687) (xy 241.51971 -319.800224) (xy 241.547081 -319.800678)
			(xy 241.601261 -319.808498) (xy 241.653764 -319.82399) (xy 241.703511 -319.846834) (xy 241.749477 -319.876561)
			(xy 241.770408 -319.894204) (xy 241.77752 -319.9003) (xy 241.794538 -319.90665) (xy 241.879882 -319.90665)
			(xy 241.8969 -319.9003) (xy 241.904012 -319.894204) (xy 241.924945 -319.876563) (xy 241.970913 -319.846839)
			(xy 242.020659 -319.823993) (xy 242.073161 -319.808497) (xy 242.127339 -319.800668) (xy 242.182081 -319.800668)
			(xy 242.236259 -319.808497) (xy 242.288761 -319.823993) (xy 242.338507 -319.846839) (xy 242.384475 -319.876563)
			(xy 242.405408 -319.894204) (xy 242.41252 -319.9003) (xy 242.429538 -319.90665) (xy 242.514882 -319.90665)
			(xy 242.5319 -319.9003) (xy 242.539012 -319.894204) (xy 242.559967 -319.876593) (xy 242.605933 -319.846877)
			(xy 242.655675 -319.824036) (xy 242.708171 -319.808538) (xy 242.762342 -319.800702) (xy 242.78971 -319.800224)
			(xy 242.816965 -319.800646) (xy 242.870919 -319.808405) (xy 242.923219 -319.823764) (xy 242.972802 -319.84641)
			(xy 243.018656 -319.875882) (xy 243.05985 -319.91158) (xy 243.095543 -319.952777) (xy 243.12501 -319.998635)
			(xy 243.147651 -320.04822) (xy 243.163004 -320.100522) (xy 243.170757 -320.154477) (xy 243.171218 -320.181732)
			(xy 243.170791 -320.209104) (xy 243.162967 -320.263285) (xy 243.14747 -320.31579) (xy 243.124619 -320.365536)
			(xy 243.094884 -320.4115) (xy 243.077238 -320.43243) (xy 243.071142 -320.439542) (xy 243.064792 -320.45656)
			(xy 243.064792 -320.541904) (xy 243.071142 -320.558922) (xy 243.077238 -320.566034) (xy 243.094866 -320.586975)
			(xy 243.124578 -320.632946) (xy 243.147416 -320.682691) (xy 243.16291 -320.73519) (xy 243.170742 -320.789364)
			(xy 243.171218 -320.816732) (xy 243.170752 -320.843984) (xy 243.162991 -320.897931) (xy 243.147633 -320.950226)
			(xy 243.124989 -320.999803) (xy 243.09552 -321.045652) (xy 243.059826 -321.086842) (xy 243.018635 -321.122533)
			(xy 242.972783 -321.151999) (xy 242.923205 -321.17464) (xy 242.87091 -321.189996) (xy 242.816962 -321.197754)
			(xy 242.78971 -321.19824) (xy 242.762339 -321.197783) (xy 242.708159 -321.189965) (xy 242.655655 -321.174475)
			(xy 242.605909 -321.151631) (xy 242.559943 -321.121903) (xy 242.539012 -321.10426) (xy 242.5319 -321.098164)
			(xy 242.514882 -321.091814) (xy 242.429538 -321.091814) (xy 242.41252 -321.098164) (xy 242.405408 -321.10426)
			(xy 242.384475 -321.121901) (xy 242.338507 -321.151625) (xy 242.288761 -321.174471) (xy 242.236259 -321.189967)
			(xy 242.182081 -321.197796) (xy 242.127339 -321.197796) (xy 242.073161 -321.189967) (xy 242.020659 -321.174471)
			(xy 241.970913 -321.151625) (xy 241.924945 -321.121901) (xy 241.904012 -321.10426) (xy 241.8969 -321.098164)
			(xy 241.879882 -321.091814) (xy 241.794538 -321.091814) (xy 241.77752 -321.098164) (xy 241.770408 -321.10426)
			(xy 241.749479 -321.121903) (xy 241.703506 -321.151615) (xy 241.653758 -321.174451) (xy 241.601256 -321.189941)
			(xy 241.547079 -321.197767) (xy 241.51971 -321.19824) (xy 241.49246 -321.197713) (xy 241.438516 -321.189958)
			(xy 241.386224 -321.174606) (xy 241.336649 -321.151968) (xy 241.2908 -321.122506) (xy 241.249611 -321.086819)
			(xy 241.213919 -321.045634) (xy 241.184452 -320.999788) (xy 241.161809 -320.950215) (xy 241.146451 -320.897925)
			(xy 241.13869 -320.843981) (xy 241.138202 -320.816732) (xy 234.475274 -320.816732) (xy 234.475274 -321.122548)
			(xy 234.475705 -321.132615) (xy 234.483429 -321.151209) (xy 234.49026 -321.158616) (xy 234.7595 -321.427856)
			(xy 234.766896 -321.434707) (xy 234.785495 -321.442449) (xy 234.795568 -321.442842)
		)
		(stroke
			(width 0)
			(type solid)
		)
		(fill yes)
		(layer "In5.Cu")
		(net "GND")
	)
	(gr_poly
		(pts
			(xy 154.780488 -295.88714) (xy 154.919426 -295.88714) (xy 154.922982 -295.887394) (xy 155.727146 -295.887394)
			(xy 155.730702 -295.88714) (xy 155.869386 -295.88714) (xy 155.872942 -295.887394) (xy 156.677106 -295.887394)
			(xy 156.680662 -295.88714) (xy 157.769306 -295.88714) (xy 157.772862 -295.887394) (xy 158.577026 -295.887394)
			(xy 158.580582 -295.88714) (xy 159.669226 -295.88714) (xy 159.672782 -295.887394) (xy 160.476946 -295.887394)
			(xy 160.480502 -295.88714) (xy 160.61944 -295.88714) (xy 160.622996 -295.887394) (xy 161.42716 -295.887394)
			(xy 161.430716 -295.88714) (xy 161.5694 -295.88714) (xy 161.572956 -295.887394) (xy 162.37712 -295.887394)
			(xy 162.380676 -295.88714) (xy 162.51936 -295.88714) (xy 162.522916 -295.887394) (xy 162.523932 -295.887394)
			(xy 162.994086 -295.887394) (xy 163.004149 -295.886955) (xy 163.02273 -295.879218) (xy 163.030154 -295.872408)
			(xy 163.26866 -295.633902) (xy 163.275511 -295.626505) (xy 163.283253 -295.607907) (xy 163.283646 -295.597834)
			(xy 163.283646 -293.995094) (xy 163.28322 -293.985025) (xy 163.275498 -293.966428) (xy 163.26866 -293.959026)
			(xy 163.137088 -293.827454) (xy 163.129155 -293.820196) (xy 163.109086 -293.812533) (xy 163.087639 -293.813747)
			(xy 163.077906 -293.81831) (xy 163.077652 -293.81831) (xy 163.05394 -293.830064) (xy 163.003704 -293.846707)
			(xy 162.951458 -293.855135) (xy 162.924998 -293.855648) (xy 162.924744 -293.855648) (xy 162.901229 -293.855236)
			(xy 162.854674 -293.84857) (xy 162.809535 -293.835367) (xy 162.766726 -293.815894) (xy 162.74669 -293.803578)
			(xy 162.731704 -293.793926) (xy 162.696398 -293.797482) (xy 162.676078 -293.817548) (xy 162.65779 -293.825168)
			(xy 162.649916 -293.825168) (xy 162.252406 -293.825168) (xy 162.242246 -293.825168) (xy 162.223958 -293.817548)
			(xy 162.203638 -293.797482) (xy 162.168332 -293.793926) (xy 162.153346 -293.803578) (xy 162.133308 -293.815888)
			(xy 162.090492 -293.835339) (xy 162.045355 -293.848538) (xy 161.998805 -293.855218) (xy 161.975292 -293.855648)
			(xy 161.974784 -293.855648) (xy 161.951268 -293.855239) (xy 161.904711 -293.848578) (xy 161.859569 -293.83538)
			(xy 161.816756 -293.815911) (xy 161.79673 -293.803578) (xy 161.781744 -293.793926) (xy 161.746438 -293.797482)
			(xy 161.726118 -293.817548) (xy 161.70783 -293.825168) (xy 161.699956 -293.825168) (xy 160.352232 -293.825168)
			(xy 160.342072 -293.825168) (xy 160.323784 -293.817548) (xy 160.303464 -293.797482) (xy 160.268158 -293.793926)
			(xy 160.253172 -293.803578) (xy 160.233134 -293.815889) (xy 160.190319 -293.835344) (xy 160.145182 -293.848547)
			(xy 160.098632 -293.85523) (xy 160.075118 -293.855648) (xy 160.07461 -293.855648) (xy 160.051094 -293.855241)
			(xy 160.004535 -293.848583) (xy 159.959391 -293.835388) (xy 159.916576 -293.815921) (xy 159.896556 -293.803578)
			(xy 159.88157 -293.793926) (xy 159.846264 -293.797482) (xy 159.825944 -293.817548) (xy 159.807656 -293.825168)
			(xy 159.799782 -293.825168) (xy 159.385 -293.825168) (xy 159.381065 -293.825195) (xy 159.37328 -293.82634)
			(xy 159.369506 -293.827454) (xy 159.347916 -293.834566) (xy 159.341566 -293.838884) (xy 159.317545 -293.854814)
			(xy 159.265722 -293.880042) (xy 159.210699 -293.8972) (xy 159.153722 -293.905901) (xy 159.124904 -293.906448)
			(xy 159.096082 -293.905926) (xy 159.039095 -293.897255) (xy 158.984066 -293.880095) (xy 158.932251 -293.854838)
			(xy 158.908242 -293.838884) (xy 158.901892 -293.834566) (xy 158.880302 -293.827454) (xy 158.876521 -293.826372)
			(xy 158.86874 -293.82523) (xy 158.864808 -293.825168) (xy 158.452312 -293.825168) (xy 158.442152 -293.825168)
			(xy 158.423864 -293.817548) (xy 158.403544 -293.797482) (xy 158.368238 -293.793926) (xy 158.353252 -293.803578)
			(xy 158.333214 -293.815888) (xy 158.290398 -293.835341) (xy 158.245262 -293.84854) (xy 158.198711 -293.855221)
			(xy 158.175198 -293.855648) (xy 158.17469 -293.855648) (xy 158.151174 -293.855239) (xy 158.104616 -293.848579)
			(xy 158.059474 -293.835382) (xy 158.016661 -293.815913) (xy 157.996636 -293.803578) (xy 157.98165 -293.793926)
			(xy 157.946344 -293.797482) (xy 157.926024 -293.817548) (xy 157.907736 -293.825168) (xy 157.899862 -293.825168)
			(xy 157.502352 -293.825168) (xy 157.492192 -293.825168) (xy 157.473904 -293.817548) (xy 157.453584 -293.797482)
			(xy 157.418278 -293.793926) (xy 157.403292 -293.803578) (xy 157.383255 -293.81589) (xy 157.34044 -293.835348)
			(xy 157.295303 -293.848553) (xy 157.248752 -293.85524) (xy 157.225238 -293.855648) (xy 157.22473 -293.855648)
			(xy 157.201215 -293.855235) (xy 157.154661 -293.848567) (xy 157.109523 -293.835363) (xy 157.066715 -293.815888)
			(xy 157.046676 -293.803578) (xy 157.03169 -293.793926) (xy 156.996384 -293.797482) (xy 156.976064 -293.817548)
			(xy 156.957776 -293.825168) (xy 156.949902 -293.825168) (xy 156.552392 -293.825168) (xy 156.542232 -293.825168)
			(xy 156.523944 -293.817548) (xy 156.503624 -293.797482) (xy 156.468318 -293.793926) (xy 156.453332 -293.803578)
			(xy 156.433294 -293.815887) (xy 156.390478 -293.835337) (xy 156.345341 -293.848533) (xy 156.298791 -293.855212)
			(xy 156.275278 -293.855648) (xy 156.275024 -293.855648) (xy 156.247282 -293.855077) (xy 156.192575 -293.845812)
			(xy 156.140181 -293.827553) (xy 156.091564 -293.800812) (xy 156.048089 -293.766338) (xy 156.010971 -293.725096)
			(xy 155.995624 -293.701978) (xy 155.988512 -293.693088) (xy 155.822904 -293.52748) (xy 155.812744 -293.51732)
			(xy 155.785312 -293.510462) (xy 155.672028 -293.546276) (xy 155.653486 -293.567358) (xy 155.650946 -293.581582)
			(xy 155.646064 -293.606834) (xy 155.629522 -293.65553) (xy 155.60564 -293.701078) (xy 155.574993 -293.742379)
			(xy 155.53832 -293.778436) (xy 155.496507 -293.80838) (xy 155.450561 -293.831488) (xy 155.401591 -293.847203)
			(xy 155.350779 -293.855145) (xy 155.325064 -293.855648) (xy 155.299078 -293.855136) (xy 155.247745 -293.847001)
			(xy 155.198317 -293.830937) (xy 155.152009 -293.80734) (xy 155.109963 -293.776791) (xy 155.073212 -293.74004)
			(xy 155.042662 -293.697994) (xy 155.019064 -293.651687) (xy 155.003 -293.602259) (xy 154.994865 -293.550926)
			(xy 154.994356 -293.52494) (xy 154.994848 -293.499228) (xy 155.002814 -293.448424) (xy 155.018545 -293.399465)
			(xy 155.041661 -293.353529) (xy 155.071607 -293.311724) (xy 155.10766 -293.275055) (xy 155.148953 -293.244405)
			(xy 155.19449 -293.220514) (xy 155.243176 -293.203957) (xy 155.268422 -293.199058) (xy 155.282646 -293.196518)
			(xy 155.303728 -293.177976) (xy 155.335224 -293.078408) (xy 155.337616 -293.069421) (xy 155.336489 -293.050873)
			(xy 155.328817 -293.03395) (xy 155.322524 -293.0271) (xy 155.157932 -292.862508) (xy 155.153614 -292.858698)
			(xy 155.147264 -292.853618) (xy 155.145232 -292.852348) (xy 155.125949 -292.839387) (xy 155.090872 -292.808918)
			(xy 155.060404 -292.77384) (xy 155.047442 -292.754558) (xy 155.046172 -292.752526) (xy 155.041092 -292.746176)
			(xy 155.037282 -292.741858) (xy 154.872944 -292.57752) (xy 154.862784 -292.56736) (xy 154.835352 -292.560502)
			(xy 154.722068 -292.596316) (xy 154.703526 -292.617398) (xy 154.700986 -292.631622) (xy 154.696101 -292.656873)
			(xy 154.679557 -292.705567) (xy 154.655672 -292.751114) (xy 154.625025 -292.792413) (xy 154.588353 -292.828469)
			(xy 154.546541 -292.858413) (xy 154.500597 -292.881523) (xy 154.451629 -292.897241) (xy 154.400818 -292.905189)
			(xy 154.375104 -292.905688) (xy 154.349115 -292.905205) (xy 154.297777 -292.897074) (xy 154.248343 -292.881012)
			(xy 154.202031 -292.857414) (xy 154.159981 -292.826862) (xy 154.123228 -292.790107) (xy 154.092677 -292.748055)
			(xy 154.069082 -292.701742) (xy 154.053022 -292.652307) (xy 154.044894 -292.600969) (xy 154.044396 -292.57498)
			(xy 154.044885 -292.549267) (xy 154.052847 -292.498461) (xy 154.068574 -292.449499) (xy 154.091689 -292.40356)
			(xy 154.121635 -292.361752) (xy 154.157689 -292.325082) (xy 154.198984 -292.294433) (xy 154.244525 -292.270543)
			(xy 154.293214 -292.253989) (xy 154.318462 -292.249098) (xy 154.332686 -292.246558) (xy 154.353768 -292.228016)
			(xy 154.385264 -292.128448) (xy 154.387663 -292.119458) (xy 154.386549 -292.100902) (xy 154.378888 -292.083963)
			(xy 154.372564 -292.07714) (xy 154.207972 -291.912548) (xy 154.203654 -291.908738) (xy 154.197304 -291.903658)
			(xy 154.195272 -291.902388) (xy 154.175989 -291.889427) (xy 154.140914 -291.858957) (xy 154.110448 -291.823878)
			(xy 154.097482 -291.804598) (xy 154.096212 -291.802566) (xy 154.091132 -291.796216) (xy 154.087322 -291.791898)
			(xy 153.92273 -291.627306) (xy 153.91257 -291.617146) (xy 153.885138 -291.610288) (xy 153.771854 -291.646102)
			(xy 153.753312 -291.667184) (xy 153.750772 -291.681408) (xy 153.745888 -291.706659) (xy 153.729345 -291.755354)
			(xy 153.705461 -291.800901) (xy 153.674814 -291.842201) (xy 153.638141 -291.878258) (xy 153.596329 -291.908202)
			(xy 153.550384 -291.931311) (xy 153.501416 -291.947028) (xy 153.450605 -291.954973) (xy 153.42489 -291.955474)
			(xy 153.398902 -291.95499) (xy 153.347567 -291.946857) (xy 153.298136 -291.930794) (xy 153.251826 -291.907195)
			(xy 153.209779 -291.876642) (xy 153.173029 -291.839887) (xy 153.142482 -291.797836) (xy 153.118889 -291.751523)
			(xy 153.102832 -291.70209) (xy 153.094706 -291.650754) (xy 153.094182 -291.624766) (xy 153.094672 -291.599053)
			(xy 153.102635 -291.548248) (xy 153.118364 -291.499287) (xy 153.141479 -291.453349) (xy 153.171425 -291.411542)
			(xy 153.207479 -291.374872) (xy 153.248773 -291.344223) (xy 153.294313 -291.320333) (xy 153.343 -291.303778)
			(xy 153.368248 -291.298884) (xy 153.382472 -291.296344) (xy 153.403554 -291.277802) (xy 153.43505 -291.178234)
			(xy 153.437446 -291.169245) (xy 153.436328 -291.150692) (xy 153.428663 -291.133759) (xy 153.42235 -291.126926)
			(xy 153.252678 -290.957254) (xy 153.247852 -290.954206) (xy 153.227526 -290.940816) (xy 153.190675 -290.909021)
			(xy 153.158881 -290.872169) (xy 153.14549 -290.851844) (xy 153.142442 -290.847018) (xy 152.97277 -290.677346)
			(xy 152.96261 -290.667186) (xy 152.935178 -290.660328) (xy 152.821894 -290.696142) (xy 152.803352 -290.717224)
			(xy 152.800812 -290.731448) (xy 152.795933 -290.756704) (xy 152.779396 -290.805409) (xy 152.755517 -290.850967)
			(xy 152.724873 -290.892278) (xy 152.688201 -290.928346) (xy 152.646387 -290.958301) (xy 152.600439 -290.98142)
			(xy 152.551466 -290.997146) (xy 152.500648 -291.0051) (xy 152.47493 -291.005514) (xy 152.448939 -291.005033)
			(xy 152.397596 -290.996906) (xy 152.348158 -290.980846) (xy 152.30184 -290.95725) (xy 152.259784 -290.926698)
			(xy 152.223025 -290.889944) (xy 152.192469 -290.847891) (xy 152.168868 -290.801576) (xy 152.152803 -290.752139)
			(xy 152.14467 -290.700797) (xy 152.144222 -290.674806) (xy 152.144717 -290.649095) (xy 152.152687 -290.598293)
			(xy 152.16842 -290.549337) (xy 152.191537 -290.503403) (xy 152.221483 -290.461599) (xy 152.257535 -290.424931)
			(xy 152.298826 -290.394282) (xy 152.344361 -290.37039) (xy 152.393044 -290.35383) (xy 152.418288 -290.348924)
			(xy 152.432512 -290.346384) (xy 152.453594 -290.327842) (xy 152.48509 -290.228274) (xy 152.487496 -290.219284)
			(xy 152.486389 -290.200723) (xy 152.478724 -290.183782) (xy 152.47239 -290.176966) (xy 152.302718 -290.007294)
			(xy 152.297892 -290.004246) (xy 152.277898 -289.991079) (xy 152.241567 -289.959902) (xy 152.210102 -289.923821)
			(xy 152.1968 -289.903916) (xy 152.19553 -289.901884) (xy 152.19045 -289.895534) (xy 152.18664 -289.891216)
			(xy 151.553926 -289.258502) (xy 151.546577 -289.251703) (xy 151.528114 -289.243997) (xy 151.518112 -289.243516)
			(xy 148.276564 -289.243516) (xy 148.263925 -289.244199) (xy 148.24168 -289.256203) (xy 148.234146 -289.266376)
			(xy 148.18741 -289.336734) (xy 148.180968 -289.347565) (xy 148.178587 -289.37262) (xy 148.182838 -289.384486)
			(xy 148.182838 -289.38474) (xy 148.192178 -289.408036) (xy 148.205361 -289.456465) (xy 148.212089 -289.506204)
			(xy 148.212556 -289.531298) (xy 148.212556 -289.536886) (xy 148.211759 -289.563922) (xy 148.203477 -289.617371)
			(xy 148.187728 -289.669115) (xy 148.164828 -289.718115) (xy 148.135237 -289.76339) (xy 148.099547 -289.804031)
			(xy 148.058475 -289.839224) (xy 148.012844 -289.868262) (xy 147.963569 -289.890565) (xy 147.911638 -289.905683)
			(xy 147.858092 -289.913316) (xy 147.831048 -289.913822) (xy 147.802238 -289.913292) (xy 147.745272 -289.904624)
			(xy 147.690257 -289.887492) (xy 147.638441 -289.862287) (xy 147.591002 -289.829579) (xy 147.549019 -289.790113)
			(xy 147.53082 -289.767772) (xy 147.52066 -289.754818) (xy 147.489672 -289.745674) (xy 147.3835 -289.78225)
			(xy 147.373722 -289.78618) (xy 147.358248 -289.800453) (xy 147.349794 -289.819731) (xy 147.34921 -289.830256)
			(xy 147.34921 -290.294314) (xy 149.72106 -290.294314) (xy 149.725131 -290.238692) (xy 149.737257 -290.184255)
			(xy 149.75718 -290.132164) (xy 149.784476 -290.083529) (xy 149.818562 -290.039386) (xy 149.858711 -290.000677)
			(xy 149.904069 -289.968226) (xy 149.953669 -289.942725) (xy 150.006453 -289.924718) (xy 150.061296 -289.914588)
			(xy 150.11703 -289.912551) (xy 150.172467 -289.918651) (xy 150.226424 -289.932757) (xy 150.277753 -289.954569)
			(xy 150.325359 -289.983623) (xy 150.368227 -290.019298) (xy 150.405444 -290.060835) (xy 150.436217 -290.107348)
			(xy 150.459889 -290.157845) (xy 150.475957 -290.211252) (xy 150.484077 -290.266428) (xy 150.484586 -290.294314)
			(xy 150.484077 -290.3222) (xy 150.475957 -290.377376) (xy 150.459889 -290.430783) (xy 150.436217 -290.48128)
			(xy 150.405444 -290.527793) (xy 150.368227 -290.56933) (xy 150.325359 -290.605005) (xy 150.277753 -290.634059)
			(xy 150.226424 -290.655871) (xy 150.172467 -290.669977) (xy 150.11703 -290.676077) (xy 150.061296 -290.67404)
			(xy 150.006453 -290.66391) (xy 149.953669 -290.645903) (xy 149.904069 -290.620402) (xy 149.858711 -290.587951)
			(xy 149.818562 -290.549242) (xy 149.784476 -290.505099) (xy 149.75718 -290.456464) (xy 149.737257 -290.404373)
			(xy 149.725131 -290.349936) (xy 149.72106 -290.294314) (xy 147.34921 -290.294314) (xy 147.34921 -291.624766)
			(xy 152.169126 -291.624766) (xy 152.173086 -291.575712) (xy 152.184863 -291.527928) (xy 152.204154 -291.482652)
			(xy 152.230457 -291.441056) (xy 152.263092 -291.404219) (xy 152.301213 -291.373094) (xy 152.343834 -291.348487)
			(xy 152.38985 -291.331035) (xy 152.438069 -291.321191) (xy 152.487244 -291.31921) (xy 152.536099 -291.325142)
			(xy 152.58337 -291.338834) (xy 152.627832 -291.359932) (xy 152.668335 -291.387888) (xy 152.703828 -291.42198)
			(xy 152.733393 -291.461324) (xy 152.756264 -291.504901) (xy 152.771848 -291.551582) (xy 152.779743 -291.600159)
			(xy 152.780238 -291.624766) (xy 152.779743 -291.649373) (xy 152.771848 -291.69795) (xy 152.756264 -291.744631)
			(xy 152.733393 -291.788208) (xy 152.703828 -291.827552) (xy 152.668335 -291.861644) (xy 152.627832 -291.8896)
			(xy 152.58337 -291.910698) (xy 152.536099 -291.92439) (xy 152.487244 -291.930322) (xy 152.438069 -291.928341)
			(xy 152.38985 -291.918497) (xy 152.343834 -291.901045) (xy 152.301213 -291.876438) (xy 152.263092 -291.845313)
			(xy 152.230457 -291.808476) (xy 152.204154 -291.76688) (xy 152.184863 -291.721604) (xy 152.173086 -291.67382)
			(xy 152.169126 -291.624766) (xy 147.34921 -291.624766) (xy 147.34921 -292.169088) (xy 147.349631 -292.179159)
			(xy 147.357344 -292.197766) (xy 147.364196 -292.205156) (xy 147.43303 -292.27399) (xy 147.44043 -292.280833)
			(xy 147.459028 -292.288558) (xy 147.469098 -292.288976) (xy 150.309834 -292.288976) (xy 150.319902 -292.289405)
			(xy 150.3385 -292.297125) (xy 150.345902 -292.303962) (xy 150.61692 -292.57498) (xy 152.169126 -292.57498)
			(xy 152.173086 -292.525926) (xy 152.184863 -292.478142) (xy 152.204154 -292.432866) (xy 152.230457 -292.39127)
			(xy 152.263092 -292.354433) (xy 152.301213 -292.323308) (xy 152.343834 -292.298701) (xy 152.38985 -292.281249)
			(xy 152.438069 -292.271405) (xy 152.487244 -292.269424) (xy 152.536099 -292.275356) (xy 152.58337 -292.289048)
			(xy 152.627832 -292.310146) (xy 152.668335 -292.338102) (xy 152.703828 -292.372194) (xy 152.733393 -292.411538)
			(xy 152.756264 -292.455115) (xy 152.771848 -292.501796) (xy 152.779743 -292.550373) (xy 152.780238 -292.57498)
			(xy 153.119086 -292.57498) (xy 153.123046 -292.525926) (xy 153.134823 -292.478142) (xy 153.154114 -292.432866)
			(xy 153.180417 -292.39127) (xy 153.213052 -292.354433) (xy 153.251173 -292.323308) (xy 153.293794 -292.298701)
			(xy 153.33981 -292.281249) (xy 153.388029 -292.271405) (xy 153.437204 -292.269424) (xy 153.486059 -292.275356)
			(xy 153.53333 -292.289048) (xy 153.577792 -292.310146) (xy 153.618295 -292.338102) (xy 153.653788 -292.372194)
			(xy 153.683353 -292.411538) (xy 153.706224 -292.455115) (xy 153.721808 -292.501796) (xy 153.729703 -292.550373)
			(xy 153.730198 -292.57498) (xy 153.729703 -292.599587) (xy 153.721808 -292.648164) (xy 153.706224 -292.694845)
			(xy 153.683353 -292.738422) (xy 153.653788 -292.777766) (xy 153.618295 -292.811858) (xy 153.577792 -292.839814)
			(xy 153.53333 -292.860912) (xy 153.486059 -292.874604) (xy 153.437204 -292.880536) (xy 153.388029 -292.878555)
			(xy 153.33981 -292.868711) (xy 153.293794 -292.851259) (xy 153.251173 -292.826652) (xy 153.213052 -292.795527)
			(xy 153.180417 -292.75869) (xy 153.154114 -292.717094) (xy 153.134823 -292.671818) (xy 153.123046 -292.624034)
			(xy 153.119086 -292.57498) (xy 152.780238 -292.57498) (xy 152.779743 -292.599587) (xy 152.771848 -292.648164)
			(xy 152.756264 -292.694845) (xy 152.733393 -292.738422) (xy 152.703828 -292.777766) (xy 152.668335 -292.811858)
			(xy 152.627832 -292.839814) (xy 152.58337 -292.860912) (xy 152.536099 -292.874604) (xy 152.487244 -292.880536)
			(xy 152.438069 -292.878555) (xy 152.38985 -292.868711) (xy 152.343834 -292.851259) (xy 152.301213 -292.826652)
			(xy 152.263092 -292.795527) (xy 152.230457 -292.75869) (xy 152.204154 -292.717094) (xy 152.184863 -292.671818)
			(xy 152.173086 -292.624034) (xy 152.169126 -292.57498) (xy 150.61692 -292.57498) (xy 151.56688 -293.52494)
			(xy 154.0693 -293.52494) (xy 154.07326 -293.475886) (xy 154.085037 -293.428102) (xy 154.104328 -293.382826)
			(xy 154.130631 -293.34123) (xy 154.163266 -293.304393) (xy 154.201387 -293.273268) (xy 154.244008 -293.248661)
			(xy 154.290024 -293.231209) (xy 154.338243 -293.221365) (xy 154.387418 -293.219384) (xy 154.436273 -293.225316)
			(xy 154.483544 -293.239008) (xy 154.528006 -293.260106) (xy 154.568509 -293.288062) (xy 154.604002 -293.322154)
			(xy 154.633567 -293.361498) (xy 154.656438 -293.405075) (xy 154.672022 -293.451756) (xy 154.679917 -293.500333)
			(xy 154.680412 -293.52494) (xy 154.679917 -293.549547) (xy 154.672022 -293.598124) (xy 154.656438 -293.644805)
			(xy 154.633567 -293.688382) (xy 154.604002 -293.727726) (xy 154.568509 -293.761818) (xy 154.528006 -293.789774)
			(xy 154.483544 -293.810872) (xy 154.436273 -293.824564) (xy 154.387418 -293.830496) (xy 154.338243 -293.828515)
			(xy 154.290024 -293.818671) (xy 154.244008 -293.801219) (xy 154.201387 -293.776612) (xy 154.163266 -293.745487)
			(xy 154.130631 -293.70865) (xy 154.104328 -293.667054) (xy 154.085037 -293.621778) (xy 154.07326 -293.573994)
			(xy 154.0693 -293.52494) (xy 151.56688 -293.52494) (xy 152.24506 -294.20312) (xy 152.280366 -294.20693)
			(xy 152.295606 -294.197024) (xy 152.315742 -294.184512) (xy 152.358834 -294.164756) (xy 152.404307 -294.151358)
			(xy 152.451227 -294.144591) (xy 152.47493 -294.144192) (xy 152.500916 -294.144704) (xy 152.552246 -294.152838)
			(xy 152.601673 -294.168902) (xy 152.647978 -294.192499) (xy 152.690022 -294.223049) (xy 152.72677 -294.2598)
			(xy 152.757317 -294.301847) (xy 152.78091 -294.348155) (xy 152.796969 -294.397583) (xy 152.805099 -294.448914)
			(xy 152.805638 -294.4749) (xy 153.119086 -294.4749) (xy 153.123046 -294.425846) (xy 153.134823 -294.378062)
			(xy 153.154114 -294.332786) (xy 153.180417 -294.29119) (xy 153.213052 -294.254353) (xy 153.251173 -294.223228)
			(xy 153.293794 -294.198621) (xy 153.33981 -294.181169) (xy 153.388029 -294.171325) (xy 153.437204 -294.169344)
			(xy 153.486059 -294.175276) (xy 153.53333 -294.188968) (xy 153.577792 -294.210066) (xy 153.618295 -294.238022)
			(xy 153.653788 -294.272114) (xy 153.683353 -294.311458) (xy 153.706224 -294.355035) (xy 153.721808 -294.401716)
			(xy 153.729703 -294.450293) (xy 153.730198 -294.4749) (xy 154.0693 -294.4749) (xy 154.07326 -294.425846)
			(xy 154.085037 -294.378062) (xy 154.104328 -294.332786) (xy 154.130631 -294.29119) (xy 154.163266 -294.254353)
			(xy 154.201387 -294.223228) (xy 154.244008 -294.198621) (xy 154.290024 -294.181169) (xy 154.338243 -294.171325)
			(xy 154.387418 -294.169344) (xy 154.436273 -294.175276) (xy 154.483544 -294.188968) (xy 154.528006 -294.210066)
			(xy 154.568509 -294.238022) (xy 154.604002 -294.272114) (xy 154.633567 -294.311458) (xy 154.656438 -294.355035)
			(xy 154.672022 -294.401716) (xy 154.679917 -294.450293) (xy 154.680412 -294.4749) (xy 156.91918 -294.4749)
			(xy 156.92314 -294.425846) (xy 156.934917 -294.378062) (xy 156.954208 -294.332786) (xy 156.980511 -294.29119)
			(xy 157.013146 -294.254353) (xy 157.051267 -294.223228) (xy 157.093888 -294.198621) (xy 157.139904 -294.181169)
			(xy 157.188123 -294.171325) (xy 157.237298 -294.169344) (xy 157.286153 -294.175276) (xy 157.333424 -294.188968)
			(xy 157.377886 -294.210066) (xy 157.418389 -294.238022) (xy 157.453882 -294.272114) (xy 157.483447 -294.311458)
			(xy 157.506318 -294.355035) (xy 157.521902 -294.401716) (xy 157.529797 -294.450293) (xy 157.530292 -294.4749)
			(xy 157.529797 -294.499507) (xy 157.529465 -294.501549) (xy 157.819334 -294.501549) (xy 157.819334 -294.448251)
			(xy 157.827277 -294.395547) (xy 157.842987 -294.344617) (xy 157.866113 -294.296596) (xy 157.896137 -294.252559)
			(xy 157.932389 -294.213488) (xy 157.97406 -294.180257) (xy 158.020218 -294.153608) (xy 158.069832 -294.134136)
			(xy 158.121794 -294.122276) (xy 158.174944 -294.118293) (xy 158.228094 -294.122276) (xy 158.280056 -294.134136)
			(xy 158.32967 -294.153608) (xy 158.375828 -294.180257) (xy 158.417499 -294.213488) (xy 158.453751 -294.252559)
			(xy 158.483775 -294.296596) (xy 158.506901 -294.344617) (xy 158.522611 -294.395547) (xy 158.530554 -294.448251)
			(xy 158.531052 -294.4749) (xy 158.8191 -294.4749) (xy 158.82306 -294.425846) (xy 158.834837 -294.378062)
			(xy 158.854128 -294.332786) (xy 158.880431 -294.29119) (xy 158.913066 -294.254353) (xy 158.951187 -294.223228)
			(xy 158.993808 -294.198621) (xy 159.039824 -294.181169) (xy 159.088043 -294.171325) (xy 159.137218 -294.169344)
			(xy 159.186073 -294.175276) (xy 159.233344 -294.188968) (xy 159.277806 -294.210066) (xy 159.318309 -294.238022)
			(xy 159.353802 -294.272114) (xy 159.383367 -294.311458) (xy 159.406238 -294.355035) (xy 159.421822 -294.401716)
			(xy 159.429717 -294.450293) (xy 159.430212 -294.4749) (xy 159.76906 -294.4749) (xy 159.77302 -294.425846)
			(xy 159.784797 -294.378062) (xy 159.804088 -294.332786) (xy 159.830391 -294.29119) (xy 159.863026 -294.254353)
			(xy 159.901147 -294.223228) (xy 159.943768 -294.198621) (xy 159.989784 -294.181169) (xy 160.038003 -294.171325)
			(xy 160.087178 -294.169344) (xy 160.136033 -294.175276) (xy 160.183304 -294.188968) (xy 160.227766 -294.210066)
			(xy 160.268269 -294.238022) (xy 160.303762 -294.272114) (xy 160.333327 -294.311458) (xy 160.356198 -294.355035)
			(xy 160.371782 -294.401716) (xy 160.379677 -294.450293) (xy 160.380172 -294.4749) (xy 160.719274 -294.4749)
			(xy 160.723234 -294.425846) (xy 160.735011 -294.378062) (xy 160.754302 -294.332786) (xy 160.780605 -294.29119)
			(xy 160.81324 -294.254353) (xy 160.851361 -294.223228) (xy 160.893982 -294.198621) (xy 160.939998 -294.181169)
			(xy 160.988217 -294.171325) (xy 161.037392 -294.169344) (xy 161.086247 -294.175276) (xy 161.133518 -294.188968)
			(xy 161.17798 -294.210066) (xy 161.218483 -294.238022) (xy 161.253976 -294.272114) (xy 161.283541 -294.311458)
			(xy 161.306412 -294.355035) (xy 161.321996 -294.401716) (xy 161.329891 -294.450293) (xy 161.330386 -294.4749)
			(xy 161.669234 -294.4749) (xy 161.673194 -294.425846) (xy 161.684971 -294.378062) (xy 161.704262 -294.332786)
			(xy 161.730565 -294.29119) (xy 161.7632 -294.254353) (xy 161.801321 -294.223228) (xy 161.843942 -294.198621)
			(xy 161.889958 -294.181169) (xy 161.938177 -294.171325) (xy 161.987352 -294.169344) (xy 162.036207 -294.175276)
			(xy 162.083478 -294.188968) (xy 162.12794 -294.210066) (xy 162.168443 -294.238022) (xy 162.203936 -294.272114)
			(xy 162.233501 -294.311458) (xy 162.256372 -294.355035) (xy 162.271956 -294.401716) (xy 162.279851 -294.450293)
			(xy 162.280346 -294.4749) (xy 162.279851 -294.499507) (xy 162.271956 -294.548084) (xy 162.256372 -294.594765)
			(xy 162.233501 -294.638342) (xy 162.203936 -294.677686) (xy 162.168443 -294.711778) (xy 162.12794 -294.739734)
			(xy 162.083478 -294.760832) (xy 162.036207 -294.774524) (xy 161.987352 -294.780456) (xy 161.938177 -294.778475)
			(xy 161.889958 -294.768631) (xy 161.843942 -294.751179) (xy 161.801321 -294.726572) (xy 161.7632 -294.695447)
			(xy 161.730565 -294.65861) (xy 161.704262 -294.617014) (xy 161.684971 -294.571738) (xy 161.673194 -294.523954)
			(xy 161.669234 -294.4749) (xy 161.330386 -294.4749) (xy 161.329891 -294.499507) (xy 161.321996 -294.548084)
			(xy 161.306412 -294.594765) (xy 161.283541 -294.638342) (xy 161.253976 -294.677686) (xy 161.218483 -294.711778)
			(xy 161.17798 -294.739734) (xy 161.133518 -294.760832) (xy 161.086247 -294.774524) (xy 161.037392 -294.780456)
			(xy 160.988217 -294.778475) (xy 160.939998 -294.768631) (xy 160.893982 -294.751179) (xy 160.851361 -294.726572)
			(xy 160.81324 -294.695447) (xy 160.780605 -294.65861) (xy 160.754302 -294.617014) (xy 160.735011 -294.571738)
			(xy 160.723234 -294.523954) (xy 160.719274 -294.4749) (xy 160.380172 -294.4749) (xy 160.379677 -294.499507)
			(xy 160.371782 -294.548084) (xy 160.356198 -294.594765) (xy 160.333327 -294.638342) (xy 160.303762 -294.677686)
			(xy 160.268269 -294.711778) (xy 160.227766 -294.739734) (xy 160.183304 -294.760832) (xy 160.136033 -294.774524)
			(xy 160.087178 -294.780456) (xy 160.038003 -294.778475) (xy 159.989784 -294.768631) (xy 159.943768 -294.751179)
			(xy 159.901147 -294.726572) (xy 159.863026 -294.695447) (xy 159.830391 -294.65861) (xy 159.804088 -294.617014)
			(xy 159.784797 -294.571738) (xy 159.77302 -294.523954) (xy 159.76906 -294.4749) (xy 159.430212 -294.4749)
			(xy 159.429717 -294.499507) (xy 159.421822 -294.548084) (xy 159.406238 -294.594765) (xy 159.383367 -294.638342)
			(xy 159.353802 -294.677686) (xy 159.318309 -294.711778) (xy 159.277806 -294.739734) (xy 159.233344 -294.760832)
			(xy 159.186073 -294.774524) (xy 159.137218 -294.780456) (xy 159.088043 -294.778475) (xy 159.039824 -294.768631)
			(xy 158.993808 -294.751179) (xy 158.951187 -294.726572) (xy 158.913066 -294.695447) (xy 158.880431 -294.65861)
			(xy 158.854128 -294.617014) (xy 158.834837 -294.571738) (xy 158.82306 -294.523954) (xy 158.8191 -294.4749)
			(xy 158.531052 -294.4749) (xy 158.530554 -294.501549) (xy 158.522611 -294.554253) (xy 158.506901 -294.605183)
			(xy 158.483775 -294.653204) (xy 158.453751 -294.697241) (xy 158.417499 -294.736312) (xy 158.375828 -294.769543)
			(xy 158.32967 -294.796192) (xy 158.280056 -294.815664) (xy 158.228094 -294.827524) (xy 158.174944 -294.831508)
			(xy 158.121794 -294.827524) (xy 158.069832 -294.815664) (xy 158.020218 -294.796192) (xy 157.97406 -294.769543)
			(xy 157.932389 -294.736312) (xy 157.896137 -294.697241) (xy 157.866113 -294.653204) (xy 157.842987 -294.605183)
			(xy 157.827277 -294.554253) (xy 157.819334 -294.501549) (xy 157.529465 -294.501549) (xy 157.521902 -294.548084)
			(xy 157.506318 -294.594765) (xy 157.483447 -294.638342) (xy 157.453882 -294.677686) (xy 157.418389 -294.711778)
			(xy 157.377886 -294.739734) (xy 157.333424 -294.760832) (xy 157.286153 -294.774524) (xy 157.237298 -294.780456)
			(xy 157.188123 -294.778475) (xy 157.139904 -294.768631) (xy 157.093888 -294.751179) (xy 157.051267 -294.726572)
			(xy 157.013146 -294.695447) (xy 156.980511 -294.65861) (xy 156.954208 -294.617014) (xy 156.934917 -294.571738)
			(xy 156.92314 -294.523954) (xy 156.91918 -294.4749) (xy 154.680412 -294.4749) (xy 154.679917 -294.499507)
			(xy 154.672022 -294.548084) (xy 154.656438 -294.594765) (xy 154.633567 -294.638342) (xy 154.604002 -294.677686)
			(xy 154.568509 -294.711778) (xy 154.528006 -294.739734) (xy 154.483544 -294.760832) (xy 154.436273 -294.774524)
			(xy 154.387418 -294.780456) (xy 154.338243 -294.778475) (xy 154.290024 -294.768631) (xy 154.244008 -294.751179)
			(xy 154.201387 -294.726572) (xy 154.163266 -294.695447) (xy 154.130631 -294.65861) (xy 154.104328 -294.617014)
			(xy 154.085037 -294.571738) (xy 154.07326 -294.523954) (xy 154.0693 -294.4749) (xy 153.730198 -294.4749)
			(xy 153.729703 -294.499507) (xy 153.721808 -294.548084) (xy 153.706224 -294.594765) (xy 153.683353 -294.638342)
			(xy 153.653788 -294.677686) (xy 153.618295 -294.711778) (xy 153.577792 -294.739734) (xy 153.53333 -294.760832)
			(xy 153.486059 -294.774524) (xy 153.437204 -294.780456) (xy 153.388029 -294.778475) (xy 153.33981 -294.768631)
			(xy 153.293794 -294.751179) (xy 153.251173 -294.726572) (xy 153.213052 -294.695447) (xy 153.180417 -294.65861)
			(xy 153.154114 -294.617014) (xy 153.134823 -294.571738) (xy 153.123046 -294.523954) (xy 153.119086 -294.4749)
			(xy 152.805638 -294.4749) (xy 152.805231 -294.498602) (xy 152.798463 -294.545521) (xy 152.785066 -294.590993)
			(xy 152.765314 -294.634087) (xy 152.752806 -294.654224) (xy 152.7429 -294.669464) (xy 152.74671 -294.70477)
			(xy 153.622502 -295.580562) (xy 153.628099 -295.586559) (xy 153.635476 -295.6012) (xy 153.63698 -295.609264)
			(xy 153.63825 -295.617392) (xy 153.645616 -295.632124) (xy 153.8859 -295.872408) (xy 153.89331 -295.879091)
			(xy 153.911746 -295.886672) (xy 153.921714 -295.88714) (xy 153.969212 -295.88714) (xy 153.972768 -295.887394)
			(xy 154.776932 -295.887394)
		)
		(stroke
			(width 0)
			(type solid)
		)
		(fill yes)
		(layer "In5.Cu")
		(net "PCEPLL4_VDDA18_PEX1")
	)
	(gr_poly
		(pts
			(xy 465.322666 -401.877784) (xy 465.332731 -401.877348) (xy 465.351316 -401.869615) (xy 465.358734 -401.862798)
			(xy 465.977478 -401.244054) (xy 465.98432 -401.236654) (xy 465.992041 -401.218056) (xy 465.992464 -401.207986)
			(xy 465.992464 -308.571392) (xy 465.967826 -308.542944) (xy 465.94903 -308.54015) (xy 465.922217 -308.535696)
			(xy 465.870125 -308.520188) (xy 465.82076 -308.497445) (xy 465.775121 -308.467928) (xy 465.734134 -308.432233)
			(xy 465.698626 -308.391082) (xy 465.669317 -308.34531) (xy 465.6468 -308.295842) (xy 465.631531 -308.243679)
			(xy 465.623818 -308.189877) (xy 465.623818 -308.135525) (xy 465.63153 -308.081723) (xy 465.6468 -308.02956)
			(xy 465.669316 -307.980092) (xy 465.698625 -307.934319) (xy 465.734133 -307.893169) (xy 465.77512 -307.857473)
			(xy 465.820758 -307.827955) (xy 465.870123 -307.805212) (xy 465.922216 -307.789705) (xy 465.94903 -307.785262)
			(xy 465.967826 -307.782468) (xy 465.992464 -307.75402) (xy 465.992464 -290.987226) (xy 465.992027 -290.977163)
			(xy 465.984289 -290.958581) (xy 465.977478 -290.951158) (xy 465.377022 -290.350702) (xy 465.369619 -290.343868)
			(xy 465.351021 -290.336162) (xy 465.340954 -290.335716) (xy 459.932024 -290.335716) (xy 459.921618 -290.336209)
			(xy 459.902511 -290.34446) (xy 459.888248 -290.359616) (xy 459.884272 -290.369244) (xy 459.846172 -290.473892)
			(xy 459.854554 -290.50488) (xy 459.866746 -290.515294) (xy 459.88773 -290.533506) (xy 459.924717 -290.574965)
			(xy 459.955297 -290.621352) (xy 459.978823 -290.671685) (xy 459.994796 -290.724899) (xy 460.00288 -290.779868)
			(xy 460.003398 -290.807648) (xy 460.002908 -290.834897) (xy 459.995146 -290.888839) (xy 459.979787 -290.941127)
			(xy 459.957143 -290.990697) (xy 459.927675 -291.036541) (xy 459.891984 -291.077725) (xy 459.850795 -291.11341)
			(xy 459.804947 -291.142871) (xy 459.755373 -291.165507) (xy 459.703082 -291.180859) (xy 459.649139 -291.188613)
			(xy 459.62189 -291.189156) (xy 459.59452 -291.188683) (xy 459.540344 -291.180858) (xy 459.487842 -291.165368)
			(xy 459.438093 -291.142533) (xy 459.392119 -291.112821) (xy 459.371192 -291.095176) (xy 459.36408 -291.08908)
			(xy 459.347062 -291.08273) (xy 459.261718 -291.08273) (xy 459.2447 -291.08908) (xy 459.237588 -291.095176)
			(xy 459.216657 -291.112818) (xy 459.170691 -291.142545) (xy 459.120944 -291.165388) (xy 459.06844 -291.180877)
			(xy 459.014261 -291.188695) (xy 458.98689 -291.189156) (xy 458.959638 -291.18867) (xy 458.905689 -291.180912)
			(xy 458.853392 -291.165557) (xy 458.803813 -291.142916) (xy 458.757961 -291.11345) (xy 458.716768 -291.077759)
			(xy 458.681073 -291.03657) (xy 458.651603 -290.99072) (xy 458.628957 -290.941143) (xy 458.613596 -290.888848)
			(xy 458.605833 -290.8349) (xy 458.605382 -290.807648) (xy 458.605901 -290.779868) (xy 458.613992 -290.7249)
			(xy 458.629967 -290.671685) (xy 458.653487 -290.621349) (xy 458.684057 -290.574954) (xy 458.72103 -290.533482)
			(xy 458.742034 -290.515294) (xy 458.754226 -290.50488) (xy 458.762608 -290.473892) (xy 458.724508 -290.369244)
			(xy 458.720496 -290.359639) (xy 458.706239 -290.3445) (xy 458.687153 -290.336245) (xy 458.676756 -290.335716)
			(xy 452.700898 -290.335716) (xy 452.690828 -290.335293) (xy 452.672222 -290.32758) (xy 452.66483 -290.32073)
			(xy 451.82282 -289.47872) (xy 451.815418 -289.471884) (xy 451.79682 -289.464176) (xy 451.786752 -289.463734)
			(xy 444.755524 -289.463734) (xy 444.745502 -289.46415) (xy 444.726983 -289.471817) (xy 444.712811 -289.485991)
			(xy 444.705148 -289.504512) (xy 444.704724 -289.514534) (xy 444.704724 -291.574054) (xy 452.196643 -291.574054)
			(xy 452.196643 -291.519546) (xy 452.2044 -291.465593) (xy 452.219757 -291.413292) (xy 452.242401 -291.36371)
			(xy 452.271871 -291.317855) (xy 452.307566 -291.276661) (xy 452.348761 -291.240966) (xy 452.394617 -291.211497)
			(xy 452.4442 -291.188854) (xy 452.4965 -291.173499) (xy 452.550454 -291.165742) (xy 452.577708 -291.16528)
			(xy 452.605079 -291.165722) (xy 452.65926 -291.173543) (xy 452.711764 -291.189036) (xy 452.761511 -291.211884)
			(xy 452.807476 -291.241615) (xy 452.828406 -291.25926) (xy 452.835518 -291.265356) (xy 452.852536 -291.271706)
			(xy 452.93788 -291.271706) (xy 452.954898 -291.265356) (xy 452.96201 -291.25926) (xy 452.982922 -291.241596)
			(xy 453.028901 -291.211889) (xy 453.078654 -291.189059) (xy 453.131158 -291.173573) (xy 453.185338 -291.165751)
			(xy 453.212708 -291.16528) (xy 453.239958 -291.165791) (xy 453.293903 -291.173548) (xy 453.346195 -291.188903)
			(xy 453.39577 -291.211544) (xy 453.441618 -291.24101) (xy 453.482806 -291.2767) (xy 453.518495 -291.317889)
			(xy 453.54796 -291.363737) (xy 453.5706 -291.413312) (xy 453.585954 -291.465605) (xy 453.59371 -291.51955)
			(xy 453.59371 -291.57405) (xy 453.585954 -291.627995) (xy 453.5706 -291.680288) (xy 453.54796 -291.729863)
			(xy 453.518495 -291.775711) (xy 453.482806 -291.8169) (xy 453.441618 -291.85259) (xy 453.39577 -291.882056)
			(xy 453.346195 -291.904697) (xy 453.293903 -291.920052) (xy 453.239958 -291.927809) (xy 453.212708 -291.928296)
			(xy 453.185338 -291.927826) (xy 453.131159 -291.920009) (xy 453.078656 -291.904521) (xy 453.028909 -291.88168)
			(xy 452.982942 -291.851957) (xy 452.96201 -291.834316) (xy 452.954898 -291.82822) (xy 452.93788 -291.82187)
			(xy 452.852536 -291.82187) (xy 452.835518 -291.82822) (xy 452.828406 -291.834316) (xy 452.807485 -291.851968)
			(xy 452.761509 -291.881678) (xy 452.711758 -291.904511) (xy 452.659255 -291.919999) (xy 452.605078 -291.927824)
			(xy 452.577708 -291.928296) (xy 452.550454 -291.927858) (xy 452.4965 -291.920101) (xy 452.4442 -291.904746)
			(xy 452.394617 -291.882103) (xy 452.348761 -291.852634) (xy 452.307566 -291.816939) (xy 452.271871 -291.775745)
			(xy 452.242401 -291.72989) (xy 452.219757 -291.680308) (xy 452.2044 -291.628007) (xy 452.196643 -291.574054)
			(xy 444.704724 -291.574054) (xy 444.704724 -305.5366) (xy 444.704296 -305.569474) (xy 444.696964 -305.634811)
			(xy 444.68236 -305.698916) (xy 444.660666 -305.760982) (xy 444.632157 -305.820227) (xy 444.59719 -305.875905)
			(xy 444.556206 -305.927315) (xy 444.533274 -305.950874) (xy 444.46571 -306.018438) (xy 444.458904 -306.025785)
			(xy 444.451184 -306.044247) (xy 444.450724 -306.054252) (xy 444.450724 -306.158646) (xy 459.899002 -306.158646)
			(xy 459.903073 -306.103024) (xy 459.915199 -306.048587) (xy 459.935122 -305.996496) (xy 459.962418 -305.947861)
			(xy 459.996504 -305.903718) (xy 460.036653 -305.865009) (xy 460.082011 -305.832558) (xy 460.131611 -305.807057)
			(xy 460.184395 -305.78905) (xy 460.239238 -305.77892) (xy 460.294972 -305.776883) (xy 460.350409 -305.782983)
			(xy 460.404366 -305.797089) (xy 460.455695 -305.818901) (xy 460.503301 -305.847955) (xy 460.546169 -305.88363)
			(xy 460.583386 -305.925167) (xy 460.614159 -305.97168) (xy 460.637831 -306.022177) (xy 460.653899 -306.075584)
			(xy 460.662019 -306.13076) (xy 460.662528 -306.158646) (xy 460.662019 -306.186532) (xy 460.653899 -306.241708)
			(xy 460.637831 -306.295115) (xy 460.614159 -306.345612) (xy 460.583386 -306.392125) (xy 460.546169 -306.433662)
			(xy 460.503301 -306.469337) (xy 460.455695 -306.498391) (xy 460.404366 -306.520203) (xy 460.350409 -306.534309)
			(xy 460.294972 -306.540409) (xy 460.239238 -306.538372) (xy 460.184395 -306.528242) (xy 460.131611 -306.510235)
			(xy 460.082011 -306.484734) (xy 460.036653 -306.452283) (xy 459.996504 -306.413574) (xy 459.962418 -306.369431)
			(xy 459.935122 -306.320796) (xy 459.915199 -306.268705) (xy 459.903073 -306.214268) (xy 459.899002 -306.158646)
			(xy 444.450724 -306.158646) (xy 444.450724 -306.86756) (xy 452.570594 -306.86756) (xy 452.574665 -306.811938)
			(xy 452.586791 -306.757501) (xy 452.606714 -306.70541) (xy 452.63401 -306.656775) (xy 452.668096 -306.612632)
			(xy 452.708245 -306.573923) (xy 452.753603 -306.541472) (xy 452.803203 -306.515971) (xy 452.855987 -306.497964)
			(xy 452.91083 -306.487834) (xy 452.966564 -306.485797) (xy 453.022001 -306.491897) (xy 453.075958 -306.506003)
			(xy 453.127287 -306.527815) (xy 453.174893 -306.556869) (xy 453.217761 -306.592544) (xy 453.254978 -306.634081)
			(xy 453.285751 -306.680594) (xy 453.309423 -306.731091) (xy 453.325491 -306.784498) (xy 453.333611 -306.839674)
			(xy 453.33412 -306.86756) (xy 453.333611 -306.895446) (xy 453.325491 -306.950622) (xy 453.309423 -307.004029)
			(xy 453.285751 -307.054526) (xy 453.254978 -307.101039) (xy 453.217761 -307.142576) (xy 453.174893 -307.178251)
			(xy 453.127287 -307.207305) (xy 453.075958 -307.229117) (xy 453.022001 -307.243223) (xy 452.966564 -307.249323)
			(xy 452.91083 -307.247286) (xy 452.855987 -307.237156) (xy 452.803203 -307.219149) (xy 452.753603 -307.193648)
			(xy 452.708245 -307.161197) (xy 452.668096 -307.122488) (xy 452.63401 -307.078345) (xy 452.606714 -307.02971)
			(xy 452.586791 -306.977619) (xy 452.574665 -306.923182) (xy 452.570594 -306.86756) (xy 444.450724 -306.86756)
			(xy 444.450724 -307.56987) (xy 457.496162 -307.56987) (xy 457.500233 -307.514248) (xy 457.512359 -307.459811)
			(xy 457.532282 -307.40772) (xy 457.559578 -307.359085) (xy 457.593664 -307.314942) (xy 457.633813 -307.276233)
			(xy 457.679171 -307.243782) (xy 457.728771 -307.218281) (xy 457.781555 -307.200274) (xy 457.836398 -307.190144)
			(xy 457.892132 -307.188107) (xy 457.947569 -307.194207) (xy 458.001526 -307.208313) (xy 458.052855 -307.230125)
			(xy 458.100461 -307.259179) (xy 458.143329 -307.294854) (xy 458.180546 -307.336391) (xy 458.211319 -307.382904)
			(xy 458.234991 -307.433401) (xy 458.251059 -307.486808) (xy 458.259179 -307.541984) (xy 458.259688 -307.56987)
			(xy 458.259179 -307.597756) (xy 458.257713 -307.607716) (xy 462.556604 -307.607716) (xy 462.560677 -307.552057)
			(xy 462.572812 -307.497584) (xy 462.592748 -307.445458) (xy 462.620062 -307.39679) (xy 462.65417 -307.352618)
			(xy 462.694347 -307.313883) (xy 462.739735 -307.281411) (xy 462.789367 -307.255893) (xy 462.842187 -307.237874)
			(xy 462.897066 -307.227737) (xy 462.952837 -307.225699) (xy 463.008311 -307.231802) (xy 463.062304 -307.245918)
			(xy 463.113667 -307.267745) (xy 463.161305 -307.296818) (xy 463.204201 -307.332517) (xy 463.241443 -307.374081)
			(xy 463.272237 -307.420625) (xy 463.295925 -307.471156) (xy 463.312003 -307.524598) (xy 463.320129 -307.579812)
			(xy 463.320638 -307.607716) (xy 463.320129 -307.63562) (xy 463.312003 -307.690834) (xy 463.295925 -307.744276)
			(xy 463.272237 -307.794807) (xy 463.241443 -307.841351) (xy 463.204201 -307.882915) (xy 463.161305 -307.918614)
			(xy 463.113667 -307.947687) (xy 463.062304 -307.969514) (xy 463.008311 -307.98363) (xy 462.952837 -307.989733)
			(xy 462.897066 -307.987695) (xy 462.842187 -307.977558) (xy 462.789367 -307.959539) (xy 462.739735 -307.934021)
			(xy 462.694347 -307.901549) (xy 462.65417 -307.862814) (xy 462.620062 -307.818642) (xy 462.592748 -307.769974)
			(xy 462.572812 -307.717848) (xy 462.560677 -307.663375) (xy 462.556604 -307.607716) (xy 458.257713 -307.607716)
			(xy 458.251059 -307.652932) (xy 458.234991 -307.706339) (xy 458.211319 -307.756836) (xy 458.180546 -307.803349)
			(xy 458.143329 -307.844886) (xy 458.100461 -307.880561) (xy 458.052855 -307.909615) (xy 458.001526 -307.931427)
			(xy 457.947569 -307.945533) (xy 457.892132 -307.951633) (xy 457.836398 -307.949596) (xy 457.781555 -307.939466)
			(xy 457.728771 -307.921459) (xy 457.679171 -307.895958) (xy 457.633813 -307.863507) (xy 457.593664 -307.824798)
			(xy 457.559578 -307.780655) (xy 457.532282 -307.73202) (xy 457.512359 -307.679929) (xy 457.500233 -307.625492)
			(xy 457.496162 -307.56987) (xy 444.450724 -307.56987) (xy 444.450724 -308.525672) (xy 458.554072 -308.525672)
			(xy 458.558143 -308.47005) (xy 458.570269 -308.415613) (xy 458.590192 -308.363522) (xy 458.617488 -308.314887)
			(xy 458.651574 -308.270744) (xy 458.691723 -308.232035) (xy 458.737081 -308.199584) (xy 458.786681 -308.174083)
			(xy 458.839465 -308.156076) (xy 458.894308 -308.145946) (xy 458.950042 -308.143909) (xy 459.005479 -308.150009)
			(xy 459.059436 -308.164115) (xy 459.110765 -308.185927) (xy 459.158371 -308.214981) (xy 459.201239 -308.250656)
			(xy 459.238456 -308.292193) (xy 459.269229 -308.338706) (xy 459.292901 -308.389203) (xy 459.308969 -308.44261)
			(xy 459.317089 -308.497786) (xy 459.317598 -308.525672) (xy 459.317089 -308.553558) (xy 459.308969 -308.608734)
			(xy 459.292901 -308.662141) (xy 459.278765 -308.692296) (xy 462.556604 -308.692296) (xy 462.560677 -308.636637)
			(xy 462.572812 -308.582164) (xy 462.592748 -308.530038) (xy 462.620062 -308.48137) (xy 462.65417 -308.437198)
			(xy 462.694347 -308.398463) (xy 462.739735 -308.365991) (xy 462.789367 -308.340473) (xy 462.842187 -308.322454)
			(xy 462.897066 -308.312317) (xy 462.952837 -308.310279) (xy 463.008311 -308.316382) (xy 463.062304 -308.330498)
			(xy 463.113667 -308.352325) (xy 463.161305 -308.381398) (xy 463.204201 -308.417097) (xy 463.241443 -308.458661)
			(xy 463.272237 -308.505205) (xy 463.295925 -308.555736) (xy 463.312003 -308.609178) (xy 463.320129 -308.664392)
			(xy 463.320638 -308.692296) (xy 463.320129 -308.7202) (xy 463.312003 -308.775414) (xy 463.295925 -308.828856)
			(xy 463.272237 -308.879387) (xy 463.241443 -308.925931) (xy 463.204201 -308.967495) (xy 463.161305 -309.003194)
			(xy 463.113667 -309.032267) (xy 463.062304 -309.054094) (xy 463.008311 -309.06821) (xy 462.952837 -309.074313)
			(xy 462.897066 -309.072275) (xy 462.842187 -309.062138) (xy 462.789367 -309.044119) (xy 462.739735 -309.018601)
			(xy 462.694347 -308.986129) (xy 462.65417 -308.947394) (xy 462.620062 -308.903222) (xy 462.592748 -308.854554)
			(xy 462.572812 -308.802428) (xy 462.560677 -308.747955) (xy 462.556604 -308.692296) (xy 459.278765 -308.692296)
			(xy 459.269229 -308.712638) (xy 459.238456 -308.759151) (xy 459.201239 -308.800688) (xy 459.158371 -308.836363)
			(xy 459.110765 -308.865417) (xy 459.059436 -308.887229) (xy 459.005479 -308.901335) (xy 458.950042 -308.907435)
			(xy 458.894308 -308.905398) (xy 458.839465 -308.895268) (xy 458.786681 -308.877261) (xy 458.737081 -308.85176)
			(xy 458.691723 -308.819309) (xy 458.651574 -308.7806) (xy 458.617488 -308.736457) (xy 458.590192 -308.687822)
			(xy 458.570269 -308.635731) (xy 458.558143 -308.581294) (xy 458.554072 -308.525672) (xy 444.450724 -308.525672)
			(xy 444.450724 -309.141622) (xy 460.562196 -309.141622) (xy 460.566267 -309.086) (xy 460.578393 -309.031563)
			(xy 460.598316 -308.979472) (xy 460.625612 -308.930837) (xy 460.659698 -308.886694) (xy 460.699847 -308.847985)
			(xy 460.745205 -308.815534) (xy 460.794805 -308.790033) (xy 460.847589 -308.772026) (xy 460.902432 -308.761896)
			(xy 460.958166 -308.759859) (xy 461.013603 -308.765959) (xy 461.06756 -308.780065) (xy 461.118889 -308.801877)
			(xy 461.166495 -308.830931) (xy 461.209363 -308.866606) (xy 461.24658 -308.908143) (xy 461.277353 -308.954656)
			(xy 461.301025 -309.005153) (xy 461.317093 -309.05856) (xy 461.325213 -309.113736) (xy 461.325722 -309.141622)
			(xy 461.325213 -309.169508) (xy 461.317093 -309.224684) (xy 461.301025 -309.278091) (xy 461.277353 -309.328588)
			(xy 461.24658 -309.375101) (xy 461.209363 -309.416638) (xy 461.166495 -309.452313) (xy 461.118889 -309.481367)
			(xy 461.06756 -309.503179) (xy 461.013603 -309.517285) (xy 460.958166 -309.523385) (xy 460.902432 -309.521348)
			(xy 460.847589 -309.511218) (xy 460.794805 -309.493211) (xy 460.745205 -309.46771) (xy 460.699847 -309.435259)
			(xy 460.659698 -309.39655) (xy 460.625612 -309.352407) (xy 460.598316 -309.303772) (xy 460.578393 -309.251681)
			(xy 460.566267 -309.197244) (xy 460.562196 -309.141622) (xy 444.450724 -309.141622) (xy 444.450724 -310.031892)
			(xy 456.942188 -310.031892) (xy 456.946259 -309.97627) (xy 456.958385 -309.921833) (xy 456.978308 -309.869742)
			(xy 457.005604 -309.821107) (xy 457.03969 -309.776964) (xy 457.079839 -309.738255) (xy 457.125197 -309.705804)
			(xy 457.174797 -309.680303) (xy 457.227581 -309.662296) (xy 457.282424 -309.652166) (xy 457.338158 -309.650129)
			(xy 457.393595 -309.656229) (xy 457.447552 -309.670335) (xy 457.498881 -309.692147) (xy 457.546487 -309.721201)
			(xy 457.589355 -309.756876) (xy 457.626572 -309.798413) (xy 457.657345 -309.844926) (xy 457.668429 -309.86857)
			(xy 458.657704 -309.86857) (xy 458.661775 -309.812948) (xy 458.673901 -309.758511) (xy 458.693824 -309.70642)
			(xy 458.72112 -309.657785) (xy 458.755206 -309.613642) (xy 458.795355 -309.574933) (xy 458.840713 -309.542482)
			(xy 458.890313 -309.516981) (xy 458.943097 -309.498974) (xy 458.99794 -309.488844) (xy 459.053674 -309.486807)
			(xy 459.109111 -309.492907) (xy 459.163068 -309.507013) (xy 459.214397 -309.528825) (xy 459.262003 -309.557879)
			(xy 459.304871 -309.593554) (xy 459.342088 -309.635091) (xy 459.372861 -309.681604) (xy 459.396533 -309.732101)
			(xy 459.412601 -309.785508) (xy 459.420721 -309.840684) (xy 459.42123 -309.86857) (xy 459.420721 -309.896456)
			(xy 459.412601 -309.951632) (xy 459.396533 -310.005039) (xy 459.372861 -310.055536) (xy 459.342088 -310.102049)
			(xy 459.304871 -310.143586) (xy 459.262003 -310.179261) (xy 459.214397 -310.208315) (xy 459.163068 -310.230127)
			(xy 459.109111 -310.244233) (xy 459.053674 -310.250333) (xy 458.99794 -310.248296) (xy 458.943097 -310.238166)
			(xy 458.890313 -310.220159) (xy 458.840713 -310.194658) (xy 458.795355 -310.162207) (xy 458.755206 -310.123498)
			(xy 458.72112 -310.079355) (xy 458.693824 -310.03072) (xy 458.673901 -309.978629) (xy 458.661775 -309.924192)
			(xy 458.657704 -309.86857) (xy 457.668429 -309.86857) (xy 457.681017 -309.895423) (xy 457.697085 -309.94883)
			(xy 457.705205 -310.004006) (xy 457.705714 -310.031892) (xy 457.705205 -310.059778) (xy 457.697085 -310.114954)
			(xy 457.681017 -310.168361) (xy 457.657345 -310.218858) (xy 457.626572 -310.265371) (xy 457.589355 -310.306908)
			(xy 457.546487 -310.342583) (xy 457.498881 -310.371637) (xy 457.447552 -310.393449) (xy 457.393595 -310.407555)
			(xy 457.338158 -310.413655) (xy 457.282424 -310.411618) (xy 457.227581 -310.401488) (xy 457.174797 -310.383481)
			(xy 457.125197 -310.35798) (xy 457.079839 -310.325529) (xy 457.03969 -310.28682) (xy 457.005604 -310.242677)
			(xy 456.978308 -310.194042) (xy 456.958385 -310.141951) (xy 456.946259 -310.087514) (xy 456.942188 -310.031892)
			(xy 444.450724 -310.031892) (xy 444.450724 -310.860948) (xy 444.451253 -310.870939) (xy 444.458955 -310.889383)
			(xy 444.46571 -310.896762) (xy 444.908178 -311.33923) (xy 458.119986 -311.33923) (xy 458.124057 -311.283608)
			(xy 458.136183 -311.229171) (xy 458.156106 -311.17708) (xy 458.183402 -311.128445) (xy 458.217488 -311.084302)
			(xy 458.257637 -311.045593) (xy 458.302995 -311.013142) (xy 458.352595 -310.987641) (xy 458.405379 -310.969634)
			(xy 458.460222 -310.959504) (xy 458.515956 -310.957467) (xy 458.571393 -310.963567) (xy 458.62535 -310.977673)
			(xy 458.676679 -310.999485) (xy 458.724285 -311.028539) (xy 458.767153 -311.064214) (xy 458.80437 -311.105751)
			(xy 458.835143 -311.152264) (xy 458.858815 -311.202761) (xy 458.874883 -311.256168) (xy 458.883003 -311.311344)
			(xy 458.883512 -311.33923) (xy 458.883003 -311.367116) (xy 458.874883 -311.422292) (xy 458.858815 -311.475699)
			(xy 458.842059 -311.511442) (xy 459.73441 -311.511442) (xy 459.738481 -311.45582) (xy 459.750607 -311.401383)
			(xy 459.77053 -311.349292) (xy 459.797826 -311.300657) (xy 459.831912 -311.256514) (xy 459.872061 -311.217805)
			(xy 459.917419 -311.185354) (xy 459.967019 -311.159853) (xy 460.019803 -311.141846) (xy 460.074646 -311.131716)
			(xy 460.13038 -311.129679) (xy 460.185817 -311.135779) (xy 460.239774 -311.149885) (xy 460.291103 -311.171697)
			(xy 460.338709 -311.200751) (xy 460.381577 -311.236426) (xy 460.418794 -311.277963) (xy 460.449567 -311.324476)
			(xy 460.473239 -311.374973) (xy 460.489307 -311.42838) (xy 460.497427 -311.483556) (xy 460.497936 -311.511442)
			(xy 460.497427 -311.539328) (xy 460.489307 -311.594504) (xy 460.473239 -311.647911) (xy 460.449567 -311.698408)
			(xy 460.418794 -311.744921) (xy 460.381577 -311.786458) (xy 460.338709 -311.822133) (xy 460.291103 -311.851187)
			(xy 460.239774 -311.872999) (xy 460.185817 -311.887105) (xy 460.13038 -311.893205) (xy 460.074646 -311.891168)
			(xy 460.019803 -311.881038) (xy 459.967019 -311.863031) (xy 459.917419 -311.83753) (xy 459.872061 -311.805079)
			(xy 459.831912 -311.76637) (xy 459.797826 -311.722227) (xy 459.77053 -311.673592) (xy 459.750607 -311.621501)
			(xy 459.738481 -311.567064) (xy 459.73441 -311.511442) (xy 458.842059 -311.511442) (xy 458.835143 -311.526196)
			(xy 458.80437 -311.572709) (xy 458.767153 -311.614246) (xy 458.724285 -311.649921) (xy 458.676679 -311.678975)
			(xy 458.62535 -311.700787) (xy 458.571393 -311.714893) (xy 458.515956 -311.720993) (xy 458.460222 -311.718956)
			(xy 458.405379 -311.708826) (xy 458.352595 -311.690819) (xy 458.302995 -311.665318) (xy 458.257637 -311.632867)
			(xy 458.217488 -311.594158) (xy 458.183402 -311.550015) (xy 458.156106 -311.50138) (xy 458.136183 -311.449289)
			(xy 458.124057 -311.394852) (xy 458.119986 -311.33923) (xy 444.908178 -311.33923) (xy 449.867274 -316.298326)
			(xy 449.890184 -316.321904) (xy 449.931157 -316.373318) (xy 449.966118 -316.428996) (xy 449.994627 -316.488237)
			(xy 450.016325 -316.550297) (xy 450.03094 -316.614396) (xy 450.038288 -316.679728) (xy 450.038724 -316.7126)
			(xy 450.038724 -320.940176) (xy 455.509122 -320.940176) (xy 455.509569 -320.912805) (xy 455.51739 -320.858625)
			(xy 455.532884 -320.806121) (xy 455.55573 -320.756375) (xy 455.585459 -320.710409) (xy 455.603102 -320.689478)
			(xy 455.609198 -320.682366) (xy 455.615548 -320.665348) (xy 455.615548 -320.580004) (xy 455.609198 -320.562986)
			(xy 455.603102 -320.555874) (xy 455.585484 -320.534925) (xy 455.555769 -320.488957) (xy 455.532929 -320.439213)
			(xy 455.517433 -320.386717) (xy 455.509599 -320.332544) (xy 455.509122 -320.305176) (xy 455.509533 -320.277921)
			(xy 455.517294 -320.223967) (xy 455.532654 -320.171666) (xy 455.555302 -320.122084) (xy 455.584775 -320.076229)
			(xy 455.620474 -320.035036) (xy 455.661673 -319.999343) (xy 455.707531 -319.969876) (xy 455.757117 -319.947235)
			(xy 455.80942 -319.931882) (xy 455.863375 -319.924129) (xy 455.89063 -319.923668) (xy 455.918002 -319.9241)
			(xy 455.972183 -319.931923) (xy 456.024687 -319.94742) (xy 456.074433 -319.970269) (xy 456.120398 -320.000002)
			(xy 456.141328 -320.017648) (xy 456.14844 -320.023744) (xy 456.165458 -320.030094) (xy 456.250802 -320.030094)
			(xy 456.26782 -320.023744) (xy 456.274932 -320.017648) (xy 456.295865 -320.000007) (xy 456.341833 -319.970283)
			(xy 456.391579 -319.947437) (xy 456.444081 -319.931941) (xy 456.498259 -319.924112) (xy 456.553001 -319.924112)
			(xy 456.607179 -319.931941) (xy 456.659681 -319.947437) (xy 456.709427 -319.970283) (xy 456.755395 -320.000007)
			(xy 456.776328 -320.017648) (xy 456.78344 -320.023744) (xy 456.800458 -320.030094) (xy 456.885802 -320.030094)
			(xy 456.90282 -320.023744) (xy 456.909932 -320.017648) (xy 456.930885 -320.000035) (xy 456.976851 -319.970317)
			(xy 457.026593 -319.947476) (xy 457.07909 -319.931979) (xy 457.133262 -319.924145) (xy 457.16063 -319.923668)
			(xy 457.187881 -319.92415) (xy 457.241828 -319.93191) (xy 457.294121 -319.947268) (xy 457.343697 -319.96991)
			(xy 457.389546 -319.999378) (xy 457.430735 -320.035069) (xy 457.466426 -320.076259) (xy 457.495892 -320.122109)
			(xy 457.518535 -320.171685) (xy 457.533891 -320.223978) (xy 457.541651 -320.277925) (xy 457.542138 -320.305176)
			(xy 457.541673 -320.332546) (xy 457.533857 -320.386726) (xy 457.518369 -320.43923) (xy 457.495526 -320.488977)
			(xy 457.4658 -320.534943) (xy 457.448158 -320.555874) (xy 457.442062 -320.562986) (xy 457.435712 -320.580004)
			(xy 457.435712 -320.665348) (xy 457.442062 -320.682366) (xy 457.448158 -320.689478) (xy 457.465794 -320.710413)
			(xy 457.495507 -320.756384) (xy 457.518345 -320.806131) (xy 457.533836 -320.858631) (xy 457.541664 -320.912807)
			(xy 457.542138 -320.940176) (xy 457.5416 -320.967425) (xy 457.533847 -321.021369) (xy 457.518496 -321.073661)
			(xy 457.49586 -321.123236) (xy 457.466399 -321.169085) (xy 457.430713 -321.210275) (xy 457.389529 -321.245967)
			(xy 457.343684 -321.275434) (xy 457.294112 -321.298078) (xy 457.241822 -321.313436) (xy 457.187879 -321.321196)
			(xy 457.16063 -321.321684) (xy 457.13326 -321.321204) (xy 457.079082 -321.31339) (xy 457.026578 -321.297905)
			(xy 456.976831 -321.275066) (xy 456.930864 -321.245344) (xy 456.909932 -321.227704) (xy 456.90282 -321.221608)
			(xy 456.885802 -321.215258) (xy 456.800458 -321.215258) (xy 456.78344 -321.221608) (xy 456.776328 -321.227704)
			(xy 456.755395 -321.245345) (xy 456.709427 -321.275069) (xy 456.659681 -321.297915) (xy 456.607179 -321.313411)
			(xy 456.553001 -321.32124) (xy 456.498259 -321.32124) (xy 456.444081 -321.313411) (xy 456.391579 -321.297915)
			(xy 456.341833 -321.275069) (xy 456.295865 -321.245345) (xy 456.274932 -321.227704) (xy 456.26782 -321.221608)
			(xy 456.250802 -321.215258) (xy 456.165458 -321.215258) (xy 456.14844 -321.221608) (xy 456.141328 -321.227704)
			(xy 456.120397 -321.245344) (xy 456.074424 -321.275056) (xy 456.024676 -321.297891) (xy 455.972175 -321.313382)
			(xy 455.917999 -321.32121) (xy 455.89063 -321.321684) (xy 455.863377 -321.321217) (xy 455.809425 -321.313463)
			(xy 455.757126 -321.29811) (xy 455.707544 -321.275469) (xy 455.661689 -321.246002) (xy 455.620496 -321.210308)
			(xy 455.584802 -321.169115) (xy 455.555334 -321.123261) (xy 455.532692 -321.07368) (xy 455.517338 -321.021381)
			(xy 455.509584 -320.967429) (xy 455.509122 -320.940176) (xy 450.038724 -320.940176) (xy 450.038724 -324.19163)
			(xy 450.039267 -324.201615) (xy 450.046991 -324.220037) (xy 450.05371 -324.227444) (xy 452.45274 -326.626474)
			(xy 452.460139 -326.633317) (xy 452.478738 -326.641041) (xy 452.488808 -326.64146) (xy 461.990186 -326.64146)
			(xy 462.000248 -326.6419) (xy 462.018824 -326.649644) (xy 462.026254 -326.656446) (xy 463.52206 -328.152252)
			(xy 463.528903 -328.159651) (xy 463.536624 -328.17825) (xy 463.537046 -328.18832) (xy 463.537046 -377.21032)
			(xy 463.536618 -377.220387) (xy 463.528892 -377.238981) (xy 463.52206 -377.246388) (xy 457.277978 -383.49047)
			(xy 457.269814 -383.499555) (xy 457.262384 -383.522782) (xy 457.263754 -383.53492) (xy 457.279756 -383.629154)
			(xy 457.294488 -383.648458) (xy 457.305918 -383.654046) (xy 457.364681 -383.682796) (xy 457.478884 -383.746637)
			(xy 457.588883 -383.817475) (xy 457.694249 -383.895037) (xy 457.794573 -383.979019) (xy 457.889464 -384.069094)
			(xy 457.978552 -384.164913) (xy 458.06149 -384.266101) (xy 458.137956 -384.372266) (xy 458.207651 -384.482992)
			(xy 458.270305 -384.59785) (xy 458.325673 -384.716392) (xy 458.37354 -384.838157) (xy 458.413719 -384.96267)
			(xy 458.446055 -385.089446) (xy 458.47042 -385.217993) (xy 458.486721 -385.347809) (xy 458.494893 -385.478388)
			(xy 458.4954 -385.543806) (xy 458.494899 -385.609155) (xy 458.486754 -385.739599) (xy 458.470498 -385.869282)
			(xy 458.446193 -385.997701) (xy 458.413933 -386.124355) (xy 458.373844 -386.248753) (xy 458.326081 -386.370411)
			(xy 458.270831 -386.488857) (xy 458.208308 -386.60363) (xy 458.138754 -386.714284) (xy 458.062441 -386.820389)
			(xy 457.979665 -386.921533) (xy 457.890747 -387.017323) (xy 457.796034 -387.107386) (xy 457.695892 -387.191372)
			(xy 457.590712 -387.268955) (xy 457.480903 -387.339834) (xy 457.36689 -387.403733) (xy 457.249117 -387.460403)
			(xy 457.128041 -387.509625) (xy 457.004134 -387.551207) (xy 456.877877 -387.584987) (xy 456.81392 -387.598412)
			(xy 456.79614 -387.601968) (xy 456.77328 -387.630162) (xy 456.77328 -398.100042) (xy 459.541382 -398.100042)
			(xy 459.545364 -397.972056) (xy 459.557296 -397.844565) (xy 459.57713 -397.718062) (xy 459.604791 -397.593037)
			(xy 459.640171 -397.469974) (xy 459.683133 -397.349348) (xy 459.733511 -397.231627) (xy 459.791111 -397.117265)
			(xy 459.855709 -397.006706) (xy 459.927056 -396.900376) (xy 460.004875 -396.798688) (xy 460.088865 -396.702034)
			(xy 460.178702 -396.610789) (xy 460.274038 -396.525306) (xy 460.374503 -396.445915) (xy 460.479711 -396.372923)
			(xy 460.589252 -396.306614) (xy 460.702704 -396.247243) (xy 460.819628 -396.195039) (xy 460.939571 -396.150206)
			(xy 461.062069 -396.112917) (xy 461.186649 -396.083315) (xy 461.312827 -396.061516) (xy 461.440117 -396.047603)
			(xy 461.568026 -396.041631) (xy 461.696059 -396.043622) (xy 461.82372 -396.05357) (xy 461.950516 -396.071434)
			(xy 462.075955 -396.097147) (xy 462.199554 -396.130609) (xy 462.320833 -396.17169) (xy 462.439324 -396.220232)
			(xy 462.554568 -396.276046) (xy 462.666118 -396.338917) (xy 462.773545 -396.408601) (xy 462.876431 -396.484829)
			(xy 462.974379 -396.567306) (xy 463.06701 -396.655713) (xy 463.153966 -396.749708) (xy 463.23491 -396.848927)
			(xy 463.309529 -396.952986) (xy 463.377534 -397.061483) (xy 463.438662 -397.173998) (xy 463.492677 -397.290096)
			(xy 463.53937 -397.409327) (xy 463.57856 -397.531231) (xy 463.610096 -397.655335) (xy 463.633855 -397.781159)
			(xy 463.649745 -397.908218) (xy 463.657706 -398.036018) (xy 463.658204 -398.100042) (xy 463.657706 -398.164066)
			(xy 463.649745 -398.291866) (xy 463.633855 -398.418925) (xy 463.610096 -398.544749) (xy 463.57856 -398.668853)
			(xy 463.53937 -398.790757) (xy 463.492677 -398.909988) (xy 463.438662 -399.026086) (xy 463.377534 -399.138601)
			(xy 463.309529 -399.247098) (xy 463.23491 -399.351157) (xy 463.153966 -399.450376) (xy 463.06701 -399.544371)
			(xy 462.974379 -399.632778) (xy 462.876431 -399.715255) (xy 462.773545 -399.791483) (xy 462.666118 -399.861167)
			(xy 462.554568 -399.924038) (xy 462.439324 -399.979852) (xy 462.320833 -400.028394) (xy 462.199554 -400.069475)
			(xy 462.075955 -400.102937) (xy 461.950516 -400.12865) (xy 461.82372 -400.146514) (xy 461.696059 -400.156462)
			(xy 461.568026 -400.158453) (xy 461.440117 -400.152481) (xy 461.312827 -400.138568) (xy 461.186649 -400.116769)
			(xy 461.062069 -400.087167) (xy 460.939571 -400.049878) (xy 460.819628 -400.005045) (xy 460.702704 -399.952841)
			(xy 460.589252 -399.89347) (xy 460.479711 -399.827161) (xy 460.374503 -399.754169) (xy 460.274038 -399.674778)
			(xy 460.178702 -399.589295) (xy 460.088865 -399.49805) (xy 460.004875 -399.401396) (xy 459.927056 -399.299708)
			(xy 459.855709 -399.193378) (xy 459.791111 -399.082819) (xy 459.733511 -398.968457) (xy 459.683133 -398.850736)
			(xy 459.640171 -398.73011) (xy 459.604791 -398.607047) (xy 459.57713 -398.482022) (xy 459.557296 -398.355519)
			(xy 459.545364 -398.228028) (xy 459.541382 -398.100042) (xy 456.77328 -398.100042) (xy 456.77328 -399.772124)
			(xy 456.773707 -399.782193) (xy 456.781425 -399.800793) (xy 456.788266 -399.808192) (xy 458.842872 -401.862798)
			(xy 458.850274 -401.869633) (xy 458.868873 -401.877342) (xy 458.87894 -401.877784)
		)
		(stroke
			(width 0)
			(type solid)
		)
		(fill yes)
		(layer "In5.Cu")
		(net "GND")
	)
	(gr_poly
		(pts
			(xy 386.98043 -295.88714) (xy 387.119368 -295.88714) (xy 387.122924 -295.887394) (xy 387.927088 -295.887394)
			(xy 387.930644 -295.88714) (xy 388.069328 -295.88714) (xy 388.072884 -295.887394) (xy 388.877048 -295.887394)
			(xy 388.880604 -295.88714) (xy 389.969248 -295.88714) (xy 389.972804 -295.887394) (xy 390.776968 -295.887394)
			(xy 390.780524 -295.88714) (xy 391.869168 -295.88714) (xy 391.872724 -295.887394) (xy 392.676888 -295.887394)
			(xy 392.680444 -295.88714) (xy 392.819382 -295.88714) (xy 392.822938 -295.887394) (xy 393.627102 -295.887394)
			(xy 393.630658 -295.88714) (xy 393.769342 -295.88714) (xy 393.772898 -295.887394) (xy 394.577062 -295.887394)
			(xy 394.580618 -295.88714) (xy 394.719302 -295.88714) (xy 394.722858 -295.887394) (xy 394.723874 -295.887394)
			(xy 395.194028 -295.887394) (xy 395.204096 -295.886966) (xy 395.222692 -295.879243) (xy 395.230096 -295.872408)
			(xy 395.468602 -295.633902) (xy 395.475449 -295.626503) (xy 395.483184 -295.607906) (xy 395.483588 -295.597834)
			(xy 395.483588 -293.995094) (xy 395.483163 -293.985025) (xy 395.475446 -293.966423) (xy 395.468602 -293.959026)
			(xy 395.33703 -293.827454) (xy 395.329096 -293.820207) (xy 395.309034 -293.812567) (xy 395.287601 -293.8138)
			(xy 395.277848 -293.81831) (xy 395.277594 -293.81831) (xy 395.253881 -293.83006) (xy 395.203644 -293.846694)
			(xy 395.1514 -293.855113) (xy 395.12494 -293.855648) (xy 395.124686 -293.855648) (xy 395.10117 -293.855239)
			(xy 395.054612 -293.848579) (xy 395.009471 -293.83538) (xy 394.966658 -293.815912) (xy 394.946632 -293.803578)
			(xy 394.936685 -293.797808) (xy 394.913882 -293.795016) (xy 394.892144 -293.802445) (xy 394.88364 -293.810182)
			(xy 394.87602 -293.817548) (xy 394.857732 -293.825168) (xy 394.849858 -293.825168) (xy 394.452348 -293.825168)
			(xy 394.442188 -293.825168) (xy 394.4239 -293.817548) (xy 394.41628 -293.810182) (xy 394.407675 -293.802598)
			(xy 394.386001 -293.79519) (xy 394.363259 -293.797913) (xy 394.353288 -293.803578) (xy 394.333251 -293.81589)
			(xy 394.290436 -293.835347) (xy 394.245299 -293.848552) (xy 394.198748 -293.855238) (xy 394.175234 -293.855648)
			(xy 394.174726 -293.855648) (xy 394.151211 -293.855235) (xy 394.104657 -293.848567) (xy 394.05952 -293.835362)
			(xy 394.016712 -293.815887) (xy 393.996672 -293.803578) (xy 393.986727 -293.797822) (xy 393.963939 -293.795054)
			(xy 393.942223 -293.802496) (xy 393.93368 -293.810182) (xy 393.92606 -293.817548) (xy 393.907772 -293.825168)
			(xy 393.899898 -293.825168) (xy 392.552174 -293.825168) (xy 392.542014 -293.825168) (xy 392.523726 -293.817548)
			(xy 392.516106 -293.810182) (xy 392.507501 -293.802614) (xy 392.485838 -293.795236) (xy 392.463118 -293.797983)
			(xy 392.453114 -293.803578) (xy 392.433075 -293.815886) (xy 392.390259 -293.835333) (xy 392.345122 -293.848528)
			(xy 392.298573 -293.855203) (xy 392.27506 -293.855648) (xy 392.274552 -293.855648) (xy 392.251037 -293.855237)
			(xy 392.204481 -293.848572) (xy 392.159342 -293.83537) (xy 392.116532 -293.815898) (xy 392.096498 -293.803578)
			(xy 392.086552 -293.797816) (xy 392.063758 -293.795037) (xy 392.042032 -293.802474) (xy 392.033506 -293.810182)
			(xy 392.025886 -293.817548) (xy 392.007598 -293.825168) (xy 391.999724 -293.825168) (xy 391.584942 -293.825168)
			(xy 391.581008 -293.8252) (xy 391.573226 -293.826354) (xy 391.569448 -293.827454) (xy 391.547858 -293.834566)
			(xy 391.541508 -293.838884) (xy 391.517486 -293.854811) (xy 391.465662 -293.88003) (xy 391.410638 -293.89718)
			(xy 391.353663 -293.905873) (xy 391.324846 -293.906448) (xy 391.296023 -293.905929) (xy 391.239034 -293.897263)
			(xy 391.184001 -293.880108) (xy 391.132182 -293.854856) (xy 391.108184 -293.838884) (xy 391.101834 -293.834566)
			(xy 391.080244 -293.827454) (xy 391.076463 -293.826369) (xy 391.068683 -293.82522) (xy 391.06475 -293.825168)
			(xy 390.652254 -293.825168) (xy 390.642094 -293.825168) (xy 390.623806 -293.817548) (xy 390.616186 -293.810182)
			(xy 390.607581 -293.802596) (xy 390.585906 -293.795185) (xy 390.563162 -293.797907) (xy 390.553194 -293.803578)
			(xy 390.533157 -293.815891) (xy 390.490342 -293.835349) (xy 390.445205 -293.848554) (xy 390.398654 -293.855241)
			(xy 390.37514 -293.855648) (xy 390.374632 -293.855648) (xy 390.351117 -293.855235) (xy 390.304563 -293.848568)
			(xy 390.259425 -293.835364) (xy 390.216617 -293.815889) (xy 390.196578 -293.803578) (xy 390.186633 -293.79782)
			(xy 390.163843 -293.79505) (xy 390.142125 -293.802491) (xy 390.133586 -293.810182) (xy 390.125966 -293.817548)
			(xy 390.107678 -293.825168) (xy 390.099804 -293.825168) (xy 389.702294 -293.825168) (xy 389.692134 -293.825168)
			(xy 389.673846 -293.817548) (xy 389.666226 -293.810182) (xy 389.657621 -293.802609) (xy 389.635955 -293.795223)
			(xy 389.613229 -293.797965) (xy 389.603234 -293.803578) (xy 389.583196 -293.815887) (xy 389.54038 -293.835337)
			(xy 389.495243 -293.848534) (xy 389.448693 -293.855213) (xy 389.42518 -293.855648) (xy 389.424672 -293.855648)
			(xy 389.401156 -293.855238) (xy 389.3546 -293.848576) (xy 389.309459 -293.835376) (xy 389.266647 -293.815906)
			(xy 389.246618 -293.803578) (xy 389.236671 -293.797811) (xy 389.213872 -293.795025) (xy 389.192139 -293.802457)
			(xy 389.183626 -293.810182) (xy 389.176006 -293.817548) (xy 389.157718 -293.825168) (xy 389.149844 -293.825168)
			(xy 388.752334 -293.825168) (xy 388.742174 -293.825168) (xy 388.723886 -293.817548) (xy 388.716266 -293.810182)
			(xy 388.707661 -293.802601) (xy 388.685989 -293.795198) (xy 388.663251 -293.797926) (xy 388.653274 -293.803578)
			(xy 388.633236 -293.815889) (xy 388.590421 -293.835345) (xy 388.545284 -293.848547) (xy 388.498734 -293.855231)
			(xy 388.47522 -293.855648) (xy 388.474966 -293.855648) (xy 388.447222 -293.855081) (xy 388.392511 -293.845821)
			(xy 388.340112 -293.827567) (xy 388.29149 -293.800829) (xy 388.248009 -293.766357) (xy 388.210885 -293.725116)
			(xy 388.195566 -293.701978) (xy 388.188454 -293.693088) (xy 388.022846 -293.52748) (xy 388.012686 -293.51732)
			(xy 387.985254 -293.510462) (xy 387.87197 -293.546276) (xy 387.853428 -293.567358) (xy 387.850888 -293.581582)
			(xy 387.846006 -293.606835) (xy 387.829465 -293.655535) (xy 387.805584 -293.701086) (xy 387.774938 -293.742391)
			(xy 387.738266 -293.778452) (xy 387.696453 -293.8084) (xy 387.650507 -293.831514) (xy 387.601536 -293.847234)
			(xy 387.550722 -293.855183) (xy 387.525006 -293.855648) (xy 387.499017 -293.855139) (xy 387.44768 -293.847009)
			(xy 387.398246 -293.830949) (xy 387.351933 -293.807355) (xy 387.30988 -293.776806) (xy 387.273124 -293.740055)
			(xy 387.24257 -293.698007) (xy 387.218968 -293.651697) (xy 387.202901 -293.602265) (xy 387.194765 -293.550929)
			(xy 387.194298 -293.52494) (xy 387.19479 -293.499229) (xy 387.202757 -293.448427) (xy 387.218488 -293.39947)
			(xy 387.241605 -293.353537) (xy 387.271552 -293.311735) (xy 387.307606 -293.27507) (xy 387.3489 -293.244425)
			(xy 387.394439 -293.220539) (xy 387.443124 -293.203988) (xy 387.468364 -293.199058) (xy 387.482588 -293.196518)
			(xy 387.50367 -293.177976) (xy 387.535166 -293.078408) (xy 387.537557 -293.06942) (xy 387.536431 -293.050872)
			(xy 387.528763 -293.033945) (xy 387.522466 -293.0271) (xy 387.357874 -292.862508) (xy 387.353556 -292.858698)
			(xy 387.347206 -292.853618) (xy 387.345174 -292.852348) (xy 387.325889 -292.839389) (xy 387.290809 -292.808922)
			(xy 387.260338 -292.773847) (xy 387.247384 -292.754558) (xy 387.246114 -292.752526) (xy 387.241034 -292.746176)
			(xy 387.237224 -292.741858) (xy 387.072886 -292.57752) (xy 387.062726 -292.56736) (xy 387.035294 -292.560502)
			(xy 386.92201 -292.596316) (xy 386.903468 -292.617398) (xy 386.900928 -292.631622) (xy 386.896043 -292.656871)
			(xy 386.879497 -292.705561) (xy 386.855612 -292.751103) (xy 386.824963 -292.792397) (xy 386.78829 -292.828447)
			(xy 386.746478 -292.858385) (xy 386.700534 -292.881487) (xy 386.651567 -292.897197) (xy 386.600759 -292.905136)
			(xy 386.575046 -292.905688) (xy 386.549055 -292.905208) (xy 386.497712 -292.897083) (xy 386.448273 -292.881024)
			(xy 386.401954 -292.857429) (xy 386.359898 -292.826877) (xy 386.32314 -292.790121) (xy 386.292585 -292.748068)
			(xy 386.268986 -292.701751) (xy 386.252923 -292.652313) (xy 386.244794 -292.600971) (xy 386.244338 -292.57498)
			(xy 386.244827 -292.549266) (xy 386.252788 -292.498457) (xy 386.268514 -292.449491) (xy 386.291628 -292.403549)
			(xy 386.321572 -292.361737) (xy 386.357625 -292.325061) (xy 386.398918 -292.294406) (xy 386.444458 -292.270509)
			(xy 386.493147 -292.253946) (xy 386.518404 -292.249098) (xy 386.532628 -292.246558) (xy 386.55371 -292.228016)
			(xy 386.585206 -292.128448) (xy 386.587606 -292.119459) (xy 386.586491 -292.100903) (xy 386.578824 -292.083969)
			(xy 386.572506 -292.07714) (xy 386.407914 -291.912548) (xy 386.403596 -291.908738) (xy 386.397246 -291.903658)
			(xy 386.395214 -291.902388) (xy 386.375929 -291.889429) (xy 386.34085 -291.858962) (xy 386.310381 -291.823884)
			(xy 386.297424 -291.804598) (xy 386.296154 -291.802566) (xy 386.291074 -291.796216) (xy 386.287264 -291.791898)
			(xy 386.122672 -291.627306) (xy 386.112512 -291.617146) (xy 386.08508 -291.610288) (xy 385.971796 -291.646102)
			(xy 385.953254 -291.667184) (xy 385.950714 -291.681408) (xy 385.945831 -291.706661) (xy 385.929288 -291.755359)
			(xy 385.905405 -291.800909) (xy 385.874759 -291.842213) (xy 385.838087 -291.878274) (xy 385.796275 -291.908223)
			(xy 385.75033 -291.931337) (xy 385.701361 -291.94706) (xy 385.650548 -291.955012) (xy 385.624832 -291.955474)
			(xy 385.598842 -291.954993) (xy 385.547502 -291.946866) (xy 385.498065 -291.930806) (xy 385.45175 -291.907209)
			(xy 385.409697 -291.876657) (xy 385.372942 -291.839902) (xy 385.34239 -291.797848) (xy 385.318793 -291.751533)
			(xy 385.302734 -291.702096) (xy 385.294607 -291.650756) (xy 385.294124 -291.624766) (xy 385.294614 -291.599052)
			(xy 385.302577 -291.548244) (xy 385.318304 -291.49928) (xy 385.341418 -291.453338) (xy 385.371362 -291.411527)
			(xy 385.407415 -291.374852) (xy 385.448707 -291.344196) (xy 385.494246 -291.320299) (xy 385.542934 -291.303735)
			(xy 385.56819 -291.298884) (xy 385.582414 -291.296344) (xy 385.603496 -291.277802) (xy 385.634992 -291.178234)
			(xy 385.63739 -291.169246) (xy 385.636271 -291.150694) (xy 385.628599 -291.133764) (xy 385.622292 -291.126926)
			(xy 385.456684 -290.961318) (xy 385.447794 -290.954206) (xy 385.427467 -290.940817) (xy 385.390612 -290.909025)
			(xy 385.358814 -290.872175) (xy 385.345432 -290.851844) (xy 385.33832 -290.842954) (xy 385.172712 -290.677346)
			(xy 385.162552 -290.667186) (xy 385.13512 -290.660328) (xy 385.021836 -290.696142) (xy 385.003294 -290.717224)
			(xy 385.000754 -290.731448) (xy 384.995874 -290.756702) (xy 384.979336 -290.805403) (xy 384.955456 -290.850956)
			(xy 384.92481 -290.892262) (xy 384.888138 -290.928324) (xy 384.846324 -290.958272) (xy 384.800376 -290.981384)
			(xy 384.751404 -290.997102) (xy 384.700589 -291.005047) (xy 384.674872 -291.005514) (xy 384.648886 -291.005002)
			(xy 384.597555 -290.996868) (xy 384.548127 -290.980805) (xy 384.501821 -290.957208) (xy 384.459777 -290.926658)
			(xy 384.423028 -290.889907) (xy 384.392481 -290.84786) (xy 384.368887 -290.801552) (xy 384.352826 -290.752124)
			(xy 384.344696 -290.700792) (xy 384.344164 -290.674806) (xy 384.344659 -290.649096) (xy 384.352629 -290.598296)
			(xy 384.368363 -290.549342) (xy 384.391481 -290.503411) (xy 384.421428 -290.46161) (xy 384.457481 -290.424946)
			(xy 384.498773 -290.394302) (xy 384.544309 -290.370415) (xy 384.592992 -290.353861) (xy 384.61823 -290.348924)
			(xy 384.632454 -290.346384) (xy 384.653536 -290.327842) (xy 384.685032 -290.228274) (xy 384.687437 -290.219284)
			(xy 384.68633 -290.200722) (xy 384.67867 -290.183778) (xy 384.672332 -290.176966) (xy 384.506724 -290.011358)
			(xy 384.497834 -290.004246) (xy 384.477842 -289.991076) (xy 384.441516 -289.959896) (xy 384.410056 -289.923812)
			(xy 384.396742 -289.903916) (xy 384.395472 -289.901884) (xy 384.390392 -289.895534) (xy 384.386582 -289.891216)
			(xy 383.753868 -289.258502) (xy 383.746521 -289.251696) (xy 383.728059 -289.243975) (xy 383.718054 -289.243516)
			(xy 380.476506 -289.243516) (xy 380.463862 -289.24419) (xy 380.441601 -289.256184) (xy 380.434088 -289.266376)
			(xy 380.387352 -289.336734) (xy 380.380916 -289.347567) (xy 380.378537 -289.372619) (xy 380.38278 -289.384486)
			(xy 380.38278 -289.38474) (xy 380.392121 -289.408036) (xy 380.405306 -289.456465) (xy 380.412036 -289.506203)
			(xy 380.412498 -289.531298) (xy 380.412498 -289.536886) (xy 380.411702 -289.563923) (xy 380.403419 -289.617375)
			(xy 380.387671 -289.669121) (xy 380.364772 -289.718124) (xy 380.335181 -289.763402) (xy 380.299492 -289.804046)
			(xy 380.258421 -289.839243) (xy 380.21279 -289.868286) (xy 380.163514 -289.890593) (xy 380.111582 -289.905717)
			(xy 380.058035 -289.913355) (xy 380.03099 -289.913822) (xy 380.002178 -289.913295) (xy 379.945209 -289.904633)
			(xy 379.89019 -289.887506) (xy 379.838369 -289.862303) (xy 379.790926 -289.829598) (xy 379.748937 -289.790133)
			(xy 379.730762 -289.767772) (xy 379.720602 -289.754818) (xy 379.689614 -289.745674) (xy 379.583442 -289.78225)
			(xy 379.573658 -289.786175) (xy 379.558172 -289.800444) (xy 379.549709 -289.819727) (xy 379.549152 -289.830256)
			(xy 379.549152 -290.294314) (xy 381.921002 -290.294314) (xy 381.925073 -290.238692) (xy 381.937199 -290.184255)
			(xy 381.957122 -290.132164) (xy 381.984418 -290.083529) (xy 382.018504 -290.039386) (xy 382.058653 -290.000677)
			(xy 382.104011 -289.968226) (xy 382.153611 -289.942725) (xy 382.206395 -289.924718) (xy 382.261238 -289.914588)
			(xy 382.316972 -289.912551) (xy 382.372409 -289.918651) (xy 382.426366 -289.932757) (xy 382.477695 -289.954569)
			(xy 382.525301 -289.983623) (xy 382.568169 -290.019298) (xy 382.605386 -290.060835) (xy 382.636159 -290.107348)
			(xy 382.659831 -290.157845) (xy 382.675899 -290.211252) (xy 382.684019 -290.266428) (xy 382.684528 -290.294314)
			(xy 382.684019 -290.3222) (xy 382.675899 -290.377376) (xy 382.659831 -290.430783) (xy 382.636159 -290.48128)
			(xy 382.605386 -290.527793) (xy 382.568169 -290.56933) (xy 382.525301 -290.605005) (xy 382.477695 -290.634059)
			(xy 382.426366 -290.655871) (xy 382.372409 -290.669977) (xy 382.316972 -290.676077) (xy 382.261238 -290.67404)
			(xy 382.206395 -290.66391) (xy 382.153611 -290.645903) (xy 382.104011 -290.620402) (xy 382.058653 -290.587951)
			(xy 382.018504 -290.549242) (xy 381.984418 -290.505099) (xy 381.957122 -290.456464) (xy 381.937199 -290.404373)
			(xy 381.925073 -290.349936) (xy 381.921002 -290.294314) (xy 379.549152 -290.294314) (xy 379.549152 -291.624766)
			(xy 384.369068 -291.624766) (xy 384.373028 -291.575712) (xy 384.384805 -291.527928) (xy 384.404096 -291.482652)
			(xy 384.430399 -291.441056) (xy 384.463034 -291.404219) (xy 384.501155 -291.373094) (xy 384.543776 -291.348487)
			(xy 384.589792 -291.331035) (xy 384.638011 -291.321191) (xy 384.687186 -291.31921) (xy 384.736041 -291.325142)
			(xy 384.783312 -291.338834) (xy 384.827774 -291.359932) (xy 384.868277 -291.387888) (xy 384.90377 -291.42198)
			(xy 384.933335 -291.461324) (xy 384.956206 -291.504901) (xy 384.97179 -291.551582) (xy 384.979685 -291.600159)
			(xy 384.98018 -291.624766) (xy 384.979685 -291.649373) (xy 384.97179 -291.69795) (xy 384.956206 -291.744631)
			(xy 384.933335 -291.788208) (xy 384.90377 -291.827552) (xy 384.868277 -291.861644) (xy 384.827774 -291.8896)
			(xy 384.783312 -291.910698) (xy 384.736041 -291.92439) (xy 384.687186 -291.930322) (xy 384.638011 -291.928341)
			(xy 384.589792 -291.918497) (xy 384.543776 -291.901045) (xy 384.501155 -291.876438) (xy 384.463034 -291.845313)
			(xy 384.430399 -291.808476) (xy 384.404096 -291.76688) (xy 384.384805 -291.721604) (xy 384.373028 -291.67382)
			(xy 384.369068 -291.624766) (xy 379.549152 -291.624766) (xy 379.549152 -292.169088) (xy 379.549574 -292.179158)
			(xy 379.557292 -292.197761) (xy 379.564138 -292.205156) (xy 379.632972 -292.27399) (xy 379.640374 -292.280826)
			(xy 379.658972 -292.288536) (xy 379.66904 -292.288976) (xy 382.509776 -292.288976) (xy 382.519827 -292.289481)
			(xy 382.538388 -292.297202) (xy 382.545844 -292.303962) (xy 382.816862 -292.57498) (xy 384.369068 -292.57498)
			(xy 384.373028 -292.525926) (xy 384.384805 -292.478142) (xy 384.404096 -292.432866) (xy 384.430399 -292.39127)
			(xy 384.463034 -292.354433) (xy 384.501155 -292.323308) (xy 384.543776 -292.298701) (xy 384.589792 -292.281249)
			(xy 384.638011 -292.271405) (xy 384.687186 -292.269424) (xy 384.736041 -292.275356) (xy 384.783312 -292.289048)
			(xy 384.827774 -292.310146) (xy 384.868277 -292.338102) (xy 384.90377 -292.372194) (xy 384.933335 -292.411538)
			(xy 384.956206 -292.455115) (xy 384.97179 -292.501796) (xy 384.979685 -292.550373) (xy 384.98018 -292.57498)
			(xy 385.319028 -292.57498) (xy 385.322988 -292.525926) (xy 385.334765 -292.478142) (xy 385.354056 -292.432866)
			(xy 385.380359 -292.39127) (xy 385.412994 -292.354433) (xy 385.451115 -292.323308) (xy 385.493736 -292.298701)
			(xy 385.539752 -292.281249) (xy 385.587971 -292.271405) (xy 385.637146 -292.269424) (xy 385.686001 -292.275356)
			(xy 385.733272 -292.289048) (xy 385.777734 -292.310146) (xy 385.818237 -292.338102) (xy 385.85373 -292.372194)
			(xy 385.883295 -292.411538) (xy 385.906166 -292.455115) (xy 385.92175 -292.501796) (xy 385.929645 -292.550373)
			(xy 385.93014 -292.57498) (xy 385.929645 -292.599587) (xy 385.92175 -292.648164) (xy 385.906166 -292.694845)
			(xy 385.883295 -292.738422) (xy 385.85373 -292.777766) (xy 385.818237 -292.811858) (xy 385.777734 -292.839814)
			(xy 385.733272 -292.860912) (xy 385.686001 -292.874604) (xy 385.637146 -292.880536) (xy 385.587971 -292.878555)
			(xy 385.539752 -292.868711) (xy 385.493736 -292.851259) (xy 385.451115 -292.826652) (xy 385.412994 -292.795527)
			(xy 385.380359 -292.75869) (xy 385.354056 -292.717094) (xy 385.334765 -292.671818) (xy 385.322988 -292.624034)
			(xy 385.319028 -292.57498) (xy 384.98018 -292.57498) (xy 384.979685 -292.599587) (xy 384.97179 -292.648164)
			(xy 384.956206 -292.694845) (xy 384.933335 -292.738422) (xy 384.90377 -292.777766) (xy 384.868277 -292.811858)
			(xy 384.827774 -292.839814) (xy 384.783312 -292.860912) (xy 384.736041 -292.874604) (xy 384.687186 -292.880536)
			(xy 384.638011 -292.878555) (xy 384.589792 -292.868711) (xy 384.543776 -292.851259) (xy 384.501155 -292.826652)
			(xy 384.463034 -292.795527) (xy 384.430399 -292.75869) (xy 384.404096 -292.717094) (xy 384.384805 -292.671818)
			(xy 384.373028 -292.624034) (xy 384.369068 -292.57498) (xy 382.816862 -292.57498) (xy 383.766822 -293.52494)
			(xy 384.369068 -293.52494) (xy 384.373028 -293.475886) (xy 384.384805 -293.428102) (xy 384.404096 -293.382826)
			(xy 384.430399 -293.34123) (xy 384.463034 -293.304393) (xy 384.501155 -293.273268) (xy 384.543776 -293.248661)
			(xy 384.589792 -293.231209) (xy 384.638011 -293.221365) (xy 384.687186 -293.219384) (xy 384.736041 -293.225316)
			(xy 384.783312 -293.239008) (xy 384.827774 -293.260106) (xy 384.868277 -293.288062) (xy 384.90377 -293.322154)
			(xy 384.933335 -293.361498) (xy 384.956206 -293.405075) (xy 384.97179 -293.451756) (xy 384.979685 -293.500333)
			(xy 384.98018 -293.52494) (xy 385.319028 -293.52494) (xy 385.322988 -293.475886) (xy 385.334765 -293.428102)
			(xy 385.354056 -293.382826) (xy 385.380359 -293.34123) (xy 385.412994 -293.304393) (xy 385.451115 -293.273268)
			(xy 385.493736 -293.248661) (xy 385.539752 -293.231209) (xy 385.587971 -293.221365) (xy 385.637146 -293.219384)
			(xy 385.686001 -293.225316) (xy 385.733272 -293.239008) (xy 385.777734 -293.260106) (xy 385.818237 -293.288062)
			(xy 385.85373 -293.322154) (xy 385.883295 -293.361498) (xy 385.906166 -293.405075) (xy 385.92175 -293.451756)
			(xy 385.929645 -293.500333) (xy 385.93014 -293.52494) (xy 386.269242 -293.52494) (xy 386.273202 -293.475886)
			(xy 386.284979 -293.428102) (xy 386.30427 -293.382826) (xy 386.330573 -293.34123) (xy 386.363208 -293.304393)
			(xy 386.401329 -293.273268) (xy 386.44395 -293.248661) (xy 386.489966 -293.231209) (xy 386.538185 -293.221365)
			(xy 386.58736 -293.219384) (xy 386.636215 -293.225316) (xy 386.683486 -293.239008) (xy 386.727948 -293.260106)
			(xy 386.768451 -293.288062) (xy 386.803944 -293.322154) (xy 386.833509 -293.361498) (xy 386.85638 -293.405075)
			(xy 386.871964 -293.451756) (xy 386.879859 -293.500333) (xy 386.880354 -293.52494) (xy 386.879859 -293.549547)
			(xy 386.871964 -293.598124) (xy 386.85638 -293.644805) (xy 386.833509 -293.688382) (xy 386.803944 -293.727726)
			(xy 386.768451 -293.761818) (xy 386.727948 -293.789774) (xy 386.683486 -293.810872) (xy 386.636215 -293.824564)
			(xy 386.58736 -293.830496) (xy 386.538185 -293.828515) (xy 386.489966 -293.818671) (xy 386.44395 -293.801219)
			(xy 386.401329 -293.776612) (xy 386.363208 -293.745487) (xy 386.330573 -293.70865) (xy 386.30427 -293.667054)
			(xy 386.284979 -293.621778) (xy 386.273202 -293.573994) (xy 386.269242 -293.52494) (xy 385.93014 -293.52494)
			(xy 385.929645 -293.549547) (xy 385.92175 -293.598124) (xy 385.906166 -293.644805) (xy 385.883295 -293.688382)
			(xy 385.85373 -293.727726) (xy 385.818237 -293.761818) (xy 385.777734 -293.789774) (xy 385.733272 -293.810872)
			(xy 385.686001 -293.824564) (xy 385.637146 -293.830496) (xy 385.587971 -293.828515) (xy 385.539752 -293.818671)
			(xy 385.493736 -293.801219) (xy 385.451115 -293.776612) (xy 385.412994 -293.745487) (xy 385.380359 -293.70865)
			(xy 385.354056 -293.667054) (xy 385.334765 -293.621778) (xy 385.322988 -293.573994) (xy 385.319028 -293.52494)
			(xy 384.98018 -293.52494) (xy 384.979685 -293.549547) (xy 384.97179 -293.598124) (xy 384.956206 -293.644805)
			(xy 384.933335 -293.688382) (xy 384.90377 -293.727726) (xy 384.868277 -293.761818) (xy 384.827774 -293.789774)
			(xy 384.783312 -293.810872) (xy 384.736041 -293.824564) (xy 384.687186 -293.830496) (xy 384.638011 -293.828515)
			(xy 384.589792 -293.818671) (xy 384.543776 -293.801219) (xy 384.501155 -293.776612) (xy 384.463034 -293.745487)
			(xy 384.430399 -293.70865) (xy 384.404096 -293.667054) (xy 384.384805 -293.621778) (xy 384.373028 -293.573994)
			(xy 384.369068 -293.52494) (xy 383.766822 -293.52494) (xy 384.432048 -294.190166) (xy 384.440604 -294.198006)
			(xy 384.462496 -294.205632) (xy 384.48551 -294.202849) (xy 384.495548 -294.197024) (xy 384.515684 -294.184515)
			(xy 384.558778 -294.164764) (xy 384.604251 -294.151371) (xy 384.65117 -294.144611) (xy 384.674872 -294.144192)
			(xy 384.700863 -294.144673) (xy 384.752205 -294.152801) (xy 384.801643 -294.168861) (xy 384.84796 -294.192457)
			(xy 384.890015 -294.223009) (xy 384.926773 -294.259763) (xy 384.957329 -294.301816) (xy 384.980929 -294.348131)
			(xy 384.996993 -294.397568) (xy 385.005125 -294.448909) (xy 385.00558 -294.4749) (xy 385.319028 -294.4749)
			(xy 385.322988 -294.425846) (xy 385.334765 -294.378062) (xy 385.354056 -294.332786) (xy 385.380359 -294.29119)
			(xy 385.412994 -294.254353) (xy 385.451115 -294.223228) (xy 385.493736 -294.198621) (xy 385.539752 -294.181169)
			(xy 385.587971 -294.171325) (xy 385.637146 -294.169344) (xy 385.686001 -294.175276) (xy 385.733272 -294.188968)
			(xy 385.777734 -294.210066) (xy 385.818237 -294.238022) (xy 385.85373 -294.272114) (xy 385.883295 -294.311458)
			(xy 385.906166 -294.355035) (xy 385.92175 -294.401716) (xy 385.929645 -294.450293) (xy 385.93014 -294.4749)
			(xy 386.269242 -294.4749) (xy 386.273202 -294.425846) (xy 386.284979 -294.378062) (xy 386.30427 -294.332786)
			(xy 386.330573 -294.29119) (xy 386.363208 -294.254353) (xy 386.401329 -294.223228) (xy 386.44395 -294.198621)
			(xy 386.489966 -294.181169) (xy 386.538185 -294.171325) (xy 386.58736 -294.169344) (xy 386.636215 -294.175276)
			(xy 386.683486 -294.188968) (xy 386.727948 -294.210066) (xy 386.768451 -294.238022) (xy 386.803944 -294.272114)
			(xy 386.833509 -294.311458) (xy 386.85638 -294.355035) (xy 386.871964 -294.401716) (xy 386.879859 -294.450293)
			(xy 386.880354 -294.4749) (xy 389.119122 -294.4749) (xy 389.123082 -294.425846) (xy 389.134859 -294.378062)
			(xy 389.15415 -294.332786) (xy 389.180453 -294.29119) (xy 389.213088 -294.254353) (xy 389.251209 -294.223228)
			(xy 389.29383 -294.198621) (xy 389.339846 -294.181169) (xy 389.388065 -294.171325) (xy 389.43724 -294.169344)
			(xy 389.486095 -294.175276) (xy 389.533366 -294.188968) (xy 389.577828 -294.210066) (xy 389.618331 -294.238022)
			(xy 389.653824 -294.272114) (xy 389.683389 -294.311458) (xy 389.70626 -294.355035) (xy 389.721844 -294.401716)
			(xy 389.729739 -294.450293) (xy 389.730234 -294.4749) (xy 389.729739 -294.499507) (xy 389.729407 -294.501549)
			(xy 390.019276 -294.501549) (xy 390.019276 -294.448251) (xy 390.027219 -294.395547) (xy 390.042929 -294.344617)
			(xy 390.066055 -294.296596) (xy 390.096079 -294.252559) (xy 390.132331 -294.213488) (xy 390.174002 -294.180257)
			(xy 390.22016 -294.153608) (xy 390.269774 -294.134136) (xy 390.321736 -294.122276) (xy 390.374886 -294.118293)
			(xy 390.428036 -294.122276) (xy 390.479998 -294.134136) (xy 390.529612 -294.153608) (xy 390.57577 -294.180257)
			(xy 390.617441 -294.213488) (xy 390.653693 -294.252559) (xy 390.683717 -294.296596) (xy 390.706843 -294.344617)
			(xy 390.722553 -294.395547) (xy 390.730496 -294.448251) (xy 390.730994 -294.4749) (xy 391.019042 -294.4749)
			(xy 391.023002 -294.425846) (xy 391.034779 -294.378062) (xy 391.05407 -294.332786) (xy 391.080373 -294.29119)
			(xy 391.113008 -294.254353) (xy 391.151129 -294.223228) (xy 391.19375 -294.198621) (xy 391.239766 -294.181169)
			(xy 391.287985 -294.171325) (xy 391.33716 -294.169344) (xy 391.386015 -294.175276) (xy 391.433286 -294.188968)
			(xy 391.477748 -294.210066) (xy 391.518251 -294.238022) (xy 391.553744 -294.272114) (xy 391.583309 -294.311458)
			(xy 391.60618 -294.355035) (xy 391.621764 -294.401716) (xy 391.629659 -294.450293) (xy 391.630154 -294.4749)
			(xy 391.969002 -294.4749) (xy 391.972962 -294.425846) (xy 391.984739 -294.378062) (xy 392.00403 -294.332786)
			(xy 392.030333 -294.29119) (xy 392.062968 -294.254353) (xy 392.101089 -294.223228) (xy 392.14371 -294.198621)
			(xy 392.189726 -294.181169) (xy 392.237945 -294.171325) (xy 392.28712 -294.169344) (xy 392.335975 -294.175276)
			(xy 392.383246 -294.188968) (xy 392.427708 -294.210066) (xy 392.468211 -294.238022) (xy 392.503704 -294.272114)
			(xy 392.533269 -294.311458) (xy 392.55614 -294.355035) (xy 392.571724 -294.401716) (xy 392.579619 -294.450293)
			(xy 392.580114 -294.4749) (xy 392.919216 -294.4749) (xy 392.923176 -294.425846) (xy 392.934953 -294.378062)
			(xy 392.954244 -294.332786) (xy 392.980547 -294.29119) (xy 393.013182 -294.254353) (xy 393.051303 -294.223228)
			(xy 393.093924 -294.198621) (xy 393.13994 -294.181169) (xy 393.188159 -294.171325) (xy 393.237334 -294.169344)
			(xy 393.286189 -294.175276) (xy 393.33346 -294.188968) (xy 393.377922 -294.210066) (xy 393.418425 -294.238022)
			(xy 393.453918 -294.272114) (xy 393.483483 -294.311458) (xy 393.506354 -294.355035) (xy 393.521938 -294.401716)
			(xy 393.529833 -294.450293) (xy 393.530328 -294.4749) (xy 393.869176 -294.4749) (xy 393.873136 -294.425846)
			(xy 393.884913 -294.378062) (xy 393.904204 -294.332786) (xy 393.930507 -294.29119) (xy 393.963142 -294.254353)
			(xy 394.001263 -294.223228) (xy 394.043884 -294.198621) (xy 394.0899 -294.181169) (xy 394.138119 -294.171325)
			(xy 394.187294 -294.169344) (xy 394.236149 -294.175276) (xy 394.28342 -294.188968) (xy 394.327882 -294.210066)
			(xy 394.368385 -294.238022) (xy 394.403878 -294.272114) (xy 394.433443 -294.311458) (xy 394.456314 -294.355035)
			(xy 394.471898 -294.401716) (xy 394.479793 -294.450293) (xy 394.480288 -294.4749) (xy 394.479793 -294.499507)
			(xy 394.471898 -294.548084) (xy 394.456314 -294.594765) (xy 394.433443 -294.638342) (xy 394.403878 -294.677686)
			(xy 394.368385 -294.711778) (xy 394.327882 -294.739734) (xy 394.28342 -294.760832) (xy 394.236149 -294.774524)
			(xy 394.187294 -294.780456) (xy 394.138119 -294.778475) (xy 394.0899 -294.768631) (xy 394.043884 -294.751179)
			(xy 394.001263 -294.726572) (xy 393.963142 -294.695447) (xy 393.930507 -294.65861) (xy 393.904204 -294.617014)
			(xy 393.884913 -294.571738) (xy 393.873136 -294.523954) (xy 393.869176 -294.4749) (xy 393.530328 -294.4749)
			(xy 393.529833 -294.499507) (xy 393.521938 -294.548084) (xy 393.506354 -294.594765) (xy 393.483483 -294.638342)
			(xy 393.453918 -294.677686) (xy 393.418425 -294.711778) (xy 393.377922 -294.739734) (xy 393.33346 -294.760832)
			(xy 393.286189 -294.774524) (xy 393.237334 -294.780456) (xy 393.188159 -294.778475) (xy 393.13994 -294.768631)
			(xy 393.093924 -294.751179) (xy 393.051303 -294.726572) (xy 393.013182 -294.695447) (xy 392.980547 -294.65861)
			(xy 392.954244 -294.617014) (xy 392.934953 -294.571738) (xy 392.923176 -294.523954) (xy 392.919216 -294.4749)
			(xy 392.580114 -294.4749) (xy 392.579619 -294.499507) (xy 392.571724 -294.548084) (xy 392.55614 -294.594765)
			(xy 392.533269 -294.638342) (xy 392.503704 -294.677686) (xy 392.468211 -294.711778) (xy 392.427708 -294.739734)
			(xy 392.383246 -294.760832) (xy 392.335975 -294.774524) (xy 392.28712 -294.780456) (xy 392.237945 -294.778475)
			(xy 392.189726 -294.768631) (xy 392.14371 -294.751179) (xy 392.101089 -294.726572) (xy 392.062968 -294.695447)
			(xy 392.030333 -294.65861) (xy 392.00403 -294.617014) (xy 391.984739 -294.571738) (xy 391.972962 -294.523954)
			(xy 391.969002 -294.4749) (xy 391.630154 -294.4749) (xy 391.629659 -294.499507) (xy 391.621764 -294.548084)
			(xy 391.60618 -294.594765) (xy 391.583309 -294.638342) (xy 391.553744 -294.677686) (xy 391.518251 -294.711778)
			(xy 391.477748 -294.739734) (xy 391.433286 -294.760832) (xy 391.386015 -294.774524) (xy 391.33716 -294.780456)
			(xy 391.287985 -294.778475) (xy 391.239766 -294.768631) (xy 391.19375 -294.751179) (xy 391.151129 -294.726572)
			(xy 391.113008 -294.695447) (xy 391.080373 -294.65861) (xy 391.05407 -294.617014) (xy 391.034779 -294.571738)
			(xy 391.023002 -294.523954) (xy 391.019042 -294.4749) (xy 390.730994 -294.4749) (xy 390.730496 -294.501549)
			(xy 390.722553 -294.554253) (xy 390.706843 -294.605183) (xy 390.683717 -294.653204) (xy 390.653693 -294.697241)
			(xy 390.617441 -294.736312) (xy 390.57577 -294.769543) (xy 390.529612 -294.796192) (xy 390.479998 -294.815664)
			(xy 390.428036 -294.827524) (xy 390.374886 -294.831508) (xy 390.321736 -294.827524) (xy 390.269774 -294.815664)
			(xy 390.22016 -294.796192) (xy 390.174002 -294.769543) (xy 390.132331 -294.736312) (xy 390.096079 -294.697241)
			(xy 390.066055 -294.653204) (xy 390.042929 -294.605183) (xy 390.027219 -294.554253) (xy 390.019276 -294.501549)
			(xy 389.729407 -294.501549) (xy 389.721844 -294.548084) (xy 389.70626 -294.594765) (xy 389.683389 -294.638342)
			(xy 389.653824 -294.677686) (xy 389.618331 -294.711778) (xy 389.577828 -294.739734) (xy 389.533366 -294.760832)
			(xy 389.486095 -294.774524) (xy 389.43724 -294.780456) (xy 389.388065 -294.778475) (xy 389.339846 -294.768631)
			(xy 389.29383 -294.751179) (xy 389.251209 -294.726572) (xy 389.213088 -294.695447) (xy 389.180453 -294.65861)
			(xy 389.15415 -294.617014) (xy 389.134859 -294.571738) (xy 389.123082 -294.523954) (xy 389.119122 -294.4749)
			(xy 386.880354 -294.4749) (xy 386.879859 -294.499507) (xy 386.871964 -294.548084) (xy 386.85638 -294.594765)
			(xy 386.833509 -294.638342) (xy 386.803944 -294.677686) (xy 386.768451 -294.711778) (xy 386.727948 -294.739734)
			(xy 386.683486 -294.760832) (xy 386.636215 -294.774524) (xy 386.58736 -294.780456) (xy 386.538185 -294.778475)
			(xy 386.489966 -294.768631) (xy 386.44395 -294.751179) (xy 386.401329 -294.726572) (xy 386.363208 -294.695447)
			(xy 386.330573 -294.65861) (xy 386.30427 -294.617014) (xy 386.284979 -294.571738) (xy 386.273202 -294.523954)
			(xy 386.269242 -294.4749) (xy 385.93014 -294.4749) (xy 385.929645 -294.499507) (xy 385.92175 -294.548084)
			(xy 385.906166 -294.594765) (xy 385.883295 -294.638342) (xy 385.85373 -294.677686) (xy 385.818237 -294.711778)
			(xy 385.777734 -294.739734) (xy 385.733272 -294.760832) (xy 385.686001 -294.774524) (xy 385.637146 -294.780456)
			(xy 385.587971 -294.778475) (xy 385.539752 -294.768631) (xy 385.493736 -294.751179) (xy 385.451115 -294.726572)
			(xy 385.412994 -294.695447) (xy 385.380359 -294.65861) (xy 385.354056 -294.617014) (xy 385.334765 -294.571738)
			(xy 385.322988 -294.523954) (xy 385.319028 -294.4749) (xy 385.00558 -294.4749) (xy 385.005173 -294.498602)
			(xy 384.998406 -294.545522) (xy 384.98501 -294.590994) (xy 384.96526 -294.634089) (xy 384.952748 -294.654224)
			(xy 384.946972 -294.664271) (xy 384.944248 -294.687261) (xy 384.951822 -294.709139) (xy 384.959606 -294.717724)
			(xy 385.822444 -295.580562) (xy 385.828037 -295.586561) (xy 385.835409 -295.601202) (xy 385.836922 -295.609264)
			(xy 385.838192 -295.617392) (xy 385.845558 -295.632124) (xy 386.085842 -295.872408) (xy 386.093254 -295.879085)
			(xy 386.11169 -295.88665) (xy 386.121656 -295.88714) (xy 386.169154 -295.88714) (xy 386.17271 -295.887394)
			(xy 386.976874 -295.887394)
		)
		(stroke
			(width 0)
			(type solid)
		)
		(fill yes)
		(layer "In5.Cu")
		(net "PCEPLL4_VDDA18_PEX3")
	)
	(gr_poly
		(pts
			(xy 156.894022 -293.54145) (xy 156.894276 -293.520368) (xy 156.895124 -293.494616) (xy 156.903816 -293.443832)
			(xy 156.920279 -293.39501) (xy 156.944113 -293.349331) (xy 156.974742 -293.307901) (xy 157.011425 -293.271721)
			(xy 157.053274 -293.241668) (xy 157.099278 -293.218468) (xy 157.148323 -293.202682) (xy 157.199223 -293.194692)
			(xy 157.250745 -293.194692) (xy 157.301645 -293.202682) (xy 157.35069 -293.218468) (xy 157.396694 -293.241668)
			(xy 157.438543 -293.271721) (xy 157.475226 -293.307901) (xy 157.505855 -293.349331) (xy 157.529689 -293.39501)
			(xy 157.546152 -293.443832) (xy 157.554844 -293.494616) (xy 157.555692 -293.520368) (xy 157.555946 -293.54145)
			(xy 157.585664 -293.57066) (xy 157.814264 -293.57066) (xy 157.843982 -293.54145) (xy 157.844236 -293.520368)
			(xy 157.845084 -293.494616) (xy 157.853776 -293.443832) (xy 157.870239 -293.39501) (xy 157.894073 -293.349331)
			(xy 157.924702 -293.307901) (xy 157.961385 -293.271721) (xy 158.003234 -293.241668) (xy 158.049238 -293.218468)
			(xy 158.098283 -293.202682) (xy 158.149183 -293.194692) (xy 158.200705 -293.194692) (xy 158.251605 -293.202682)
			(xy 158.30065 -293.218468) (xy 158.346654 -293.241668) (xy 158.388503 -293.271721) (xy 158.425186 -293.307901)
			(xy 158.455815 -293.349331) (xy 158.479649 -293.39501) (xy 158.496112 -293.443832) (xy 158.504804 -293.494616)
			(xy 158.505652 -293.520368) (xy 158.505906 -293.54145) (xy 158.535624 -293.57066) (xy 158.713678 -293.57066)
			(xy 158.743142 -293.54145) (xy 158.743396 -293.520368) (xy 158.744191 -293.49333) (xy 158.752472 -293.439876)
			(xy 158.768219 -293.388128) (xy 158.791118 -293.339123) (xy 158.820708 -293.293842) (xy 158.856396 -293.253195)
			(xy 158.897468 -293.217996) (xy 158.9431 -293.188951) (xy 158.992376 -293.166641) (xy 159.044309 -293.151515)
			(xy 159.097858 -293.143876) (xy 159.15195 -293.143876) (xy 159.205499 -293.151515) (xy 159.257432 -293.166641)
			(xy 159.306708 -293.188951) (xy 159.35234 -293.217996) (xy 159.393412 -293.253195) (xy 159.4291 -293.293842)
			(xy 159.45869 -293.339123) (xy 159.481589 -293.388128) (xy 159.497336 -293.439876) (xy 159.505617 -293.49333)
			(xy 159.506412 -293.520368) (xy 159.506666 -293.54145) (xy 159.53613 -293.57066) (xy 159.714184 -293.57066)
			(xy 159.743902 -293.54145) (xy 159.744156 -293.520368) (xy 159.745004 -293.494616) (xy 159.753696 -293.443832)
			(xy 159.770159 -293.39501) (xy 159.793993 -293.349331) (xy 159.824622 -293.307901) (xy 159.861305 -293.271721)
			(xy 159.903154 -293.241668) (xy 159.949158 -293.218468) (xy 159.998203 -293.202682) (xy 160.049103 -293.194692)
			(xy 160.100625 -293.194692) (xy 160.151525 -293.202682) (xy 160.20057 -293.218468) (xy 160.246574 -293.241668)
			(xy 160.288423 -293.271721) (xy 160.325106 -293.307901) (xy 160.355735 -293.349331) (xy 160.379569 -293.39501)
			(xy 160.396032 -293.443832) (xy 160.404724 -293.494616) (xy 160.405572 -293.520368) (xy 160.405826 -293.54145)
			(xy 160.435544 -293.57066) (xy 161.614358 -293.57066) (xy 161.644076 -293.54145) (xy 161.64433 -293.520368)
			(xy 161.645178 -293.494616) (xy 161.65387 -293.443832) (xy 161.670333 -293.39501) (xy 161.694167 -293.349331)
			(xy 161.724796 -293.307901) (xy 161.761479 -293.271721) (xy 161.803328 -293.241668) (xy 161.849332 -293.218468)
			(xy 161.898377 -293.202682) (xy 161.949277 -293.194692) (xy 162.000799 -293.194692) (xy 162.051699 -293.202682)
			(xy 162.100744 -293.218468) (xy 162.146748 -293.241668) (xy 162.188597 -293.271721) (xy 162.22528 -293.307901)
			(xy 162.255909 -293.349331) (xy 162.279743 -293.39501) (xy 162.296206 -293.443832) (xy 162.304898 -293.494616)
			(xy 162.305746 -293.520368) (xy 162.306 -293.54145) (xy 162.335718 -293.57066) (xy 162.564318 -293.57066)
			(xy 162.594036 -293.54145) (xy 162.59429 -293.520368) (xy 162.595136 -293.494617) (xy 162.603824 -293.443833)
			(xy 162.620284 -293.395013) (xy 162.644117 -293.349336) (xy 162.674747 -293.307908) (xy 162.711433 -293.271733)
			(xy 162.753285 -293.241687) (xy 162.799291 -293.218495) (xy 162.848337 -293.20272) (xy 162.899237 -293.194744)
			(xy 162.924998 -293.194232) (xy 162.949217 -293.194656) (xy 162.997138 -293.201724) (xy 163.043513 -293.21571)
			(xy 163.087352 -293.236315) (xy 163.127714 -293.263096) (xy 163.163735 -293.295481) (xy 163.179506 -293.313866)
			(xy 163.186364 -293.321994) (xy 163.205414 -293.331646) (xy 163.291266 -293.33571) (xy 163.301924 -293.335651)
			(xy 163.321758 -293.327918) (xy 163.32962 -293.320724) (xy 163.33724 -293.313104) (xy 163.344094 -293.305709)
			(xy 163.351839 -293.28711) (xy 163.352226 -293.277036) (xy 163.352226 -292.129464) (xy 163.351797 -292.119396)
			(xy 163.344076 -292.100799) (xy 163.33724 -292.093396) (xy 163.158932 -291.915088) (xy 163.150488 -291.907466)
			(xy 163.129096 -291.89982) (xy 163.106496 -291.90213) (xy 163.096448 -291.907468) (xy 163.076984 -291.918849)
			(xy 163.035626 -291.936805) (xy 162.99221 -291.948965) (xy 162.947542 -291.955102) (xy 162.924998 -291.955474)
			(xy 162.89883 -291.954975) (xy 162.847148 -291.946723) (xy 162.797414 -291.930427) (xy 162.750871 -291.906492)
			(xy 162.708684 -291.87552) (xy 162.671908 -291.838283) (xy 162.656266 -291.817298) (xy 162.648603 -291.807879)
			(xy 162.62699 -291.796885) (xy 162.614864 -291.796216) (xy 162.285172 -291.796216) (xy 162.27304 -291.796847)
			(xy 162.251431 -291.807867) (xy 162.24377 -291.817298) (xy 162.228138 -291.838289) (xy 162.191356 -291.875519)
			(xy 162.149165 -291.906486) (xy 162.102621 -291.930415) (xy 162.052887 -291.946708) (xy 162.001206 -291.954958)
			(xy 161.94887 -291.954958) (xy 161.897189 -291.946708) (xy 161.847455 -291.930415) (xy 161.800911 -291.906486)
			(xy 161.75872 -291.875519) (xy 161.721938 -291.838289) (xy 161.706306 -291.817298) (xy 161.698645 -291.807872)
			(xy 161.677033 -291.796862) (xy 161.664904 -291.796216) (xy 161.335212 -291.796216) (xy 161.323075 -291.796838)
			(xy 161.301452 -291.807849) (xy 161.29381 -291.817298) (xy 161.278178 -291.838289) (xy 161.241396 -291.875519)
			(xy 161.199205 -291.906486) (xy 161.152661 -291.930415) (xy 161.102927 -291.946708) (xy 161.051246 -291.954958)
			(xy 160.99891 -291.954958) (xy 160.947229 -291.946708) (xy 160.897495 -291.930415) (xy 160.850951 -291.906486)
			(xy 160.80876 -291.875519) (xy 160.771978 -291.838289) (xy 160.756346 -291.817298) (xy 160.748681 -291.807882)
			(xy 160.727068 -291.796897) (xy 160.714944 -291.796216) (xy 160.384998 -291.796216) (xy 160.372863 -291.796841)
			(xy 160.351244 -291.807855) (xy 160.343596 -291.817298) (xy 160.327964 -291.838289) (xy 160.291182 -291.875519)
			(xy 160.248991 -291.906486) (xy 160.202447 -291.930415) (xy 160.152713 -291.946708) (xy 160.101032 -291.954958)
			(xy 160.048696 -291.954958) (xy 159.997015 -291.946708) (xy 159.947281 -291.930415) (xy 159.900737 -291.906486)
			(xy 159.858546 -291.875519) (xy 159.821764 -291.838289) (xy 159.806132 -291.817298) (xy 159.798466 -291.807884)
			(xy 159.776853 -291.796906) (xy 159.76473 -291.796216) (xy 159.435038 -291.796216) (xy 159.422898 -291.796833)
			(xy 159.401265 -291.807837) (xy 159.393636 -291.817298) (xy 159.378004 -291.838289) (xy 159.341222 -291.875519)
			(xy 159.299031 -291.906486) (xy 159.252487 -291.930415) (xy 159.202753 -291.946708) (xy 159.151072 -291.954958)
			(xy 159.098736 -291.954958) (xy 159.047055 -291.946708) (xy 158.997321 -291.930415) (xy 158.950777 -291.906486)
			(xy 158.908586 -291.875519) (xy 158.871804 -291.838289) (xy 158.856172 -291.817298) (xy 158.848509 -291.807878)
			(xy 158.826896 -291.796882) (xy 158.81477 -291.796216) (xy 158.485078 -291.796216) (xy 158.472945 -291.796846)
			(xy 158.451334 -291.807864) (xy 158.443676 -291.817298) (xy 158.428044 -291.838289) (xy 158.391262 -291.875519)
			(xy 158.349071 -291.906486) (xy 158.302527 -291.930415) (xy 158.252793 -291.946708) (xy 158.201112 -291.954958)
			(xy 158.148776 -291.954958) (xy 158.097095 -291.946708) (xy 158.047361 -291.930415) (xy 158.000817 -291.906486)
			(xy 157.958626 -291.875519) (xy 157.921844 -291.838289) (xy 157.906212 -291.817298) (xy 157.898552 -291.807871)
			(xy 157.876939 -291.796858) (xy 157.86481 -291.796216) (xy 157.738064 -291.796216) (xy 157.727996 -291.795787)
			(xy 157.7094 -291.788065) (xy 157.701996 -291.78123) (xy 157.677866 -291.7571) (xy 157.66896 -291.749161)
			(xy 157.646312 -291.741759) (xy 157.634432 -291.742876) (xy 157.541976 -291.756592) (xy 157.522164 -291.770308)
			(xy 157.516576 -291.780976) (xy 157.5041 -291.803223) (xy 157.47337 -291.843929) (xy 157.43676 -291.879441)
			(xy 157.395136 -291.908917) (xy 157.349484 -291.93166) (xy 157.300884 -291.947133) (xy 157.250486 -291.954969)
			(xy 157.224984 -291.955474) (xy 157.198997 -291.95499) (xy 157.147662 -291.946856) (xy 157.098232 -291.930792)
			(xy 157.051923 -291.907193) (xy 157.009877 -291.87664) (xy 156.973128 -291.839885) (xy 156.942581 -291.797834)
			(xy 156.918989 -291.751522) (xy 156.902932 -291.702089) (xy 156.894806 -291.650754) (xy 156.894276 -291.624766)
			(xy 156.894743 -291.59926) (xy 156.902563 -291.548851) (xy 156.918029 -291.500239) (xy 156.940773 -291.454578)
			(xy 156.970257 -291.412949) (xy 157.005782 -291.37634) (xy 157.046505 -291.345618) (xy 157.068774 -291.333174)
			(xy 157.079442 -291.327586) (xy 157.093158 -291.307774) (xy 157.106874 -291.215318) (xy 157.108031 -291.203438)
			(xy 157.100601 -291.180788) (xy 157.09265 -291.171884) (xy 155.777946 -289.85718) (xy 155.769043 -289.849228)
			(xy 155.746391 -289.841794) (xy 155.734512 -289.842956) (xy 155.642056 -289.856672) (xy 155.622244 -289.870388)
			(xy 155.616656 -289.881056) (xy 155.604182 -289.903307) (xy 155.573456 -289.944024) (xy 155.536848 -289.979546)
			(xy 155.495226 -290.009034) (xy 155.449573 -290.03179) (xy 155.400971 -290.047275) (xy 155.350569 -290.055123)
			(xy 155.325064 -290.055554) (xy 155.299077 -290.055042) (xy 155.247745 -290.046907) (xy 155.198316 -290.030843)
			(xy 155.152008 -290.007246) (xy 155.109961 -289.976697) (xy 155.07321 -289.939947) (xy 155.042659 -289.897901)
			(xy 155.01906 -289.851593) (xy 155.002995 -289.802165) (xy 154.994859 -289.750833) (xy 154.994356 -289.724846)
			(xy 154.994824 -289.69934) (xy 155.002647 -289.648932) (xy 155.018114 -289.600323) (xy 155.040859 -289.554663)
			(xy 155.070343 -289.513035) (xy 155.105867 -289.476426) (xy 155.146589 -289.445704) (xy 155.168854 -289.433254)
			(xy 155.179522 -289.427666) (xy 155.193238 -289.407854) (xy 155.206954 -289.315398) (xy 155.208107 -289.303518)
			(xy 155.20068 -289.280868) (xy 155.19273 -289.271964) (xy 154.827986 -288.90722) (xy 154.819082 -288.899275)
			(xy 154.796432 -288.89186) (xy 154.784552 -288.892996) (xy 154.692096 -288.906712) (xy 154.672284 -288.920428)
			(xy 154.666696 -288.931096) (xy 154.654219 -288.953342) (xy 154.623489 -288.994049) (xy 154.586878 -289.02956)
			(xy 154.545255 -289.059037) (xy 154.499603 -289.081782) (xy 154.451004 -289.097256) (xy 154.400606 -289.105094)
			(xy 154.375104 -289.105594) (xy 154.349115 -289.105111) (xy 154.297777 -289.09698) (xy 154.248343 -289.080918)
			(xy 154.20203 -289.057321) (xy 154.159979 -289.026768) (xy 154.123225 -288.990013) (xy 154.092674 -288.947962)
			(xy 154.069078 -288.901648) (xy 154.053017 -288.852214) (xy 154.044888 -288.800875) (xy 154.044396 -288.774886)
			(xy 154.044861 -288.749379) (xy 154.052679 -288.698969) (xy 154.068144 -288.650356) (xy 154.090887 -288.604693)
			(xy 154.120371 -288.563064) (xy 154.155896 -288.526454) (xy 154.196621 -288.495731) (xy 154.218894 -288.483294)
			(xy 154.229562 -288.477706) (xy 154.243278 -288.457894) (xy 154.256994 -288.365438) (xy 154.258156 -288.353556)
			(xy 154.250735 -288.330898) (xy 154.24277 -288.322004) (xy 153.877772 -287.957006) (xy 153.868922 -287.949105)
			(xy 153.84641 -287.941711) (xy 153.834592 -287.942782) (xy 153.741882 -287.956498) (xy 153.72207 -287.970214)
			(xy 153.716482 -287.980882) (xy 153.704032 -288.003161) (xy 153.673338 -288.043935) (xy 153.636745 -288.079511)
			(xy 153.595123 -288.109043) (xy 153.549458 -288.131833) (xy 153.500835 -288.147338) (xy 153.450408 -288.15519)
			(xy 153.42489 -288.155634) (xy 153.398903 -288.155124) (xy 153.347568 -288.146992) (xy 153.298137 -288.130931)
			(xy 153.251827 -288.107335) (xy 153.209778 -288.076785) (xy 153.173025 -288.040034) (xy 153.142474 -287.997987)
			(xy 153.118876 -287.951678) (xy 153.102812 -287.902248) (xy 153.094678 -287.850913) (xy 153.094182 -287.824926)
			(xy 153.094654 -287.799408) (xy 153.102492 -287.748979) (xy 153.117987 -287.700352) (xy 153.14077 -287.654685)
			(xy 153.1703 -287.61306) (xy 153.205875 -287.576468) (xy 153.246651 -287.545777) (xy 153.268934 -287.533334)
			(xy 153.279602 -287.527746) (xy 153.293318 -287.507934) (xy 153.307034 -287.415224) (xy 153.308129 -287.403409)
			(xy 153.300704 -287.380904) (xy 153.29281 -287.372044) (xy 152.927812 -287.007046) (xy 152.918965 -286.999133)
			(xy 152.89645 -286.991715) (xy 152.884632 -286.992822) (xy 152.791922 -287.006538) (xy 152.77211 -287.020254)
			(xy 152.766522 -287.030922) (xy 152.754069 -287.053196) (xy 152.723371 -287.09396) (xy 152.686776 -287.129524)
			(xy 152.645152 -287.159046) (xy 152.599489 -287.181824) (xy 152.550868 -287.197319) (xy 152.500445 -287.205161)
			(xy 152.47493 -287.205674) (xy 152.44894 -287.205193) (xy 152.3976 -287.197065) (xy 152.348164 -287.181005)
			(xy 152.301849 -287.157409) (xy 152.259796 -287.126856) (xy 152.223041 -287.090101) (xy 152.192489 -287.048048)
			(xy 152.168893 -287.001733) (xy 152.152834 -286.952296) (xy 152.144707 -286.900956) (xy 152.144222 -286.874966)
			(xy 152.145238 -286.850074) (xy 152.146 -286.839406) (xy 152.139142 -286.819594) (xy 152.080976 -286.75711)
			(xy 152.073505 -286.749775) (xy 152.054349 -286.741384) (xy 152.043892 -286.740854) (xy 150.515574 -286.740854)
			(xy 150.506588 -286.741201) (xy 150.489725 -286.747411) (xy 150.476063 -286.759087) (xy 150.471378 -286.766762)
			(xy 150.421086 -286.85617) (xy 150.421594 -286.883348) (xy 150.428706 -286.895286) (xy 150.441964 -286.917807)
			(xy 150.462862 -286.965707) (xy 150.477016 -287.016014) (xy 150.484159 -287.067784) (xy 150.484586 -287.093914)
			(xy 150.4841 -287.121165) (xy 150.476344 -287.175113) (xy 150.460989 -287.227408) (xy 150.438347 -287.276985)
			(xy 150.408881 -287.322835) (xy 150.37319 -287.364026) (xy 150.331999 -287.399717) (xy 150.286149 -287.429183)
			(xy 150.236572 -287.451825) (xy 150.184277 -287.46718) (xy 150.130329 -287.474936) (xy 150.075827 -287.474936)
			(xy 150.021879 -287.46718) (xy 149.969584 -287.451825) (xy 149.920007 -287.429183) (xy 149.874157 -287.399717)
			(xy 149.832966 -287.364026) (xy 149.797275 -287.322835) (xy 149.767809 -287.276985) (xy 149.745167 -287.227408)
			(xy 149.729812 -287.175113) (xy 149.722056 -287.121165) (xy 149.72157 -287.093914) (xy 149.722023 -287.067787)
			(xy 149.729193 -287.016027) (xy 149.743348 -286.965726) (xy 149.764223 -286.917822) (xy 149.77745 -286.895286)
			(xy 149.784562 -286.883348) (xy 149.78507 -286.85617) (xy 149.734778 -286.766762) (xy 149.730054 -286.759126)
			(xy 149.716384 -286.7475) (xy 149.699553 -286.741276) (xy 149.690582 -286.740854) (xy 147.576032 -286.740854)
			(xy 147.491196 -286.82569) (xy 147.491196 -287.850913) (xy 152.144732 -287.850913) (xy 152.144732 -287.798939)
			(xy 152.152862 -287.747604) (xy 152.168923 -287.698174) (xy 152.192519 -287.651864) (xy 152.223069 -287.609816)
			(xy 152.25982 -287.573065) (xy 152.301868 -287.542515) (xy 152.348178 -287.518919) (xy 152.397608 -287.502858)
			(xy 152.448943 -287.494728) (xy 152.500917 -287.494728) (xy 152.552252 -287.502858) (xy 152.601682 -287.518919)
			(xy 152.647992 -287.542515) (xy 152.69004 -287.573065) (xy 152.726791 -287.609816) (xy 152.757341 -287.651864)
			(xy 152.780937 -287.698174) (xy 152.796998 -287.747604) (xy 152.805128 -287.798939) (xy 152.805638 -287.824926)
			(xy 152.805128 -287.850913) (xy 152.796998 -287.902248) (xy 152.780937 -287.951678) (xy 152.757341 -287.997988)
			(xy 152.726791 -288.040036) (xy 152.69004 -288.076787) (xy 152.647992 -288.107337) (xy 152.601682 -288.130933)
			(xy 152.552252 -288.146994) (xy 152.500917 -288.155124) (xy 152.448943 -288.155124) (xy 152.397608 -288.146994)
			(xy 152.348178 -288.130933) (xy 152.301868 -288.107337) (xy 152.25982 -288.076787) (xy 152.223069 -288.040036)
			(xy 152.192519 -287.997988) (xy 152.168923 -287.951678) (xy 152.152862 -287.902248) (xy 152.144732 -287.850913)
			(xy 147.491196 -287.850913) (xy 147.491196 -288.473642) (xy 147.491196 -288.7853) (xy 147.506769 -288.800873)
			(xy 152.144732 -288.800873) (xy 152.144732 -288.748899) (xy 152.152862 -288.697564) (xy 152.168923 -288.648134)
			(xy 152.192519 -288.601824) (xy 152.223069 -288.559776) (xy 152.25982 -288.523025) (xy 152.301868 -288.492475)
			(xy 152.348178 -288.468879) (xy 152.397608 -288.452818) (xy 152.448943 -288.444688) (xy 152.500917 -288.444688)
			(xy 152.552252 -288.452818) (xy 152.601682 -288.468879) (xy 152.647992 -288.492475) (xy 152.69004 -288.523025)
			(xy 152.726791 -288.559776) (xy 152.757341 -288.601824) (xy 152.780937 -288.648134) (xy 152.796998 -288.697564)
			(xy 152.805128 -288.748899) (xy 152.805638 -288.774886) (xy 152.805128 -288.800873) (xy 153.094692 -288.800873)
			(xy 153.094692 -288.748899) (xy 153.102822 -288.697564) (xy 153.118883 -288.648134) (xy 153.142479 -288.601824)
			(xy 153.173029 -288.559776) (xy 153.20978 -288.523025) (xy 153.251828 -288.492475) (xy 153.298138 -288.468879)
			(xy 153.347568 -288.452818) (xy 153.398903 -288.444688) (xy 153.450877 -288.444688) (xy 153.502212 -288.452818)
			(xy 153.551642 -288.468879) (xy 153.597952 -288.492475) (xy 153.64 -288.523025) (xy 153.676751 -288.559776)
			(xy 153.707301 -288.601824) (xy 153.730897 -288.648134) (xy 153.746958 -288.697564) (xy 153.755088 -288.748899)
			(xy 153.755598 -288.774886) (xy 153.755088 -288.800873) (xy 153.746958 -288.852208) (xy 153.730897 -288.901638)
			(xy 153.707301 -288.947948) (xy 153.676751 -288.989996) (xy 153.64 -289.026747) (xy 153.597952 -289.057297)
			(xy 153.551642 -289.080893) (xy 153.502212 -289.096954) (xy 153.450877 -289.105084) (xy 153.398903 -289.105084)
			(xy 153.347568 -289.096954) (xy 153.298138 -289.080893) (xy 153.251828 -289.057297) (xy 153.20978 -289.026747)
			(xy 153.173029 -288.989996) (xy 153.142479 -288.947948) (xy 153.118883 -288.901638) (xy 153.102822 -288.852208)
			(xy 153.094692 -288.800873) (xy 152.805128 -288.800873) (xy 152.796998 -288.852208) (xy 152.780937 -288.901638)
			(xy 152.757341 -288.947948) (xy 152.726791 -288.989996) (xy 152.69004 -289.026747) (xy 152.647992 -289.057297)
			(xy 152.601682 -289.080893) (xy 152.552252 -289.096954) (xy 152.500917 -289.105084) (xy 152.448943 -289.105084)
			(xy 152.397608 -289.096954) (xy 152.348178 -289.080893) (xy 152.301868 -289.057297) (xy 152.25982 -289.026747)
			(xy 152.223069 -288.989996) (xy 152.192519 -288.947948) (xy 152.168923 -288.901638) (xy 152.152862 -288.852208)
			(xy 152.144732 -288.800873) (xy 147.506769 -288.800873) (xy 147.695158 -288.989262) (xy 151.846788 -288.989262)
			(xy 152.2857 -289.428174) (xy 152.317196 -289.433762) (xy 152.332182 -289.42665) (xy 152.354573 -289.416411)
			(xy 152.40163 -289.401935) (xy 152.450314 -289.394596) (xy 152.47493 -289.394138) (xy 152.500916 -289.394623)
			(xy 152.552249 -289.402759) (xy 152.601676 -289.418824) (xy 152.647982 -289.442424) (xy 152.690026 -289.472978)
			(xy 152.726772 -289.509732) (xy 152.757316 -289.551783) (xy 152.780905 -289.598094) (xy 152.796959 -289.647525)
			(xy 152.805083 -289.698859) (xy 152.805638 -289.724846) (xy 152.805167 -289.749462) (xy 152.80496 -289.750833)
			(xy 153.094692 -289.750833) (xy 153.094692 -289.698859) (xy 153.102822 -289.647524) (xy 153.118883 -289.598094)
			(xy 153.142479 -289.551784) (xy 153.173029 -289.509736) (xy 153.20978 -289.472985) (xy 153.251828 -289.442435)
			(xy 153.298138 -289.418839) (xy 153.347568 -289.402778) (xy 153.398903 -289.394648) (xy 153.450877 -289.394648)
			(xy 153.502212 -289.402778) (xy 153.551642 -289.418839) (xy 153.597952 -289.442435) (xy 153.64 -289.472985)
			(xy 153.676751 -289.509736) (xy 153.707301 -289.551784) (xy 153.730897 -289.598094) (xy 153.746958 -289.647524)
			(xy 153.755088 -289.698859) (xy 153.755598 -289.724846) (xy 153.755088 -289.750833) (xy 154.044906 -289.750833)
			(xy 154.044906 -289.698859) (xy 154.053036 -289.647524) (xy 154.069097 -289.598094) (xy 154.092693 -289.551784)
			(xy 154.123243 -289.509736) (xy 154.159994 -289.472985) (xy 154.202042 -289.442435) (xy 154.248352 -289.418839)
			(xy 154.297782 -289.402778) (xy 154.349117 -289.394648) (xy 154.401091 -289.394648) (xy 154.452426 -289.402778)
			(xy 154.501856 -289.418839) (xy 154.548166 -289.442435) (xy 154.590214 -289.472985) (xy 154.626965 -289.509736)
			(xy 154.657515 -289.551784) (xy 154.681111 -289.598094) (xy 154.697172 -289.647524) (xy 154.705302 -289.698859)
			(xy 154.705812 -289.724846) (xy 154.705302 -289.750833) (xy 154.697172 -289.802168) (xy 154.681111 -289.851598)
			(xy 154.657515 -289.897908) (xy 154.626965 -289.939956) (xy 154.590214 -289.976707) (xy 154.548166 -290.007257)
			(xy 154.501856 -290.030853) (xy 154.452426 -290.046914) (xy 154.401091 -290.055044) (xy 154.349117 -290.055044)
			(xy 154.297782 -290.046914) (xy 154.248352 -290.030853) (xy 154.202042 -290.007257) (xy 154.159994 -289.976707)
			(xy 154.123243 -289.939956) (xy 154.092693 -289.897908) (xy 154.069097 -289.851598) (xy 154.053036 -289.802168)
			(xy 154.044906 -289.750833) (xy 153.755088 -289.750833) (xy 153.746958 -289.802168) (xy 153.730897 -289.851598)
			(xy 153.707301 -289.897908) (xy 153.676751 -289.939956) (xy 153.64 -289.976707) (xy 153.597952 -290.007257)
			(xy 153.551642 -290.030853) (xy 153.502212 -290.046914) (xy 153.450877 -290.055044) (xy 153.398903 -290.055044)
			(xy 153.347568 -290.046914) (xy 153.298138 -290.030853) (xy 153.251828 -290.007257) (xy 153.20978 -289.976707)
			(xy 153.173029 -289.939956) (xy 153.142479 -289.897908) (xy 153.118883 -289.851598) (xy 153.102822 -289.802168)
			(xy 153.094692 -289.750833) (xy 152.80496 -289.750833) (xy 152.797833 -289.798145) (xy 152.783363 -289.845203)
			(xy 152.773126 -289.867594) (xy 152.766014 -289.88258) (xy 152.771602 -289.914076) (xy 153.23566 -290.378134)
			(xy 153.267156 -290.383722) (xy 153.282142 -290.37661) (xy 153.304533 -290.366374) (xy 153.351591 -290.351903)
			(xy 153.400274 -290.344571) (xy 153.42489 -290.344098) (xy 153.45088 -290.34458) (xy 153.502219 -290.35271)
			(xy 153.551655 -290.368772) (xy 153.597969 -290.392369) (xy 153.640021 -290.422921) (xy 153.676776 -290.459676)
			(xy 153.707329 -290.501728) (xy 153.730927 -290.548042) (xy 153.746989 -290.597477) (xy 153.755119 -290.648816)
			(xy 153.755598 -290.674806) (xy 153.755123 -290.699421) (xy 153.754916 -290.700793) (xy 154.044906 -290.700793)
			(xy 154.044906 -290.648819) (xy 154.053036 -290.597484) (xy 154.069097 -290.548054) (xy 154.092693 -290.501744)
			(xy 154.123243 -290.459696) (xy 154.159994 -290.422945) (xy 154.202042 -290.392395) (xy 154.248352 -290.368799)
			(xy 154.297782 -290.352738) (xy 154.349117 -290.344608) (xy 154.401091 -290.344608) (xy 154.452426 -290.352738)
			(xy 154.501856 -290.368799) (xy 154.548166 -290.392395) (xy 154.590214 -290.422945) (xy 154.626965 -290.459696)
			(xy 154.657515 -290.501744) (xy 154.681111 -290.548054) (xy 154.697172 -290.597484) (xy 154.705302 -290.648819)
			(xy 154.705812 -290.674806) (xy 154.705302 -290.700793) (xy 154.697172 -290.752128) (xy 154.681111 -290.801558)
			(xy 154.657515 -290.847868) (xy 154.626965 -290.889916) (xy 154.590214 -290.926667) (xy 154.548166 -290.957217)
			(xy 154.501856 -290.980813) (xy 154.452426 -290.996874) (xy 154.401091 -291.005004) (xy 154.349117 -291.005004)
			(xy 154.297782 -290.996874) (xy 154.248352 -290.980813) (xy 154.202042 -290.957217) (xy 154.159994 -290.926667)
			(xy 154.123243 -290.889916) (xy 154.092693 -290.847868) (xy 154.069097 -290.801558) (xy 154.053036 -290.752128)
			(xy 154.044906 -290.700793) (xy 153.754916 -290.700793) (xy 153.747782 -290.748101) (xy 153.733307 -290.795156)
			(xy 153.723086 -290.817554) (xy 153.715974 -290.83254) (xy 153.721562 -290.864036) (xy 154.18562 -291.328094)
			(xy 154.217624 -291.333682) (xy 154.232102 -291.32657) (xy 154.254533 -291.316317) (xy 154.301674 -291.30183)
			(xy 154.350445 -291.294505) (xy 154.375104 -291.294058) (xy 154.401092 -291.294568) (xy 154.452428 -291.302699)
			(xy 154.50186 -291.31876) (xy 154.548172 -291.342355) (xy 154.590222 -291.372904) (xy 154.626976 -291.409655)
			(xy 154.657529 -291.451703) (xy 154.681129 -291.498012) (xy 154.697194 -291.547443) (xy 154.70533 -291.598778)
			(xy 154.705812 -291.624766) (xy 154.705359 -291.649425) (xy 154.698043 -291.698198) (xy 154.683566 -291.745343)
			(xy 154.6733 -291.767768) (xy 154.666188 -291.782246) (xy 154.671776 -291.81425) (xy 155.13558 -292.278054)
			(xy 155.167584 -292.283642) (xy 155.182062 -292.27653) (xy 155.204493 -292.266279) (xy 155.251635 -292.251798)
			(xy 155.300406 -292.244481) (xy 155.325064 -292.244018) (xy 155.351054 -292.244498) (xy 155.402396 -292.252625)
			(xy 155.451833 -292.268685) (xy 155.49815 -292.292281) (xy 155.540204 -292.322833) (xy 155.57696 -292.359588)
			(xy 155.607514 -292.401642) (xy 155.631111 -292.447957) (xy 155.647172 -292.497394) (xy 155.655301 -292.548736)
			(xy 155.655772 -292.574726) (xy 155.655314 -292.599384) (xy 155.655114 -292.600713) (xy 155.944826 -292.600713)
			(xy 155.944826 -292.548739) (xy 155.952956 -292.497404) (xy 155.969017 -292.447974) (xy 155.992613 -292.401664)
			(xy 156.023163 -292.359616) (xy 156.059914 -292.322865) (xy 156.101962 -292.292315) (xy 156.148272 -292.268719)
			(xy 156.197702 -292.252658) (xy 156.249037 -292.244528) (xy 156.301011 -292.244528) (xy 156.352346 -292.252658)
			(xy 156.401776 -292.268719) (xy 156.448086 -292.292315) (xy 156.490134 -292.322865) (xy 156.526885 -292.359616)
			(xy 156.557435 -292.401664) (xy 156.581031 -292.447974) (xy 156.597092 -292.497404) (xy 156.605222 -292.548739)
			(xy 156.605732 -292.574726) (xy 156.605222 -292.600713) (xy 156.605182 -292.600967) (xy 156.894786 -292.600967)
			(xy 156.894786 -292.548993) (xy 156.902916 -292.497658) (xy 156.918977 -292.448228) (xy 156.942573 -292.401918)
			(xy 156.973123 -292.35987) (xy 157.009874 -292.323119) (xy 157.051922 -292.292569) (xy 157.098232 -292.268973)
			(xy 157.147662 -292.252912) (xy 157.198997 -292.244782) (xy 157.250971 -292.244782) (xy 157.302306 -292.252912)
			(xy 157.351736 -292.268973) (xy 157.398046 -292.292569) (xy 157.440094 -292.323119) (xy 157.476845 -292.35987)
			(xy 157.507395 -292.401918) (xy 157.530991 -292.448228) (xy 157.547052 -292.497658) (xy 157.555182 -292.548993)
			(xy 157.555692 -292.57498) (xy 157.792926 -292.57498) (xy 157.796997 -292.519358) (xy 157.809123 -292.464921)
			(xy 157.829046 -292.41283) (xy 157.856342 -292.364195) (xy 157.890428 -292.320052) (xy 157.930577 -292.281343)
			(xy 157.975935 -292.248892) (xy 158.025535 -292.223391) (xy 158.078319 -292.205384) (xy 158.133162 -292.195254)
			(xy 158.188896 -292.193217) (xy 158.244333 -292.199317) (xy 158.29829 -292.213423) (xy 158.349619 -292.235235)
			(xy 158.397225 -292.264289) (xy 158.440093 -292.299964) (xy 158.47731 -292.341501) (xy 158.508083 -292.388014)
			(xy 158.531755 -292.438511) (xy 158.547823 -292.491918) (xy 158.555943 -292.547094) (xy 158.556452 -292.57498)
			(xy 158.555978 -292.600967) (xy 158.794706 -292.600967) (xy 158.794706 -292.548993) (xy 158.802836 -292.497658)
			(xy 158.818897 -292.448228) (xy 158.842493 -292.401918) (xy 158.873043 -292.35987) (xy 158.909794 -292.323119)
			(xy 158.951842 -292.292569) (xy 158.998152 -292.268973) (xy 159.047582 -292.252912) (xy 159.098917 -292.244782)
			(xy 159.150891 -292.244782) (xy 159.202226 -292.252912) (xy 159.251656 -292.268973) (xy 159.297966 -292.292569)
			(xy 159.340014 -292.323119) (xy 159.376765 -292.35987) (xy 159.407315 -292.401918) (xy 159.430911 -292.448228)
			(xy 159.446972 -292.497658) (xy 159.455102 -292.548993) (xy 159.455612 -292.57498) (xy 159.455102 -292.600967)
			(xy 159.744666 -292.600967) (xy 159.744666 -292.548993) (xy 159.752796 -292.497658) (xy 159.768857 -292.448228)
			(xy 159.792453 -292.401918) (xy 159.823003 -292.35987) (xy 159.859754 -292.323119) (xy 159.901802 -292.292569)
			(xy 159.948112 -292.268973) (xy 159.997542 -292.252912) (xy 160.048877 -292.244782) (xy 160.100851 -292.244782)
			(xy 160.152186 -292.252912) (xy 160.201616 -292.268973) (xy 160.247926 -292.292569) (xy 160.289974 -292.323119)
			(xy 160.326725 -292.35987) (xy 160.357275 -292.401918) (xy 160.380871 -292.448228) (xy 160.396932 -292.497658)
			(xy 160.405062 -292.548993) (xy 160.405572 -292.57498) (xy 160.405062 -292.600967) (xy 160.69488 -292.600967)
			(xy 160.69488 -292.548993) (xy 160.70301 -292.497658) (xy 160.719071 -292.448228) (xy 160.742667 -292.401918)
			(xy 160.773217 -292.35987) (xy 160.809968 -292.323119) (xy 160.852016 -292.292569) (xy 160.898326 -292.268973)
			(xy 160.947756 -292.252912) (xy 160.999091 -292.244782) (xy 161.051065 -292.244782) (xy 161.1024 -292.252912)
			(xy 161.15183 -292.268973) (xy 161.19814 -292.292569) (xy 161.240188 -292.323119) (xy 161.276939 -292.35987)
			(xy 161.307489 -292.401918) (xy 161.331085 -292.448228) (xy 161.347146 -292.497658) (xy 161.355276 -292.548993)
			(xy 161.355786 -292.57498) (xy 161.355276 -292.600967) (xy 161.64484 -292.600967) (xy 161.64484 -292.548993)
			(xy 161.65297 -292.497658) (xy 161.669031 -292.448228) (xy 161.692627 -292.401918) (xy 161.723177 -292.35987)
			(xy 161.759928 -292.323119) (xy 161.801976 -292.292569) (xy 161.848286 -292.268973) (xy 161.897716 -292.252912)
			(xy 161.949051 -292.244782) (xy 162.001025 -292.244782) (xy 162.05236 -292.252912) (xy 162.10179 -292.268973)
			(xy 162.1481 -292.292569) (xy 162.190148 -292.323119) (xy 162.226899 -292.35987) (xy 162.257449 -292.401918)
			(xy 162.281045 -292.448228) (xy 162.297106 -292.497658) (xy 162.305236 -292.548993) (xy 162.305746 -292.57498)
			(xy 162.305236 -292.600967) (xy 162.297106 -292.652302) (xy 162.281045 -292.701732) (xy 162.257449 -292.748042)
			(xy 162.226899 -292.79009) (xy 162.190148 -292.826841) (xy 162.1481 -292.857391) (xy 162.10179 -292.880987)
			(xy 162.05236 -292.897048) (xy 162.001025 -292.905178) (xy 161.949051 -292.905178) (xy 161.897716 -292.897048)
			(xy 161.848286 -292.880987) (xy 161.801976 -292.857391) (xy 161.759928 -292.826841) (xy 161.723177 -292.79009)
			(xy 161.692627 -292.748042) (xy 161.669031 -292.701732) (xy 161.65297 -292.652302) (xy 161.64484 -292.600967)
			(xy 161.355276 -292.600967) (xy 161.347146 -292.652302) (xy 161.331085 -292.701732) (xy 161.307489 -292.748042)
			(xy 161.276939 -292.79009) (xy 161.240188 -292.826841) (xy 161.19814 -292.857391) (xy 161.15183 -292.880987)
			(xy 161.1024 -292.897048) (xy 161.051065 -292.905178) (xy 160.999091 -292.905178) (xy 160.947756 -292.897048)
			(xy 160.898326 -292.880987) (xy 160.852016 -292.857391) (xy 160.809968 -292.826841) (xy 160.773217 -292.79009)
			(xy 160.742667 -292.748042) (xy 160.719071 -292.701732) (xy 160.70301 -292.652302) (xy 160.69488 -292.600967)
			(xy 160.405062 -292.600967) (xy 160.396932 -292.652302) (xy 160.380871 -292.701732) (xy 160.357275 -292.748042)
			(xy 160.326725 -292.79009) (xy 160.289974 -292.826841) (xy 160.247926 -292.857391) (xy 160.201616 -292.880987)
			(xy 160.152186 -292.897048) (xy 160.100851 -292.905178) (xy 160.048877 -292.905178) (xy 159.997542 -292.897048)
			(xy 159.948112 -292.880987) (xy 159.901802 -292.857391) (xy 159.859754 -292.826841) (xy 159.823003 -292.79009)
			(xy 159.792453 -292.748042) (xy 159.768857 -292.701732) (xy 159.752796 -292.652302) (xy 159.744666 -292.600967)
			(xy 159.455102 -292.600967) (xy 159.446972 -292.652302) (xy 159.430911 -292.701732) (xy 159.407315 -292.748042)
			(xy 159.376765 -292.79009) (xy 159.340014 -292.826841) (xy 159.297966 -292.857391) (xy 159.251656 -292.880987)
			(xy 159.202226 -292.897048) (xy 159.150891 -292.905178) (xy 159.098917 -292.905178) (xy 159.047582 -292.897048)
			(xy 158.998152 -292.880987) (xy 158.951842 -292.857391) (xy 158.909794 -292.826841) (xy 158.873043 -292.79009)
			(xy 158.842493 -292.748042) (xy 158.818897 -292.701732) (xy 158.802836 -292.652302) (xy 158.794706 -292.600967)
			(xy 158.555978 -292.600967) (xy 158.555943 -292.602866) (xy 158.547823 -292.658042) (xy 158.531755 -292.711449)
			(xy 158.508083 -292.761946) (xy 158.47731 -292.808459) (xy 158.440093 -292.849996) (xy 158.397225 -292.885671)
			(xy 158.349619 -292.914725) (xy 158.29829 -292.936537) (xy 158.244333 -292.950643) (xy 158.188896 -292.956743)
			(xy 158.133162 -292.954706) (xy 158.078319 -292.944576) (xy 158.025535 -292.926569) (xy 157.975935 -292.901068)
			(xy 157.930577 -292.868617) (xy 157.890428 -292.829908) (xy 157.856342 -292.785765) (xy 157.829046 -292.73713)
			(xy 157.809123 -292.685039) (xy 157.796997 -292.630602) (xy 157.792926 -292.57498) (xy 157.555692 -292.57498)
			(xy 157.555182 -292.600967) (xy 157.547052 -292.652302) (xy 157.530991 -292.701732) (xy 157.507395 -292.748042)
			(xy 157.476845 -292.79009) (xy 157.440094 -292.826841) (xy 157.398046 -292.857391) (xy 157.351736 -292.880987)
			(xy 157.302306 -292.897048) (xy 157.250971 -292.905178) (xy 157.198997 -292.905178) (xy 157.147662 -292.897048)
			(xy 157.098232 -292.880987) (xy 157.051922 -292.857391) (xy 157.009874 -292.826841) (xy 156.973123 -292.79009)
			(xy 156.942573 -292.748042) (xy 156.918977 -292.701732) (xy 156.902916 -292.652302) (xy 156.894786 -292.600967)
			(xy 156.605182 -292.600967) (xy 156.597092 -292.652048) (xy 156.581031 -292.701478) (xy 156.557435 -292.747788)
			(xy 156.526885 -292.789836) (xy 156.490134 -292.826587) (xy 156.448086 -292.857137) (xy 156.401776 -292.880733)
			(xy 156.352346 -292.896794) (xy 156.301011 -292.904924) (xy 156.249037 -292.904924) (xy 156.197702 -292.896794)
			(xy 156.148272 -292.880733) (xy 156.101962 -292.857137) (xy 156.059914 -292.826587) (xy 156.023163 -292.789836)
			(xy 155.992613 -292.747788) (xy 155.969017 -292.701478) (xy 155.952956 -292.652048) (xy 155.944826 -292.600713)
			(xy 155.655114 -292.600713) (xy 155.647989 -292.648153) (xy 155.633503 -292.695293) (xy 155.62326 -292.717728)
			(xy 155.616148 -292.732206) (xy 155.621736 -292.76421) (xy 156.085794 -293.228268) (xy 156.11729 -293.233856)
			(xy 156.132276 -293.226744) (xy 156.154667 -293.216505) (xy 156.201724 -293.202028) (xy 156.250408 -293.194688)
			(xy 156.275024 -293.194232) (xy 156.300783 -293.194725) (xy 156.351679 -293.202717) (xy 156.40072 -293.218503)
			(xy 156.44672 -293.241701) (xy 156.488567 -293.271751) (xy 156.525249 -293.307925) (xy 156.555879 -293.34935)
			(xy 156.579716 -293.395023) (xy 156.596184 -293.443839) (xy 156.604883 -293.494618) (xy 156.605732 -293.520368)
			(xy 156.605986 -293.54145) (xy 156.635704 -293.57066) (xy 156.864304 -293.57066)
		)
		(stroke
			(width 0)
			(type solid)
		)
		(fill yes)
		(layer "In5.Cu")
		(net "PCEPLL6_VDDA18_PEX1")
	)
	(gr_poly
		(pts
			(xy 389.093964 -293.54145) (xy 389.094218 -293.520368) (xy 389.095066 -293.494616) (xy 389.103758 -293.443832)
			(xy 389.120221 -293.39501) (xy 389.144055 -293.349331) (xy 389.174684 -293.307901) (xy 389.211367 -293.271721)
			(xy 389.253216 -293.241668) (xy 389.29922 -293.218468) (xy 389.348265 -293.202682) (xy 389.399165 -293.194692)
			(xy 389.450687 -293.194692) (xy 389.501587 -293.202682) (xy 389.550632 -293.218468) (xy 389.596636 -293.241668)
			(xy 389.638485 -293.271721) (xy 389.675168 -293.307901) (xy 389.705797 -293.349331) (xy 389.729631 -293.39501)
			(xy 389.746094 -293.443832) (xy 389.754786 -293.494616) (xy 389.755634 -293.520368) (xy 389.755888 -293.54145)
			(xy 389.785606 -293.57066) (xy 390.014206 -293.57066) (xy 390.043924 -293.54145) (xy 390.044178 -293.520368)
			(xy 390.045026 -293.494616) (xy 390.053718 -293.443832) (xy 390.070181 -293.39501) (xy 390.094015 -293.349331)
			(xy 390.124644 -293.307901) (xy 390.161327 -293.271721) (xy 390.203176 -293.241668) (xy 390.24918 -293.218468)
			(xy 390.298225 -293.202682) (xy 390.349125 -293.194692) (xy 390.400647 -293.194692) (xy 390.451547 -293.202682)
			(xy 390.500592 -293.218468) (xy 390.546596 -293.241668) (xy 390.588445 -293.271721) (xy 390.625128 -293.307901)
			(xy 390.655757 -293.349331) (xy 390.679591 -293.39501) (xy 390.696054 -293.443832) (xy 390.704746 -293.494616)
			(xy 390.705594 -293.520368) (xy 390.705848 -293.54145) (xy 390.735566 -293.57066) (xy 390.91362 -293.57066)
			(xy 390.943084 -293.54145) (xy 390.943338 -293.520368) (xy 390.944133 -293.49333) (xy 390.952414 -293.439876)
			(xy 390.968161 -293.388128) (xy 390.99106 -293.339123) (xy 391.02065 -293.293842) (xy 391.056338 -293.253195)
			(xy 391.09741 -293.217996) (xy 391.143042 -293.188951) (xy 391.192318 -293.166641) (xy 391.244251 -293.151515)
			(xy 391.2978 -293.143876) (xy 391.351892 -293.143876) (xy 391.405441 -293.151515) (xy 391.457374 -293.166641)
			(xy 391.50665 -293.188951) (xy 391.552282 -293.217996) (xy 391.593354 -293.253195) (xy 391.629042 -293.293842)
			(xy 391.658632 -293.339123) (xy 391.681531 -293.388128) (xy 391.697278 -293.439876) (xy 391.705559 -293.49333)
			(xy 391.706354 -293.520368) (xy 391.706608 -293.54145) (xy 391.736072 -293.57066) (xy 391.914126 -293.57066)
			(xy 391.943844 -293.54145) (xy 391.944098 -293.520368) (xy 391.944946 -293.494616) (xy 391.953638 -293.443832)
			(xy 391.970101 -293.39501) (xy 391.993935 -293.349331) (xy 392.024564 -293.307901) (xy 392.061247 -293.271721)
			(xy 392.103096 -293.241668) (xy 392.1491 -293.218468) (xy 392.198145 -293.202682) (xy 392.249045 -293.194692)
			(xy 392.300567 -293.194692) (xy 392.351467 -293.202682) (xy 392.400512 -293.218468) (xy 392.446516 -293.241668)
			(xy 392.488365 -293.271721) (xy 392.525048 -293.307901) (xy 392.555677 -293.349331) (xy 392.579511 -293.39501)
			(xy 392.595974 -293.443832) (xy 392.604666 -293.494616) (xy 392.605514 -293.520368) (xy 392.605768 -293.54145)
			(xy 392.635486 -293.57066) (xy 393.8143 -293.57066) (xy 393.844018 -293.54145) (xy 393.844272 -293.520368)
			(xy 393.84512 -293.494616) (xy 393.853812 -293.443832) (xy 393.870275 -293.39501) (xy 393.894109 -293.349331)
			(xy 393.924738 -293.307901) (xy 393.961421 -293.271721) (xy 394.00327 -293.241668) (xy 394.049274 -293.218468)
			(xy 394.098319 -293.202682) (xy 394.149219 -293.194692) (xy 394.200741 -293.194692) (xy 394.251641 -293.202682)
			(xy 394.300686 -293.218468) (xy 394.34669 -293.241668) (xy 394.388539 -293.271721) (xy 394.425222 -293.307901)
			(xy 394.455851 -293.349331) (xy 394.479685 -293.39501) (xy 394.496148 -293.443832) (xy 394.50484 -293.494616)
			(xy 394.505688 -293.520368) (xy 394.505942 -293.54145) (xy 394.53566 -293.57066) (xy 394.76426 -293.57066)
			(xy 394.793978 -293.54145) (xy 394.794232 -293.520368) (xy 394.795077 -293.494615) (xy 394.803765 -293.443828)
			(xy 394.820224 -293.395004) (xy 394.844057 -293.349322) (xy 394.874686 -293.30789) (xy 394.91137 -293.27171)
			(xy 394.953222 -293.241656) (xy 394.999228 -293.218457) (xy 395.048276 -293.202675) (xy 395.099178 -293.19469)
			(xy 395.12494 -293.194232) (xy 395.149158 -293.194659) (xy 395.197075 -293.201732) (xy 395.243447 -293.215723)
			(xy 395.28728 -293.236331) (xy 395.327638 -293.263115) (xy 395.363655 -293.295501) (xy 395.379448 -293.313866)
			(xy 395.386306 -293.321994) (xy 395.405356 -293.331646) (xy 395.491208 -293.33571) (xy 395.501863 -293.335643)
			(xy 395.521685 -293.327898) (xy 395.529562 -293.320724) (xy 395.537182 -293.313104) (xy 395.544031 -293.305706)
			(xy 395.55177 -293.287108) (xy 395.552168 -293.277036) (xy 395.552168 -292.129464) (xy 395.551738 -292.119397)
			(xy 395.54401 -292.100805) (xy 395.537182 -292.093396) (xy 395.358874 -291.915088) (xy 395.35043 -291.907457)
			(xy 395.329033 -291.899794) (xy 395.30642 -291.90209) (xy 395.29639 -291.907468) (xy 395.276925 -291.918845)
			(xy 395.235567 -291.936794) (xy 395.19215 -291.948947) (xy 395.147483 -291.955076) (xy 395.12494 -291.955474)
			(xy 395.09877 -291.954978) (xy 395.047085 -291.946732) (xy 394.997346 -291.93044) (xy 394.950799 -291.906509)
			(xy 394.908606 -291.875538) (xy 394.871825 -291.838303) (xy 394.856208 -291.817298) (xy 394.848547 -291.807872)
			(xy 394.826935 -291.796861) (xy 394.814806 -291.796216) (xy 394.485114 -291.796216) (xy 394.472977 -291.796838)
			(xy 394.451353 -291.807848) (xy 394.443712 -291.817298) (xy 394.42808 -291.838289) (xy 394.391298 -291.875519)
			(xy 394.349107 -291.906486) (xy 394.302563 -291.930415) (xy 394.252829 -291.946708) (xy 394.201148 -291.954958)
			(xy 394.148812 -291.954958) (xy 394.097131 -291.946708) (xy 394.047397 -291.930415) (xy 394.000853 -291.906486)
			(xy 393.958662 -291.875519) (xy 393.92188 -291.838289) (xy 393.906248 -291.817298) (xy 393.898584 -291.807882)
			(xy 393.876971 -291.796896) (xy 393.864846 -291.796216) (xy 393.535154 -291.796216) (xy 393.523024 -291.796851)
			(xy 393.501421 -291.807875) (xy 393.493752 -291.817298) (xy 393.47812 -291.838289) (xy 393.441338 -291.875519)
			(xy 393.399147 -291.906486) (xy 393.352603 -291.930415) (xy 393.302869 -291.946708) (xy 393.251188 -291.954958)
			(xy 393.198852 -291.954958) (xy 393.147171 -291.946708) (xy 393.097437 -291.930415) (xy 393.050893 -291.906486)
			(xy 393.008702 -291.875519) (xy 392.97192 -291.838289) (xy 392.956288 -291.817298) (xy 392.948626 -291.807875)
			(xy 392.927014 -291.796872) (xy 392.914886 -291.796216) (xy 392.58494 -291.796216) (xy 392.5728 -291.796832)
			(xy 392.551166 -291.807836) (xy 392.543538 -291.817298) (xy 392.527906 -291.838289) (xy 392.491124 -291.875519)
			(xy 392.448933 -291.906486) (xy 392.402389 -291.930415) (xy 392.352655 -291.946708) (xy 392.300974 -291.954958)
			(xy 392.248638 -291.954958) (xy 392.196957 -291.946708) (xy 392.147223 -291.930415) (xy 392.100679 -291.906486)
			(xy 392.058488 -291.875519) (xy 392.021706 -291.838289) (xy 392.006074 -291.817298) (xy 391.998411 -291.807877)
			(xy 391.976798 -291.796881) (xy 391.964672 -291.796216) (xy 391.63498 -291.796216) (xy 391.622847 -291.796845)
			(xy 391.601235 -291.807863) (xy 391.593578 -291.817298) (xy 391.577946 -291.838289) (xy 391.541164 -291.875519)
			(xy 391.498973 -291.906486) (xy 391.452429 -291.930415) (xy 391.402695 -291.946708) (xy 391.351014 -291.954958)
			(xy 391.298678 -291.954958) (xy 391.246997 -291.946708) (xy 391.197263 -291.930415) (xy 391.150719 -291.906486)
			(xy 391.108528 -291.875519) (xy 391.071746 -291.838289) (xy 391.056114 -291.817298) (xy 391.048454 -291.807871)
			(xy 391.026841 -291.796857) (xy 391.014712 -291.796216) (xy 390.68502 -291.796216) (xy 390.672882 -291.796837)
			(xy 390.651256 -291.807845) (xy 390.643618 -291.817298) (xy 390.627986 -291.838289) (xy 390.591204 -291.875519)
			(xy 390.549013 -291.906486) (xy 390.502469 -291.930415) (xy 390.452735 -291.946708) (xy 390.401054 -291.954958)
			(xy 390.348718 -291.954958) (xy 390.297037 -291.946708) (xy 390.247303 -291.930415) (xy 390.200759 -291.906486)
			(xy 390.158568 -291.875519) (xy 390.121786 -291.838289) (xy 390.106154 -291.817298) (xy 390.09849 -291.807881)
			(xy 390.076877 -291.796892) (xy 390.064752 -291.796216) (xy 389.938006 -291.796216) (xy 389.927935 -291.795795)
			(xy 389.909327 -291.788083) (xy 389.901938 -291.78123) (xy 389.877808 -291.7571) (xy 389.868904 -291.749153)
			(xy 389.846253 -291.741732) (xy 389.834374 -291.742876) (xy 389.741918 -291.756592) (xy 389.722106 -291.770308)
			(xy 389.716518 -291.780976) (xy 389.704043 -291.803225) (xy 389.673314 -291.843935) (xy 389.636705 -291.879451)
			(xy 389.595082 -291.908933) (xy 389.54943 -291.931682) (xy 389.500829 -291.947161) (xy 389.450429 -291.955002)
			(xy 389.424926 -291.955474) (xy 389.398936 -291.954993) (xy 389.347597 -291.946865) (xy 389.298161 -291.930804)
			(xy 389.251846 -291.907207) (xy 389.209794 -291.876655) (xy 389.17304 -291.8399) (xy 389.142489 -291.797847)
			(xy 389.118893 -291.751532) (xy 389.102834 -291.702096) (xy 389.094707 -291.650756) (xy 389.094218 -291.624766)
			(xy 389.094685 -291.59926) (xy 389.102506 -291.548852) (xy 389.117973 -291.500243) (xy 389.140719 -291.454584)
			(xy 389.170205 -291.412958) (xy 389.205731 -291.376352) (xy 389.246456 -291.345634) (xy 389.268716 -291.333174)
			(xy 389.279384 -291.327586) (xy 389.2931 -291.307774) (xy 389.306816 -291.215318) (xy 389.307973 -291.203437)
			(xy 389.300548 -291.180784) (xy 389.292592 -291.171884) (xy 387.977888 -289.85718) (xy 387.968982 -289.849239)
			(xy 387.946333 -289.84183) (xy 387.934454 -289.842956) (xy 387.841998 -289.856672) (xy 387.822186 -289.870388)
			(xy 387.816598 -289.881056) (xy 387.804123 -289.903305) (xy 387.773395 -289.944016) (xy 387.736786 -289.979532)
			(xy 387.695163 -290.009013) (xy 387.64951 -290.031761) (xy 387.600909 -290.047237) (xy 387.550509 -290.055077)
			(xy 387.525006 -290.055554) (xy 387.499017 -290.055045) (xy 387.447679 -290.046915) (xy 387.398245 -290.030856)
			(xy 387.351931 -290.007261) (xy 387.309879 -289.976712) (xy 387.273122 -289.939961) (xy 387.242566 -289.897913)
			(xy 387.218964 -289.851603) (xy 387.202897 -289.802171) (xy 387.194759 -289.750835) (xy 387.194298 -289.724846)
			(xy 387.194766 -289.699341) (xy 387.202589 -289.648934) (xy 387.218058 -289.600326) (xy 387.240805 -289.554668)
			(xy 387.27029 -289.513044) (xy 387.305816 -289.476439) (xy 387.346541 -289.445721) (xy 387.368796 -289.433254)
			(xy 387.379464 -289.427666) (xy 387.39318 -289.407854) (xy 387.406896 -289.315398) (xy 387.408048 -289.303519)
			(xy 387.400615 -289.280874) (xy 387.392672 -289.271964) (xy 387.027928 -288.90722) (xy 387.019026 -288.899266)
			(xy 386.996373 -288.891834) (xy 386.984494 -288.892996) (xy 386.892038 -288.906712) (xy 386.872226 -288.920428)
			(xy 386.866638 -288.931096) (xy 386.854162 -288.953344) (xy 386.823433 -288.994055) (xy 386.786823 -289.029571)
			(xy 386.745201 -289.059053) (xy 386.699549 -289.081803) (xy 386.650948 -289.097284) (xy 386.600549 -289.105128)
			(xy 386.575046 -289.105594) (xy 386.549055 -289.105114) (xy 386.497711 -289.096989) (xy 386.448272 -289.08093)
			(xy 386.401953 -289.057335) (xy 386.359896 -289.026783) (xy 386.323138 -288.990028) (xy 386.292582 -288.947974)
			(xy 386.268982 -288.901658) (xy 386.252919 -288.85222) (xy 386.244788 -288.800877) (xy 386.244338 -288.774886)
			(xy 386.244803 -288.74938) (xy 386.252622 -288.698971) (xy 386.268087 -288.65036) (xy 386.290833 -288.604699)
			(xy 386.320319 -288.563072) (xy 386.355846 -288.526466) (xy 386.396572 -288.495748) (xy 386.418836 -288.483294)
			(xy 386.429504 -288.477706) (xy 386.44322 -288.457894) (xy 386.456936 -288.365438) (xy 386.458098 -288.353555)
			(xy 386.450681 -288.330894) (xy 386.442712 -288.322004) (xy 386.077714 -287.957006) (xy 386.068866 -287.949097)
			(xy 386.046351 -287.941684) (xy 386.034534 -287.942782) (xy 385.941824 -287.956498) (xy 385.922012 -287.970214)
			(xy 385.916424 -287.980882) (xy 385.903973 -288.003159) (xy 385.873277 -288.043927) (xy 385.836683 -288.079496)
			(xy 385.79506 -288.109021) (xy 385.749396 -288.131803) (xy 385.700773 -288.1473) (xy 385.650348 -288.155144)
			(xy 385.624832 -288.155634) (xy 385.59884 -288.155153) (xy 385.547496 -288.147026) (xy 385.498056 -288.130967)
			(xy 385.451736 -288.107371) (xy 385.409678 -288.07682) (xy 385.372917 -288.040066) (xy 385.342359 -287.998013)
			(xy 385.318755 -287.951698) (xy 385.302687 -287.90226) (xy 385.294551 -287.850918) (xy 385.294124 -287.824926)
			(xy 385.294596 -287.799409) (xy 385.302435 -287.748981) (xy 385.317931 -287.700356) (xy 385.340715 -287.65469)
			(xy 385.370247 -287.613069) (xy 385.405825 -287.57648) (xy 385.446603 -287.545794) (xy 385.468876 -287.533334)
			(xy 385.479544 -287.527746) (xy 385.49326 -287.507934) (xy 385.506976 -287.415224) (xy 385.508071 -287.40341)
			(xy 385.50064 -287.38091) (xy 385.492752 -287.372044) (xy 385.127754 -287.007046) (xy 385.118909 -286.999124)
			(xy 385.096391 -286.991688) (xy 385.084574 -286.992822) (xy 384.991864 -287.006538) (xy 384.972052 -287.020254)
			(xy 384.966464 -287.030922) (xy 384.954012 -287.053198) (xy 384.923315 -287.093966) (xy 384.886721 -287.129535)
			(xy 384.845098 -287.159062) (xy 384.799434 -287.181846) (xy 384.750813 -287.197346) (xy 384.700388 -287.205195)
			(xy 384.674872 -287.205674) (xy 384.648885 -287.205189) (xy 384.597552 -287.197054) (xy 384.548123 -287.180989)
			(xy 384.501817 -287.157389) (xy 384.459772 -287.126836) (xy 384.423024 -287.090081) (xy 384.392479 -287.048031)
			(xy 384.368888 -287.001719) (xy 384.352832 -286.952288) (xy 384.344706 -286.900953) (xy 384.344164 -286.874966)
			(xy 384.34518 -286.850074) (xy 384.345942 -286.839406) (xy 384.339084 -286.819594) (xy 384.280918 -286.75711)
			(xy 384.273449 -286.749769) (xy 384.254293 -286.741362) (xy 384.243834 -286.740854) (xy 382.715516 -286.740854)
			(xy 382.706526 -286.741194) (xy 382.689652 -286.747395) (xy 382.675979 -286.759068) (xy 382.67132 -286.766762)
			(xy 382.621028 -286.85617) (xy 382.621536 -286.883348) (xy 382.628648 -286.895286) (xy 382.641907 -286.917807)
			(xy 382.662809 -286.965706) (xy 382.676965 -287.016013) (xy 382.684109 -287.067783) (xy 382.684528 -287.093914)
			(xy 382.684042 -287.121165) (xy 382.676286 -287.175113) (xy 382.660931 -287.227408) (xy 382.638289 -287.276985)
			(xy 382.608823 -287.322835) (xy 382.573132 -287.364026) (xy 382.531941 -287.399717) (xy 382.486091 -287.429183)
			(xy 382.436514 -287.451825) (xy 382.384219 -287.46718) (xy 382.330271 -287.474936) (xy 382.275769 -287.474936)
			(xy 382.221821 -287.46718) (xy 382.169526 -287.451825) (xy 382.119949 -287.429183) (xy 382.074099 -287.399717)
			(xy 382.032908 -287.364026) (xy 381.997217 -287.322835) (xy 381.967751 -287.276985) (xy 381.945109 -287.227408)
			(xy 381.929754 -287.175113) (xy 381.921998 -287.121165) (xy 381.921512 -287.093914) (xy 381.921965 -287.067787)
			(xy 381.929136 -287.016027) (xy 381.943292 -286.965727) (xy 381.964169 -286.917825) (xy 381.977392 -286.895286)
			(xy 381.984504 -286.883348) (xy 381.985012 -286.85617) (xy 381.93472 -286.766762) (xy 381.929998 -286.759121)
			(xy 381.91633 -286.747484) (xy 381.899498 -286.741247) (xy 381.890524 -286.740854) (xy 379.775974 -286.740854)
			(xy 379.691138 -286.82569) (xy 379.691138 -287.850913) (xy 384.344674 -287.850913) (xy 384.344674 -287.798939)
			(xy 384.352804 -287.747604) (xy 384.368865 -287.698174) (xy 384.392461 -287.651864) (xy 384.423011 -287.609816)
			(xy 384.459762 -287.573065) (xy 384.50181 -287.542515) (xy 384.54812 -287.518919) (xy 384.59755 -287.502858)
			(xy 384.648885 -287.494728) (xy 384.700859 -287.494728) (xy 384.752194 -287.502858) (xy 384.801624 -287.518919)
			(xy 384.847934 -287.542515) (xy 384.889982 -287.573065) (xy 384.926733 -287.609816) (xy 384.957283 -287.651864)
			(xy 384.980879 -287.698174) (xy 384.99694 -287.747604) (xy 385.00507 -287.798939) (xy 385.00558 -287.824926)
			(xy 385.00507 -287.850913) (xy 384.99694 -287.902248) (xy 384.980879 -287.951678) (xy 384.957283 -287.997988)
			(xy 384.926733 -288.040036) (xy 384.889982 -288.076787) (xy 384.847934 -288.107337) (xy 384.801624 -288.130933)
			(xy 384.752194 -288.146994) (xy 384.700859 -288.155124) (xy 384.648885 -288.155124) (xy 384.59755 -288.146994)
			(xy 384.54812 -288.130933) (xy 384.50181 -288.107337) (xy 384.459762 -288.076787) (xy 384.423011 -288.040036)
			(xy 384.392461 -287.997988) (xy 384.368865 -287.951678) (xy 384.352804 -287.902248) (xy 384.344674 -287.850913)
			(xy 379.691138 -287.850913) (xy 379.691138 -288.473642) (xy 379.691138 -288.7853) (xy 379.706711 -288.800873)
			(xy 384.344674 -288.800873) (xy 384.344674 -288.748899) (xy 384.352804 -288.697564) (xy 384.368865 -288.648134)
			(xy 384.392461 -288.601824) (xy 384.423011 -288.559776) (xy 384.459762 -288.523025) (xy 384.50181 -288.492475)
			(xy 384.54812 -288.468879) (xy 384.59755 -288.452818) (xy 384.648885 -288.444688) (xy 384.700859 -288.444688)
			(xy 384.752194 -288.452818) (xy 384.801624 -288.468879) (xy 384.847934 -288.492475) (xy 384.889982 -288.523025)
			(xy 384.926733 -288.559776) (xy 384.957283 -288.601824) (xy 384.980879 -288.648134) (xy 384.99694 -288.697564)
			(xy 385.00507 -288.748899) (xy 385.00558 -288.774886) (xy 385.00507 -288.800873) (xy 385.294634 -288.800873)
			(xy 385.294634 -288.748899) (xy 385.302764 -288.697564) (xy 385.318825 -288.648134) (xy 385.342421 -288.601824)
			(xy 385.372971 -288.559776) (xy 385.409722 -288.523025) (xy 385.45177 -288.492475) (xy 385.49808 -288.468879)
			(xy 385.54751 -288.452818) (xy 385.598845 -288.444688) (xy 385.650819 -288.444688) (xy 385.702154 -288.452818)
			(xy 385.751584 -288.468879) (xy 385.797894 -288.492475) (xy 385.839942 -288.523025) (xy 385.876693 -288.559776)
			(xy 385.907243 -288.601824) (xy 385.930839 -288.648134) (xy 385.9469 -288.697564) (xy 385.95503 -288.748899)
			(xy 385.95554 -288.774886) (xy 385.95503 -288.800873) (xy 385.9469 -288.852208) (xy 385.930839 -288.901638)
			(xy 385.907243 -288.947948) (xy 385.876693 -288.989996) (xy 385.839942 -289.026747) (xy 385.797894 -289.057297)
			(xy 385.751584 -289.080893) (xy 385.702154 -289.096954) (xy 385.650819 -289.105084) (xy 385.598845 -289.105084)
			(xy 385.54751 -289.096954) (xy 385.49808 -289.080893) (xy 385.45177 -289.057297) (xy 385.409722 -289.026747)
			(xy 385.372971 -288.989996) (xy 385.342421 -288.947948) (xy 385.318825 -288.901638) (xy 385.302764 -288.852208)
			(xy 385.294634 -288.800873) (xy 385.00507 -288.800873) (xy 384.99694 -288.852208) (xy 384.980879 -288.901638)
			(xy 384.957283 -288.947948) (xy 384.926733 -288.989996) (xy 384.889982 -289.026747) (xy 384.847934 -289.057297)
			(xy 384.801624 -289.080893) (xy 384.752194 -289.096954) (xy 384.700859 -289.105084) (xy 384.648885 -289.105084)
			(xy 384.59755 -289.096954) (xy 384.54812 -289.080893) (xy 384.50181 -289.057297) (xy 384.459762 -289.026747)
			(xy 384.423011 -288.989996) (xy 384.392461 -288.947948) (xy 384.368865 -288.901638) (xy 384.352804 -288.852208)
			(xy 384.344674 -288.800873) (xy 379.706711 -288.800873) (xy 379.8951 -288.989262) (xy 384.04673 -288.989262)
			(xy 384.485642 -289.428174) (xy 384.517138 -289.433762) (xy 384.532124 -289.42665) (xy 384.554516 -289.416414)
			(xy 384.601573 -289.401944) (xy 384.650256 -289.394611) (xy 384.674872 -289.394138) (xy 384.700861 -289.394619)
			(xy 384.752201 -289.402747) (xy 384.801636 -289.418807) (xy 384.84795 -289.442404) (xy 384.890001 -289.472957)
			(xy 384.926755 -289.509712) (xy 384.957305 -289.551766) (xy 384.980899 -289.598081) (xy 384.996957 -289.647517)
			(xy 385.005082 -289.698857) (xy 385.00558 -289.724846) (xy 385.00511 -289.749462) (xy 385.004903 -289.750833)
			(xy 385.294634 -289.750833) (xy 385.294634 -289.698859) (xy 385.302764 -289.647524) (xy 385.318825 -289.598094)
			(xy 385.342421 -289.551784) (xy 385.372971 -289.509736) (xy 385.409722 -289.472985) (xy 385.45177 -289.442435)
			(xy 385.49808 -289.418839) (xy 385.54751 -289.402778) (xy 385.598845 -289.394648) (xy 385.650819 -289.394648)
			(xy 385.702154 -289.402778) (xy 385.751584 -289.418839) (xy 385.797894 -289.442435) (xy 385.839942 -289.472985)
			(xy 385.876693 -289.509736) (xy 385.907243 -289.551784) (xy 385.930839 -289.598094) (xy 385.9469 -289.647524)
			(xy 385.95503 -289.698859) (xy 385.95554 -289.724846) (xy 385.95503 -289.750833) (xy 386.244848 -289.750833)
			(xy 386.244848 -289.698859) (xy 386.252978 -289.647524) (xy 386.269039 -289.598094) (xy 386.292635 -289.551784)
			(xy 386.323185 -289.509736) (xy 386.359936 -289.472985) (xy 386.401984 -289.442435) (xy 386.448294 -289.418839)
			(xy 386.497724 -289.402778) (xy 386.549059 -289.394648) (xy 386.601033 -289.394648) (xy 386.652368 -289.402778)
			(xy 386.701798 -289.418839) (xy 386.748108 -289.442435) (xy 386.790156 -289.472985) (xy 386.826907 -289.509736)
			(xy 386.857457 -289.551784) (xy 386.881053 -289.598094) (xy 386.897114 -289.647524) (xy 386.905244 -289.698859)
			(xy 386.905754 -289.724846) (xy 386.905244 -289.750833) (xy 386.897114 -289.802168) (xy 386.881053 -289.851598)
			(xy 386.857457 -289.897908) (xy 386.826907 -289.939956) (xy 386.790156 -289.976707) (xy 386.748108 -290.007257)
			(xy 386.701798 -290.030853) (xy 386.652368 -290.046914) (xy 386.601033 -290.055044) (xy 386.549059 -290.055044)
			(xy 386.497724 -290.046914) (xy 386.448294 -290.030853) (xy 386.401984 -290.007257) (xy 386.359936 -289.976707)
			(xy 386.323185 -289.939956) (xy 386.292635 -289.897908) (xy 386.269039 -289.851598) (xy 386.252978 -289.802168)
			(xy 386.244848 -289.750833) (xy 385.95503 -289.750833) (xy 385.9469 -289.802168) (xy 385.930839 -289.851598)
			(xy 385.907243 -289.897908) (xy 385.876693 -289.939956) (xy 385.839942 -289.976707) (xy 385.797894 -290.007257)
			(xy 385.751584 -290.030853) (xy 385.702154 -290.046914) (xy 385.650819 -290.055044) (xy 385.598845 -290.055044)
			(xy 385.54751 -290.046914) (xy 385.49808 -290.030853) (xy 385.45177 -290.007257) (xy 385.409722 -289.976707)
			(xy 385.372971 -289.939956) (xy 385.342421 -289.897908) (xy 385.318825 -289.851598) (xy 385.302764 -289.802168)
			(xy 385.294634 -289.750833) (xy 385.004903 -289.750833) (xy 384.997776 -289.798145) (xy 384.983308 -289.845204)
			(xy 384.973068 -289.867594) (xy 384.965956 -289.88258) (xy 384.971544 -289.914076) (xy 385.435602 -290.378134)
			(xy 385.467098 -290.383722) (xy 385.482084 -290.37661) (xy 385.504475 -290.36637) (xy 385.551532 -290.351891)
			(xy 385.600215 -290.344551) (xy 385.624832 -290.344098) (xy 385.650817 -290.34461) (xy 385.702148 -290.352745)
			(xy 385.751574 -290.368808) (xy 385.797878 -290.392406) (xy 385.839921 -290.422956) (xy 385.876668 -290.459708)
			(xy 385.907214 -290.501754) (xy 385.930806 -290.548062) (xy 385.946864 -290.597489) (xy 385.954993 -290.648821)
			(xy 385.95554 -290.674806) (xy 385.955065 -290.699421) (xy 385.954858 -290.700793) (xy 386.244848 -290.700793)
			(xy 386.244848 -290.648819) (xy 386.252978 -290.597484) (xy 386.269039 -290.548054) (xy 386.292635 -290.501744)
			(xy 386.323185 -290.459696) (xy 386.359936 -290.422945) (xy 386.401984 -290.392395) (xy 386.448294 -290.368799)
			(xy 386.497724 -290.352738) (xy 386.549059 -290.344608) (xy 386.601033 -290.344608) (xy 386.652368 -290.352738)
			(xy 386.701798 -290.368799) (xy 386.748108 -290.392395) (xy 386.790156 -290.422945) (xy 386.826907 -290.459696)
			(xy 386.857457 -290.501744) (xy 386.881053 -290.548054) (xy 386.897114 -290.597484) (xy 386.905244 -290.648819)
			(xy 386.905754 -290.674806) (xy 386.905244 -290.700793) (xy 386.897114 -290.752128) (xy 386.881053 -290.801558)
			(xy 386.857457 -290.847868) (xy 386.826907 -290.889916) (xy 386.790156 -290.926667) (xy 386.748108 -290.957217)
			(xy 386.701798 -290.980813) (xy 386.652368 -290.996874) (xy 386.601033 -291.005004) (xy 386.549059 -291.005004)
			(xy 386.497724 -290.996874) (xy 386.448294 -290.980813) (xy 386.401984 -290.957217) (xy 386.359936 -290.926667)
			(xy 386.323185 -290.889916) (xy 386.292635 -290.847868) (xy 386.269039 -290.801558) (xy 386.252978 -290.752128)
			(xy 386.244848 -290.700793) (xy 385.954858 -290.700793) (xy 385.947722 -290.748101) (xy 385.933245 -290.795154)
			(xy 385.923028 -290.817554) (xy 385.915916 -290.83254) (xy 385.921504 -290.864036) (xy 386.385562 -291.328094)
			(xy 386.417566 -291.333682) (xy 386.432044 -291.32657) (xy 386.454475 -291.31632) (xy 386.501618 -291.301838)
			(xy 386.550388 -291.29452) (xy 386.575046 -291.294058) (xy 386.601032 -291.294571) (xy 386.652363 -291.302707)
			(xy 386.701789 -291.318772) (xy 386.748095 -291.342369) (xy 386.79014 -291.372919) (xy 386.826888 -291.40967)
			(xy 386.857437 -291.451715) (xy 386.881033 -291.498022) (xy 386.897096 -291.547449) (xy 386.90523 -291.59878)
			(xy 386.905754 -291.624766) (xy 386.905301 -291.649425) (xy 386.897983 -291.698197) (xy 386.883504 -291.745342)
			(xy 386.873242 -291.767768) (xy 386.86613 -291.782246) (xy 386.871718 -291.81425) (xy 387.335522 -292.278054)
			(xy 387.367526 -292.283642) (xy 387.382004 -292.27653) (xy 387.404434 -292.266275) (xy 387.451576 -292.251786)
			(xy 387.500347 -292.24446) (xy 387.525006 -292.244018) (xy 387.550994 -292.244502) (xy 387.602331 -292.252634)
			(xy 387.651763 -292.268697) (xy 387.698073 -292.292295) (xy 387.740122 -292.322848) (xy 387.776873 -292.359603)
			(xy 387.807421 -292.401654) (xy 387.831015 -292.447967) (xy 387.847074 -292.497401) (xy 387.855201 -292.548738)
			(xy 387.855714 -292.574726) (xy 387.855257 -292.599384) (xy 387.855057 -292.600713) (xy 388.144768 -292.600713)
			(xy 388.144768 -292.548739) (xy 388.152898 -292.497404) (xy 388.168959 -292.447974) (xy 388.192555 -292.401664)
			(xy 388.223105 -292.359616) (xy 388.259856 -292.322865) (xy 388.301904 -292.292315) (xy 388.348214 -292.268719)
			(xy 388.397644 -292.252658) (xy 388.448979 -292.244528) (xy 388.500953 -292.244528) (xy 388.552288 -292.252658)
			(xy 388.601718 -292.268719) (xy 388.648028 -292.292315) (xy 388.690076 -292.322865) (xy 388.726827 -292.359616)
			(xy 388.757377 -292.401664) (xy 388.780973 -292.447974) (xy 388.797034 -292.497404) (xy 388.805164 -292.548739)
			(xy 388.805674 -292.574726) (xy 388.805164 -292.600713) (xy 388.805124 -292.600967) (xy 389.094728 -292.600967)
			(xy 389.094728 -292.548993) (xy 389.102858 -292.497658) (xy 389.118919 -292.448228) (xy 389.142515 -292.401918)
			(xy 389.173065 -292.35987) (xy 389.209816 -292.323119) (xy 389.251864 -292.292569) (xy 389.298174 -292.268973)
			(xy 389.347604 -292.252912) (xy 389.398939 -292.244782) (xy 389.450913 -292.244782) (xy 389.502248 -292.252912)
			(xy 389.551678 -292.268973) (xy 389.597988 -292.292569) (xy 389.640036 -292.323119) (xy 389.676787 -292.35987)
			(xy 389.707337 -292.401918) (xy 389.730933 -292.448228) (xy 389.746994 -292.497658) (xy 389.755124 -292.548993)
			(xy 389.755634 -292.57498) (xy 389.992868 -292.57498) (xy 389.996939 -292.519358) (xy 390.009065 -292.464921)
			(xy 390.028988 -292.41283) (xy 390.056284 -292.364195) (xy 390.09037 -292.320052) (xy 390.130519 -292.281343)
			(xy 390.175877 -292.248892) (xy 390.225477 -292.223391) (xy 390.278261 -292.205384) (xy 390.333104 -292.195254)
			(xy 390.388838 -292.193217) (xy 390.444275 -292.199317) (xy 390.498232 -292.213423) (xy 390.549561 -292.235235)
			(xy 390.597167 -292.264289) (xy 390.640035 -292.299964) (xy 390.677252 -292.341501) (xy 390.708025 -292.388014)
			(xy 390.731697 -292.438511) (xy 390.747765 -292.491918) (xy 390.755885 -292.547094) (xy 390.756394 -292.57498)
			(xy 390.75592 -292.600967) (xy 390.994648 -292.600967) (xy 390.994648 -292.548993) (xy 391.002778 -292.497658)
			(xy 391.018839 -292.448228) (xy 391.042435 -292.401918) (xy 391.072985 -292.35987) (xy 391.109736 -292.323119)
			(xy 391.151784 -292.292569) (xy 391.198094 -292.268973) (xy 391.247524 -292.252912) (xy 391.298859 -292.244782)
			(xy 391.350833 -292.244782) (xy 391.402168 -292.252912) (xy 391.451598 -292.268973) (xy 391.497908 -292.292569)
			(xy 391.539956 -292.323119) (xy 391.576707 -292.35987) (xy 391.607257 -292.401918) (xy 391.630853 -292.448228)
			(xy 391.646914 -292.497658) (xy 391.655044 -292.548993) (xy 391.655554 -292.57498) (xy 391.655044 -292.600967)
			(xy 391.944608 -292.600967) (xy 391.944608 -292.548993) (xy 391.952738 -292.497658) (xy 391.968799 -292.448228)
			(xy 391.992395 -292.401918) (xy 392.022945 -292.35987) (xy 392.059696 -292.323119) (xy 392.101744 -292.292569)
			(xy 392.148054 -292.268973) (xy 392.197484 -292.252912) (xy 392.248819 -292.244782) (xy 392.300793 -292.244782)
			(xy 392.352128 -292.252912) (xy 392.401558 -292.268973) (xy 392.447868 -292.292569) (xy 392.489916 -292.323119)
			(xy 392.526667 -292.35987) (xy 392.557217 -292.401918) (xy 392.580813 -292.448228) (xy 392.596874 -292.497658)
			(xy 392.605004 -292.548993) (xy 392.605514 -292.57498) (xy 392.605004 -292.600967) (xy 392.894822 -292.600967)
			(xy 392.894822 -292.548993) (xy 392.902952 -292.497658) (xy 392.919013 -292.448228) (xy 392.942609 -292.401918)
			(xy 392.973159 -292.35987) (xy 393.00991 -292.323119) (xy 393.051958 -292.292569) (xy 393.098268 -292.268973)
			(xy 393.147698 -292.252912) (xy 393.199033 -292.244782) (xy 393.251007 -292.244782) (xy 393.302342 -292.252912)
			(xy 393.351772 -292.268973) (xy 393.398082 -292.292569) (xy 393.44013 -292.323119) (xy 393.476881 -292.35987)
			(xy 393.507431 -292.401918) (xy 393.531027 -292.448228) (xy 393.547088 -292.497658) (xy 393.555218 -292.548993)
			(xy 393.555728 -292.57498) (xy 393.555218 -292.600967) (xy 393.844782 -292.600967) (xy 393.844782 -292.548993)
			(xy 393.852912 -292.497658) (xy 393.868973 -292.448228) (xy 393.892569 -292.401918) (xy 393.923119 -292.35987)
			(xy 393.95987 -292.323119) (xy 394.001918 -292.292569) (xy 394.048228 -292.268973) (xy 394.097658 -292.252912)
			(xy 394.148993 -292.244782) (xy 394.200967 -292.244782) (xy 394.252302 -292.252912) (xy 394.301732 -292.268973)
			(xy 394.348042 -292.292569) (xy 394.39009 -292.323119) (xy 394.426841 -292.35987) (xy 394.457391 -292.401918)
			(xy 394.480987 -292.448228) (xy 394.497048 -292.497658) (xy 394.505178 -292.548993) (xy 394.505688 -292.57498)
			(xy 394.505178 -292.600967) (xy 394.497048 -292.652302) (xy 394.480987 -292.701732) (xy 394.457391 -292.748042)
			(xy 394.426841 -292.79009) (xy 394.39009 -292.826841) (xy 394.348042 -292.857391) (xy 394.301732 -292.880987)
			(xy 394.252302 -292.897048) (xy 394.200967 -292.905178) (xy 394.148993 -292.905178) (xy 394.097658 -292.897048)
			(xy 394.048228 -292.880987) (xy 394.001918 -292.857391) (xy 393.95987 -292.826841) (xy 393.923119 -292.79009)
			(xy 393.892569 -292.748042) (xy 393.868973 -292.701732) (xy 393.852912 -292.652302) (xy 393.844782 -292.600967)
			(xy 393.555218 -292.600967) (xy 393.547088 -292.652302) (xy 393.531027 -292.701732) (xy 393.507431 -292.748042)
			(xy 393.476881 -292.79009) (xy 393.44013 -292.826841) (xy 393.398082 -292.857391) (xy 393.351772 -292.880987)
			(xy 393.302342 -292.897048) (xy 393.251007 -292.905178) (xy 393.199033 -292.905178) (xy 393.147698 -292.897048)
			(xy 393.098268 -292.880987) (xy 393.051958 -292.857391) (xy 393.00991 -292.826841) (xy 392.973159 -292.79009)
			(xy 392.942609 -292.748042) (xy 392.919013 -292.701732) (xy 392.902952 -292.652302) (xy 392.894822 -292.600967)
			(xy 392.605004 -292.600967) (xy 392.596874 -292.652302) (xy 392.580813 -292.701732) (xy 392.557217 -292.748042)
			(xy 392.526667 -292.79009) (xy 392.489916 -292.826841) (xy 392.447868 -292.857391) (xy 392.401558 -292.880987)
			(xy 392.352128 -292.897048) (xy 392.300793 -292.905178) (xy 392.248819 -292.905178) (xy 392.197484 -292.897048)
			(xy 392.148054 -292.880987) (xy 392.101744 -292.857391) (xy 392.059696 -292.826841) (xy 392.022945 -292.79009)
			(xy 391.992395 -292.748042) (xy 391.968799 -292.701732) (xy 391.952738 -292.652302) (xy 391.944608 -292.600967)
			(xy 391.655044 -292.600967) (xy 391.646914 -292.652302) (xy 391.630853 -292.701732) (xy 391.607257 -292.748042)
			(xy 391.576707 -292.79009) (xy 391.539956 -292.826841) (xy 391.497908 -292.857391) (xy 391.451598 -292.880987)
			(xy 391.402168 -292.897048) (xy 391.350833 -292.905178) (xy 391.298859 -292.905178) (xy 391.247524 -292.897048)
			(xy 391.198094 -292.880987) (xy 391.151784 -292.857391) (xy 391.109736 -292.826841) (xy 391.072985 -292.79009)
			(xy 391.042435 -292.748042) (xy 391.018839 -292.701732) (xy 391.002778 -292.652302) (xy 390.994648 -292.600967)
			(xy 390.75592 -292.600967) (xy 390.755885 -292.602866) (xy 390.747765 -292.658042) (xy 390.731697 -292.711449)
			(xy 390.708025 -292.761946) (xy 390.677252 -292.808459) (xy 390.640035 -292.849996) (xy 390.597167 -292.885671)
			(xy 390.549561 -292.914725) (xy 390.498232 -292.936537) (xy 390.444275 -292.950643) (xy 390.388838 -292.956743)
			(xy 390.333104 -292.954706) (xy 390.278261 -292.944576) (xy 390.225477 -292.926569) (xy 390.175877 -292.901068)
			(xy 390.130519 -292.868617) (xy 390.09037 -292.829908) (xy 390.056284 -292.785765) (xy 390.028988 -292.73713)
			(xy 390.009065 -292.685039) (xy 389.996939 -292.630602) (xy 389.992868 -292.57498) (xy 389.755634 -292.57498)
			(xy 389.755124 -292.600967) (xy 389.746994 -292.652302) (xy 389.730933 -292.701732) (xy 389.707337 -292.748042)
			(xy 389.676787 -292.79009) (xy 389.640036 -292.826841) (xy 389.597988 -292.857391) (xy 389.551678 -292.880987)
			(xy 389.502248 -292.897048) (xy 389.450913 -292.905178) (xy 389.398939 -292.905178) (xy 389.347604 -292.897048)
			(xy 389.298174 -292.880987) (xy 389.251864 -292.857391) (xy 389.209816 -292.826841) (xy 389.173065 -292.79009)
			(xy 389.142515 -292.748042) (xy 389.118919 -292.701732) (xy 389.102858 -292.652302) (xy 389.094728 -292.600967)
			(xy 388.805124 -292.600967) (xy 388.797034 -292.652048) (xy 388.780973 -292.701478) (xy 388.757377 -292.747788)
			(xy 388.726827 -292.789836) (xy 388.690076 -292.826587) (xy 388.648028 -292.857137) (xy 388.601718 -292.880733)
			(xy 388.552288 -292.896794) (xy 388.500953 -292.904924) (xy 388.448979 -292.904924) (xy 388.397644 -292.896794)
			(xy 388.348214 -292.880733) (xy 388.301904 -292.857137) (xy 388.259856 -292.826587) (xy 388.223105 -292.789836)
			(xy 388.192555 -292.747788) (xy 388.168959 -292.701478) (xy 388.152898 -292.652048) (xy 388.144768 -292.600713)
			(xy 387.855057 -292.600713) (xy 387.847932 -292.648153) (xy 387.833448 -292.695295) (xy 387.823202 -292.717728)
			(xy 387.81609 -292.732206) (xy 387.821678 -292.76421) (xy 388.285736 -293.228268) (xy 388.317232 -293.233856)
			(xy 388.332218 -293.226744) (xy 388.35461 -293.216508) (xy 388.401667 -293.202037) (xy 388.45035 -293.194703)
			(xy 388.474966 -293.194232) (xy 388.500723 -293.194728) (xy 388.551614 -293.202725) (xy 388.600649 -293.218515)
			(xy 388.646643 -293.241715) (xy 388.688485 -293.271766) (xy 388.725162 -293.30794) (xy 388.755787 -293.349363)
			(xy 388.779621 -293.395033) (xy 388.796085 -293.443846) (xy 388.804784 -293.494621) (xy 388.805674 -293.520368)
			(xy 388.805928 -293.54145) (xy 388.835646 -293.57066) (xy 389.064246 -293.57066)
		)
		(stroke
			(width 0)
			(type solid)
		)
		(fill yes)
		(layer "In5.Cu")
		(net "PCEPLL6_VDDA18_PEX3")
	)
	(gr_poly
		(pts
			(xy 453.584564 -417.22675) (xy 453.594628 -417.226314) (xy 453.613211 -417.218577) (xy 453.620632 -417.211764)
			(xy 455.389742 -415.442654) (xy 455.396587 -415.435256) (xy 455.404314 -415.416657) (xy 455.404728 -415.406586)
			(xy 455.404728 -391.531348) (xy 455.397108 -391.512806) (xy 455.395838 -391.511536) (xy 455.395838 -387.414262)
			(xy 455.395534 -387.405229) (xy 455.389358 -387.388258) (xy 455.377652 -387.374505) (xy 455.36993 -387.369812)
			(xy 455.313368 -387.337367) (xy 455.203955 -387.266404) (xy 455.099166 -387.188775) (xy 454.999406 -387.104782)
			(xy 454.905061 -387.014749) (xy 454.816496 -386.919025) (xy 454.734053 -386.81798) (xy 454.658051 -386.712005)
			(xy 454.588785 -386.60151) (xy 454.526523 -386.486923) (xy 454.471505 -386.368686) (xy 454.423944 -386.247258)
			(xy 454.384024 -386.123107) (xy 454.3519 -385.996715) (xy 454.327696 -385.868571) (xy 454.311506 -385.739169)
			(xy 454.303392 -385.609011) (xy 454.302876 -385.543806) (xy 454.303403 -385.477578) (xy 454.311785 -385.345387)
			(xy 454.328496 -385.21399) (xy 454.35347 -385.083909) (xy 454.386606 -384.955665) (xy 454.427774 -384.829769)
			(xy 454.476808 -384.706724) (xy 454.533514 -384.587019) (xy 454.597664 -384.471134) (xy 454.669002 -384.359531)
			(xy 454.747245 -384.252654) (xy 454.83208 -384.15093) (xy 454.923168 -384.054766) (xy 455.020145 -383.964544)
			(xy 455.122626 -383.880626) (xy 455.2302 -383.803345) (xy 455.34244 -383.73301) (xy 455.458896 -383.669902)
			(xy 455.518774 -383.6416) (xy 455.522755 -383.639618) (xy 455.530032 -383.634507) (xy 455.533252 -383.63144)
			(xy 462.968848 -376.195844) (xy 462.975691 -376.188445) (xy 462.983414 -376.169846) (xy 462.983834 -376.159776)
			(xy 462.983834 -328.302874) (xy 462.983404 -328.292807) (xy 462.975676 -328.274216) (xy 462.968848 -328.266806)
			(xy 462.324196 -327.622154) (xy 462.3168 -327.615302) (xy 462.298201 -327.607561) (xy 462.288128 -327.607168)
			(xy 455.735436 -327.607168) (xy 455.725384 -327.607671) (xy 455.706819 -327.615387) (xy 455.699368 -327.622154)
			(xy 454.824338 -328.497184) (xy 454.817501 -328.504585) (xy 454.809791 -328.523184) (xy 454.809352 -328.533252)
			(xy 454.809352 -360.94162) (xy 454.808924 -360.951688) (xy 454.801199 -360.970282) (xy 454.794366 -360.977688)
			(xy 451.885558 -363.886496) (xy 459.91729 -363.886496) (xy 459.921361 -363.830874) (xy 459.933487 -363.776437)
			(xy 459.95341 -363.724346) (xy 459.980706 -363.675711) (xy 460.014792 -363.631568) (xy 460.054941 -363.592859)
			(xy 460.100299 -363.560408) (xy 460.149899 -363.534907) (xy 460.202683 -363.5169) (xy 460.257526 -363.50677)
			(xy 460.31326 -363.504733) (xy 460.368697 -363.510833) (xy 460.422654 -363.524939) (xy 460.473983 -363.546751)
			(xy 460.521589 -363.575805) (xy 460.564457 -363.61148) (xy 460.601674 -363.653017) (xy 460.632447 -363.69953)
			(xy 460.656119 -363.750027) (xy 460.672187 -363.803434) (xy 460.680307 -363.85861) (xy 460.680816 -363.886496)
			(xy 460.680307 -363.914382) (xy 460.672187 -363.969558) (xy 460.656119 -364.022965) (xy 460.632447 -364.073462)
			(xy 460.601674 -364.119975) (xy 460.564457 -364.161512) (xy 460.521589 -364.197187) (xy 460.473983 -364.226241)
			(xy 460.422654 -364.248053) (xy 460.368697 -364.262159) (xy 460.31326 -364.268259) (xy 460.257526 -364.266222)
			(xy 460.202683 -364.256092) (xy 460.149899 -364.238085) (xy 460.100299 -364.212584) (xy 460.054941 -364.180133)
			(xy 460.014792 -364.141424) (xy 459.980706 -364.097281) (xy 459.95341 -364.048646) (xy 459.933487 -363.996555)
			(xy 459.921361 -363.942118) (xy 459.91729 -363.886496) (xy 451.885558 -363.886496) (xy 450.945758 -364.826296)
			(xy 450.938949 -364.833776) (xy 450.931359 -364.852508) (xy 450.931026 -364.862618) (xy 450.931534 -364.945422)
			(xy 450.939662 -364.963964) (xy 450.947028 -364.971076) (xy 450.965132 -364.989111) (xy 450.996842 -365.029183)
			(xy 451.022915 -365.073132) (xy 451.042885 -365.12017) (xy 451.04769 -365.1377) (xy 452.545194 -365.1377)
			(xy 452.549265 -365.082078) (xy 452.561391 -365.027641) (xy 452.581314 -364.97555) (xy 452.60861 -364.926915)
			(xy 452.642696 -364.882772) (xy 452.682845 -364.844063) (xy 452.728203 -364.811612) (xy 452.777803 -364.786111)
			(xy 452.830587 -364.768104) (xy 452.88543 -364.757974) (xy 452.941164 -364.755937) (xy 452.996601 -364.762037)
			(xy 453.050558 -364.776143) (xy 453.101887 -364.797955) (xy 453.149493 -364.827009) (xy 453.192361 -364.862684)
			(xy 453.229578 -364.904221) (xy 453.260351 -364.950734) (xy 453.284023 -365.001231) (xy 453.300091 -365.054638)
			(xy 453.308211 -365.109814) (xy 453.30872 -365.1377) (xy 453.308211 -365.165586) (xy 453.304278 -365.19231)
			(xy 453.705212 -365.19231) (xy 453.709283 -365.136688) (xy 453.721409 -365.082251) (xy 453.741332 -365.03016)
			(xy 453.768628 -364.981525) (xy 453.802714 -364.937382) (xy 453.842863 -364.898673) (xy 453.888221 -364.866222)
			(xy 453.937821 -364.840721) (xy 453.990605 -364.822714) (xy 454.045448 -364.812584) (xy 454.101182 -364.810547)
			(xy 454.156619 -364.816647) (xy 454.210576 -364.830753) (xy 454.21264 -364.83163) (xy 458.695804 -364.83163)
			(xy 458.699875 -364.776008) (xy 458.712001 -364.721571) (xy 458.731924 -364.66948) (xy 458.75922 -364.620845)
			(xy 458.793306 -364.576702) (xy 458.833455 -364.537993) (xy 458.878813 -364.505542) (xy 458.928413 -364.480041)
			(xy 458.981197 -364.462034) (xy 459.03604 -364.451904) (xy 459.091774 -364.449867) (xy 459.147211 -364.455967)
			(xy 459.201168 -364.470073) (xy 459.252497 -364.491885) (xy 459.300103 -364.520939) (xy 459.342971 -364.556614)
			(xy 459.380188 -364.598151) (xy 459.410961 -364.644664) (xy 459.434633 -364.695161) (xy 459.450701 -364.748568)
			(xy 459.458821 -364.803744) (xy 459.45933 -364.83163) (xy 459.458821 -364.859516) (xy 459.450701 -364.914692)
			(xy 459.434633 -364.968099) (xy 459.410961 -365.018596) (xy 459.380188 -365.065109) (xy 459.342971 -365.106646)
			(xy 459.300103 -365.142321) (xy 459.252497 -365.171375) (xy 459.201168 -365.193187) (xy 459.147211 -365.207293)
			(xy 459.091774 -365.213393) (xy 459.03604 -365.211356) (xy 458.981197 -365.201226) (xy 458.928413 -365.183219)
			(xy 458.878813 -365.157718) (xy 458.833455 -365.125267) (xy 458.793306 -365.086558) (xy 458.75922 -365.042415)
			(xy 458.731924 -364.99378) (xy 458.712001 -364.941689) (xy 458.699875 -364.887252) (xy 458.695804 -364.83163)
			(xy 454.21264 -364.83163) (xy 454.261905 -364.852565) (xy 454.309511 -364.881619) (xy 454.352379 -364.917294)
			(xy 454.389596 -364.958831) (xy 454.420369 -365.005344) (xy 454.444041 -365.055841) (xy 454.460109 -365.109248)
			(xy 454.468229 -365.164424) (xy 454.468738 -365.19231) (xy 454.468229 -365.220196) (xy 454.460109 -365.275372)
			(xy 454.444041 -365.328779) (xy 454.420369 -365.379276) (xy 454.389596 -365.425789) (xy 454.352379 -365.467326)
			(xy 454.309511 -365.503001) (xy 454.261905 -365.532055) (xy 454.210576 -365.553867) (xy 454.156619 -365.567973)
			(xy 454.101182 -365.574073) (xy 454.045448 -365.572036) (xy 453.990605 -365.561906) (xy 453.937821 -365.543899)
			(xy 453.888221 -365.518398) (xy 453.842863 -365.485947) (xy 453.802714 -365.447238) (xy 453.768628 -365.403095)
			(xy 453.741332 -365.35446) (xy 453.721409 -365.302369) (xy 453.709283 -365.247932) (xy 453.705212 -365.19231)
			(xy 453.304278 -365.19231) (xy 453.300091 -365.220762) (xy 453.284023 -365.274169) (xy 453.260351 -365.324666)
			(xy 453.229578 -365.371179) (xy 453.192361 -365.412716) (xy 453.149493 -365.448391) (xy 453.101887 -365.477445)
			(xy 453.050558 -365.499257) (xy 452.996601 -365.513363) (xy 452.941164 -365.519463) (xy 452.88543 -365.517426)
			(xy 452.830587 -365.507296) (xy 452.777803 -365.489289) (xy 452.728203 -365.463788) (xy 452.682845 -365.431337)
			(xy 452.642696 -365.392628) (xy 452.60861 -365.348485) (xy 452.581314 -365.29985) (xy 452.561391 -365.247759)
			(xy 452.549265 -365.193322) (xy 452.545194 -365.1377) (xy 451.04769 -365.1377) (xy 451.056394 -365.169453)
			(xy 451.063199 -365.220099) (xy 451.063614 -365.24565) (xy 451.063154 -365.272905) (xy 451.055403 -365.326862)
			(xy 451.040051 -365.379166) (xy 451.017412 -365.428753) (xy 450.987945 -365.474613) (xy 450.952252 -365.515812)
			(xy 450.911058 -365.551512) (xy 450.865202 -365.580985) (xy 450.815619 -365.603632) (xy 450.763317 -365.618991)
			(xy 450.709361 -365.62675) (xy 450.682106 -365.627158) (xy 450.656558 -365.626743) (xy 450.605919 -365.619914)
			(xy 450.556644 -365.606392) (xy 450.509612 -365.586418) (xy 450.465666 -365.560349) (xy 450.42559 -365.528651)
			(xy 450.407532 -365.510572) (xy 450.40042 -365.503206) (xy 450.381878 -365.495078) (xy 450.299074 -365.49457)
			(xy 450.288967 -365.494908) (xy 450.270244 -365.502508) (xy 450.262752 -365.509302) (xy 450.05371 -365.718344)
			(xy 450.046905 -365.725691) (xy 450.039187 -365.744154) (xy 450.038724 -365.754158) (xy 450.038724 -365.953548)
			(xy 455.287886 -365.953548) (xy 455.291957 -365.897926) (xy 455.304083 -365.843489) (xy 455.324006 -365.791398)
			(xy 455.351302 -365.742763) (xy 455.385388 -365.69862) (xy 455.425537 -365.659911) (xy 455.470895 -365.62746)
			(xy 455.520495 -365.601959) (xy 455.573279 -365.583952) (xy 455.628122 -365.573822) (xy 455.683856 -365.571785)
			(xy 455.739293 -365.577885) (xy 455.79325 -365.591991) (xy 455.844579 -365.613803) (xy 455.892185 -365.642857)
			(xy 455.935053 -365.678532) (xy 455.97227 -365.720069) (xy 456.003043 -365.766582) (xy 456.026715 -365.817079)
			(xy 456.042783 -365.870486) (xy 456.050903 -365.925662) (xy 456.051412 -365.953548) (xy 456.050903 -365.981434)
			(xy 456.042783 -366.03661) (xy 456.026715 -366.090017) (xy 456.003043 -366.140514) (xy 455.97227 -366.187027)
			(xy 455.935053 -366.228564) (xy 455.892185 -366.264239) (xy 455.844579 -366.293293) (xy 455.79325 -366.315105)
			(xy 455.739293 -366.329211) (xy 455.683856 -366.335311) (xy 455.628122 -366.333274) (xy 455.573279 -366.323144)
			(xy 455.520495 -366.305137) (xy 455.470895 -366.279636) (xy 455.425537 -366.247185) (xy 455.385388 -366.208476)
			(xy 455.351302 -366.164333) (xy 455.324006 -366.115698) (xy 455.304083 -366.063607) (xy 455.291957 -366.00917)
			(xy 455.287886 -365.953548) (xy 450.038724 -365.953548) (xy 450.038724 -366.70361) (xy 453.285096 -366.70361)
			(xy 453.289167 -366.647988) (xy 453.301293 -366.593551) (xy 453.321216 -366.54146) (xy 453.348512 -366.492825)
			(xy 453.382598 -366.448682) (xy 453.422747 -366.409973) (xy 453.468105 -366.377522) (xy 453.517705 -366.352021)
			(xy 453.570489 -366.334014) (xy 453.625332 -366.323884) (xy 453.681066 -366.321847) (xy 453.736503 -366.327947)
			(xy 453.79046 -366.342053) (xy 453.841789 -366.363865) (xy 453.889395 -366.392919) (xy 453.932263 -366.428594)
			(xy 453.96948 -366.470131) (xy 454.000253 -366.516644) (xy 454.023925 -366.567141) (xy 454.039993 -366.620548)
			(xy 454.048113 -366.675724) (xy 454.048622 -366.70361) (xy 454.048113 -366.731496) (xy 454.039993 -366.786672)
			(xy 454.023925 -366.840079) (xy 454.000253 -366.890576) (xy 453.984807 -366.913922) (xy 455.642978 -366.913922)
			(xy 455.647049 -366.8583) (xy 455.659175 -366.803863) (xy 455.679098 -366.751772) (xy 455.706394 -366.703137)
			(xy 455.74048 -366.658994) (xy 455.780629 -366.620285) (xy 455.825987 -366.587834) (xy 455.875587 -366.562333)
			(xy 455.928371 -366.544326) (xy 455.983214 -366.534196) (xy 456.038948 -366.532159) (xy 456.094385 -366.538259)
			(xy 456.148342 -366.552365) (xy 456.199671 -366.574177) (xy 456.247277 -366.603231) (xy 456.290145 -366.638906)
			(xy 456.327362 -366.680443) (xy 456.358135 -366.726956) (xy 456.381807 -366.777453) (xy 456.397875 -366.83086)
			(xy 456.405995 -366.886036) (xy 456.406504 -366.913922) (xy 456.405995 -366.941808) (xy 456.397875 -366.996984)
			(xy 456.381807 -367.050391) (xy 456.358135 -367.100888) (xy 456.327362 -367.147401) (xy 456.290145 -367.188938)
			(xy 456.247277 -367.224613) (xy 456.199671 -367.253667) (xy 456.148342 -367.275479) (xy 456.094385 -367.289585)
			(xy 456.038948 -367.295685) (xy 455.983214 -367.293648) (xy 455.928371 -367.283518) (xy 455.875587 -367.265511)
			(xy 455.825987 -367.24001) (xy 455.780629 -367.207559) (xy 455.74048 -367.16885) (xy 455.706394 -367.124707)
			(xy 455.679098 -367.076072) (xy 455.659175 -367.023981) (xy 455.647049 -366.969544) (xy 455.642978 -366.913922)
			(xy 453.984807 -366.913922) (xy 453.96948 -366.937089) (xy 453.932263 -366.978626) (xy 453.889395 -367.014301)
			(xy 453.841789 -367.043355) (xy 453.79046 -367.065167) (xy 453.736503 -367.079273) (xy 453.681066 -367.085373)
			(xy 453.625332 -367.083336) (xy 453.570489 -367.073206) (xy 453.517705 -367.055199) (xy 453.468105 -367.029698)
			(xy 453.422747 -366.997247) (xy 453.382598 -366.958538) (xy 453.348512 -366.914395) (xy 453.321216 -366.86576)
			(xy 453.301293 -366.813669) (xy 453.289167 -366.759232) (xy 453.285096 -366.70361) (xy 450.038724 -366.70361)
			(xy 450.038724 -367.453672) (xy 451.704454 -367.453672) (xy 451.708525 -367.39805) (xy 451.720651 -367.343613)
			(xy 451.740574 -367.291522) (xy 451.76787 -367.242887) (xy 451.801956 -367.198744) (xy 451.842105 -367.160035)
			(xy 451.887463 -367.127584) (xy 451.937063 -367.102083) (xy 451.989847 -367.084076) (xy 452.04469 -367.073946)
			(xy 452.100424 -367.071909) (xy 452.155861 -367.078009) (xy 452.209818 -367.092115) (xy 452.261147 -367.113927)
			(xy 452.308753 -367.142981) (xy 452.351621 -367.178656) (xy 452.388838 -367.220193) (xy 452.419611 -367.266706)
			(xy 452.443283 -367.317203) (xy 452.459351 -367.37061) (xy 452.467471 -367.425786) (xy 452.46798 -367.453672)
			(xy 452.467471 -367.481558) (xy 452.459351 -367.536734) (xy 452.443283 -367.590141) (xy 452.419611 -367.640638)
			(xy 452.388838 -367.687151) (xy 452.351621 -367.728688) (xy 452.308753 -367.764363) (xy 452.261147 -367.793417)
			(xy 452.209818 -367.815229) (xy 452.155861 -367.829335) (xy 452.100424 -367.835435) (xy 452.04469 -367.833398)
			(xy 451.989847 -367.823268) (xy 451.937063 -367.805261) (xy 451.887463 -367.77976) (xy 451.842105 -367.747309)
			(xy 451.801956 -367.7086) (xy 451.76787 -367.664457) (xy 451.740574 -367.615822) (xy 451.720651 -367.563731)
			(xy 451.708525 -367.509294) (xy 451.704454 -367.453672) (xy 450.038724 -367.453672) (xy 450.038724 -371.85981)
			(xy 457.532484 -371.85981) (xy 457.536555 -371.804188) (xy 457.548681 -371.749751) (xy 457.568604 -371.69766)
			(xy 457.5959 -371.649025) (xy 457.629986 -371.604882) (xy 457.670135 -371.566173) (xy 457.715493 -371.533722)
			(xy 457.765093 -371.508221) (xy 457.817877 -371.490214) (xy 457.87272 -371.480084) (xy 457.928454 -371.478047)
			(xy 457.983891 -371.484147) (xy 458.037848 -371.498253) (xy 458.089177 -371.520065) (xy 458.136783 -371.549119)
			(xy 458.179651 -371.584794) (xy 458.216868 -371.626331) (xy 458.247641 -371.672844) (xy 458.271313 -371.723341)
			(xy 458.287381 -371.776748) (xy 458.295501 -371.831924) (xy 458.29601 -371.85981) (xy 458.295501 -371.887696)
			(xy 458.287381 -371.942872) (xy 458.271313 -371.996279) (xy 458.247641 -372.046776) (xy 458.216868 -372.093289)
			(xy 458.179651 -372.134826) (xy 458.136783 -372.170501) (xy 458.089177 -372.199555) (xy 458.037848 -372.221367)
			(xy 457.983891 -372.235473) (xy 457.928454 -372.241573) (xy 457.87272 -372.239536) (xy 457.817877 -372.229406)
			(xy 457.765093 -372.211399) (xy 457.715493 -372.185898) (xy 457.670135 -372.153447) (xy 457.629986 -372.114738)
			(xy 457.5959 -372.070595) (xy 457.568604 -372.02196) (xy 457.548681 -371.969869) (xy 457.536555 -371.915432)
			(xy 457.532484 -371.85981) (xy 450.038724 -371.85981) (xy 450.038724 -373.00789) (xy 458.664562 -373.00789)
			(xy 458.668633 -372.952268) (xy 458.680759 -372.897831) (xy 458.700682 -372.84574) (xy 458.727978 -372.797105)
			(xy 458.762064 -372.752962) (xy 458.802213 -372.714253) (xy 458.847571 -372.681802) (xy 458.897171 -372.656301)
			(xy 458.949955 -372.638294) (xy 459.004798 -372.628164) (xy 459.060532 -372.626127) (xy 459.115969 -372.632227)
			(xy 459.169926 -372.646333) (xy 459.221255 -372.668145) (xy 459.268861 -372.697199) (xy 459.311729 -372.732874)
			(xy 459.348946 -372.774411) (xy 459.379719 -372.820924) (xy 459.403391 -372.871421) (xy 459.419459 -372.924828)
			(xy 459.427579 -372.980004) (xy 459.428088 -373.00789) (xy 459.427579 -373.035776) (xy 459.419459 -373.090952)
			(xy 459.403391 -373.144359) (xy 459.379719 -373.194856) (xy 459.348946 -373.241369) (xy 459.311729 -373.282906)
			(xy 459.268861 -373.318581) (xy 459.221255 -373.347635) (xy 459.169926 -373.369447) (xy 459.115969 -373.383553)
			(xy 459.060532 -373.389653) (xy 459.004798 -373.387616) (xy 458.949955 -373.377486) (xy 458.897171 -373.359479)
			(xy 458.847571 -373.333978) (xy 458.802213 -373.301527) (xy 458.762064 -373.262818) (xy 458.727978 -373.218675)
			(xy 458.700682 -373.17004) (xy 458.680759 -373.117949) (xy 458.668633 -373.063512) (xy 458.664562 -373.00789)
			(xy 450.038724 -373.00789) (xy 450.038724 -373.42191) (xy 450.268846 -373.42191) (xy 450.272917 -373.366288)
			(xy 450.285043 -373.311851) (xy 450.304966 -373.25976) (xy 450.332262 -373.211125) (xy 450.366348 -373.166982)
			(xy 450.406497 -373.128273) (xy 450.451855 -373.095822) (xy 450.501455 -373.070321) (xy 450.554239 -373.052314)
			(xy 450.609082 -373.042184) (xy 450.664816 -373.040147) (xy 450.720253 -373.046247) (xy 450.77421 -373.060353)
			(xy 450.825539 -373.082165) (xy 450.873145 -373.111219) (xy 450.916013 -373.146894) (xy 450.95323 -373.188431)
			(xy 450.984003 -373.234944) (xy 451.007675 -373.285441) (xy 451.023743 -373.338848) (xy 451.031863 -373.394024)
			(xy 451.032372 -373.42191) (xy 451.031863 -373.449796) (xy 451.023743 -373.504972) (xy 451.007675 -373.558379)
			(xy 450.984003 -373.608876) (xy 450.95323 -373.655389) (xy 450.916013 -373.696926) (xy 450.873145 -373.732601)
			(xy 450.825539 -373.761655) (xy 450.77421 -373.783467) (xy 450.720253 -373.797573) (xy 450.664816 -373.803673)
			(xy 450.609082 -373.801636) (xy 450.554239 -373.791506) (xy 450.501455 -373.773499) (xy 450.451855 -373.747998)
			(xy 450.406497 -373.715547) (xy 450.366348 -373.676838) (xy 450.332262 -373.632695) (xy 450.304966 -373.58406)
			(xy 450.285043 -373.531969) (xy 450.272917 -373.477532) (xy 450.268846 -373.42191) (xy 450.038724 -373.42191)
			(xy 450.038724 -374.129808) (xy 455.263248 -374.129808) (xy 455.267319 -374.074186) (xy 455.279445 -374.019749)
			(xy 455.299368 -373.967658) (xy 455.326664 -373.919023) (xy 455.36075 -373.87488) (xy 455.400899 -373.836171)
			(xy 455.446257 -373.80372) (xy 455.495857 -373.778219) (xy 455.548641 -373.760212) (xy 455.603484 -373.750082)
			(xy 455.659218 -373.748045) (xy 455.714655 -373.754145) (xy 455.768612 -373.768251) (xy 455.819941 -373.790063)
			(xy 455.867547 -373.819117) (xy 455.910415 -373.854792) (xy 455.947632 -373.896329) (xy 455.978405 -373.942842)
			(xy 456.002077 -373.993339) (xy 456.018145 -374.046746) (xy 456.026265 -374.101922) (xy 456.026774 -374.129808)
			(xy 456.026265 -374.157694) (xy 456.018145 -374.21287) (xy 456.002077 -374.266277) (xy 455.978405 -374.316774)
			(xy 455.947632 -374.363287) (xy 455.910415 -374.404824) (xy 455.867547 -374.440499) (xy 455.819941 -374.469553)
			(xy 455.768612 -374.491365) (xy 455.714655 -374.505471) (xy 455.659218 -374.511571) (xy 455.603484 -374.509534)
			(xy 455.548641 -374.499404) (xy 455.495857 -374.481397) (xy 455.446257 -374.455896) (xy 455.400899 -374.423445)
			(xy 455.36075 -374.384736) (xy 455.326664 -374.340593) (xy 455.299368 -374.291958) (xy 455.279445 -374.239867)
			(xy 455.267319 -374.18543) (xy 455.263248 -374.129808) (xy 450.038724 -374.129808) (xy 450.038724 -375.629932)
			(xy 453.405238 -375.629932) (xy 453.409309 -375.57431) (xy 453.421435 -375.519873) (xy 453.441358 -375.467782)
			(xy 453.468654 -375.419147) (xy 453.50274 -375.375004) (xy 453.542889 -375.336295) (xy 453.588247 -375.303844)
			(xy 453.637847 -375.278343) (xy 453.690631 -375.260336) (xy 453.745474 -375.250206) (xy 453.801208 -375.248169)
			(xy 453.856645 -375.254269) (xy 453.910602 -375.268375) (xy 453.961931 -375.290187) (xy 454.009537 -375.319241)
			(xy 454.052405 -375.354916) (xy 454.089622 -375.396453) (xy 454.120395 -375.442966) (xy 454.144067 -375.493463)
			(xy 454.160135 -375.54687) (xy 454.168255 -375.602046) (xy 454.168764 -375.629932) (xy 454.168255 -375.657818)
			(xy 454.160135 -375.712994) (xy 454.144067 -375.766401) (xy 454.120395 -375.816898) (xy 454.089622 -375.863411)
			(xy 454.052405 -375.904948) (xy 454.009537 -375.940623) (xy 453.961931 -375.969677) (xy 453.910602 -375.991489)
			(xy 453.856645 -376.005595) (xy 453.801208 -376.011695) (xy 453.745474 -376.009658) (xy 453.690631 -375.999528)
			(xy 453.637847 -375.981521) (xy 453.588247 -375.95602) (xy 453.542889 -375.923569) (xy 453.50274 -375.88486)
			(xy 453.468654 -375.840717) (xy 453.441358 -375.792082) (xy 453.421435 -375.739991) (xy 453.409309 -375.685554)
			(xy 453.405238 -375.629932) (xy 450.038724 -375.629932) (xy 450.038724 -403.577806) (xy 450.038296 -403.61068)
			(xy 450.030964 -403.676017) (xy 450.016358 -403.740122) (xy 449.994664 -403.802187) (xy 449.966154 -403.861431)
			(xy 449.931187 -403.917109) (xy 449.890203 -403.968519) (xy 449.867274 -403.99208) (xy 449.402454 -404.4569)
			(xy 449.378899 -404.479846) (xy 449.3275 -404.520866) (xy 449.271829 -404.555869) (xy 449.212586 -404.584416)
			(xy 449.150519 -404.606145) (xy 449.086408 -404.620785) (xy 449.021061 -404.62815) (xy 448.98818 -404.628604)
			(xy 448.93738 -404.628604) (xy 448.927414 -404.629082) (xy 448.908978 -404.636658) (xy 448.901566 -404.643336)
			(xy 448.701414 -404.843488) (xy 448.694011 -404.850322) (xy 448.675413 -404.858027) (xy 448.665346 -404.858474)
			(xy 445.699896 -404.858474) (xy 445.689826 -404.858897) (xy 445.67122 -404.86661) (xy 445.663828 -404.87346)
			(xy 444.383922 -406.153366) (xy 446.64452 -406.153366) (xy 446.648591 -406.097744) (xy 446.660717 -406.043307)
			(xy 446.68064 -405.991216) (xy 446.707936 -405.942581) (xy 446.742022 -405.898438) (xy 446.782171 -405.859729)
			(xy 446.827529 -405.827278) (xy 446.877129 -405.801777) (xy 446.929913 -405.78377) (xy 446.984756 -405.77364)
			(xy 447.04049 -405.771603) (xy 447.095927 -405.777703) (xy 447.149884 -405.791809) (xy 447.201213 -405.813621)
			(xy 447.248819 -405.842675) (xy 447.291687 -405.87835) (xy 447.328904 -405.919887) (xy 447.359677 -405.9664)
			(xy 447.383349 -406.016897) (xy 447.399417 -406.070304) (xy 447.407537 -406.12548) (xy 447.408046 -406.153366)
			(xy 447.407537 -406.181252) (xy 447.399417 -406.236428) (xy 447.387573 -406.275794) (xy 447.938142 -406.275794)
			(xy 447.942213 -406.220172) (xy 447.954339 -406.165735) (xy 447.974262 -406.113644) (xy 448.001558 -406.065009)
			(xy 448.035644 -406.020866) (xy 448.075793 -405.982157) (xy 448.121151 -405.949706) (xy 448.170751 -405.924205)
			(xy 448.223535 -405.906198) (xy 448.278378 -405.896068) (xy 448.334112 -405.894031) (xy 448.389549 -405.900131)
			(xy 448.443506 -405.914237) (xy 448.494835 -405.936049) (xy 448.542441 -405.965103) (xy 448.585309 -406.000778)
			(xy 448.622526 -406.042315) (xy 448.653299 -406.088828) (xy 448.676971 -406.139325) (xy 448.693039 -406.192732)
			(xy 448.701159 -406.247908) (xy 448.701668 -406.275794) (xy 448.701159 -406.30368) (xy 448.693039 -406.358856)
			(xy 448.676971 -406.412263) (xy 448.653299 -406.46276) (xy 448.622526 -406.509273) (xy 448.585309 -406.55081)
			(xy 448.542441 -406.586485) (xy 448.494835 -406.615539) (xy 448.443506 -406.637351) (xy 448.389549 -406.651457)
			(xy 448.334112 -406.657557) (xy 448.278378 -406.65552) (xy 448.223535 -406.64539) (xy 448.170751 -406.627383)
			(xy 448.121151 -406.601882) (xy 448.075793 -406.569431) (xy 448.035644 -406.530722) (xy 448.001558 -406.486579)
			(xy 447.974262 -406.437944) (xy 447.954339 -406.385853) (xy 447.942213 -406.331416) (xy 447.938142 -406.275794)
			(xy 447.387573 -406.275794) (xy 447.383349 -406.289835) (xy 447.359677 -406.340332) (xy 447.328904 -406.386845)
			(xy 447.291687 -406.428382) (xy 447.248819 -406.464057) (xy 447.201213 -406.493111) (xy 447.149884 -406.514923)
			(xy 447.095927 -406.529029) (xy 447.04049 -406.535129) (xy 446.984756 -406.533092) (xy 446.929913 -406.522962)
			(xy 446.877129 -406.504955) (xy 446.827529 -406.479454) (xy 446.782171 -406.447003) (xy 446.742022 -406.408294)
			(xy 446.707936 -406.364151) (xy 446.68064 -406.315516) (xy 446.660717 -406.263425) (xy 446.648591 -406.208988)
			(xy 446.64452 -406.153366) (xy 444.383922 -406.153366) (xy 444.063374 -406.473914) (xy 444.056522 -406.48131)
			(xy 444.048781 -406.499909) (xy 444.048388 -406.509982) (xy 444.048388 -407.506678) (xy 451.009256 -407.506678)
			(xy 451.013327 -407.451056) (xy 451.025453 -407.396619) (xy 451.045376 -407.344528) (xy 451.072672 -407.295893)
			(xy 451.106758 -407.25175) (xy 451.146907 -407.213041) (xy 451.192265 -407.18059) (xy 451.241865 -407.155089)
			(xy 451.294649 -407.137082) (xy 451.349492 -407.126952) (xy 451.405226 -407.124915) (xy 451.460663 -407.131015)
			(xy 451.51462 -407.145121) (xy 451.565949 -407.166933) (xy 451.613555 -407.195987) (xy 451.656423 -407.231662)
			(xy 451.69364 -407.273199) (xy 451.724413 -407.319712) (xy 451.748085 -407.370209) (xy 451.764153 -407.423616)
			(xy 451.772273 -407.478792) (xy 451.772782 -407.506678) (xy 451.772273 -407.534564) (xy 451.764153 -407.58974)
			(xy 451.748085 -407.643147) (xy 451.724413 -407.693644) (xy 451.69364 -407.740157) (xy 451.656423 -407.781694)
			(xy 451.613555 -407.817369) (xy 451.565949 -407.846423) (xy 451.51462 -407.868235) (xy 451.460663 -407.882341)
			(xy 451.405226 -407.888441) (xy 451.349492 -407.886404) (xy 451.294649 -407.876274) (xy 451.241865 -407.858267)
			(xy 451.192265 -407.832766) (xy 451.146907 -407.800315) (xy 451.106758 -407.761606) (xy 451.072672 -407.717463)
			(xy 451.045376 -407.668828) (xy 451.025453 -407.616737) (xy 451.013327 -407.5623) (xy 451.009256 -407.506678)
			(xy 444.048388 -407.506678) (xy 444.048388 -411.100016) (xy 444.291972 -411.100016) (xy 444.296043 -411.044394)
			(xy 444.308169 -410.989957) (xy 444.328092 -410.937866) (xy 444.355388 -410.889231) (xy 444.389474 -410.845088)
			(xy 444.429623 -410.806379) (xy 444.474981 -410.773928) (xy 444.524581 -410.748427) (xy 444.577365 -410.73042)
			(xy 444.632208 -410.72029) (xy 444.687942 -410.718253) (xy 444.743379 -410.724353) (xy 444.797336 -410.738459)
			(xy 444.848665 -410.760271) (xy 444.896271 -410.789325) (xy 444.939139 -410.825) (xy 444.976356 -410.866537)
			(xy 445.007129 -410.91305) (xy 445.030801 -410.963547) (xy 445.046869 -411.016954) (xy 445.054989 -411.07213)
			(xy 445.055498 -411.100016) (xy 445.054989 -411.127902) (xy 445.046869 -411.183078) (xy 445.030801 -411.236485)
			(xy 445.007129 -411.286982) (xy 444.976356 -411.333495) (xy 444.939139 -411.375032) (xy 444.896271 -411.410707)
			(xy 444.848665 -411.439761) (xy 444.797336 -411.461573) (xy 444.743379 -411.475679) (xy 444.687942 -411.481779)
			(xy 444.632208 -411.479742) (xy 444.577365 -411.469612) (xy 444.524581 -411.451605) (xy 444.474981 -411.426104)
			(xy 444.429623 -411.393653) (xy 444.389474 -411.354944) (xy 444.355388 -411.310801) (xy 444.328092 -411.262166)
			(xy 444.308169 -411.210075) (xy 444.296043 -411.155638) (xy 444.291972 -411.100016) (xy 444.048388 -411.100016)
			(xy 444.048388 -414.403794) (xy 447.176396 -414.403794) (xy 447.180467 -414.348172) (xy 447.192593 -414.293735)
			(xy 447.212516 -414.241644) (xy 447.239812 -414.193009) (xy 447.273898 -414.148866) (xy 447.314047 -414.110157)
			(xy 447.359405 -414.077706) (xy 447.409005 -414.052205) (xy 447.461789 -414.034198) (xy 447.516632 -414.024068)
			(xy 447.572366 -414.022031) (xy 447.627803 -414.028131) (xy 447.68176 -414.042237) (xy 447.733089 -414.064049)
			(xy 447.780695 -414.093103) (xy 447.823563 -414.128778) (xy 447.86078 -414.170315) (xy 447.891553 -414.216828)
			(xy 447.915225 -414.267325) (xy 447.931293 -414.320732) (xy 447.939413 -414.375908) (xy 447.939922 -414.403794)
			(xy 447.939413 -414.43168) (xy 447.931293 -414.486856) (xy 447.915225 -414.540263) (xy 447.891801 -414.59023)
			(xy 448.79717 -414.59023) (xy 448.801241 -414.534608) (xy 448.813367 -414.480171) (xy 448.83329 -414.42808)
			(xy 448.860586 -414.379445) (xy 448.894672 -414.335302) (xy 448.934821 -414.296593) (xy 448.980179 -414.264142)
			(xy 449.029779 -414.238641) (xy 449.082563 -414.220634) (xy 449.137406 -414.210504) (xy 449.19314 -414.208467)
			(xy 449.248577 -414.214567) (xy 449.302534 -414.228673) (xy 449.353863 -414.250485) (xy 449.401469 -414.279539)
			(xy 449.444337 -414.315214) (xy 449.461574 -414.334452) (xy 450.168262 -414.334452) (xy 450.172333 -414.27883)
			(xy 450.184459 -414.224393) (xy 450.204382 -414.172302) (xy 450.231678 -414.123667) (xy 450.265764 -414.079524)
			(xy 450.305913 -414.040815) (xy 450.351271 -414.008364) (xy 450.400871 -413.982863) (xy 450.453655 -413.964856)
			(xy 450.508498 -413.954726) (xy 450.564232 -413.952689) (xy 450.619669 -413.958789) (xy 450.673626 -413.972895)
			(xy 450.724955 -413.994707) (xy 450.772561 -414.023761) (xy 450.815429 -414.059436) (xy 450.852646 -414.100973)
			(xy 450.883419 -414.147486) (xy 450.907091 -414.197983) (xy 450.923159 -414.25139) (xy 450.931279 -414.306566)
			(xy 450.931788 -414.334452) (xy 450.931279 -414.362338) (xy 450.923159 -414.417514) (xy 450.907091 -414.470921)
			(xy 450.883419 -414.521418) (xy 450.852646 -414.567931) (xy 450.815429 -414.609468) (xy 450.772561 -414.645143)
			(xy 450.724955 -414.674197) (xy 450.673626 -414.696009) (xy 450.619669 -414.710115) (xy 450.564232 -414.716215)
			(xy 450.508498 -414.714178) (xy 450.453655 -414.704048) (xy 450.400871 -414.686041) (xy 450.351271 -414.66054)
			(xy 450.305913 -414.628089) (xy 450.265764 -414.58938) (xy 450.231678 -414.545237) (xy 450.204382 -414.496602)
			(xy 450.184459 -414.444511) (xy 450.172333 -414.390074) (xy 450.168262 -414.334452) (xy 449.461574 -414.334452)
			(xy 449.481554 -414.356751) (xy 449.512327 -414.403264) (xy 449.535999 -414.453761) (xy 449.552067 -414.507168)
			(xy 449.560187 -414.562344) (xy 449.560696 -414.59023) (xy 449.560187 -414.618116) (xy 449.552067 -414.673292)
			(xy 449.535999 -414.726699) (xy 449.512327 -414.777196) (xy 449.481554 -414.823709) (xy 449.444337 -414.865246)
			(xy 449.401469 -414.900921) (xy 449.353863 -414.929975) (xy 449.302534 -414.951787) (xy 449.248577 -414.965893)
			(xy 449.19314 -414.971993) (xy 449.137406 -414.969956) (xy 449.082563 -414.959826) (xy 449.029779 -414.941819)
			(xy 448.980179 -414.916318) (xy 448.934821 -414.883867) (xy 448.894672 -414.845158) (xy 448.860586 -414.801015)
			(xy 448.83329 -414.75238) (xy 448.813367 -414.700289) (xy 448.801241 -414.645852) (xy 448.79717 -414.59023)
			(xy 447.891801 -414.59023) (xy 447.891553 -414.59076) (xy 447.86078 -414.637273) (xy 447.823563 -414.67881)
			(xy 447.780695 -414.714485) (xy 447.733089 -414.743539) (xy 447.68176 -414.765351) (xy 447.627803 -414.779457)
			(xy 447.572366 -414.785557) (xy 447.516632 -414.78352) (xy 447.461789 -414.77339) (xy 447.409005 -414.755383)
			(xy 447.359405 -414.729882) (xy 447.314047 -414.697431) (xy 447.273898 -414.658722) (xy 447.239812 -414.614579)
			(xy 447.212516 -414.565944) (xy 447.192593 -414.513853) (xy 447.180467 -414.459416) (xy 447.176396 -414.403794)
			(xy 444.048388 -414.403794) (xy 444.048388 -416.390582) (xy 444.048826 -416.400646) (xy 444.05656 -416.41923)
			(xy 444.063374 -416.42665) (xy 444.273686 -416.636962) (xy 445.74917 -416.636962) (xy 445.753241 -416.58134)
			(xy 445.765367 -416.526903) (xy 445.78529 -416.474812) (xy 445.812586 -416.426177) (xy 445.846672 -416.382034)
			(xy 445.886821 -416.343325) (xy 445.932179 -416.310874) (xy 445.981779 -416.285373) (xy 446.034563 -416.267366)
			(xy 446.089406 -416.257236) (xy 446.14514 -416.255199) (xy 446.200577 -416.261299) (xy 446.254534 -416.275405)
			(xy 446.305863 -416.297217) (xy 446.353469 -416.326271) (xy 446.396337 -416.361946) (xy 446.433554 -416.403483)
			(xy 446.464327 -416.449996) (xy 446.487999 -416.500493) (xy 446.504067 -416.5539) (xy 446.512187 -416.609076)
			(xy 446.512696 -416.636962) (xy 447.78117 -416.636962) (xy 447.785241 -416.58134) (xy 447.797367 -416.526903)
			(xy 447.81729 -416.474812) (xy 447.844586 -416.426177) (xy 447.878672 -416.382034) (xy 447.918821 -416.343325)
			(xy 447.964179 -416.310874) (xy 448.013779 -416.285373) (xy 448.066563 -416.267366) (xy 448.121406 -416.257236)
			(xy 448.17714 -416.255199) (xy 448.232577 -416.261299) (xy 448.286534 -416.275405) (xy 448.337863 -416.297217)
			(xy 448.385469 -416.326271) (xy 448.428337 -416.361946) (xy 448.465554 -416.403483) (xy 448.496327 -416.449996)
			(xy 448.519999 -416.500493) (xy 448.536067 -416.5539) (xy 448.544187 -416.609076) (xy 448.544696 -416.636962)
			(xy 450.82917 -416.636962) (xy 450.833241 -416.58134) (xy 450.845367 -416.526903) (xy 450.86529 -416.474812)
			(xy 450.892586 -416.426177) (xy 450.926672 -416.382034) (xy 450.966821 -416.343325) (xy 451.012179 -416.310874)
			(xy 451.061779 -416.285373) (xy 451.114563 -416.267366) (xy 451.169406 -416.257236) (xy 451.22514 -416.255199)
			(xy 451.280577 -416.261299) (xy 451.334534 -416.275405) (xy 451.385863 -416.297217) (xy 451.433469 -416.326271)
			(xy 451.476337 -416.361946) (xy 451.513554 -416.403483) (xy 451.544327 -416.449996) (xy 451.567999 -416.500493)
			(xy 451.584067 -416.5539) (xy 451.592187 -416.609076) (xy 451.592696 -416.636962) (xy 451.592187 -416.664848)
			(xy 451.584067 -416.720024) (xy 451.567999 -416.773431) (xy 451.544327 -416.823928) (xy 451.513554 -416.870441)
			(xy 451.476337 -416.911978) (xy 451.433469 -416.947653) (xy 451.385863 -416.976707) (xy 451.334534 -416.998519)
			(xy 451.280577 -417.012625) (xy 451.22514 -417.018725) (xy 451.169406 -417.016688) (xy 451.114563 -417.006558)
			(xy 451.061779 -416.988551) (xy 451.012179 -416.96305) (xy 450.966821 -416.930599) (xy 450.926672 -416.89189)
			(xy 450.892586 -416.847747) (xy 450.86529 -416.799112) (xy 450.845367 -416.747021) (xy 450.833241 -416.692584)
			(xy 450.82917 -416.636962) (xy 448.544696 -416.636962) (xy 448.544187 -416.664848) (xy 448.536067 -416.720024)
			(xy 448.519999 -416.773431) (xy 448.496327 -416.823928) (xy 448.465554 -416.870441) (xy 448.428337 -416.911978)
			(xy 448.385469 -416.947653) (xy 448.337863 -416.976707) (xy 448.286534 -416.998519) (xy 448.232577 -417.012625)
			(xy 448.17714 -417.018725) (xy 448.121406 -417.016688) (xy 448.066563 -417.006558) (xy 448.013779 -416.988551)
			(xy 447.964179 -416.96305) (xy 447.918821 -416.930599) (xy 447.878672 -416.89189) (xy 447.844586 -416.847747)
			(xy 447.81729 -416.799112) (xy 447.797367 -416.747021) (xy 447.785241 -416.692584) (xy 447.78117 -416.636962)
			(xy 446.512696 -416.636962) (xy 446.512187 -416.664848) (xy 446.504067 -416.720024) (xy 446.487999 -416.773431)
			(xy 446.464327 -416.823928) (xy 446.433554 -416.870441) (xy 446.396337 -416.911978) (xy 446.353469 -416.947653)
			(xy 446.305863 -416.976707) (xy 446.254534 -416.998519) (xy 446.200577 -417.012625) (xy 446.14514 -417.018725)
			(xy 446.089406 -417.016688) (xy 446.034563 -417.006558) (xy 445.981779 -416.988551) (xy 445.932179 -416.96305)
			(xy 445.886821 -416.930599) (xy 445.846672 -416.89189) (xy 445.812586 -416.847747) (xy 445.78529 -416.799112)
			(xy 445.765367 -416.747021) (xy 445.753241 -416.692584) (xy 445.74917 -416.636962) (xy 444.273686 -416.636962)
			(xy 444.848488 -417.211764) (xy 444.855884 -417.218616) (xy 444.874482 -417.226361) (xy 444.884556 -417.22675)
		)
		(stroke
			(width 0)
			(type solid)
		)
		(fill yes)
		(layer "In5.Cu")
		(net "P3V3_AUX")
	)
	(gr_poly
		(pts
			(xy 152.232868 -300.88078) (xy 152.239537 -300.880591) (xy 152.252417 -300.877127) (xy 152.258268 -300.873922)
			(xy 152.263094 -300.871128) (xy 152.266396 -300.868588) (xy 152.288641 -300.851176) (xy 152.337838 -300.823418)
			(xy 152.391036 -300.804424) (xy 152.446687 -300.794746) (xy 152.47493 -300.794166) (xy 152.488521 -300.794336)
			(xy 152.515606 -300.796625) (xy 152.529032 -300.798738) (xy 152.541224 -300.80077) (xy 152.56383 -300.793658)
			(xy 152.640284 -300.72076) (xy 152.648158 -300.698408) (xy 152.646888 -300.68647) (xy 152.645835 -300.677362)
			(xy 152.644693 -300.659062) (xy 152.644602 -300.649894) (xy 152.645124 -300.624639) (xy 152.653437 -300.574817)
			(xy 152.669838 -300.527043) (xy 152.693879 -300.48262) (xy 152.724903 -300.44276) (xy 152.762065 -300.40855)
			(xy 152.804351 -300.380924) (xy 152.850607 -300.360634) (xy 152.899572 -300.348234) (xy 152.94991 -300.344063)
			(xy 153.000248 -300.348234) (xy 153.049213 -300.360634) (xy 153.095469 -300.380924) (xy 153.137755 -300.40855)
			(xy 153.174917 -300.44276) (xy 153.205941 -300.48262) (xy 153.229982 -300.527043) (xy 153.246383 -300.574817)
			(xy 153.254696 -300.624639) (xy 153.255218 -300.649894) (xy 153.255126 -300.659062) (xy 153.253983 -300.677362)
			(xy 153.252932 -300.68647) (xy 153.251662 -300.698408) (xy 153.259536 -300.72076) (xy 153.33599 -300.793658)
			(xy 153.358596 -300.80077) (xy 153.370788 -300.798738) (xy 153.384213 -300.796618) (xy 153.411299 -300.794327)
			(xy 153.42489 -300.794166) (xy 153.438481 -300.794334) (xy 153.465566 -300.79662) (xy 153.478992 -300.798738)
			(xy 153.491184 -300.80077) (xy 153.51379 -300.793658) (xy 153.590244 -300.72076) (xy 153.598118 -300.698408)
			(xy 153.596848 -300.68647) (xy 153.595795 -300.677362) (xy 153.594653 -300.659062) (xy 153.594562 -300.649894)
			(xy 153.595084 -300.624639) (xy 153.603397 -300.574817) (xy 153.619798 -300.527043) (xy 153.643839 -300.48262)
			(xy 153.674863 -300.44276) (xy 153.712025 -300.40855) (xy 153.754311 -300.380924) (xy 153.800567 -300.360634)
			(xy 153.849532 -300.348234) (xy 153.89987 -300.344063) (xy 153.950208 -300.348234) (xy 153.999173 -300.360634)
			(xy 154.045429 -300.380924) (xy 154.087715 -300.40855) (xy 154.124877 -300.44276) (xy 154.155901 -300.48262)
			(xy 154.179942 -300.527043) (xy 154.196343 -300.574817) (xy 154.204656 -300.624639) (xy 154.205178 -300.649894)
			(xy 154.205086 -300.659062) (xy 154.203942 -300.677362) (xy 154.202892 -300.68647) (xy 154.201622 -300.698662)
			(xy 154.209496 -300.721014) (xy 154.28595 -300.793912) (xy 154.308556 -300.801024) (xy 154.320494 -300.798992)
			(xy 154.333982 -300.79686) (xy 154.361195 -300.794568) (xy 154.37485 -300.79442) (xy 154.445462 -300.79442)
			(xy 154.456151 -300.79385) (xy 154.475697 -300.785184) (xy 154.483308 -300.777656) (xy 154.540966 -300.713394)
			(xy 154.54757 -300.693074) (xy 154.546554 -300.682152) (xy 154.544776 -300.649894) (xy 154.545298 -300.624639)
			(xy 154.553611 -300.574817) (xy 154.570012 -300.527043) (xy 154.594053 -300.48262) (xy 154.625077 -300.44276)
			(xy 154.662239 -300.40855) (xy 154.704525 -300.380924) (xy 154.750781 -300.360634) (xy 154.799746 -300.348234)
			(xy 154.850084 -300.344063) (xy 154.900422 -300.348234) (xy 154.949387 -300.360634) (xy 154.995643 -300.380924)
			(xy 155.037929 -300.40855) (xy 155.075091 -300.44276) (xy 155.106115 -300.48262) (xy 155.130156 -300.527043)
			(xy 155.146557 -300.574817) (xy 155.15487 -300.624639) (xy 155.155392 -300.649894) (xy 155.153614 -300.682152)
			(xy 155.152598 -300.693074) (xy 155.159202 -300.713394) (xy 155.21686 -300.777656) (xy 155.224374 -300.785323)
			(xy 155.243979 -300.794023) (xy 155.254706 -300.79442) (xy 155.325318 -300.79442) (xy 155.338909 -300.794589)
			(xy 155.365994 -300.796877) (xy 155.37942 -300.798992) (xy 155.391358 -300.80077) (xy 155.413964 -300.793912)
			(xy 155.490418 -300.72076) (xy 155.498292 -300.698662) (xy 155.497022 -300.68647) (xy 155.495969 -300.677362)
			(xy 155.494827 -300.659062) (xy 155.494736 -300.649894) (xy 155.495258 -300.624639) (xy 155.503571 -300.574817)
			(xy 155.519972 -300.527043) (xy 155.544013 -300.48262) (xy 155.575037 -300.44276) (xy 155.612199 -300.40855)
			(xy 155.654485 -300.380924) (xy 155.700741 -300.360634) (xy 155.749706 -300.348234) (xy 155.800044 -300.344063)
			(xy 155.850382 -300.348234) (xy 155.899347 -300.360634) (xy 155.945603 -300.380924) (xy 155.987889 -300.40855)
			(xy 156.025051 -300.44276) (xy 156.056075 -300.48262) (xy 156.080116 -300.527043) (xy 156.096517 -300.574817)
			(xy 156.10483 -300.624639) (xy 156.105352 -300.649894) (xy 156.10526 -300.659062) (xy 156.104116 -300.677362)
			(xy 156.103066 -300.68647) (xy 156.101796 -300.698408) (xy 156.10967 -300.72076) (xy 156.186124 -300.793658)
			(xy 156.20873 -300.80077) (xy 156.220922 -300.798738) (xy 156.234348 -300.796619) (xy 156.261433 -300.794331)
			(xy 156.275024 -300.794166) (xy 156.288615 -300.794336) (xy 156.3157 -300.796624) (xy 156.329126 -300.798738)
			(xy 156.341318 -300.80077) (xy 156.363924 -300.793658) (xy 156.440378 -300.72076) (xy 156.448252 -300.698408)
			(xy 156.446982 -300.68647) (xy 156.445929 -300.677362) (xy 156.444787 -300.659062) (xy 156.444696 -300.649894)
			(xy 156.445218 -300.624639) (xy 156.453531 -300.574817) (xy 156.469932 -300.527043) (xy 156.493973 -300.48262)
			(xy 156.524997 -300.44276) (xy 156.562159 -300.40855) (xy 156.604445 -300.380924) (xy 156.650701 -300.360634)
			(xy 156.699666 -300.348234) (xy 156.750004 -300.344063) (xy 156.800342 -300.348234) (xy 156.849307 -300.360634)
			(xy 156.895563 -300.380924) (xy 156.937849 -300.40855) (xy 156.975011 -300.44276) (xy 157.006035 -300.48262)
			(xy 157.030076 -300.527043) (xy 157.046477 -300.574817) (xy 157.05479 -300.624639) (xy 157.055312 -300.649894)
			(xy 157.055216 -300.658998) (xy 157.054075 -300.677172) (xy 157.053026 -300.686216) (xy 157.051756 -300.698154)
			(xy 157.05963 -300.720506) (xy 157.136084 -300.793404) (xy 157.15869 -300.800516) (xy 157.170628 -300.798484)
			(xy 157.184116 -300.796353) (xy 157.211329 -300.794062) (xy 157.224984 -300.793912) (xy 157.295342 -300.793912)
			(xy 157.306007 -300.793464) (xy 157.325493 -300.784798) (xy 157.332934 -300.777148) (xy 157.390846 -300.712886)
			(xy 157.39745 -300.692566) (xy 157.396434 -300.681644) (xy 157.394656 -300.649894) (xy 157.395178 -300.624639)
			(xy 157.403491 -300.574817) (xy 157.419892 -300.527043) (xy 157.443933 -300.48262) (xy 157.474957 -300.44276)
			(xy 157.512119 -300.40855) (xy 157.554405 -300.380924) (xy 157.600661 -300.360634) (xy 157.649626 -300.348234)
			(xy 157.699964 -300.344063) (xy 157.750302 -300.348234) (xy 157.799267 -300.360634) (xy 157.845523 -300.380924)
			(xy 157.887809 -300.40855) (xy 157.924971 -300.44276) (xy 157.955995 -300.48262) (xy 157.980036 -300.527043)
			(xy 157.996437 -300.574817) (xy 158.00475 -300.624639) (xy 158.005272 -300.649894) (xy 158.003494 -300.681644)
			(xy 158.002478 -300.692566) (xy 158.009082 -300.712886) (xy 158.066994 -300.777148) (xy 158.074538 -300.784659)
			(xy 158.093957 -300.793323) (xy 158.104586 -300.793912) (xy 158.174944 -300.793912) (xy 158.188598 -300.794073)
			(xy 158.215811 -300.796361) (xy 158.2293 -300.798484) (xy 158.241238 -300.800516) (xy 158.263844 -300.793404)
			(xy 158.340298 -300.720506) (xy 158.348172 -300.698154) (xy 158.346902 -300.686216) (xy 158.345854 -300.677172)
			(xy 158.34471 -300.658998) (xy 158.344616 -300.649894) (xy 158.345138 -300.624639) (xy 158.353451 -300.574817)
			(xy 158.369852 -300.527043) (xy 158.393893 -300.48262) (xy 158.424917 -300.44276) (xy 158.462079 -300.40855)
			(xy 158.504365 -300.380924) (xy 158.550621 -300.360634) (xy 158.599586 -300.348234) (xy 158.649924 -300.344063)
			(xy 158.700262 -300.348234) (xy 158.749227 -300.360634) (xy 158.795483 -300.380924) (xy 158.837769 -300.40855)
			(xy 158.874931 -300.44276) (xy 158.905955 -300.48262) (xy 158.929996 -300.527043) (xy 158.946397 -300.574817)
			(xy 158.95471 -300.624639) (xy 158.955232 -300.649894) (xy 158.95514 -300.659062) (xy 158.953997 -300.677362)
			(xy 158.952946 -300.68647) (xy 158.951676 -300.698408) (xy 158.95955 -300.72076) (xy 159.036004 -300.793658)
			(xy 159.05861 -300.80077) (xy 159.070802 -300.798738) (xy 159.084228 -300.796618) (xy 159.111313 -300.794329)
			(xy 159.124904 -300.794166) (xy 159.138495 -300.794335) (xy 159.16558 -300.796622) (xy 159.179006 -300.798738)
			(xy 159.191198 -300.80077) (xy 159.213804 -300.793658) (xy 159.290258 -300.72076) (xy 159.298132 -300.698408)
			(xy 159.296862 -300.68647) (xy 159.295809 -300.677362) (xy 159.294667 -300.659062) (xy 159.294576 -300.649894)
			(xy 159.295047 -300.625903) (xy 159.302554 -300.578511) (xy 159.317382 -300.532876) (xy 159.339165 -300.490123)
			(xy 159.367368 -300.451304) (xy 159.401297 -300.417375) (xy 159.440115 -300.38917) (xy 159.482867 -300.367385)
			(xy 159.528501 -300.352556) (xy 159.575893 -300.345048) (xy 159.599884 -300.344586) (xy 159.614067 -300.344772)
			(xy 159.642306 -300.347444) (xy 159.656272 -300.34992) (xy 159.668718 -300.352206) (xy 159.69234 -300.34484)
			(xy 159.76981 -300.26737) (xy 159.777176 -300.243748) (xy 159.77489 -300.231302) (xy 159.772404 -300.217337)
			(xy 159.769731 -300.189097) (xy 159.769556 -300.174914) (xy 159.770041 -300.150089) (xy 159.778071 -300.101094)
			(xy 159.793923 -300.054043) (xy 159.817178 -300.010177) (xy 159.847223 -299.97065) (xy 159.883268 -299.936506)
			(xy 159.924362 -299.908643) (xy 159.969422 -299.887796) (xy 160.017261 -299.874513) (xy 160.06662 -299.869145)
			(xy 160.116196 -299.871834) (xy 160.164684 -299.882507) (xy 160.210807 -299.900886) (xy 160.253349 -299.926484)
			(xy 160.291188 -299.958627) (xy 160.323329 -299.996469) (xy 160.348924 -300.039013) (xy 160.367299 -300.085137)
			(xy 160.377969 -300.133626) (xy 160.380205 -300.174914) (xy 160.719274 -300.174914) (xy 160.723234 -300.12586)
			(xy 160.735011 -300.078076) (xy 160.754302 -300.0328) (xy 160.780605 -299.991204) (xy 160.81324 -299.954367)
			(xy 160.851361 -299.923242) (xy 160.893982 -299.898635) (xy 160.939998 -299.881183) (xy 160.988217 -299.871339)
			(xy 161.037392 -299.869358) (xy 161.086247 -299.87529) (xy 161.133518 -299.888982) (xy 161.17798 -299.91008)
			(xy 161.218483 -299.938036) (xy 161.253976 -299.972128) (xy 161.283541 -300.011472) (xy 161.306412 -300.055049)
			(xy 161.321996 -300.10173) (xy 161.329891 -300.150307) (xy 161.330386 -300.174914) (xy 161.669234 -300.174914)
			(xy 161.673194 -300.12586) (xy 161.684971 -300.078076) (xy 161.704262 -300.0328) (xy 161.730565 -299.991204)
			(xy 161.7632 -299.954367) (xy 161.801321 -299.923242) (xy 161.843942 -299.898635) (xy 161.889958 -299.881183)
			(xy 161.938177 -299.871339) (xy 161.987352 -299.869358) (xy 162.036207 -299.87529) (xy 162.083478 -299.888982)
			(xy 162.12794 -299.91008) (xy 162.168443 -299.938036) (xy 162.203936 -299.972128) (xy 162.233501 -300.011472)
			(xy 162.256372 -300.055049) (xy 162.271956 -300.10173) (xy 162.279851 -300.150307) (xy 162.280346 -300.174914)
			(xy 162.279851 -300.199521) (xy 162.271956 -300.248098) (xy 162.256372 -300.294779) (xy 162.233501 -300.338356)
			(xy 162.203936 -300.3777) (xy 162.168443 -300.411792) (xy 162.12794 -300.439748) (xy 162.083478 -300.460846)
			(xy 162.036207 -300.474538) (xy 161.987352 -300.48047) (xy 161.938177 -300.478489) (xy 161.889958 -300.468645)
			(xy 161.843942 -300.451193) (xy 161.801321 -300.426586) (xy 161.7632 -300.395461) (xy 161.730565 -300.358624)
			(xy 161.704262 -300.317028) (xy 161.684971 -300.271752) (xy 161.673194 -300.223968) (xy 161.669234 -300.174914)
			(xy 161.330386 -300.174914) (xy 161.329891 -300.199521) (xy 161.321996 -300.248098) (xy 161.306412 -300.294779)
			(xy 161.283541 -300.338356) (xy 161.253976 -300.3777) (xy 161.218483 -300.411792) (xy 161.17798 -300.439748)
			(xy 161.133518 -300.460846) (xy 161.086247 -300.474538) (xy 161.037392 -300.48047) (xy 160.988217 -300.478489)
			(xy 160.939998 -300.468645) (xy 160.893982 -300.451193) (xy 160.851361 -300.426586) (xy 160.81324 -300.395461)
			(xy 160.780605 -300.358624) (xy 160.754302 -300.317028) (xy 160.735011 -300.271752) (xy 160.723234 -300.223968)
			(xy 160.719274 -300.174914) (xy 160.380205 -300.174914) (xy 160.380654 -300.183202) (xy 160.375283 -300.23256)
			(xy 160.361997 -300.280399) (xy 160.341146 -300.325458) (xy 160.31328 -300.366549) (xy 160.279133 -300.402592)
			(xy 160.239605 -300.432634) (xy 160.195737 -300.455886) (xy 160.148685 -300.471734) (xy 160.099689 -300.479761)
			(xy 160.074864 -300.480222) (xy 160.060681 -300.480038) (xy 160.032441 -300.477371) (xy 160.018476 -300.474888)
			(xy 160.00603 -300.472602) (xy 159.982408 -300.479968) (xy 159.904938 -300.557438) (xy 159.897572 -300.58106)
			(xy 159.899858 -300.593506) (xy 159.902344 -300.607471) (xy 159.905016 -300.635711) (xy 159.905192 -300.649894)
			(xy 159.9051 -300.659062) (xy 159.903956 -300.677362) (xy 159.902906 -300.68647) (xy 159.901636 -300.698408)
			(xy 159.90951 -300.72076) (xy 159.985964 -300.793658) (xy 160.00857 -300.80077) (xy 160.020762 -300.798738)
			(xy 160.034188 -300.796621) (xy 160.061273 -300.794336) (xy 160.074864 -300.794166) (xy 160.103104 -300.794787)
			(xy 160.158749 -300.804468) (xy 160.211943 -300.823454) (xy 160.261144 -300.851192) (xy 160.283398 -300.868588)
			(xy 160.286954 -300.871382) (xy 160.292034 -300.874176) (xy 160.297798 -300.877233) (xy 160.310404 -300.88058)
			(xy 160.316926 -300.88078) (xy 160.783016 -300.88078) (xy 160.789683 -300.880584) (xy 160.802557 -300.87711)
			(xy 160.808416 -300.873922) (xy 160.813242 -300.871128) (xy 160.816544 -300.868588) (xy 160.83879 -300.85118)
			(xy 160.887988 -300.823429) (xy 160.941186 -300.804442) (xy 160.996836 -300.794772) (xy 161.025078 -300.794166)
			(xy 161.053317 -300.794788) (xy 161.108961 -300.804471) (xy 161.162154 -300.823458) (xy 161.211353 -300.851198)
			(xy 161.233612 -300.868588) (xy 161.237168 -300.871382) (xy 161.242248 -300.874176) (xy 161.248013 -300.877231)
			(xy 161.260619 -300.880574) (xy 161.26714 -300.88078) (xy 161.732976 -300.88078) (xy 161.739645 -300.88059)
			(xy 161.752524 -300.877124) (xy 161.758376 -300.873922) (xy 161.763202 -300.871128) (xy 161.766504 -300.868588)
			(xy 161.78875 -300.851177) (xy 161.837946 -300.82342) (xy 161.891144 -300.804427) (xy 161.946795 -300.794751)
			(xy 161.975038 -300.794166) (xy 162.003278 -300.794785) (xy 162.058926 -300.804462) (xy 162.112123 -300.823444)
			(xy 162.161327 -300.85118) (xy 162.183572 -300.868588) (xy 162.187128 -300.871382) (xy 162.192208 -300.874176)
			(xy 162.197972 -300.877236) (xy 162.210578 -300.880589) (xy 162.2171 -300.88078) (xy 162.682936 -300.88078)
			(xy 162.689603 -300.880582) (xy 162.702474 -300.877103) (xy 162.708336 -300.873922) (xy 162.713162 -300.871128)
			(xy 162.716464 -300.868588) (xy 162.738711 -300.851181) (xy 162.787909 -300.823433) (xy 162.841107 -300.80445)
			(xy 162.896757 -300.794783) (xy 162.924998 -300.794166) (xy 162.950299 -300.794691) (xy 163.0003 -300.802478)
			(xy 163.024566 -300.80966) (xy 163.02482 -300.80966) (xy 163.033751 -300.812057) (xy 163.052198 -300.811003)
			(xy 163.069073 -300.803477) (xy 163.075874 -300.797214) (xy 163.1188 -300.754288) (xy 163.125644 -300.746889)
			(xy 163.133374 -300.728291) (xy 163.133786 -300.71822) (xy 163.133786 -300.59376) (xy 163.133221 -300.582134)
			(xy 163.123043 -300.561228) (xy 163.114228 -300.553628) (xy 163.050728 -300.504352) (xy 163.044459 -300.499822)
			(xy 163.029982 -300.4944) (xy 163.02228 -300.493684) (xy 163.013898 -300.49343) (xy 162.992113 -300.499114)
			(xy 162.947509 -300.50523) (xy 162.924998 -300.505622) (xy 162.89901 -300.505112) (xy 162.847673 -300.496981)
			(xy 162.798241 -300.480919) (xy 162.75193 -300.457322) (xy 162.70988 -300.426771) (xy 162.673127 -300.390018)
			(xy 162.642577 -300.347968) (xy 162.61898 -300.301657) (xy 162.602918 -300.252225) (xy 162.594788 -300.200888)
			(xy 162.594788 -300.148912) (xy 162.602918 -300.097575) (xy 162.61898 -300.048143) (xy 162.642577 -300.001832)
			(xy 162.673127 -299.959782) (xy 162.70988 -299.923029) (xy 162.75193 -299.892478) (xy 162.798241 -299.868881)
			(xy 162.847673 -299.852819) (xy 162.89901 -299.844688) (xy 162.924998 -299.844206) (xy 162.94567 -299.844559)
			(xy 162.986684 -299.849786) (xy 163.006786 -299.85462) (xy 163.010527 -299.855515) (xy 163.018181 -299.856279)
			(xy 163.022026 -299.856144) (xy 163.02228 -299.856144) (xy 163.029985 -299.855448) (xy 163.044463 -299.850015)
			(xy 163.050728 -299.845476) (xy 163.114228 -299.7962) (xy 163.123051 -299.788607) (xy 163.133219 -299.767697)
			(xy 163.133786 -299.756068) (xy 163.133786 -298.697396) (xy 163.133362 -298.687326) (xy 163.125645 -298.668724)
			(xy 163.1188 -298.661328) (xy 163.053776 -298.596304) (xy 163.027614 -298.589446) (xy 163.014152 -298.593256)
			(xy 162.992368 -298.598945) (xy 162.947763 -298.605069) (xy 162.925252 -298.605448) (xy 162.924744 -298.605448)
			(xy 162.895474 -298.604818) (xy 162.837847 -298.594514) (xy 162.78293 -298.574238) (xy 162.757358 -298.559982)
			(xy 162.75177 -298.55668) (xy 162.731958 -298.551092) (xy 162.717988 -298.54906) (xy 162.182048 -298.54906)
			(xy 162.168078 -298.551092) (xy 162.148266 -298.55668) (xy 162.142678 -298.559982) (xy 162.117115 -298.574258)
			(xy 162.062197 -298.594539) (xy 162.004564 -298.60483) (xy 161.975292 -298.605448) (xy 161.974784 -298.605448)
			(xy 161.945513 -298.604821) (xy 161.887883 -298.594524) (xy 161.832962 -298.574253) (xy 161.807398 -298.559982)
			(xy 161.80181 -298.55668) (xy 161.781998 -298.551092) (xy 161.768028 -298.54906) (xy 161.232088 -298.54906)
			(xy 161.218118 -298.551092) (xy 161.198306 -298.55668) (xy 161.192718 -298.559982) (xy 161.167156 -298.574261)
			(xy 161.112238 -298.594548) (xy 161.054605 -298.604847) (xy 161.025332 -298.605448) (xy 161.024824 -298.605448)
			(xy 160.995554 -298.604816) (xy 160.937929 -298.594509) (xy 160.883014 -298.57423) (xy 160.857438 -298.559982)
			(xy 160.85185 -298.55668) (xy 160.832038 -298.551092) (xy 160.818068 -298.54906) (xy 160.281874 -298.54906)
			(xy 160.267904 -298.551092) (xy 160.248092 -298.55668) (xy 160.242504 -298.559982) (xy 160.216942 -298.57426)
			(xy 160.162023 -298.594545) (xy 160.104391 -298.604841) (xy 160.075118 -298.605448) (xy 160.07461 -298.605448)
			(xy 160.045338 -298.604823) (xy 159.987707 -298.59453) (xy 159.932783 -298.574263) (xy 159.907224 -298.559982)
			(xy 159.901636 -298.55668) (xy 159.881824 -298.551092) (xy 159.867854 -298.54906) (xy 158.381954 -298.54906)
			(xy 158.367984 -298.551092) (xy 158.348172 -298.55668) (xy 158.342584 -298.559982) (xy 158.317022 -298.574258)
			(xy 158.262103 -298.59454) (xy 158.20447 -298.604833) (xy 158.175198 -298.605448) (xy 158.17469 -298.605448)
			(xy 158.145419 -298.604822) (xy 158.087789 -298.594525) (xy 158.032867 -298.574255) (xy 158.007304 -298.559982)
			(xy 158.001716 -298.55668) (xy 157.981904 -298.551092) (xy 157.967934 -298.54906) (xy 157.431994 -298.54906)
			(xy 157.418024 -298.551092) (xy 157.398212 -298.55668) (xy 157.392624 -298.559982) (xy 157.367062 -298.574262)
			(xy 157.312144 -298.59455) (xy 157.254511 -298.60485) (xy 157.225238 -298.605448) (xy 157.22473 -298.605448)
			(xy 157.19546 -298.604817) (xy 157.137834 -298.594511) (xy 157.082919 -298.574233) (xy 157.057344 -298.559982)
			(xy 157.051756 -298.55668) (xy 157.031944 -298.551092) (xy 157.017974 -298.54906) (xy 156.482034 -298.54906)
			(xy 156.468064 -298.551092) (xy 156.448252 -298.55668) (xy 156.442664 -298.559982) (xy 156.417101 -298.574257)
			(xy 156.362182 -298.594535) (xy 156.30455 -298.604824) (xy 156.275278 -298.605448) (xy 156.27477 -298.605448)
			(xy 156.245499 -298.60482) (xy 156.187871 -298.59452) (xy 156.132951 -298.574248) (xy 156.107384 -298.559982)
			(xy 156.101796 -298.55668) (xy 156.081984 -298.551092) (xy 156.068014 -298.54906) (xy 155.532074 -298.54906)
			(xy 155.518104 -298.551092) (xy 155.498292 -298.55668) (xy 155.492704 -298.559982) (xy 155.467142 -298.57426)
			(xy 155.412223 -298.594545) (xy 155.354591 -298.604841) (xy 155.325318 -298.605448) (xy 155.32481 -298.605448)
			(xy 155.295538 -298.604823) (xy 155.237907 -298.59453) (xy 155.182983 -298.574263) (xy 155.157424 -298.559982)
			(xy 155.151836 -298.55668) (xy 155.132024 -298.551092) (xy 155.118054 -298.54906) (xy 154.58186 -298.54906)
			(xy 154.56789 -298.551092) (xy 154.548078 -298.55668) (xy 154.54249 -298.559982) (xy 154.516928 -298.574259)
			(xy 154.462009 -298.594542) (xy 154.404376 -298.604835) (xy 154.375104 -298.605448) (xy 154.374596 -298.605448)
			(xy 154.345325 -298.604822) (xy 154.287694 -298.594527) (xy 154.232772 -298.574258) (xy 154.20721 -298.559982)
			(xy 154.201622 -298.55668) (xy 154.18181 -298.551092) (xy 154.16784 -298.54906) (xy 153.631646 -298.54906)
			(xy 153.617676 -298.551092) (xy 153.597864 -298.55668) (xy 153.592276 -298.559982) (xy 153.566713 -298.574258)
			(xy 153.511794 -298.594538) (xy 153.454162 -298.604829) (xy 153.42489 -298.605448) (xy 153.424382 -298.605448)
			(xy 153.395111 -298.604821) (xy 153.337481 -298.594523) (xy 153.282561 -298.574252) (xy 153.256996 -298.559982)
			(xy 153.251408 -298.55668) (xy 153.231596 -298.551092) (xy 153.217626 -298.54906) (xy 147.96389 -298.54906)
			(xy 147.953822 -298.549487) (xy 147.935226 -298.55721) (xy 147.927822 -298.564046) (xy 147.89404 -298.597828)
			(xy 147.888106 -298.604323) (xy 147.880648 -298.620242) (xy 147.878981 -298.637743) (xy 147.880832 -298.646342)
			(xy 147.905978 -298.744132) (xy 147.92452 -298.763436) (xy 147.937474 -298.767246) (xy 147.963564 -298.775319)
			(xy 148.013295 -298.797889) (xy 148.0593 -298.827318) (xy 148.100641 -298.863004) (xy 148.136473 -298.904219)
			(xy 148.166064 -298.95012) (xy 148.18881 -298.999771) (xy 148.204246 -299.052157) (xy 148.212057 -299.106208)
			(xy 148.212556 -299.133514) (xy 148.212069 -299.160766) (xy 148.204311 -299.214715) (xy 148.201379 -299.2247)
			(xy 151.53404 -299.2247) (xy 151.538212 -299.174354) (xy 151.550614 -299.125381) (xy 151.570909 -299.079118)
			(xy 151.598541 -299.036827) (xy 151.632758 -298.999661) (xy 151.672626 -298.968634) (xy 151.717058 -298.944593)
			(xy 151.76484 -298.928193) (xy 151.814671 -298.919882) (xy 151.83993 -298.919392) (xy 151.865325 -298.919926)
			(xy 151.915413 -298.928333) (xy 151.96342 -298.944912) (xy 152.008023 -298.969204) (xy 152.047993 -299.000541)
			(xy 152.065482 -299.01896) (xy 152.073102 -299.027342) (xy 152.093168 -299.035724) (xy 152.192482 -299.033184)
			(xy 152.211786 -299.023786) (xy 152.219152 -299.014896) (xy 152.234926 -298.996339) (xy 152.271023 -298.963642)
			(xy 152.311522 -298.936588) (xy 152.355548 -298.915761) (xy 152.402151 -298.90161) (xy 152.450324 -298.89444)
			(xy 152.474676 -298.893992) (xy 153.424636 -298.893992) (xy 153.450638 -298.894597) (xy 153.502 -298.902737)
			(xy 153.551457 -298.918811) (xy 153.59779 -298.942424) (xy 153.63986 -298.972993) (xy 153.67663 -299.009767)
			(xy 153.707195 -299.05184) (xy 153.730803 -299.098177) (xy 153.746871 -299.147635) (xy 153.755006 -299.198998)
			(xy 153.755006 -299.224954) (xy 154.069046 -299.224954) (xy 154.073006 -299.1759) (xy 154.084783 -299.128116)
			(xy 154.104074 -299.08284) (xy 154.130377 -299.041244) (xy 154.163012 -299.004407) (xy 154.201133 -298.973282)
			(xy 154.243754 -298.948675) (xy 154.28977 -298.931223) (xy 154.337989 -298.921379) (xy 154.387164 -298.919398)
			(xy 154.436019 -298.92533) (xy 154.48329 -298.939022) (xy 154.527752 -298.96012) (xy 154.568255 -298.988076)
			(xy 154.603748 -299.022168) (xy 154.633313 -299.061512) (xy 154.656184 -299.105089) (xy 154.671768 -299.15177)
			(xy 154.679663 -299.200347) (xy 154.680158 -299.224954) (xy 154.679663 -299.249561) (xy 154.679428 -299.251009)
			(xy 154.994602 -299.251009) (xy 154.994602 -299.198991) (xy 155.002739 -299.147613) (xy 155.018812 -299.098141)
			(xy 155.042426 -299.051792) (xy 155.073 -299.009707) (xy 155.10978 -298.972923) (xy 155.151861 -298.942345)
			(xy 155.198208 -298.918726) (xy 155.247678 -298.902647) (xy 155.299055 -298.894505) (xy 155.325064 -298.893992)
			(xy 156.275024 -298.893992) (xy 156.301026 -298.894596) (xy 156.35239 -298.902735) (xy 156.401848 -298.918808)
			(xy 156.448184 -298.94242) (xy 156.490255 -298.972989) (xy 156.527026 -299.009763) (xy 156.557593 -299.051837)
			(xy 156.581201 -299.098174) (xy 156.597271 -299.147633) (xy 156.605406 -299.198998) (xy 156.605406 -299.224954)
			(xy 156.91918 -299.224954) (xy 156.92314 -299.1759) (xy 156.934917 -299.128116) (xy 156.954208 -299.08284)
			(xy 156.980511 -299.041244) (xy 157.013146 -299.004407) (xy 157.051267 -298.973282) (xy 157.093888 -298.948675)
			(xy 157.139904 -298.931223) (xy 157.188123 -298.921379) (xy 157.237298 -298.919398) (xy 157.286153 -298.92533)
			(xy 157.333424 -298.939022) (xy 157.377886 -298.96012) (xy 157.418389 -298.988076) (xy 157.453882 -299.022168)
			(xy 157.483447 -299.061512) (xy 157.506318 -299.105089) (xy 157.521902 -299.15177) (xy 157.529797 -299.200347)
			(xy 157.530287 -299.2247) (xy 157.86914 -299.2247) (xy 157.8731 -299.175646) (xy 157.884877 -299.127862)
			(xy 157.904168 -299.082586) (xy 157.930471 -299.04099) (xy 157.963106 -299.004153) (xy 158.001227 -298.973028)
			(xy 158.043848 -298.948421) (xy 158.089864 -298.930969) (xy 158.138083 -298.921125) (xy 158.187258 -298.919144)
			(xy 158.236113 -298.925076) (xy 158.283384 -298.938768) (xy 158.327846 -298.959866) (xy 158.368349 -298.987822)
			(xy 158.403842 -299.021914) (xy 158.433407 -299.061258) (xy 158.456278 -299.104835) (xy 158.471862 -299.151516)
			(xy 158.479757 -299.200093) (xy 158.480252 -299.2247) (xy 158.480247 -299.224954) (xy 159.76906 -299.224954)
			(xy 159.77302 -299.1759) (xy 159.784797 -299.128116) (xy 159.804088 -299.08284) (xy 159.830391 -299.041244)
			(xy 159.863026 -299.004407) (xy 159.901147 -298.973282) (xy 159.943768 -298.948675) (xy 159.989784 -298.931223)
			(xy 160.038003 -298.921379) (xy 160.087178 -298.919398) (xy 160.136033 -298.92533) (xy 160.183304 -298.939022)
			(xy 160.227766 -298.96012) (xy 160.268269 -298.988076) (xy 160.303762 -299.022168) (xy 160.333327 -299.061512)
			(xy 160.356198 -299.105089) (xy 160.371782 -299.15177) (xy 160.379677 -299.200347) (xy 160.380172 -299.224954)
			(xy 160.719274 -299.224954) (xy 160.723234 -299.1759) (xy 160.735011 -299.128116) (xy 160.754302 -299.08284)
			(xy 160.780605 -299.041244) (xy 160.81324 -299.004407) (xy 160.851361 -298.973282) (xy 160.893982 -298.948675)
			(xy 160.939998 -298.931223) (xy 160.988217 -298.921379) (xy 161.037392 -298.919398) (xy 161.086247 -298.92533)
			(xy 161.133518 -298.939022) (xy 161.17798 -298.96012) (xy 161.218483 -298.988076) (xy 161.253976 -299.022168)
			(xy 161.283541 -299.061512) (xy 161.306412 -299.105089) (xy 161.321996 -299.15177) (xy 161.329891 -299.200347)
			(xy 161.330386 -299.224954) (xy 161.669234 -299.224954) (xy 161.673194 -299.1759) (xy 161.684971 -299.128116)
			(xy 161.704262 -299.08284) (xy 161.730565 -299.041244) (xy 161.7632 -299.004407) (xy 161.801321 -298.973282)
			(xy 161.843942 -298.948675) (xy 161.889958 -298.931223) (xy 161.938177 -298.921379) (xy 161.987352 -298.919398)
			(xy 162.036207 -298.92533) (xy 162.083478 -298.939022) (xy 162.12794 -298.96012) (xy 162.168443 -298.988076)
			(xy 162.203936 -299.022168) (xy 162.233501 -299.061512) (xy 162.256372 -299.105089) (xy 162.271956 -299.15177)
			(xy 162.279851 -299.200347) (xy 162.280346 -299.224954) (xy 162.279851 -299.249561) (xy 162.271956 -299.298138)
			(xy 162.256372 -299.344819) (xy 162.233501 -299.388396) (xy 162.203936 -299.42774) (xy 162.168443 -299.461832)
			(xy 162.12794 -299.489788) (xy 162.083478 -299.510886) (xy 162.036207 -299.524578) (xy 161.987352 -299.53051)
			(xy 161.938177 -299.528529) (xy 161.889958 -299.518685) (xy 161.843942 -299.501233) (xy 161.801321 -299.476626)
			(xy 161.7632 -299.445501) (xy 161.730565 -299.408664) (xy 161.704262 -299.367068) (xy 161.684971 -299.321792)
			(xy 161.673194 -299.274008) (xy 161.669234 -299.224954) (xy 161.330386 -299.224954) (xy 161.329891 -299.249561)
			(xy 161.321996 -299.298138) (xy 161.306412 -299.344819) (xy 161.283541 -299.388396) (xy 161.253976 -299.42774)
			(xy 161.218483 -299.461832) (xy 161.17798 -299.489788) (xy 161.133518 -299.510886) (xy 161.086247 -299.524578)
			(xy 161.037392 -299.53051) (xy 160.988217 -299.528529) (xy 160.939998 -299.518685) (xy 160.893982 -299.501233)
			(xy 160.851361 -299.476626) (xy 160.81324 -299.445501) (xy 160.780605 -299.408664) (xy 160.754302 -299.367068)
			(xy 160.735011 -299.321792) (xy 160.723234 -299.274008) (xy 160.719274 -299.224954) (xy 160.380172 -299.224954)
			(xy 160.379677 -299.249561) (xy 160.371782 -299.298138) (xy 160.356198 -299.344819) (xy 160.333327 -299.388396)
			(xy 160.303762 -299.42774) (xy 160.268269 -299.461832) (xy 160.227766 -299.489788) (xy 160.183304 -299.510886)
			(xy 160.136033 -299.524578) (xy 160.087178 -299.53051) (xy 160.038003 -299.528529) (xy 159.989784 -299.518685)
			(xy 159.943768 -299.501233) (xy 159.901147 -299.476626) (xy 159.863026 -299.445501) (xy 159.830391 -299.408664)
			(xy 159.804088 -299.367068) (xy 159.784797 -299.321792) (xy 159.77302 -299.274008) (xy 159.76906 -299.224954)
			(xy 158.480247 -299.224954) (xy 158.479757 -299.249307) (xy 158.471862 -299.297884) (xy 158.456278 -299.344565)
			(xy 158.433407 -299.388142) (xy 158.403842 -299.427486) (xy 158.368349 -299.461578) (xy 158.327846 -299.489534)
			(xy 158.283384 -299.510632) (xy 158.236113 -299.524324) (xy 158.187258 -299.530256) (xy 158.138083 -299.528275)
			(xy 158.089864 -299.518431) (xy 158.043848 -299.500979) (xy 158.001227 -299.476372) (xy 157.963106 -299.445247)
			(xy 157.930471 -299.40841) (xy 157.904168 -299.366814) (xy 157.884877 -299.321538) (xy 157.8731 -299.273754)
			(xy 157.86914 -299.2247) (xy 157.530287 -299.2247) (xy 157.530292 -299.224954) (xy 157.529797 -299.249561)
			(xy 157.521902 -299.298138) (xy 157.506318 -299.344819) (xy 157.483447 -299.388396) (xy 157.453882 -299.42774)
			(xy 157.418389 -299.461832) (xy 157.377886 -299.489788) (xy 157.333424 -299.510886) (xy 157.286153 -299.524578)
			(xy 157.237298 -299.53051) (xy 157.188123 -299.528529) (xy 157.139904 -299.518685) (xy 157.093888 -299.501233)
			(xy 157.051267 -299.476626) (xy 157.013146 -299.445501) (xy 156.980511 -299.408664) (xy 156.954208 -299.367068)
			(xy 156.934917 -299.321792) (xy 156.92314 -299.274008) (xy 156.91918 -299.224954) (xy 156.605406 -299.224954)
			(xy 156.605406 -299.251002) (xy 156.597271 -299.302367) (xy 156.581201 -299.351826) (xy 156.557593 -299.398163)
			(xy 156.527026 -299.440237) (xy 156.490255 -299.477011) (xy 156.448184 -299.50758) (xy 156.401848 -299.531192)
			(xy 156.35239 -299.547265) (xy 156.301026 -299.555404) (xy 156.275024 -299.555916) (xy 156.204666 -299.555916)
			(xy 156.194039 -299.556515) (xy 156.17462 -299.565174) (xy 156.167074 -299.57268) (xy 156.109162 -299.636942)
			(xy 156.102558 -299.657008) (xy 156.103574 -299.66793) (xy 156.105352 -299.699934) (xy 156.10483 -299.725189)
			(xy 156.096517 -299.775011) (xy 156.080116 -299.822785) (xy 156.056075 -299.867208) (xy 156.025051 -299.907068)
			(xy 155.987889 -299.941278) (xy 155.945603 -299.968904) (xy 155.899347 -299.989194) (xy 155.850382 -300.001594)
			(xy 155.800044 -300.005765) (xy 155.749706 -300.001594) (xy 155.700741 -299.989194) (xy 155.654485 -299.968904)
			(xy 155.612199 -299.941278) (xy 155.575037 -299.907068) (xy 155.544013 -299.867208) (xy 155.519972 -299.822785)
			(xy 155.503571 -299.775011) (xy 155.495258 -299.725189) (xy 155.494736 -299.699934) (xy 155.496514 -299.66793)
			(xy 155.49753 -299.657008) (xy 155.490926 -299.636942) (xy 155.433014 -299.57268) (xy 155.425538 -299.56507)
			(xy 155.406079 -299.55638) (xy 155.395422 -299.555916) (xy 155.325064 -299.555916) (xy 155.299055 -299.555495)
			(xy 155.247678 -299.547353) (xy 155.198208 -299.531274) (xy 155.151861 -299.507655) (xy 155.10978 -299.477077)
			(xy 155.073 -299.440293) (xy 155.042426 -299.398208) (xy 155.018812 -299.351859) (xy 155.002739 -299.302387)
			(xy 154.994602 -299.251009) (xy 154.679428 -299.251009) (xy 154.671768 -299.298138) (xy 154.656184 -299.344819)
			(xy 154.633313 -299.388396) (xy 154.603748 -299.42774) (xy 154.568255 -299.461832) (xy 154.527752 -299.489788)
			(xy 154.48329 -299.510886) (xy 154.436019 -299.524578) (xy 154.387164 -299.53051) (xy 154.337989 -299.528529)
			(xy 154.28977 -299.518685) (xy 154.243754 -299.501233) (xy 154.201133 -299.476626) (xy 154.163012 -299.445501)
			(xy 154.130377 -299.408664) (xy 154.104074 -299.367068) (xy 154.084783 -299.321792) (xy 154.073006 -299.274008)
			(xy 154.069046 -299.224954) (xy 153.755006 -299.224954) (xy 153.755006 -299.251002) (xy 153.746871 -299.302365)
			(xy 153.730803 -299.351823) (xy 153.707195 -299.39816) (xy 153.67663 -299.440233) (xy 153.63986 -299.477007)
			(xy 153.59779 -299.507576) (xy 153.551457 -299.531189) (xy 153.502 -299.547263) (xy 153.450638 -299.555403)
			(xy 153.424636 -299.555916) (xy 152.474676 -299.555916) (xy 152.450291 -299.555513) (xy 152.402052 -299.548333)
			(xy 152.355391 -299.534148) (xy 152.311318 -299.513264) (xy 152.27079 -299.486135) (xy 152.234684 -299.453349)
			(xy 152.218898 -299.434758) (xy 152.211786 -299.426122) (xy 152.192228 -299.41647) (xy 152.092914 -299.41393)
			(xy 152.072848 -299.422312) (xy 152.065228 -299.430694) (xy 152.047764 -299.449091) (xy 152.007828 -299.480363)
			(xy 151.96327 -299.5046) (xy 151.915318 -299.521135) (xy 151.865292 -299.529511) (xy 151.83993 -299.530008)
			(xy 151.814671 -299.529518) (xy 151.76484 -299.521207) (xy 151.717058 -299.504807) (xy 151.672626 -299.480766)
			(xy 151.632758 -299.449739) (xy 151.598541 -299.412573) (xy 151.570909 -299.370282) (xy 151.550614 -299.324019)
			(xy 151.538212 -299.275046) (xy 151.53404 -299.2247) (xy 148.201379 -299.2247) (xy 148.188956 -299.26701)
			(xy 148.166314 -299.316589) (xy 148.136848 -299.362441) (xy 148.101158 -299.403634) (xy 148.059968 -299.439328)
			(xy 148.014119 -299.468798) (xy 147.964542 -299.491444) (xy 147.912248 -299.506804) (xy 147.8583 -299.514567)
			(xy 147.831048 -299.515022) (xy 147.806581 -299.514626) (xy 147.758046 -299.508381) (xy 147.734274 -299.502576)
			(xy 147.731226 -299.501814) (xy 147.724876 -299.500798) (xy 147.714869 -299.499919) (xy 147.695492 -299.505165)
			(xy 147.687284 -299.510958) (xy 147.62353 -299.559726) (xy 147.614659 -299.567307) (xy 147.604329 -299.588206)
			(xy 147.603718 -299.599858) (xy 147.603718 -299.895514) (xy 149.72106 -299.895514) (xy 149.725131 -299.839892)
			(xy 149.737257 -299.785455) (xy 149.75718 -299.733364) (xy 149.784476 -299.684729) (xy 149.818562 -299.640586)
			(xy 149.858711 -299.601877) (xy 149.904069 -299.569426) (xy 149.953669 -299.543925) (xy 150.006453 -299.525918)
			(xy 150.061296 -299.515788) (xy 150.11703 -299.513751) (xy 150.172467 -299.519851) (xy 150.226424 -299.533957)
			(xy 150.277753 -299.555769) (xy 150.325359 -299.584823) (xy 150.368227 -299.620498) (xy 150.405444 -299.662035)
			(xy 150.436217 -299.708548) (xy 150.459889 -299.759045) (xy 150.475957 -299.812452) (xy 150.484077 -299.867628)
			(xy 150.484586 -299.895514) (xy 150.484077 -299.9234) (xy 150.475957 -299.978576) (xy 150.459889 -300.031983)
			(xy 150.436217 -300.08248) (xy 150.405444 -300.128993) (xy 150.368227 -300.17053) (xy 150.325359 -300.206205)
			(xy 150.277753 -300.235259) (xy 150.226424 -300.257071) (xy 150.172467 -300.271177) (xy 150.11703 -300.277277)
			(xy 150.061296 -300.27524) (xy 150.006453 -300.26511) (xy 149.953669 -300.247103) (xy 149.904069 -300.221602)
			(xy 149.858711 -300.189151) (xy 149.818562 -300.150442) (xy 149.784476 -300.106299) (xy 149.75718 -300.057664)
			(xy 149.737257 -300.005573) (xy 149.725131 -299.951136) (xy 149.72106 -299.895514) (xy 147.603718 -299.895514)
			(xy 147.603718 -300.604936) (xy 147.604148 -300.615003) (xy 147.611874 -300.633596) (xy 147.618704 -300.641004)
			(xy 147.843494 -300.865794) (xy 147.850892 -300.872642) (xy 147.86949 -300.88038) (xy 147.879562 -300.88078)
		)
		(stroke
			(width 0)
			(type solid)
		)
		(fill yes)
		(layer "In5.Cu")
		(net "PCEPLL1_VDDA18_PEX1")
	)
	(gr_poly
		(pts
			(xy 152.169114 -298.267882) (xy 152.170638 -298.24807) (xy 152.17335 -298.223024) (xy 152.185922 -298.174243)
			(xy 152.206328 -298.128186) (xy 152.234013 -298.086101) (xy 152.268229 -298.04913) (xy 152.308047 -298.018273)
			(xy 152.352388 -297.994367) (xy 152.400051 -297.978061) (xy 152.449743 -297.969795) (xy 152.500117 -297.969795)
			(xy 152.549809 -297.978061) (xy 152.597472 -297.994367) (xy 152.641813 -298.018273) (xy 152.681631 -298.04913)
			(xy 152.715847 -298.086101) (xy 152.743532 -298.128186) (xy 152.763938 -298.174243) (xy 152.77651 -298.223024)
			(xy 152.779222 -298.24807) (xy 152.780746 -298.267882) (xy 152.809702 -298.294552) (xy 153.06421 -298.294552)
			(xy 153.09342 -298.267628) (xy 153.094944 -298.247816) (xy 153.09756 -298.222001) (xy 153.109805 -298.171581)
			(xy 153.129771 -298.123692) (xy 153.15697 -298.079508) (xy 153.190734 -298.040112) (xy 153.230234 -298.00647)
			(xy 153.274503 -297.979408) (xy 153.322453 -297.95959) (xy 153.37291 -297.947501) (xy 153.424636 -297.943438)
			(xy 153.476362 -297.947501) (xy 153.526819 -297.95959) (xy 153.574769 -297.979408) (xy 153.619038 -298.00647)
			(xy 153.658538 -298.040112) (xy 153.692302 -298.079508) (xy 153.719501 -298.123692) (xy 153.739467 -298.171581)
			(xy 153.751712 -298.222001) (xy 153.754328 -298.247816) (xy 153.755852 -298.267628) (xy 153.785062 -298.294552)
			(xy 154.014424 -298.294552) (xy 154.043634 -298.267628) (xy 154.045158 -298.247816) (xy 154.047774 -298.222001)
			(xy 154.060019 -298.171581) (xy 154.079985 -298.123692) (xy 154.107184 -298.079508) (xy 154.140948 -298.040112)
			(xy 154.180448 -298.00647) (xy 154.224717 -297.979408) (xy 154.272667 -297.95959) (xy 154.323124 -297.947501)
			(xy 154.37485 -297.943438) (xy 154.426576 -297.947501) (xy 154.477033 -297.95959) (xy 154.524983 -297.979408)
			(xy 154.569252 -298.00647) (xy 154.608752 -298.040112) (xy 154.642516 -298.079508) (xy 154.669715 -298.123692)
			(xy 154.689681 -298.171581) (xy 154.701926 -298.222001) (xy 154.704542 -298.247816) (xy 154.706066 -298.267628)
			(xy 154.735276 -298.294552) (xy 154.964638 -298.294552) (xy 154.993848 -298.267628) (xy 154.995372 -298.247816)
			(xy 154.997988 -298.222001) (xy 155.010233 -298.171581) (xy 155.030199 -298.123692) (xy 155.057398 -298.079508)
			(xy 155.091162 -298.040112) (xy 155.130662 -298.00647) (xy 155.174931 -297.979408) (xy 155.222881 -297.95959)
			(xy 155.273338 -297.947501) (xy 155.325064 -297.943438) (xy 155.37679 -297.947501) (xy 155.427247 -297.95959)
			(xy 155.475197 -297.979408) (xy 155.519466 -298.00647) (xy 155.558966 -298.040112) (xy 155.59273 -298.079508)
			(xy 155.619929 -298.123692) (xy 155.639895 -298.171581) (xy 155.65214 -298.222001) (xy 155.654756 -298.247816)
			(xy 155.65628 -298.267628) (xy 155.68549 -298.294552) (xy 155.914598 -298.294552) (xy 155.943808 -298.267628)
			(xy 155.945332 -298.247816) (xy 155.947948 -298.222001) (xy 155.960193 -298.171581) (xy 155.980159 -298.123692)
			(xy 156.007358 -298.079508) (xy 156.041122 -298.040112) (xy 156.080622 -298.00647) (xy 156.124891 -297.979408)
			(xy 156.172841 -297.95959) (xy 156.223298 -297.947501) (xy 156.275024 -297.943438) (xy 156.32675 -297.947501)
			(xy 156.377207 -297.95959) (xy 156.425157 -297.979408) (xy 156.469426 -298.00647) (xy 156.508926 -298.040112)
			(xy 156.54269 -298.079508) (xy 156.569889 -298.123692) (xy 156.589855 -298.171581) (xy 156.6021 -298.222001)
			(xy 156.604716 -298.247816) (xy 156.60624 -298.267628) (xy 156.63545 -298.294552) (xy 156.864558 -298.294552)
			(xy 156.893768 -298.267628) (xy 156.895292 -298.247816) (xy 156.897908 -298.222001) (xy 156.910153 -298.171581)
			(xy 156.930119 -298.123692) (xy 156.957318 -298.079508) (xy 156.991082 -298.040112) (xy 157.030582 -298.00647)
			(xy 157.074851 -297.979408) (xy 157.122801 -297.95959) (xy 157.173258 -297.947501) (xy 157.224984 -297.943438)
			(xy 157.27671 -297.947501) (xy 157.327167 -297.95959) (xy 157.375117 -297.979408) (xy 157.419386 -298.00647)
			(xy 157.458886 -298.040112) (xy 157.49265 -298.079508) (xy 157.519849 -298.123692) (xy 157.539815 -298.171581)
			(xy 157.55206 -298.222001) (xy 157.554676 -298.247816) (xy 157.5562 -298.267628) (xy 157.58541 -298.294552)
			(xy 157.814518 -298.294552) (xy 157.843728 -298.267628) (xy 157.845252 -298.247816) (xy 157.847868 -298.222001)
			(xy 157.860113 -298.171581) (xy 157.880079 -298.123692) (xy 157.907278 -298.079508) (xy 157.941042 -298.040112)
			(xy 157.980542 -298.00647) (xy 158.024811 -297.979408) (xy 158.072761 -297.95959) (xy 158.123218 -297.947501)
			(xy 158.174944 -297.943438) (xy 158.22667 -297.947501) (xy 158.277127 -297.95959) (xy 158.325077 -297.979408)
			(xy 158.369346 -298.00647) (xy 158.408846 -298.040112) (xy 158.44261 -298.079508) (xy 158.469809 -298.123692)
			(xy 158.489775 -298.171581) (xy 158.50202 -298.222001) (xy 158.504636 -298.247816) (xy 158.50616 -298.267628)
			(xy 158.53537 -298.294552) (xy 158.790132 -298.294552) (xy 158.819088 -298.267882) (xy 158.820866 -298.24807)
			(xy 158.823578 -298.223046) (xy 158.836142 -298.174309) (xy 158.856532 -298.128294) (xy 158.884196 -298.086248)
			(xy 158.918383 -298.04931) (xy 158.958167 -298.018482) (xy 159.00247 -297.994599) (xy 159.05009 -297.978307)
			(xy 159.099739 -297.97005) (xy 159.150069 -297.97005) (xy 159.199718 -297.978307) (xy 159.247338 -297.994599)
			(xy 159.291641 -298.018482) (xy 159.331425 -298.04931) (xy 159.365612 -298.086248) (xy 159.393276 -298.128294)
			(xy 159.413666 -298.174309) (xy 159.42623 -298.223046) (xy 159.428942 -298.24807) (xy 159.43072 -298.267882)
			(xy 159.459676 -298.294552) (xy 159.714438 -298.294552) (xy 159.743648 -298.267628) (xy 159.745172 -298.247816)
			(xy 159.747788 -298.222001) (xy 159.760033 -298.171581) (xy 159.779999 -298.123692) (xy 159.807198 -298.079508)
			(xy 159.840962 -298.040112) (xy 159.880462 -298.00647) (xy 159.924731 -297.979408) (xy 159.972681 -297.95959)
			(xy 160.023138 -297.947501) (xy 160.074864 -297.943438) (xy 160.12659 -297.947501) (xy 160.177047 -297.95959)
			(xy 160.224997 -297.979408) (xy 160.269266 -298.00647) (xy 160.308766 -298.040112) (xy 160.34253 -298.079508)
			(xy 160.369729 -298.123692) (xy 160.389695 -298.171581) (xy 160.40194 -298.222001) (xy 160.404556 -298.247816)
			(xy 160.40608 -298.267628) (xy 160.43529 -298.294552) (xy 160.664652 -298.294552) (xy 160.693862 -298.267628)
			(xy 160.695386 -298.247816) (xy 160.698002 -298.222001) (xy 160.710247 -298.171581) (xy 160.730213 -298.123692)
			(xy 160.757412 -298.079508) (xy 160.791176 -298.040112) (xy 160.830676 -298.00647) (xy 160.874945 -297.979408)
			(xy 160.922895 -297.95959) (xy 160.973352 -297.947501) (xy 161.025078 -297.943438) (xy 161.076804 -297.947501)
			(xy 161.127261 -297.95959) (xy 161.175211 -297.979408) (xy 161.21948 -298.00647) (xy 161.25898 -298.040112)
			(xy 161.292744 -298.079508) (xy 161.319943 -298.123692) (xy 161.339909 -298.171581) (xy 161.352154 -298.222001)
			(xy 161.35477 -298.247816) (xy 161.356294 -298.267628) (xy 161.385504 -298.294552) (xy 161.614612 -298.294552)
			(xy 161.643822 -298.267628) (xy 161.645346 -298.247816) (xy 161.647962 -298.222001) (xy 161.660207 -298.171581)
			(xy 161.680173 -298.123692) (xy 161.707372 -298.079508) (xy 161.741136 -298.040112) (xy 161.780636 -298.00647)
			(xy 161.824905 -297.979408) (xy 161.872855 -297.95959) (xy 161.923312 -297.947501) (xy 161.975038 -297.943438)
			(xy 162.026764 -297.947501) (xy 162.077221 -297.95959) (xy 162.125171 -297.979408) (xy 162.16944 -298.00647)
			(xy 162.20894 -298.040112) (xy 162.242704 -298.079508) (xy 162.269903 -298.123692) (xy 162.289869 -298.171581)
			(xy 162.302114 -298.222001) (xy 162.30473 -298.247816) (xy 162.306254 -298.267628) (xy 162.335464 -298.294552)
			(xy 162.564572 -298.294552) (xy 162.593782 -298.267628) (xy 162.595306 -298.247816) (xy 162.597763 -298.223291)
			(xy 162.609016 -298.175307) (xy 162.627266 -298.129524) (xy 162.65211 -298.086957) (xy 162.682996 -298.048549)
			(xy 162.719241 -298.01515) (xy 162.760041 -297.987501) (xy 162.804493 -297.966214) (xy 162.851612 -297.951759)
			(xy 162.900355 -297.944459) (xy 162.924998 -297.944032) (xy 162.954472 -297.944703) (xy 163.012479 -297.955195)
			(xy 163.067711 -297.975794) (xy 163.0934 -297.99026) (xy 163.105338 -297.997118) (xy 163.132516 -297.997372)
			(xy 163.221162 -297.946826) (xy 163.228768 -297.942092) (xy 163.240318 -297.92841) (xy 163.246438 -297.911584)
			(xy 163.246816 -297.90263) (xy 163.246816 -296.74693) (xy 163.246461 -296.737979) (xy 163.240304 -296.721167)
			(xy 163.228759 -296.707482) (xy 163.221162 -296.702734) (xy 163.132516 -296.652188) (xy 163.105084 -296.652442)
			(xy 163.0934 -296.6593) (xy 163.067716 -296.673775) (xy 163.012483 -296.694373) (xy 162.954472 -296.704856)
			(xy 162.924998 -296.705528) (xy 162.89901 -296.705018) (xy 162.847675 -296.696888) (xy 162.798243 -296.680827)
			(xy 162.751933 -296.657231) (xy 162.709883 -296.626682) (xy 162.67313 -296.589931) (xy 162.642578 -296.547883)
			(xy 162.61898 -296.501573) (xy 162.602917 -296.452143) (xy 162.594783 -296.400808) (xy 162.59429 -296.37482)
			(xy 162.594799 -296.349316) (xy 162.602705 -296.298922) (xy 162.610038 -296.27449) (xy 162.613848 -296.262806)
			(xy 162.610038 -296.23893) (xy 162.554158 -296.16273) (xy 162.547059 -296.153733) (xy 162.526957 -296.142773)
			(xy 162.51555 -296.141648) (xy 162.387026 -296.141648) (xy 162.384486 -296.141648) (xy 162.373121 -296.142904)
			(xy 162.353075 -296.153845) (xy 162.345878 -296.16273) (xy 162.299904 -296.225722) (xy 162.295345 -296.232361)
			(xy 162.290292 -296.247645) (xy 162.289998 -296.255694) (xy 162.289998 -296.274236) (xy 162.29203 -296.281348)
			(xy 162.298393 -296.304192) (xy 162.305272 -296.351111) (xy 162.305746 -296.37482) (xy 162.305236 -296.400807)
			(xy 162.297106 -296.452142) (xy 162.281045 -296.501572) (xy 162.257449 -296.547882) (xy 162.226899 -296.58993)
			(xy 162.190148 -296.626681) (xy 162.1481 -296.657231) (xy 162.10179 -296.680827) (xy 162.05236 -296.696888)
			(xy 162.001025 -296.705018) (xy 161.949051 -296.705018) (xy 161.897716 -296.696888) (xy 161.848286 -296.680827)
			(xy 161.801976 -296.657231) (xy 161.759928 -296.626681) (xy 161.723177 -296.58993) (xy 161.692627 -296.547882)
			(xy 161.669031 -296.501572) (xy 161.65297 -296.452142) (xy 161.64484 -296.400807) (xy 161.64433 -296.37482)
			(xy 161.644839 -296.349316) (xy 161.652743 -296.298922) (xy 161.660078 -296.27449) (xy 161.663888 -296.262806)
			(xy 161.660078 -296.23893) (xy 161.604198 -296.16273) (xy 161.597101 -296.153727) (xy 161.577001 -296.142751)
			(xy 161.56559 -296.141648) (xy 161.437066 -296.141648) (xy 161.434526 -296.141648) (xy 161.423156 -296.142897)
			(xy 161.403098 -296.153829) (xy 161.395918 -296.16273) (xy 161.349944 -296.225722) (xy 161.34539 -296.232363)
			(xy 161.340343 -296.247647) (xy 161.340038 -296.255694) (xy 161.340038 -296.274236) (xy 161.34207 -296.281348)
			(xy 161.348432 -296.304192) (xy 161.35531 -296.351111) (xy 161.355786 -296.37482) (xy 161.355276 -296.400807)
			(xy 161.347146 -296.452142) (xy 161.331085 -296.501572) (xy 161.307489 -296.547882) (xy 161.276939 -296.58993)
			(xy 161.240188 -296.626681) (xy 161.19814 -296.657231) (xy 161.15183 -296.680827) (xy 161.1024 -296.696888)
			(xy 161.051065 -296.705018) (xy 160.999091 -296.705018) (xy 160.947756 -296.696888) (xy 160.898326 -296.680827)
			(xy 160.852016 -296.657231) (xy 160.809968 -296.626681) (xy 160.773217 -296.58993) (xy 160.742667 -296.547882)
			(xy 160.719071 -296.501572) (xy 160.70301 -296.452142) (xy 160.69488 -296.400807) (xy 160.69437 -296.37482)
			(xy 160.694879 -296.349316) (xy 160.702784 -296.298922) (xy 160.710118 -296.27449) (xy 160.713928 -296.262806)
			(xy 160.710118 -296.23893) (xy 160.654238 -296.16273) (xy 160.647144 -296.153721) (xy 160.627045 -296.142729)
			(xy 160.61563 -296.141648) (xy 160.486852 -296.141648) (xy 160.484312 -296.141648) (xy 160.472944 -296.142899)
			(xy 160.45289 -296.153834) (xy 160.445704 -296.16273) (xy 160.39973 -296.225722) (xy 160.395177 -296.232364)
			(xy 160.390132 -296.247647) (xy 160.389824 -296.255694) (xy 160.389824 -296.274236) (xy 160.391856 -296.281348)
			(xy 160.398218 -296.304192) (xy 160.405097 -296.351111) (xy 160.405572 -296.37482) (xy 160.405062 -296.400807)
			(xy 160.396932 -296.452142) (xy 160.380871 -296.501572) (xy 160.357275 -296.547882) (xy 160.326725 -296.58993)
			(xy 160.289974 -296.626681) (xy 160.247926 -296.657231) (xy 160.201616 -296.680827) (xy 160.152186 -296.696888)
			(xy 160.100851 -296.705018) (xy 160.048877 -296.705018) (xy 159.997542 -296.696888) (xy 159.948112 -296.680827)
			(xy 159.901802 -296.657231) (xy 159.859754 -296.626681) (xy 159.823003 -296.58993) (xy 159.792453 -296.547882)
			(xy 159.768857 -296.501572) (xy 159.752796 -296.452142) (xy 159.744666 -296.400807) (xy 159.744156 -296.37482)
			(xy 159.744665 -296.349316) (xy 159.75257 -296.298922) (xy 159.759904 -296.27449) (xy 159.763714 -296.262806)
			(xy 159.759904 -296.23893) (xy 159.704024 -296.16273) (xy 159.696929 -296.153723) (xy 159.676829 -296.142737)
			(xy 159.665416 -296.141648) (xy 158.586932 -296.141648) (xy 158.584392 -296.141648) (xy 158.573026 -296.142903)
			(xy 158.552979 -296.153843) (xy 158.545784 -296.16273) (xy 158.49981 -296.225722) (xy 158.495251 -296.232362)
			(xy 158.490198 -296.247645) (xy 158.489904 -296.255694) (xy 158.489904 -296.274236) (xy 158.491936 -296.281348)
			(xy 158.498299 -296.304192) (xy 158.505178 -296.351111) (xy 158.505652 -296.37482) (xy 158.505142 -296.400807)
			(xy 158.497012 -296.452142) (xy 158.480951 -296.501572) (xy 158.457355 -296.547882) (xy 158.426805 -296.58993)
			(xy 158.390054 -296.626681) (xy 158.348006 -296.657231) (xy 158.301696 -296.680827) (xy 158.252266 -296.696888)
			(xy 158.200931 -296.705018) (xy 158.148957 -296.705018) (xy 158.097622 -296.696888) (xy 158.048192 -296.680827)
			(xy 158.001882 -296.657231) (xy 157.959834 -296.626681) (xy 157.923083 -296.58993) (xy 157.892533 -296.547882)
			(xy 157.868937 -296.501572) (xy 157.852876 -296.452142) (xy 157.844746 -296.400807) (xy 157.844236 -296.37482)
			(xy 157.844745 -296.349316) (xy 157.852649 -296.298922) (xy 157.859984 -296.27449) (xy 157.863794 -296.262806)
			(xy 157.859984 -296.23893) (xy 157.804104 -296.16273) (xy 157.797008 -296.153726) (xy 157.776907 -296.142747)
			(xy 157.765496 -296.141648) (xy 156.687012 -296.141648) (xy 156.684472 -296.141648) (xy 156.673108 -296.142907)
			(xy 156.653067 -296.153851) (xy 156.645864 -296.16273) (xy 156.59989 -296.225722) (xy 156.595332 -296.232362)
			(xy 156.590281 -296.247646) (xy 156.589984 -296.255694) (xy 156.589984 -296.274236) (xy 156.592016 -296.281348)
			(xy 156.598377 -296.304192) (xy 156.605255 -296.351111) (xy 156.605732 -296.37482) (xy 156.605222 -296.400807)
			(xy 156.597092 -296.452142) (xy 156.581031 -296.501572) (xy 156.557435 -296.547882) (xy 156.526885 -296.58993)
			(xy 156.490134 -296.626681) (xy 156.448086 -296.657231) (xy 156.401776 -296.680827) (xy 156.352346 -296.696888)
			(xy 156.301011 -296.705018) (xy 156.249037 -296.705018) (xy 156.197702 -296.696888) (xy 156.148272 -296.680827)
			(xy 156.101962 -296.657231) (xy 156.059914 -296.626681) (xy 156.023163 -296.58993) (xy 155.992613 -296.547882)
			(xy 155.969017 -296.501572) (xy 155.952956 -296.452142) (xy 155.944826 -296.400807) (xy 155.944316 -296.37482)
			(xy 155.944825 -296.349316) (xy 155.952729 -296.298922) (xy 155.960064 -296.27449) (xy 155.963874 -296.262806)
			(xy 155.960064 -296.23893) (xy 155.904184 -296.16273) (xy 155.897086 -296.153729) (xy 155.876985 -296.142759)
			(xy 155.865576 -296.141648) (xy 155.737052 -296.141648) (xy 155.734512 -296.141648) (xy 155.723144 -296.142899)
			(xy 155.70309 -296.153834) (xy 155.695904 -296.16273) (xy 155.64993 -296.225722) (xy 155.645377 -296.232364)
			(xy 155.640332 -296.247647) (xy 155.640024 -296.255694) (xy 155.640024 -296.274236) (xy 155.642056 -296.281348)
			(xy 155.648418 -296.304192) (xy 155.655297 -296.351111) (xy 155.655772 -296.37482) (xy 155.655262 -296.400807)
			(xy 155.647132 -296.452142) (xy 155.631071 -296.501572) (xy 155.607475 -296.547882) (xy 155.576925 -296.58993)
			(xy 155.540174 -296.626681) (xy 155.498126 -296.657231) (xy 155.451816 -296.680827) (xy 155.402386 -296.696888)
			(xy 155.351051 -296.705018) (xy 155.299077 -296.705018) (xy 155.247742 -296.696888) (xy 155.198312 -296.680827)
			(xy 155.152002 -296.657231) (xy 155.109954 -296.626681) (xy 155.073203 -296.58993) (xy 155.042653 -296.547882)
			(xy 155.019057 -296.501572) (xy 155.002996 -296.452142) (xy 154.994866 -296.400807) (xy 154.994356 -296.37482)
			(xy 154.994865 -296.349316) (xy 155.00277 -296.298922) (xy 155.010104 -296.27449) (xy 155.013914 -296.262806)
			(xy 155.010104 -296.23893) (xy 154.954224 -296.16273) (xy 154.947129 -296.153723) (xy 154.927029 -296.142737)
			(xy 154.915616 -296.141648) (xy 154.786838 -296.141648) (xy 154.784298 -296.141648) (xy 154.772931 -296.142902)
			(xy 154.752882 -296.15384) (xy 154.74569 -296.16273) (xy 154.699716 -296.225722) (xy 154.695163 -296.232364)
			(xy 154.69012 -296.247647) (xy 154.68981 -296.255694) (xy 154.68981 -296.274236) (xy 154.691842 -296.281348)
			(xy 154.698205 -296.304192) (xy 154.705083 -296.351111) (xy 154.705558 -296.37482) (xy 154.705048 -296.400807)
			(xy 154.696918 -296.452142) (xy 154.680857 -296.501572) (xy 154.657261 -296.547882) (xy 154.626711 -296.58993)
			(xy 154.58996 -296.626681) (xy 154.547912 -296.657231) (xy 154.501602 -296.680827) (xy 154.452172 -296.696888)
			(xy 154.400837 -296.705018) (xy 154.348863 -296.705018) (xy 154.297528 -296.696888) (xy 154.248098 -296.680827)
			(xy 154.201788 -296.657231) (xy 154.15974 -296.626681) (xy 154.122989 -296.58993) (xy 154.092439 -296.547882)
			(xy 154.068843 -296.501572) (xy 154.052782 -296.452142) (xy 154.044652 -296.400807) (xy 154.044142 -296.37482)
			(xy 154.044651 -296.349316) (xy 154.052555 -296.298922) (xy 154.05989 -296.27449) (xy 154.0637 -296.262806)
			(xy 154.05989 -296.23893) (xy 154.00401 -296.16273) (xy 153.996914 -296.153725) (xy 153.976814 -296.142744)
			(xy 153.965402 -296.141648) (xy 153.816304 -296.141648) (xy 153.810864 -296.141508) (xy 153.80023 -296.139205)
			(xy 153.795222 -296.137076) (xy 153.78176 -296.130726) (xy 153.752804 -296.13479) (xy 153.728166 -296.155364)
			(xy 153.719636 -296.1633) (xy 153.710251 -296.184597) (xy 153.711189 -296.207852) (xy 153.716228 -296.218356)
			(xy 153.728603 -296.242562) (xy 153.746146 -296.294013) (xy 153.755044 -296.34764) (xy 153.755598 -296.37482)
			(xy 153.755088 -296.400807) (xy 153.746958 -296.452142) (xy 153.730897 -296.501572) (xy 153.707301 -296.547882)
			(xy 153.676751 -296.58993) (xy 153.64 -296.626681) (xy 153.597952 -296.657231) (xy 153.551642 -296.680827)
			(xy 153.502212 -296.696888) (xy 153.450877 -296.705018) (xy 153.398903 -296.705018) (xy 153.347568 -296.696888)
			(xy 153.298138 -296.680827) (xy 153.251828 -296.657231) (xy 153.20978 -296.626681) (xy 153.173029 -296.58993)
			(xy 153.142479 -296.547882) (xy 153.118883 -296.501572) (xy 153.102822 -296.452142) (xy 153.094692 -296.400807)
			(xy 153.094182 -296.37482) (xy 153.094647 -296.349392) (xy 153.102431 -296.299137) (xy 153.117819 -296.250666)
			(xy 153.140448 -296.205123) (xy 153.169784 -296.163582) (xy 153.205135 -296.127023) (xy 153.245667 -296.096308)
			(xy 153.290424 -296.072162) (xy 153.338351 -296.055155) (xy 153.388317 -296.045687) (xy 153.413714 -296.044366)
			(xy 153.428954 -296.043858) (xy 153.453592 -296.026586) (xy 153.49347 -295.925494) (xy 153.497468 -295.913431)
			(xy 153.494407 -295.888236) (xy 153.487628 -295.877488) (xy 153.484834 -295.873678) (xy 152.415748 -294.804592)
			(xy 152.40381 -294.797988) (xy 152.396952 -294.79621) (xy 152.371356 -294.789452) (xy 152.322564 -294.768923)
			(xy 152.277659 -294.740894) (xy 152.237784 -294.706079) (xy 152.203954 -294.665364) (xy 152.177032 -294.619786)
			(xy 152.157702 -294.570507) (xy 152.151588 -294.54475) (xy 152.150064 -294.537384) (xy 152.143206 -294.524684)
			(xy 150.204932 -292.586664) (xy 150.197533 -292.579821) (xy 150.178934 -292.572101) (xy 150.168864 -292.571678)
			(xy 148.3106 -292.571678) (xy 148.299849 -292.572152) (xy 148.280236 -292.580962) (xy 148.272754 -292.588696)
			(xy 148.222208 -292.645592) (xy 148.215393 -292.654013) (xy 148.208931 -292.67467) (xy 148.209762 -292.68547)
			(xy 148.211107 -292.697234) (xy 148.212503 -292.720873) (xy 148.212556 -292.732714) (xy 148.212069 -292.759966)
			(xy 148.204311 -292.813915) (xy 148.188956 -292.86621) (xy 148.166314 -292.915789) (xy 148.136848 -292.961641)
			(xy 148.101158 -293.002834) (xy 148.059968 -293.038528) (xy 148.014119 -293.067998) (xy 147.964542 -293.090644)
			(xy 147.912248 -293.106004) (xy 147.8583 -293.113767) (xy 147.831048 -293.114222) (xy 147.806427 -293.113836)
			(xy 147.757593 -293.107507) (xy 147.709977 -293.09496) (xy 147.68703 -293.086028) (xy 147.675092 -293.081202)
			(xy 147.6502 -293.083742) (xy 147.585176 -293.12743) (xy 147.580858 -293.126922) (xy 147.564094 -293.141908)
			(xy 147.556474 -293.149473) (xy 147.547676 -293.169033) (xy 147.547076 -293.179754) (xy 147.547076 -293.494714)
			(xy 149.72106 -293.494714) (xy 149.725131 -293.439092) (xy 149.737257 -293.384655) (xy 149.75718 -293.332564)
			(xy 149.784476 -293.283929) (xy 149.818562 -293.239786) (xy 149.858711 -293.201077) (xy 149.904069 -293.168626)
			(xy 149.953669 -293.143125) (xy 150.006453 -293.125118) (xy 150.061296 -293.114988) (xy 150.11703 -293.112951)
			(xy 150.172467 -293.119051) (xy 150.226424 -293.133157) (xy 150.277753 -293.154969) (xy 150.325359 -293.184023)
			(xy 150.368227 -293.219698) (xy 150.405444 -293.261235) (xy 150.436217 -293.307748) (xy 150.459889 -293.358245)
			(xy 150.475957 -293.411652) (xy 150.484077 -293.466828) (xy 150.484586 -293.494714) (xy 150.484077 -293.5226)
			(xy 150.475957 -293.577776) (xy 150.459889 -293.631183) (xy 150.436217 -293.68168) (xy 150.405444 -293.728193)
			(xy 150.368227 -293.76973) (xy 150.325359 -293.805405) (xy 150.277753 -293.834459) (xy 150.226424 -293.856271)
			(xy 150.172467 -293.870377) (xy 150.11703 -293.876477) (xy 150.061296 -293.87444) (xy 150.006453 -293.86431)
			(xy 149.953669 -293.846303) (xy 149.904069 -293.820802) (xy 149.858711 -293.788351) (xy 149.818562 -293.749642)
			(xy 149.784476 -293.705499) (xy 149.75718 -293.656864) (xy 149.737257 -293.604773) (xy 149.725131 -293.550336)
			(xy 149.72106 -293.494714) (xy 147.547076 -293.494714) (xy 147.547076 -295.207182) (xy 147.547582 -295.217232)
			(xy 147.555304 -295.235792) (xy 147.562062 -295.24325) (xy 147.729956 -295.411144) (xy 147.737355 -295.417988)
			(xy 147.755954 -295.425711) (xy 147.766024 -295.42613) (xy 149.30628 -295.42613) (xy 149.316343 -295.426568)
			(xy 149.334924 -295.434307) (xy 149.342348 -295.441116) (xy 149.651466 -295.750234) (xy 149.658311 -295.757633)
			(xy 149.666038 -295.776231) (xy 149.666452 -295.786302) (xy 149.666452 -296.288968) (xy 149.666546 -296.293987)
			(xy 149.668467 -296.303838) (xy 149.670262 -296.308526) (xy 149.67712 -296.324782) (xy 149.678432 -296.328153)
			(xy 149.680217 -296.335164) (xy 149.680676 -296.338752) (xy 149.6822 -296.352468) (xy 149.697694 -296.374312)
			(xy 149.79523 -296.418254) (xy 149.804326 -296.42186) (xy 149.823859 -296.422637) (xy 149.842271 -296.416068)
			(xy 149.84984 -296.409872) (xy 149.870884 -296.391838) (xy 149.917204 -296.361413) (xy 149.96744 -296.338015)
			(xy 150.020535 -296.322135) (xy 150.075369 -296.314109) (xy 150.103078 -296.313606) (xy 150.130331 -296.314068)
			(xy 150.184282 -296.321822) (xy 150.236581 -296.337176) (xy 150.286162 -296.359816) (xy 150.309115 -296.374566)
			(xy 152.169126 -296.374566) (xy 152.173086 -296.325512) (xy 152.184863 -296.277728) (xy 152.204154 -296.232452)
			(xy 152.230457 -296.190856) (xy 152.263092 -296.154019) (xy 152.301213 -296.122894) (xy 152.343834 -296.098287)
			(xy 152.38985 -296.080835) (xy 152.438069 -296.070991) (xy 152.487244 -296.06901) (xy 152.536099 -296.074942)
			(xy 152.58337 -296.088634) (xy 152.627832 -296.109732) (xy 152.668335 -296.137688) (xy 152.703828 -296.17178)
			(xy 152.733393 -296.211124) (xy 152.756264 -296.254701) (xy 152.771848 -296.301382) (xy 152.779743 -296.349959)
			(xy 152.780238 -296.374566) (xy 152.779743 -296.399173) (xy 152.771848 -296.44775) (xy 152.756264 -296.494431)
			(xy 152.733393 -296.538008) (xy 152.703828 -296.577352) (xy 152.668335 -296.611444) (xy 152.627832 -296.6394)
			(xy 152.58337 -296.660498) (xy 152.536099 -296.67419) (xy 152.487244 -296.680122) (xy 152.438069 -296.678141)
			(xy 152.38985 -296.668297) (xy 152.343834 -296.650845) (xy 152.301213 -296.626238) (xy 152.263092 -296.595113)
			(xy 152.230457 -296.558276) (xy 152.204154 -296.51668) (xy 152.184863 -296.471404) (xy 152.173086 -296.42362)
			(xy 152.169126 -296.374566) (xy 150.309115 -296.374566) (xy 150.332016 -296.389282) (xy 150.37321 -296.424975)
			(xy 150.408905 -296.466166) (xy 150.438374 -296.512019) (xy 150.461017 -296.561599) (xy 150.476373 -296.613896)
			(xy 150.484131 -296.667847) (xy 150.484131 -296.722353) (xy 150.476373 -296.776304) (xy 150.461017 -296.828601)
			(xy 150.438374 -296.878181) (xy 150.408905 -296.924034) (xy 150.37321 -296.965225) (xy 150.332016 -297.000918)
			(xy 150.286162 -297.030384) (xy 150.236581 -297.053024) (xy 150.184282 -297.068378) (xy 150.130331 -297.076132)
			(xy 150.103078 -297.076622) (xy 150.075369 -297.076123) (xy 150.020535 -297.068096) (xy 149.967442 -297.052214)
			(xy 149.917207 -297.028811) (xy 149.87089 -296.998382) (xy 149.84984 -296.980356) (xy 149.83841 -296.97045)
			(xy 149.808946 -296.965878) (xy 149.710902 -297.010074) (xy 149.702209 -297.014478) (xy 149.68872 -297.02852)
			(xy 149.681415 -297.046568) (xy 149.68093 -297.056302) (xy 149.68093 -297.3248) (xy 151.53402 -297.3248)
			(xy 151.538192 -297.274451) (xy 151.550595 -297.225475) (xy 151.570891 -297.179209) (xy 151.598525 -297.136915)
			(xy 151.632745 -297.099746) (xy 151.672615 -297.068717) (xy 151.71705 -297.044674) (xy 151.764835 -297.028274)
			(xy 151.814669 -297.019962) (xy 151.83993 -297.019472) (xy 151.865324 -297.020012) (xy 151.915412 -297.028419)
			(xy 151.963419 -297.044996) (xy 152.008022 -297.069287) (xy 152.047992 -297.100622) (xy 152.065482 -297.11904)
			(xy 152.073102 -297.127168) (xy 152.092914 -297.135804) (xy 152.192228 -297.13301) (xy 152.211786 -297.123612)
			(xy 152.218898 -297.114976) (xy 152.234711 -297.096425) (xy 152.270839 -297.063704) (xy 152.311375 -297.036635)
			(xy 152.355443 -297.015803) (xy 152.402088 -297.001658) (xy 152.450304 -296.994507) (xy 152.474676 -296.994072)
			(xy 153.424636 -296.994072) (xy 153.45062 -296.994624) (xy 153.501947 -297.002759) (xy 153.55137 -297.018822)
			(xy 153.597671 -297.042418) (xy 153.639712 -297.072967) (xy 153.676457 -297.109715) (xy 153.707001 -297.151759)
			(xy 153.730592 -297.198064) (xy 153.74665 -297.247488) (xy 153.754779 -297.298816) (xy 153.754779 -297.32478)
			(xy 154.069046 -297.32478) (xy 154.073006 -297.275726) (xy 154.084783 -297.227942) (xy 154.104074 -297.182666)
			(xy 154.130377 -297.14107) (xy 154.163012 -297.104233) (xy 154.201133 -297.073108) (xy 154.243754 -297.048501)
			(xy 154.28977 -297.031049) (xy 154.337989 -297.021205) (xy 154.387164 -297.019224) (xy 154.436019 -297.025156)
			(xy 154.48329 -297.038848) (xy 154.527752 -297.059946) (xy 154.568255 -297.087902) (xy 154.603748 -297.121994)
			(xy 154.633313 -297.161338) (xy 154.656184 -297.204915) (xy 154.671768 -297.251596) (xy 154.679663 -297.300173)
			(xy 154.680158 -297.32478) (xy 155.01926 -297.32478) (xy 155.02322 -297.275726) (xy 155.034997 -297.227942)
			(xy 155.054288 -297.182666) (xy 155.080591 -297.14107) (xy 155.113226 -297.104233) (xy 155.151347 -297.073108)
			(xy 155.193968 -297.048501) (xy 155.239984 -297.031049) (xy 155.288203 -297.021205) (xy 155.337378 -297.019224)
			(xy 155.386233 -297.025156) (xy 155.433504 -297.038848) (xy 155.477966 -297.059946) (xy 155.518469 -297.087902)
			(xy 155.553962 -297.121994) (xy 155.583527 -297.161338) (xy 155.606398 -297.204915) (xy 155.621982 -297.251596)
			(xy 155.629877 -297.300173) (xy 155.630372 -297.32478) (xy 157.86914 -297.32478) (xy 157.8731 -297.275726)
			(xy 157.884877 -297.227942) (xy 157.904168 -297.182666) (xy 157.930471 -297.14107) (xy 157.963106 -297.104233)
			(xy 158.001227 -297.073108) (xy 158.043848 -297.048501) (xy 158.089864 -297.031049) (xy 158.138083 -297.021205)
			(xy 158.187258 -297.019224) (xy 158.236113 -297.025156) (xy 158.283384 -297.038848) (xy 158.327846 -297.059946)
			(xy 158.368349 -297.087902) (xy 158.403842 -297.121994) (xy 158.433407 -297.161338) (xy 158.456278 -297.204915)
			(xy 158.471862 -297.251596) (xy 158.479757 -297.300173) (xy 158.480252 -297.32478) (xy 158.8191 -297.32478)
			(xy 158.82306 -297.275726) (xy 158.834837 -297.227942) (xy 158.854128 -297.182666) (xy 158.880431 -297.14107)
			(xy 158.913066 -297.104233) (xy 158.951187 -297.073108) (xy 158.993808 -297.048501) (xy 159.039824 -297.031049)
			(xy 159.088043 -297.021205) (xy 159.137218 -297.019224) (xy 159.186073 -297.025156) (xy 159.233344 -297.038848)
			(xy 159.277806 -297.059946) (xy 159.318309 -297.087902) (xy 159.353802 -297.121994) (xy 159.383367 -297.161338)
			(xy 159.406238 -297.204915) (xy 159.421822 -297.251596) (xy 159.429717 -297.300173) (xy 159.430212 -297.32478)
			(xy 159.76906 -297.32478) (xy 159.77302 -297.275726) (xy 159.784797 -297.227942) (xy 159.804088 -297.182666)
			(xy 159.830391 -297.14107) (xy 159.863026 -297.104233) (xy 159.901147 -297.073108) (xy 159.943768 -297.048501)
			(xy 159.989784 -297.031049) (xy 160.038003 -297.021205) (xy 160.087178 -297.019224) (xy 160.136033 -297.025156)
			(xy 160.183304 -297.038848) (xy 160.227766 -297.059946) (xy 160.268269 -297.087902) (xy 160.303762 -297.121994)
			(xy 160.333327 -297.161338) (xy 160.356198 -297.204915) (xy 160.371782 -297.251596) (xy 160.379677 -297.300173)
			(xy 160.380172 -297.32478) (xy 160.719274 -297.32478) (xy 160.723234 -297.275726) (xy 160.735011 -297.227942)
			(xy 160.754302 -297.182666) (xy 160.780605 -297.14107) (xy 160.81324 -297.104233) (xy 160.851361 -297.073108)
			(xy 160.893982 -297.048501) (xy 160.939998 -297.031049) (xy 160.988217 -297.021205) (xy 161.037392 -297.019224)
			(xy 161.086247 -297.025156) (xy 161.133518 -297.038848) (xy 161.17798 -297.059946) (xy 161.218483 -297.087902)
			(xy 161.253976 -297.121994) (xy 161.283541 -297.161338) (xy 161.306412 -297.204915) (xy 161.321996 -297.251596)
			(xy 161.329891 -297.300173) (xy 161.330386 -297.32478) (xy 161.669234 -297.32478) (xy 161.673194 -297.275726)
			(xy 161.684971 -297.227942) (xy 161.704262 -297.182666) (xy 161.730565 -297.14107) (xy 161.7632 -297.104233)
			(xy 161.801321 -297.073108) (xy 161.843942 -297.048501) (xy 161.889958 -297.031049) (xy 161.938177 -297.021205)
			(xy 161.987352 -297.019224) (xy 162.036207 -297.025156) (xy 162.083478 -297.038848) (xy 162.12794 -297.059946)
			(xy 162.168443 -297.087902) (xy 162.203936 -297.121994) (xy 162.233501 -297.161338) (xy 162.256372 -297.204915)
			(xy 162.271956 -297.251596) (xy 162.279851 -297.300173) (xy 162.280346 -297.32478) (xy 162.279851 -297.349387)
			(xy 162.271956 -297.397964) (xy 162.256372 -297.444645) (xy 162.233501 -297.488222) (xy 162.203936 -297.527566)
			(xy 162.168443 -297.561658) (xy 162.12794 -297.589614) (xy 162.083478 -297.610712) (xy 162.036207 -297.624404)
			(xy 161.987352 -297.630336) (xy 161.938177 -297.628355) (xy 161.889958 -297.618511) (xy 161.843942 -297.601059)
			(xy 161.801321 -297.576452) (xy 161.7632 -297.545327) (xy 161.730565 -297.50849) (xy 161.704262 -297.466894)
			(xy 161.684971 -297.421618) (xy 161.673194 -297.373834) (xy 161.669234 -297.32478) (xy 161.330386 -297.32478)
			(xy 161.329891 -297.349387) (xy 161.321996 -297.397964) (xy 161.306412 -297.444645) (xy 161.283541 -297.488222)
			(xy 161.253976 -297.527566) (xy 161.218483 -297.561658) (xy 161.17798 -297.589614) (xy 161.133518 -297.610712)
			(xy 161.086247 -297.624404) (xy 161.037392 -297.630336) (xy 160.988217 -297.628355) (xy 160.939998 -297.618511)
			(xy 160.893982 -297.601059) (xy 160.851361 -297.576452) (xy 160.81324 -297.545327) (xy 160.780605 -297.50849)
			(xy 160.754302 -297.466894) (xy 160.735011 -297.421618) (xy 160.723234 -297.373834) (xy 160.719274 -297.32478)
			(xy 160.380172 -297.32478) (xy 160.379677 -297.349387) (xy 160.371782 -297.397964) (xy 160.356198 -297.444645)
			(xy 160.333327 -297.488222) (xy 160.303762 -297.527566) (xy 160.268269 -297.561658) (xy 160.227766 -297.589614)
			(xy 160.183304 -297.610712) (xy 160.136033 -297.624404) (xy 160.087178 -297.630336) (xy 160.038003 -297.628355)
			(xy 159.989784 -297.618511) (xy 159.943768 -297.601059) (xy 159.901147 -297.576452) (xy 159.863026 -297.545327)
			(xy 159.830391 -297.50849) (xy 159.804088 -297.466894) (xy 159.784797 -297.421618) (xy 159.77302 -297.373834)
			(xy 159.76906 -297.32478) (xy 159.430212 -297.32478) (xy 159.429717 -297.349387) (xy 159.421822 -297.397964)
			(xy 159.406238 -297.444645) (xy 159.383367 -297.488222) (xy 159.353802 -297.527566) (xy 159.318309 -297.561658)
			(xy 159.277806 -297.589614) (xy 159.233344 -297.610712) (xy 159.186073 -297.624404) (xy 159.137218 -297.630336)
			(xy 159.088043 -297.628355) (xy 159.039824 -297.618511) (xy 158.993808 -297.601059) (xy 158.951187 -297.576452)
			(xy 158.913066 -297.545327) (xy 158.880431 -297.50849) (xy 158.854128 -297.466894) (xy 158.834837 -297.421618)
			(xy 158.82306 -297.373834) (xy 158.8191 -297.32478) (xy 158.480252 -297.32478) (xy 158.479757 -297.349387)
			(xy 158.471862 -297.397964) (xy 158.456278 -297.444645) (xy 158.433407 -297.488222) (xy 158.403842 -297.527566)
			(xy 158.368349 -297.561658) (xy 158.327846 -297.589614) (xy 158.283384 -297.610712) (xy 158.236113 -297.624404)
			(xy 158.187258 -297.630336) (xy 158.138083 -297.628355) (xy 158.089864 -297.618511) (xy 158.043848 -297.601059)
			(xy 158.001227 -297.576452) (xy 157.963106 -297.545327) (xy 157.930471 -297.50849) (xy 157.904168 -297.466894)
			(xy 157.884877 -297.421618) (xy 157.8731 -297.373834) (xy 157.86914 -297.32478) (xy 155.630372 -297.32478)
			(xy 155.629877 -297.349387) (xy 155.621982 -297.397964) (xy 155.606398 -297.444645) (xy 155.583527 -297.488222)
			(xy 155.553962 -297.527566) (xy 155.518469 -297.561658) (xy 155.477966 -297.589614) (xy 155.433504 -297.610712)
			(xy 155.386233 -297.624404) (xy 155.337378 -297.630336) (xy 155.288203 -297.628355) (xy 155.239984 -297.618511)
			(xy 155.193968 -297.601059) (xy 155.151347 -297.576452) (xy 155.113226 -297.545327) (xy 155.080591 -297.50849)
			(xy 155.054288 -297.466894) (xy 155.034997 -297.421618) (xy 155.02322 -297.373834) (xy 155.01926 -297.32478)
			(xy 154.680158 -297.32478) (xy 154.679663 -297.349387) (xy 154.671768 -297.397964) (xy 154.656184 -297.444645)
			(xy 154.633313 -297.488222) (xy 154.603748 -297.527566) (xy 154.568255 -297.561658) (xy 154.527752 -297.589614)
			(xy 154.48329 -297.610712) (xy 154.436019 -297.624404) (xy 154.387164 -297.630336) (xy 154.337989 -297.628355)
			(xy 154.28977 -297.618511) (xy 154.243754 -297.601059) (xy 154.201133 -297.576452) (xy 154.163012 -297.545327)
			(xy 154.130377 -297.50849) (xy 154.104074 -297.466894) (xy 154.084783 -297.421618) (xy 154.073006 -297.373834)
			(xy 154.069046 -297.32478) (xy 153.754779 -297.32478) (xy 153.754779 -297.350784) (xy 153.74665 -297.402112)
			(xy 153.730592 -297.451536) (xy 153.707001 -297.497841) (xy 153.676457 -297.539885) (xy 153.639712 -297.576633)
			(xy 153.597671 -297.607182) (xy 153.55137 -297.630778) (xy 153.501947 -297.646841) (xy 153.45062 -297.654976)
			(xy 153.424636 -297.655488) (xy 152.474676 -297.655488) (xy 152.450304 -297.655045) (xy 152.402085 -297.647904)
			(xy 152.355436 -297.633766) (xy 152.311365 -297.612937) (xy 152.270828 -297.585868) (xy 152.234701 -297.553144)
			(xy 152.218898 -297.534584) (xy 152.211786 -297.525948) (xy 152.192228 -297.51655) (xy 152.092914 -297.513756)
			(xy 152.073102 -297.522392) (xy 152.065482 -297.53052) (xy 152.048017 -297.548966) (xy 152.008048 -297.580314)
			(xy 151.96344 -297.604613) (xy 151.915425 -297.62119) (xy 151.865328 -297.629589) (xy 151.83993 -297.630088)
			(xy 151.814669 -297.629638) (xy 151.764835 -297.621326) (xy 151.71705 -297.604926) (xy 151.672615 -297.580883)
			(xy 151.632745 -297.549854) (xy 151.598525 -297.512685) (xy 151.570891 -297.470391) (xy 151.550595 -297.424125)
			(xy 151.538192 -297.375149) (xy 151.53402 -297.3248) (xy 149.68093 -297.3248) (xy 149.68093 -297.997626)
			(xy 149.680814 -298.002722) (xy 149.678761 -298.012705) (xy 149.676866 -298.017438) (xy 149.670262 -298.032932)
			(xy 149.668468 -298.03762) (xy 149.666557 -298.047472) (xy 149.666452 -298.05249) (xy 149.666452 -298.118276)
			(xy 149.66689 -298.128339) (xy 149.67463 -298.146918) (xy 149.681438 -298.154344) (xy 149.80666 -298.279566)
			(xy 149.807168 -298.280074) (xy 149.814551 -298.286652) (xy 149.83285 -298.294094) (xy 149.842728 -298.294552)
			(xy 152.140158 -298.294552)
		)
		(stroke
			(width 0)
			(type solid)
		)
		(fill yes)
		(layer "In5.Cu")
		(net "PCEPLL2_VDDA18_PEX1")
	)
	(gr_poly
		(pts
			(xy 384.369056 -298.267882) (xy 384.37058 -298.24807) (xy 384.373292 -298.223024) (xy 384.385864 -298.174243)
			(xy 384.40627 -298.128186) (xy 384.433955 -298.086101) (xy 384.468171 -298.04913) (xy 384.507989 -298.018273)
			(xy 384.55233 -297.994367) (xy 384.599993 -297.978061) (xy 384.649685 -297.969795) (xy 384.700059 -297.969795)
			(xy 384.749751 -297.978061) (xy 384.797414 -297.994367) (xy 384.841755 -298.018273) (xy 384.881573 -298.04913)
			(xy 384.915789 -298.086101) (xy 384.943474 -298.128186) (xy 384.96388 -298.174243) (xy 384.976452 -298.223024)
			(xy 384.979164 -298.24807) (xy 384.980688 -298.267882) (xy 385.009644 -298.294552) (xy 385.264152 -298.294552)
			(xy 385.293362 -298.267628) (xy 385.294886 -298.247816) (xy 385.297502 -298.222001) (xy 385.309747 -298.171581)
			(xy 385.329713 -298.123692) (xy 385.356912 -298.079508) (xy 385.390676 -298.040112) (xy 385.430176 -298.00647)
			(xy 385.474445 -297.979408) (xy 385.522395 -297.95959) (xy 385.572852 -297.947501) (xy 385.624578 -297.943438)
			(xy 385.676304 -297.947501) (xy 385.726761 -297.95959) (xy 385.774711 -297.979408) (xy 385.81898 -298.00647)
			(xy 385.85848 -298.040112) (xy 385.892244 -298.079508) (xy 385.919443 -298.123692) (xy 385.939409 -298.171581)
			(xy 385.951654 -298.222001) (xy 385.95427 -298.247816) (xy 385.955794 -298.267628) (xy 385.985004 -298.294552)
			(xy 386.214366 -298.294552) (xy 386.243576 -298.267628) (xy 386.2451 -298.247816) (xy 386.247716 -298.222001)
			(xy 386.259961 -298.171581) (xy 386.279927 -298.123692) (xy 386.307126 -298.079508) (xy 386.34089 -298.040112)
			(xy 386.38039 -298.00647) (xy 386.424659 -297.979408) (xy 386.472609 -297.95959) (xy 386.523066 -297.947501)
			(xy 386.574792 -297.943438) (xy 386.626518 -297.947501) (xy 386.676975 -297.95959) (xy 386.724925 -297.979408)
			(xy 386.769194 -298.00647) (xy 386.808694 -298.040112) (xy 386.842458 -298.079508) (xy 386.869657 -298.123692)
			(xy 386.889623 -298.171581) (xy 386.901868 -298.222001) (xy 386.904484 -298.247816) (xy 386.906008 -298.267628)
			(xy 386.935218 -298.294552) (xy 387.16458 -298.294552) (xy 387.19379 -298.267628) (xy 387.195314 -298.247816)
			(xy 387.19793 -298.222001) (xy 387.210175 -298.171581) (xy 387.230141 -298.123692) (xy 387.25734 -298.079508)
			(xy 387.291104 -298.040112) (xy 387.330604 -298.00647) (xy 387.374873 -297.979408) (xy 387.422823 -297.95959)
			(xy 387.47328 -297.947501) (xy 387.525006 -297.943438) (xy 387.576732 -297.947501) (xy 387.627189 -297.95959)
			(xy 387.675139 -297.979408) (xy 387.719408 -298.00647) (xy 387.758908 -298.040112) (xy 387.792672 -298.079508)
			(xy 387.819871 -298.123692) (xy 387.839837 -298.171581) (xy 387.852082 -298.222001) (xy 387.854698 -298.247816)
			(xy 387.856222 -298.267628) (xy 387.885432 -298.294552) (xy 388.11454 -298.294552) (xy 388.14375 -298.267628)
			(xy 388.145274 -298.247816) (xy 388.14789 -298.222001) (xy 388.160135 -298.171581) (xy 388.180101 -298.123692)
			(xy 388.2073 -298.079508) (xy 388.241064 -298.040112) (xy 388.280564 -298.00647) (xy 388.324833 -297.979408)
			(xy 388.372783 -297.95959) (xy 388.42324 -297.947501) (xy 388.474966 -297.943438) (xy 388.526692 -297.947501)
			(xy 388.577149 -297.95959) (xy 388.625099 -297.979408) (xy 388.669368 -298.00647) (xy 388.708868 -298.040112)
			(xy 388.742632 -298.079508) (xy 388.769831 -298.123692) (xy 388.789797 -298.171581) (xy 388.802042 -298.222001)
			(xy 388.804658 -298.247816) (xy 388.806182 -298.267628) (xy 388.835392 -298.294552) (xy 389.0645 -298.294552)
			(xy 389.09371 -298.267628) (xy 389.095234 -298.247816) (xy 389.09785 -298.222001) (xy 389.110095 -298.171581)
			(xy 389.130061 -298.123692) (xy 389.15726 -298.079508) (xy 389.191024 -298.040112) (xy 389.230524 -298.00647)
			(xy 389.274793 -297.979408) (xy 389.322743 -297.95959) (xy 389.3732 -297.947501) (xy 389.424926 -297.943438)
			(xy 389.476652 -297.947501) (xy 389.527109 -297.95959) (xy 389.575059 -297.979408) (xy 389.619328 -298.00647)
			(xy 389.658828 -298.040112) (xy 389.692592 -298.079508) (xy 389.719791 -298.123692) (xy 389.739757 -298.171581)
			(xy 389.752002 -298.222001) (xy 389.754618 -298.247816) (xy 389.756142 -298.267628) (xy 389.785352 -298.294552)
			(xy 390.01446 -298.294552) (xy 390.04367 -298.267628) (xy 390.045194 -298.247816) (xy 390.04781 -298.222001)
			(xy 390.060055 -298.171581) (xy 390.080021 -298.123692) (xy 390.10722 -298.079508) (xy 390.140984 -298.040112)
			(xy 390.180484 -298.00647) (xy 390.224753 -297.979408) (xy 390.272703 -297.95959) (xy 390.32316 -297.947501)
			(xy 390.374886 -297.943438) (xy 390.426612 -297.947501) (xy 390.477069 -297.95959) (xy 390.525019 -297.979408)
			(xy 390.569288 -298.00647) (xy 390.608788 -298.040112) (xy 390.642552 -298.079508) (xy 390.669751 -298.123692)
			(xy 390.689717 -298.171581) (xy 390.701962 -298.222001) (xy 390.704578 -298.247816) (xy 390.706102 -298.267628)
			(xy 390.735312 -298.294552) (xy 390.990074 -298.294552) (xy 391.01903 -298.267882) (xy 391.020808 -298.24807)
			(xy 391.02352 -298.223046) (xy 391.036084 -298.174309) (xy 391.056474 -298.128294) (xy 391.084138 -298.086248)
			(xy 391.118325 -298.04931) (xy 391.158109 -298.018482) (xy 391.202412 -297.994599) (xy 391.250032 -297.978307)
			(xy 391.299681 -297.97005) (xy 391.350011 -297.97005) (xy 391.39966 -297.978307) (xy 391.44728 -297.994599)
			(xy 391.491583 -298.018482) (xy 391.531367 -298.04931) (xy 391.565554 -298.086248) (xy 391.593218 -298.128294)
			(xy 391.613608 -298.174309) (xy 391.626172 -298.223046) (xy 391.628884 -298.24807) (xy 391.630662 -298.267882)
			(xy 391.659618 -298.294552) (xy 391.91438 -298.294552) (xy 391.94359 -298.267628) (xy 391.945114 -298.247816)
			(xy 391.94773 -298.222001) (xy 391.959975 -298.171581) (xy 391.979941 -298.123692) (xy 392.00714 -298.079508)
			(xy 392.040904 -298.040112) (xy 392.080404 -298.00647) (xy 392.124673 -297.979408) (xy 392.172623 -297.95959)
			(xy 392.22308 -297.947501) (xy 392.274806 -297.943438) (xy 392.326532 -297.947501) (xy 392.376989 -297.95959)
			(xy 392.424939 -297.979408) (xy 392.469208 -298.00647) (xy 392.508708 -298.040112) (xy 392.542472 -298.079508)
			(xy 392.569671 -298.123692) (xy 392.589637 -298.171581) (xy 392.601882 -298.222001) (xy 392.604498 -298.247816)
			(xy 392.606022 -298.267628) (xy 392.635232 -298.294552) (xy 392.864594 -298.294552) (xy 392.893804 -298.267628)
			(xy 392.895328 -298.247816) (xy 392.897944 -298.222001) (xy 392.910189 -298.171581) (xy 392.930155 -298.123692)
			(xy 392.957354 -298.079508) (xy 392.991118 -298.040112) (xy 393.030618 -298.00647) (xy 393.074887 -297.979408)
			(xy 393.122837 -297.95959) (xy 393.173294 -297.947501) (xy 393.22502 -297.943438) (xy 393.276746 -297.947501)
			(xy 393.327203 -297.95959) (xy 393.375153 -297.979408) (xy 393.419422 -298.00647) (xy 393.458922 -298.040112)
			(xy 393.492686 -298.079508) (xy 393.519885 -298.123692) (xy 393.539851 -298.171581) (xy 393.552096 -298.222001)
			(xy 393.554712 -298.247816) (xy 393.556236 -298.267628) (xy 393.585446 -298.294552) (xy 393.814554 -298.294552)
			(xy 393.843764 -298.267628) (xy 393.845288 -298.247816) (xy 393.847904 -298.222001) (xy 393.860149 -298.171581)
			(xy 393.880115 -298.123692) (xy 393.907314 -298.079508) (xy 393.941078 -298.040112) (xy 393.980578 -298.00647)
			(xy 394.024847 -297.979408) (xy 394.072797 -297.95959) (xy 394.123254 -297.947501) (xy 394.17498 -297.943438)
			(xy 394.226706 -297.947501) (xy 394.277163 -297.95959) (xy 394.325113 -297.979408) (xy 394.369382 -298.00647)
			(xy 394.408882 -298.040112) (xy 394.442646 -298.079508) (xy 394.469845 -298.123692) (xy 394.489811 -298.171581)
			(xy 394.502056 -298.222001) (xy 394.504672 -298.247816) (xy 394.506196 -298.267628) (xy 394.535406 -298.294552)
			(xy 394.764514 -298.294552) (xy 394.793724 -298.267628) (xy 394.795248 -298.247816) (xy 394.797705 -298.223293)
			(xy 394.808959 -298.175311) (xy 394.82721 -298.129531) (xy 394.852054 -298.086967) (xy 394.882941 -298.048563)
			(xy 394.919186 -298.015168) (xy 394.959986 -297.987523) (xy 395.004438 -297.966241) (xy 395.051557 -297.951792)
			(xy 395.100298 -297.944498) (xy 395.12494 -297.944032) (xy 395.154415 -297.944698) (xy 395.212427 -297.955181)
			(xy 395.267665 -297.975772) (xy 395.293342 -297.99026) (xy 395.30528 -297.997118) (xy 395.332458 -297.997372)
			(xy 395.421104 -297.946826) (xy 395.428717 -297.942096) (xy 395.44028 -297.928417) (xy 395.446408 -297.911587)
			(xy 395.446758 -297.90263) (xy 395.446758 -296.74693) (xy 395.446402 -296.73798) (xy 395.44024 -296.721174)
			(xy 395.428689 -296.7075) (xy 395.421104 -296.702734) (xy 395.332458 -296.652188) (xy 395.305026 -296.652442)
			(xy 395.293342 -296.6593) (xy 395.267659 -296.673778) (xy 395.212426 -296.694384) (xy 395.154415 -296.704874)
			(xy 395.12494 -296.705528) (xy 395.098948 -296.705048) (xy 395.047604 -296.696922) (xy 394.998162 -296.680863)
			(xy 394.951842 -296.657268) (xy 394.909784 -296.626717) (xy 394.873022 -296.589962) (xy 394.842463 -296.547909)
			(xy 394.81886 -296.501593) (xy 394.802792 -296.452155) (xy 394.794657 -296.400812) (xy 394.794232 -296.37482)
			(xy 394.794741 -296.349316) (xy 394.802645 -296.298922) (xy 394.80998 -296.27449) (xy 394.81379 -296.262806)
			(xy 394.80998 -296.23893) (xy 394.7541 -296.16273) (xy 394.747003 -296.153727) (xy 394.726903 -296.14275)
			(xy 394.715492 -296.141648) (xy 394.586968 -296.141648) (xy 394.584428 -296.141648) (xy 394.573058 -296.142896)
			(xy 394.552999 -296.153828) (xy 394.54582 -296.16273) (xy 394.499846 -296.225722) (xy 394.495291 -296.232363)
			(xy 394.490245 -296.247647) (xy 394.48994 -296.255694) (xy 394.48994 -296.274236) (xy 394.491972 -296.281348)
			(xy 394.498334 -296.304192) (xy 394.505212 -296.351111) (xy 394.505688 -296.37482) (xy 394.505178 -296.400807)
			(xy 394.497048 -296.452142) (xy 394.480987 -296.501572) (xy 394.457391 -296.547882) (xy 394.426841 -296.58993)
			(xy 394.39009 -296.626681) (xy 394.348042 -296.657231) (xy 394.301732 -296.680827) (xy 394.252302 -296.696888)
			(xy 394.200967 -296.705018) (xy 394.148993 -296.705018) (xy 394.097658 -296.696888) (xy 394.048228 -296.680827)
			(xy 394.001918 -296.657231) (xy 393.95987 -296.626681) (xy 393.923119 -296.58993) (xy 393.892569 -296.547882)
			(xy 393.868973 -296.501572) (xy 393.852912 -296.452142) (xy 393.844782 -296.400807) (xy 393.844272 -296.37482)
			(xy 393.844781 -296.349316) (xy 393.852686 -296.298922) (xy 393.86002 -296.27449) (xy 393.86383 -296.262806)
			(xy 393.86002 -296.23893) (xy 393.80414 -296.16273) (xy 393.797046 -296.15372) (xy 393.776947 -296.142728)
			(xy 393.765532 -296.141648) (xy 393.637008 -296.141648) (xy 393.634468 -296.141648) (xy 393.623105 -296.142908)
			(xy 393.603065 -296.153853) (xy 393.59586 -296.16273) (xy 393.549886 -296.225722) (xy 393.545328 -296.232362)
			(xy 393.540278 -296.247646) (xy 393.53998 -296.255694) (xy 393.53998 -296.274236) (xy 393.542012 -296.281348)
			(xy 393.548373 -296.304192) (xy 393.555251 -296.351111) (xy 393.555728 -296.37482) (xy 393.555218 -296.400807)
			(xy 393.547088 -296.452142) (xy 393.531027 -296.501572) (xy 393.507431 -296.547882) (xy 393.476881 -296.58993)
			(xy 393.44013 -296.626681) (xy 393.398082 -296.657231) (xy 393.351772 -296.680827) (xy 393.302342 -296.696888)
			(xy 393.251007 -296.705018) (xy 393.199033 -296.705018) (xy 393.147698 -296.696888) (xy 393.098268 -296.680827)
			(xy 393.051958 -296.657231) (xy 393.00991 -296.626681) (xy 392.973159 -296.58993) (xy 392.942609 -296.547882)
			(xy 392.919013 -296.501572) (xy 392.902952 -296.452142) (xy 392.894822 -296.400807) (xy 392.894312 -296.37482)
			(xy 392.894821 -296.349316) (xy 392.902727 -296.298922) (xy 392.91006 -296.27449) (xy 392.91387 -296.262806)
			(xy 392.91006 -296.23893) (xy 392.85418 -296.16273) (xy 392.847082 -296.15373) (xy 392.826981 -296.142761)
			(xy 392.815572 -296.141648) (xy 392.686794 -296.141648) (xy 392.684254 -296.141648) (xy 392.672892 -296.142911)
			(xy 392.652857 -296.153859) (xy 392.645646 -296.16273) (xy 392.599672 -296.225722) (xy 392.595115 -296.232362)
			(xy 392.590066 -296.247646) (xy 392.589766 -296.255694) (xy 392.589766 -296.274236) (xy 392.591798 -296.281348)
			(xy 392.59816 -296.304192) (xy 392.605037 -296.351111) (xy 392.605514 -296.37482) (xy 392.605004 -296.400807)
			(xy 392.596874 -296.452142) (xy 392.580813 -296.501572) (xy 392.557217 -296.547882) (xy 392.526667 -296.58993)
			(xy 392.489916 -296.626681) (xy 392.447868 -296.657231) (xy 392.401558 -296.680827) (xy 392.352128 -296.696888)
			(xy 392.300793 -296.705018) (xy 392.248819 -296.705018) (xy 392.197484 -296.696888) (xy 392.148054 -296.680827)
			(xy 392.101744 -296.657231) (xy 392.059696 -296.626681) (xy 392.022945 -296.58993) (xy 391.992395 -296.547882)
			(xy 391.968799 -296.501572) (xy 391.952738 -296.452142) (xy 391.944608 -296.400807) (xy 391.944098 -296.37482)
			(xy 391.944607 -296.349316) (xy 391.952513 -296.298922) (xy 391.959846 -296.27449) (xy 391.963656 -296.262806)
			(xy 391.959846 -296.23893) (xy 391.903966 -296.16273) (xy 391.896867 -296.153732) (xy 391.876766 -296.142768)
			(xy 391.865358 -296.141648) (xy 390.786874 -296.141648) (xy 390.784334 -296.141648) (xy 390.772974 -296.142915)
			(xy 390.752946 -296.153867) (xy 390.745726 -296.16273) (xy 390.699752 -296.225722) (xy 390.695197 -296.232363)
			(xy 390.69015 -296.247646) (xy 390.689846 -296.255694) (xy 390.689846 -296.274236) (xy 390.691878 -296.281348)
			(xy 390.69824 -296.304192) (xy 390.705118 -296.351111) (xy 390.705594 -296.37482) (xy 390.705084 -296.400807)
			(xy 390.696954 -296.452142) (xy 390.680893 -296.501572) (xy 390.657297 -296.547882) (xy 390.626747 -296.58993)
			(xy 390.589996 -296.626681) (xy 390.547948 -296.657231) (xy 390.501638 -296.680827) (xy 390.452208 -296.696888)
			(xy 390.400873 -296.705018) (xy 390.348899 -296.705018) (xy 390.297564 -296.696888) (xy 390.248134 -296.680827)
			(xy 390.201824 -296.657231) (xy 390.159776 -296.626681) (xy 390.123025 -296.58993) (xy 390.092475 -296.547882)
			(xy 390.068879 -296.501572) (xy 390.052818 -296.452142) (xy 390.044688 -296.400807) (xy 390.044178 -296.37482)
			(xy 390.044687 -296.349316) (xy 390.052592 -296.298922) (xy 390.059926 -296.27449) (xy 390.063736 -296.262806)
			(xy 390.059926 -296.23893) (xy 390.004046 -296.16273) (xy 389.996953 -296.153719) (xy 389.976853 -296.142724)
			(xy 389.965438 -296.141648) (xy 388.886954 -296.141648) (xy 388.884414 -296.141648) (xy 388.873045 -296.142899)
			(xy 388.852991 -296.153834) (xy 388.845806 -296.16273) (xy 388.799832 -296.225722) (xy 388.795279 -296.232364)
			(xy 388.790233 -296.247647) (xy 388.789926 -296.255694) (xy 388.789926 -296.274236) (xy 388.791958 -296.281348)
			(xy 388.79832 -296.304192) (xy 388.805199 -296.351111) (xy 388.805674 -296.37482) (xy 388.805164 -296.400807)
			(xy 388.797034 -296.452142) (xy 388.780973 -296.501572) (xy 388.757377 -296.547882) (xy 388.726827 -296.58993)
			(xy 388.690076 -296.626681) (xy 388.648028 -296.657231) (xy 388.601718 -296.680827) (xy 388.552288 -296.696888)
			(xy 388.500953 -296.705018) (xy 388.448979 -296.705018) (xy 388.397644 -296.696888) (xy 388.348214 -296.680827)
			(xy 388.301904 -296.657231) (xy 388.259856 -296.626681) (xy 388.223105 -296.58993) (xy 388.192555 -296.547882)
			(xy 388.168959 -296.501572) (xy 388.152898 -296.452142) (xy 388.144768 -296.400807) (xy 388.144258 -296.37482)
			(xy 388.144767 -296.349316) (xy 388.152672 -296.298922) (xy 388.160006 -296.27449) (xy 388.163816 -296.262806)
			(xy 388.160006 -296.23893) (xy 388.104126 -296.16273) (xy 388.097031 -296.153723) (xy 388.076931 -296.142736)
			(xy 388.065518 -296.141648) (xy 387.936994 -296.141648) (xy 387.934454 -296.141648) (xy 387.923092 -296.142911)
			(xy 387.903057 -296.153859) (xy 387.895846 -296.16273) (xy 387.849872 -296.225722) (xy 387.845315 -296.232362)
			(xy 387.840266 -296.247646) (xy 387.839966 -296.255694) (xy 387.839966 -296.274236) (xy 387.841998 -296.281348)
			(xy 387.84836 -296.304192) (xy 387.855237 -296.351111) (xy 387.855714 -296.37482) (xy 387.855204 -296.400807)
			(xy 387.847074 -296.452142) (xy 387.831013 -296.501572) (xy 387.807417 -296.547882) (xy 387.776867 -296.58993)
			(xy 387.740116 -296.626681) (xy 387.698068 -296.657231) (xy 387.651758 -296.680827) (xy 387.602328 -296.696888)
			(xy 387.550993 -296.705018) (xy 387.499019 -296.705018) (xy 387.447684 -296.696888) (xy 387.398254 -296.680827)
			(xy 387.351944 -296.657231) (xy 387.309896 -296.626681) (xy 387.273145 -296.58993) (xy 387.242595 -296.547882)
			(xy 387.218999 -296.501572) (xy 387.202938 -296.452142) (xy 387.194808 -296.400807) (xy 387.194298 -296.37482)
			(xy 387.194807 -296.349316) (xy 387.202713 -296.298922) (xy 387.210046 -296.27449) (xy 387.213856 -296.262806)
			(xy 387.210046 -296.23893) (xy 387.154166 -296.16273) (xy 387.147067 -296.153732) (xy 387.126966 -296.142768)
			(xy 387.115558 -296.141648) (xy 386.98678 -296.141648) (xy 386.98424 -296.141648) (xy 386.97288 -296.142913)
			(xy 386.952849 -296.153865) (xy 386.945632 -296.16273) (xy 386.899658 -296.225722) (xy 386.895103 -296.232363)
			(xy 386.890055 -296.247646) (xy 386.889752 -296.255694) (xy 386.889752 -296.274236) (xy 386.891784 -296.281348)
			(xy 386.898146 -296.304192) (xy 386.905024 -296.351111) (xy 386.9055 -296.37482) (xy 386.90499 -296.400807)
			(xy 386.89686 -296.452142) (xy 386.880799 -296.501572) (xy 386.857203 -296.547882) (xy 386.826653 -296.58993)
			(xy 386.789902 -296.626681) (xy 386.747854 -296.657231) (xy 386.701544 -296.680827) (xy 386.652114 -296.696888)
			(xy 386.600779 -296.705018) (xy 386.548805 -296.705018) (xy 386.49747 -296.696888) (xy 386.44804 -296.680827)
			(xy 386.40173 -296.657231) (xy 386.359682 -296.626681) (xy 386.322931 -296.58993) (xy 386.292381 -296.547882)
			(xy 386.268785 -296.501572) (xy 386.252724 -296.452142) (xy 386.244594 -296.400807) (xy 386.244084 -296.37482)
			(xy 386.244593 -296.349316) (xy 386.252498 -296.298922) (xy 386.259832 -296.27449) (xy 386.263642 -296.262806)
			(xy 386.259832 -296.23893) (xy 386.203952 -296.16273) (xy 386.196859 -296.153719) (xy 386.17676 -296.142721)
			(xy 386.165344 -296.141648) (xy 386.016246 -296.141648) (xy 386.010807 -296.141502) (xy 386.000178 -296.139188)
			(xy 385.995164 -296.137076) (xy 385.981702 -296.130726) (xy 385.952746 -296.13479) (xy 385.928108 -296.155364)
			(xy 385.919572 -296.163297) (xy 385.910179 -296.184596) (xy 385.911119 -296.207855) (xy 385.91617 -296.218356)
			(xy 385.928543 -296.242562) (xy 385.946084 -296.294014) (xy 385.954981 -296.34764) (xy 385.95554 -296.37482)
			(xy 385.95503 -296.400807) (xy 385.9469 -296.452142) (xy 385.930839 -296.501572) (xy 385.907243 -296.547882)
			(xy 385.876693 -296.58993) (xy 385.839942 -296.626681) (xy 385.797894 -296.657231) (xy 385.751584 -296.680827)
			(xy 385.702154 -296.696888) (xy 385.650819 -296.705018) (xy 385.598845 -296.705018) (xy 385.54751 -296.696888)
			(xy 385.49808 -296.680827) (xy 385.45177 -296.657231) (xy 385.409722 -296.626681) (xy 385.372971 -296.58993)
			(xy 385.342421 -296.547882) (xy 385.318825 -296.501572) (xy 385.302764 -296.452142) (xy 385.294634 -296.400807)
			(xy 385.294124 -296.37482) (xy 385.294589 -296.349394) (xy 385.302374 -296.29914) (xy 385.317762 -296.250672)
			(xy 385.340392 -296.205132) (xy 385.369728 -296.163594) (xy 385.40508 -296.127039) (xy 385.445612 -296.096329)
			(xy 385.49037 -296.072188) (xy 385.538296 -296.055186) (xy 385.588261 -296.045724) (xy 385.613656 -296.044366)
			(xy 385.628896 -296.043858) (xy 385.653534 -296.026586) (xy 385.693412 -295.925494) (xy 385.697408 -295.913431)
			(xy 385.69435 -295.888235) (xy 385.68757 -295.877488) (xy 385.684776 -295.873678) (xy 384.61569 -294.804592)
			(xy 384.603752 -294.797988) (xy 384.596894 -294.79621) (xy 384.571296 -294.789455) (xy 384.522499 -294.76893)
			(xy 384.477588 -294.740903) (xy 384.437708 -294.706089) (xy 384.403874 -294.665375) (xy 384.376948 -294.619796)
			(xy 384.357615 -294.570514) (xy 384.35153 -294.54475) (xy 384.350006 -294.537384) (xy 384.343148 -294.524684)
			(xy 382.404874 -292.586664) (xy 382.397477 -292.579815) (xy 382.378878 -292.57208) (xy 382.368806 -292.571678)
			(xy 380.510542 -292.571678) (xy 380.499796 -292.572164) (xy 380.480201 -292.580988) (xy 380.472696 -292.588696)
			(xy 380.42215 -292.645592) (xy 380.415331 -292.654011) (xy 380.408863 -292.67467) (xy 380.409704 -292.68547)
			(xy 380.411049 -292.697234) (xy 380.412445 -292.720873) (xy 380.412498 -292.732714) (xy 380.412011 -292.759964)
			(xy 380.404253 -292.81391) (xy 380.388896 -292.866202) (xy 380.366254 -292.915777) (xy 380.336787 -292.961625)
			(xy 380.301096 -293.002813) (xy 380.259906 -293.038502) (xy 380.214056 -293.067966) (xy 380.16448 -293.090605)
			(xy 380.112186 -293.105958) (xy 380.05824 -293.113712) (xy 380.03099 -293.114222) (xy 380.00637 -293.113832)
			(xy 379.957539 -293.107496) (xy 379.909925 -293.094943) (xy 379.886972 -293.086028) (xy 379.875034 -293.081202)
			(xy 379.850142 -293.083742) (xy 379.785118 -293.12743) (xy 379.7808 -293.126922) (xy 379.764036 -293.141908)
			(xy 379.756411 -293.149471) (xy 379.747605 -293.169031) (xy 379.747018 -293.179754) (xy 379.747018 -293.494714)
			(xy 381.921002 -293.494714) (xy 381.925073 -293.439092) (xy 381.937199 -293.384655) (xy 381.957122 -293.332564)
			(xy 381.984418 -293.283929) (xy 382.018504 -293.239786) (xy 382.058653 -293.201077) (xy 382.104011 -293.168626)
			(xy 382.153611 -293.143125) (xy 382.206395 -293.125118) (xy 382.261238 -293.114988) (xy 382.316972 -293.112951)
			(xy 382.372409 -293.119051) (xy 382.426366 -293.133157) (xy 382.477695 -293.154969) (xy 382.525301 -293.184023)
			(xy 382.568169 -293.219698) (xy 382.605386 -293.261235) (xy 382.636159 -293.307748) (xy 382.659831 -293.358245)
			(xy 382.675899 -293.411652) (xy 382.684019 -293.466828) (xy 382.684528 -293.494714) (xy 382.684019 -293.5226)
			(xy 382.675899 -293.577776) (xy 382.659831 -293.631183) (xy 382.636159 -293.68168) (xy 382.605386 -293.728193)
			(xy 382.568169 -293.76973) (xy 382.525301 -293.805405) (xy 382.477695 -293.834459) (xy 382.426366 -293.856271)
			(xy 382.372409 -293.870377) (xy 382.316972 -293.876477) (xy 382.261238 -293.87444) (xy 382.206395 -293.86431)
			(xy 382.153611 -293.846303) (xy 382.104011 -293.820802) (xy 382.058653 -293.788351) (xy 382.018504 -293.749642)
			(xy 381.984418 -293.705499) (xy 381.957122 -293.656864) (xy 381.937199 -293.604773) (xy 381.925073 -293.550336)
			(xy 381.921002 -293.494714) (xy 379.747018 -293.494714) (xy 379.747018 -295.207182) (xy 379.747457 -295.217245)
			(xy 379.755194 -295.235826) (xy 379.762004 -295.24325) (xy 379.929898 -295.411144) (xy 379.937294 -295.417997)
			(xy 379.955892 -295.425741) (xy 379.965966 -295.42613) (xy 381.506222 -295.42613) (xy 381.51629 -295.426558)
			(xy 381.534886 -295.434281) (xy 381.54229 -295.441116) (xy 381.851408 -295.750234) (xy 381.858248 -295.757635)
			(xy 381.865969 -295.776233) (xy 381.866394 -295.786302) (xy 381.866394 -296.288968) (xy 381.866488 -296.293987)
			(xy 381.868411 -296.303837) (xy 381.870204 -296.308526) (xy 381.877062 -296.324782) (xy 381.878373 -296.328154)
			(xy 381.880156 -296.335164) (xy 381.880618 -296.338752) (xy 381.882142 -296.352468) (xy 381.897636 -296.374312)
			(xy 381.995172 -296.418254) (xy 382.004266 -296.421851) (xy 382.023791 -296.422614) (xy 382.04219 -296.416036)
			(xy 382.049782 -296.409872) (xy 382.070825 -296.391835) (xy 382.117143 -296.361403) (xy 382.167379 -296.337997)
			(xy 382.220474 -296.322109) (xy 382.27531 -296.314075) (xy 382.30302 -296.313606) (xy 382.330269 -296.314094)
			(xy 382.384213 -296.321852) (xy 382.436503 -296.337208) (xy 382.486076 -296.35985) (xy 382.508973 -296.374566)
			(xy 384.369068 -296.374566) (xy 384.373028 -296.325512) (xy 384.384805 -296.277728) (xy 384.404096 -296.232452)
			(xy 384.430399 -296.190856) (xy 384.463034 -296.154019) (xy 384.501155 -296.122894) (xy 384.543776 -296.098287)
			(xy 384.589792 -296.080835) (xy 384.638011 -296.070991) (xy 384.687186 -296.06901) (xy 384.736041 -296.074942)
			(xy 384.783312 -296.088634) (xy 384.827774 -296.109732) (xy 384.868277 -296.137688) (xy 384.90377 -296.17178)
			(xy 384.933335 -296.211124) (xy 384.956206 -296.254701) (xy 384.97179 -296.301382) (xy 384.979685 -296.349959)
			(xy 384.98018 -296.374566) (xy 384.979685 -296.399173) (xy 384.97179 -296.44775) (xy 384.956206 -296.494431)
			(xy 384.933335 -296.538008) (xy 384.90377 -296.577352) (xy 384.868277 -296.611444) (xy 384.827774 -296.6394)
			(xy 384.783312 -296.660498) (xy 384.736041 -296.67419) (xy 384.687186 -296.680122) (xy 384.638011 -296.678141)
			(xy 384.589792 -296.668297) (xy 384.543776 -296.650845) (xy 384.501155 -296.626238) (xy 384.463034 -296.595113)
			(xy 384.430399 -296.558276) (xy 384.404096 -296.51668) (xy 384.384805 -296.471404) (xy 384.373028 -296.42362)
			(xy 384.369068 -296.374566) (xy 382.508973 -296.374566) (xy 382.531922 -296.389316) (xy 382.573108 -296.425006)
			(xy 382.608796 -296.466194) (xy 382.63826 -296.512042) (xy 382.660899 -296.561616) (xy 382.676252 -296.613907)
			(xy 382.684008 -296.667851) (xy 382.684008 -296.722349) (xy 382.676252 -296.776293) (xy 382.660899 -296.828584)
			(xy 382.63826 -296.878158) (xy 382.608796 -296.924006) (xy 382.573108 -296.965194) (xy 382.531922 -297.000884)
			(xy 382.486076 -297.03035) (xy 382.436503 -297.052992) (xy 382.384213 -297.068348) (xy 382.330269 -297.076106)
			(xy 382.30302 -297.076622) (xy 382.27531 -297.076126) (xy 382.220473 -297.068104) (xy 382.167376 -297.052227)
			(xy 382.117137 -297.028828) (xy 382.070816 -296.998402) (xy 382.049782 -296.980356) (xy 382.038352 -296.97045)
			(xy 382.008888 -296.965878) (xy 381.910844 -297.010074) (xy 381.902159 -297.014484) (xy 381.888685 -297.028529)
			(xy 381.881389 -297.046573) (xy 381.880872 -297.056302) (xy 381.880872 -297.3248) (xy 383.734049 -297.3248)
			(xy 383.73822 -297.274461) (xy 383.750619 -297.225496) (xy 383.770908 -297.179239) (xy 383.798533 -297.136952)
			(xy 383.832742 -297.099788) (xy 383.872601 -297.068761) (xy 383.917022 -297.044718) (xy 383.964795 -297.028314)
			(xy 384.014617 -297.019996) (xy 384.039872 -297.019472) (xy 384.065267 -297.019985) (xy 384.115357 -297.028398)
			(xy 384.163364 -297.044982) (xy 384.207966 -297.069279) (xy 384.247935 -297.100619) (xy 384.265424 -297.11904)
			(xy 384.273044 -297.127168) (xy 384.292856 -297.135804) (xy 384.39217 -297.13301) (xy 384.411728 -297.123612)
			(xy 384.41884 -297.114976) (xy 384.43463 -297.096405) (xy 384.470763 -297.063686) (xy 384.511304 -297.036619)
			(xy 384.555376 -297.01579) (xy 384.602026 -297.00165) (xy 384.650245 -296.994504) (xy 384.674618 -296.994072)
			(xy 385.624578 -296.994072) (xy 385.650567 -296.994593) (xy 385.701905 -297.002721) (xy 385.751339 -297.018781)
			(xy 385.797653 -297.042376) (xy 385.839705 -297.072926) (xy 385.87646 -297.109678) (xy 385.907013 -297.151728)
			(xy 385.930611 -297.19804) (xy 385.946673 -297.247474) (xy 385.954805 -297.298811) (xy 385.954805 -297.32478)
			(xy 386.268988 -297.32478) (xy 386.272948 -297.275726) (xy 386.284725 -297.227942) (xy 386.304016 -297.182666)
			(xy 386.330319 -297.14107) (xy 386.362954 -297.104233) (xy 386.401075 -297.073108) (xy 386.443696 -297.048501)
			(xy 386.489712 -297.031049) (xy 386.537931 -297.021205) (xy 386.587106 -297.019224) (xy 386.635961 -297.025156)
			(xy 386.683232 -297.038848) (xy 386.727694 -297.059946) (xy 386.768197 -297.087902) (xy 386.80369 -297.121994)
			(xy 386.833255 -297.161338) (xy 386.856126 -297.204915) (xy 386.87171 -297.251596) (xy 386.879605 -297.300173)
			(xy 386.8801 -297.32478) (xy 387.219202 -297.32478) (xy 387.223162 -297.275726) (xy 387.234939 -297.227942)
			(xy 387.25423 -297.182666) (xy 387.280533 -297.14107) (xy 387.313168 -297.104233) (xy 387.351289 -297.073108)
			(xy 387.39391 -297.048501) (xy 387.439926 -297.031049) (xy 387.488145 -297.021205) (xy 387.53732 -297.019224)
			(xy 387.586175 -297.025156) (xy 387.633446 -297.038848) (xy 387.677908 -297.059946) (xy 387.718411 -297.087902)
			(xy 387.753904 -297.121994) (xy 387.783469 -297.161338) (xy 387.80634 -297.204915) (xy 387.821924 -297.251596)
			(xy 387.829819 -297.300173) (xy 387.830314 -297.32478) (xy 390.069082 -297.32478) (xy 390.073042 -297.275726)
			(xy 390.084819 -297.227942) (xy 390.10411 -297.182666) (xy 390.130413 -297.14107) (xy 390.163048 -297.104233)
			(xy 390.201169 -297.073108) (xy 390.24379 -297.048501) (xy 390.289806 -297.031049) (xy 390.338025 -297.021205)
			(xy 390.3872 -297.019224) (xy 390.436055 -297.025156) (xy 390.483326 -297.038848) (xy 390.527788 -297.059946)
			(xy 390.568291 -297.087902) (xy 390.603784 -297.121994) (xy 390.633349 -297.161338) (xy 390.65622 -297.204915)
			(xy 390.671804 -297.251596) (xy 390.679699 -297.300173) (xy 390.680194 -297.32478) (xy 391.019042 -297.32478)
			(xy 391.023002 -297.275726) (xy 391.034779 -297.227942) (xy 391.05407 -297.182666) (xy 391.080373 -297.14107)
			(xy 391.113008 -297.104233) (xy 391.151129 -297.073108) (xy 391.19375 -297.048501) (xy 391.239766 -297.031049)
			(xy 391.287985 -297.021205) (xy 391.33716 -297.019224) (xy 391.386015 -297.025156) (xy 391.433286 -297.038848)
			(xy 391.477748 -297.059946) (xy 391.518251 -297.087902) (xy 391.553744 -297.121994) (xy 391.583309 -297.161338)
			(xy 391.60618 -297.204915) (xy 391.621764 -297.251596) (xy 391.629659 -297.300173) (xy 391.630154 -297.32478)
			(xy 391.969002 -297.32478) (xy 391.972962 -297.275726) (xy 391.984739 -297.227942) (xy 392.00403 -297.182666)
			(xy 392.030333 -297.14107) (xy 392.062968 -297.104233) (xy 392.101089 -297.073108) (xy 392.14371 -297.048501)
			(xy 392.189726 -297.031049) (xy 392.237945 -297.021205) (xy 392.28712 -297.019224) (xy 392.335975 -297.025156)
			(xy 392.383246 -297.038848) (xy 392.427708 -297.059946) (xy 392.468211 -297.087902) (xy 392.503704 -297.121994)
			(xy 392.533269 -297.161338) (xy 392.55614 -297.204915) (xy 392.571724 -297.251596) (xy 392.579619 -297.300173)
			(xy 392.580114 -297.32478) (xy 392.919216 -297.32478) (xy 392.923176 -297.275726) (xy 392.934953 -297.227942)
			(xy 392.954244 -297.182666) (xy 392.980547 -297.14107) (xy 393.013182 -297.104233) (xy 393.051303 -297.073108)
			(xy 393.093924 -297.048501) (xy 393.13994 -297.031049) (xy 393.188159 -297.021205) (xy 393.237334 -297.019224)
			(xy 393.286189 -297.025156) (xy 393.33346 -297.038848) (xy 393.377922 -297.059946) (xy 393.418425 -297.087902)
			(xy 393.453918 -297.121994) (xy 393.483483 -297.161338) (xy 393.506354 -297.204915) (xy 393.521938 -297.251596)
			(xy 393.529833 -297.300173) (xy 393.530328 -297.32478) (xy 393.869176 -297.32478) (xy 393.873136 -297.275726)
			(xy 393.884913 -297.227942) (xy 393.904204 -297.182666) (xy 393.930507 -297.14107) (xy 393.963142 -297.104233)
			(xy 394.001263 -297.073108) (xy 394.043884 -297.048501) (xy 394.0899 -297.031049) (xy 394.138119 -297.021205)
			(xy 394.187294 -297.019224) (xy 394.236149 -297.025156) (xy 394.28342 -297.038848) (xy 394.327882 -297.059946)
			(xy 394.368385 -297.087902) (xy 394.403878 -297.121994) (xy 394.433443 -297.161338) (xy 394.456314 -297.204915)
			(xy 394.471898 -297.251596) (xy 394.479793 -297.300173) (xy 394.480288 -297.32478) (xy 394.479793 -297.349387)
			(xy 394.471898 -297.397964) (xy 394.456314 -297.444645) (xy 394.433443 -297.488222) (xy 394.403878 -297.527566)
			(xy 394.368385 -297.561658) (xy 394.327882 -297.589614) (xy 394.28342 -297.610712) (xy 394.236149 -297.624404)
			(xy 394.187294 -297.630336) (xy 394.138119 -297.628355) (xy 394.0899 -297.618511) (xy 394.043884 -297.601059)
			(xy 394.001263 -297.576452) (xy 393.963142 -297.545327) (xy 393.930507 -297.50849) (xy 393.904204 -297.466894)
			(xy 393.884913 -297.421618) (xy 393.873136 -297.373834) (xy 393.869176 -297.32478) (xy 393.530328 -297.32478)
			(xy 393.529833 -297.349387) (xy 393.521938 -297.397964) (xy 393.506354 -297.444645) (xy 393.483483 -297.488222)
			(xy 393.453918 -297.527566) (xy 393.418425 -297.561658) (xy 393.377922 -297.589614) (xy 393.33346 -297.610712)
			(xy 393.286189 -297.624404) (xy 393.237334 -297.630336) (xy 393.188159 -297.628355) (xy 393.13994 -297.618511)
			(xy 393.093924 -297.601059) (xy 393.051303 -297.576452) (xy 393.013182 -297.545327) (xy 392.980547 -297.50849)
			(xy 392.954244 -297.466894) (xy 392.934953 -297.421618) (xy 392.923176 -297.373834) (xy 392.919216 -297.32478)
			(xy 392.580114 -297.32478) (xy 392.579619 -297.349387) (xy 392.571724 -297.397964) (xy 392.55614 -297.444645)
			(xy 392.533269 -297.488222) (xy 392.503704 -297.527566) (xy 392.468211 -297.561658) (xy 392.427708 -297.589614)
			(xy 392.383246 -297.610712) (xy 392.335975 -297.624404) (xy 392.28712 -297.630336) (xy 392.237945 -297.628355)
			(xy 392.189726 -297.618511) (xy 392.14371 -297.601059) (xy 392.101089 -297.576452) (xy 392.062968 -297.545327)
			(xy 392.030333 -297.50849) (xy 392.00403 -297.466894) (xy 391.984739 -297.421618) (xy 391.972962 -297.373834)
			(xy 391.969002 -297.32478) (xy 391.630154 -297.32478) (xy 391.629659 -297.349387) (xy 391.621764 -297.397964)
			(xy 391.60618 -297.444645) (xy 391.583309 -297.488222) (xy 391.553744 -297.527566) (xy 391.518251 -297.561658)
			(xy 391.477748 -297.589614) (xy 391.433286 -297.610712) (xy 391.386015 -297.624404) (xy 391.33716 -297.630336)
			(xy 391.287985 -297.628355) (xy 391.239766 -297.618511) (xy 391.19375 -297.601059) (xy 391.151129 -297.576452)
			(xy 391.113008 -297.545327) (xy 391.080373 -297.50849) (xy 391.05407 -297.466894) (xy 391.034779 -297.421618)
			(xy 391.023002 -297.373834) (xy 391.019042 -297.32478) (xy 390.680194 -297.32478) (xy 390.679699 -297.349387)
			(xy 390.671804 -297.397964) (xy 390.65622 -297.444645) (xy 390.633349 -297.488222) (xy 390.603784 -297.527566)
			(xy 390.568291 -297.561658) (xy 390.527788 -297.589614) (xy 390.483326 -297.610712) (xy 390.436055 -297.624404)
			(xy 390.3872 -297.630336) (xy 390.338025 -297.628355) (xy 390.289806 -297.618511) (xy 390.24379 -297.601059)
			(xy 390.201169 -297.576452) (xy 390.163048 -297.545327) (xy 390.130413 -297.50849) (xy 390.10411 -297.466894)
			(xy 390.084819 -297.421618) (xy 390.073042 -297.373834) (xy 390.069082 -297.32478) (xy 387.830314 -297.32478)
			(xy 387.829819 -297.349387) (xy 387.821924 -297.397964) (xy 387.80634 -297.444645) (xy 387.783469 -297.488222)
			(xy 387.753904 -297.527566) (xy 387.718411 -297.561658) (xy 387.677908 -297.589614) (xy 387.633446 -297.610712)
			(xy 387.586175 -297.624404) (xy 387.53732 -297.630336) (xy 387.488145 -297.628355) (xy 387.439926 -297.618511)
			(xy 387.39391 -297.601059) (xy 387.351289 -297.576452) (xy 387.313168 -297.545327) (xy 387.280533 -297.50849)
			(xy 387.25423 -297.466894) (xy 387.234939 -297.421618) (xy 387.223162 -297.373834) (xy 387.219202 -297.32478)
			(xy 386.8801 -297.32478) (xy 386.879605 -297.349387) (xy 386.87171 -297.397964) (xy 386.856126 -297.444645)
			(xy 386.833255 -297.488222) (xy 386.80369 -297.527566) (xy 386.768197 -297.561658) (xy 386.727694 -297.589614)
			(xy 386.683232 -297.610712) (xy 386.635961 -297.624404) (xy 386.587106 -297.630336) (xy 386.537931 -297.628355)
			(xy 386.489712 -297.618511) (xy 386.443696 -297.601059) (xy 386.401075 -297.576452) (xy 386.362954 -297.545327)
			(xy 386.330319 -297.50849) (xy 386.304016 -297.466894) (xy 386.284725 -297.421618) (xy 386.272948 -297.373834)
			(xy 386.268988 -297.32478) (xy 385.954805 -297.32478) (xy 385.954805 -297.350789) (xy 385.946673 -297.402126)
			(xy 385.930611 -297.45156) (xy 385.907013 -297.497872) (xy 385.87646 -297.539922) (xy 385.839705 -297.576674)
			(xy 385.797653 -297.607224) (xy 385.751339 -297.630819) (xy 385.701905 -297.646879) (xy 385.650567 -297.655007)
			(xy 385.624578 -297.655488) (xy 384.674618 -297.655488) (xy 384.650244 -297.655085) (xy 384.602024 -297.647936)
			(xy 384.555373 -297.633791) (xy 384.511303 -297.612954) (xy 384.470767 -297.585877) (xy 384.434642 -297.553147)
			(xy 384.41884 -297.534584) (xy 384.411728 -297.525948) (xy 384.39217 -297.51655) (xy 384.292856 -297.513756)
			(xy 384.273044 -297.522392) (xy 384.265424 -297.53052) (xy 384.247939 -297.548946) (xy 384.207975 -297.580297)
			(xy 384.163372 -297.604598) (xy 384.115362 -297.621181) (xy 384.065269 -297.629585) (xy 384.039872 -297.630088)
			(xy 384.014617 -297.629604) (xy 383.964795 -297.621286) (xy 383.917022 -297.604882) (xy 383.872601 -297.580839)
			(xy 383.832742 -297.549812) (xy 383.798533 -297.512648) (xy 383.770908 -297.470361) (xy 383.750619 -297.424104)
			(xy 383.73822 -297.375139) (xy 383.734049 -297.3248) (xy 381.880872 -297.3248) (xy 381.880872 -297.997626)
			(xy 381.880757 -298.002722) (xy 381.878705 -298.012706) (xy 381.876808 -298.017438) (xy 381.870204 -298.032932)
			(xy 381.868409 -298.037619) (xy 381.866497 -298.047471) (xy 381.866394 -298.05249) (xy 381.866394 -298.118276)
			(xy 381.866831 -298.12834) (xy 381.874564 -298.146925) (xy 381.88138 -298.154344) (xy 382.006602 -298.279566)
			(xy 382.00711 -298.280074) (xy 382.01449 -298.286661) (xy 382.032788 -298.294124) (xy 382.04267 -298.294552)
			(xy 384.3401 -298.294552)
		)
		(stroke
			(width 0)
			(type solid)
		)
		(fill yes)
		(layer "In5.Cu")
		(net "PCEPLL2_VDDA18_PEX3")
	)
	(gr_poly
		(pts
			(xy 15.681452 -390.568688) (xy 15.691326 -390.568222) (xy 15.709615 -390.560768) (xy 15.717012 -390.55421)
			(xy 15.717266 -390.553956) (xy 16.030702 -390.24052) (xy 16.037535 -390.233117) (xy 16.04524 -390.214519)
			(xy 16.045688 -390.204452) (xy 16.045688 -384.527044) (xy 16.045254 -384.516979) (xy 16.037524 -384.49839)
			(xy 16.030702 -384.490976) (xy 15.507716 -383.96799) (xy 15.500317 -383.961147) (xy 15.481718 -383.953429)
			(xy 15.471648 -383.953004) (xy 13.817092 -383.953004) (xy 13.807022 -383.952579) (xy 13.78842 -383.944863)
			(xy 13.781024 -383.938018) (xy 13.086334 -383.243328) (xy 13.079495 -383.235927) (xy 13.071782 -383.217329)
			(xy 13.071348 -383.20726) (xy 13.071348 -371.219476) (xy 13.070919 -371.209409) (xy 13.063193 -371.190816)
			(xy 13.056362 -371.183408) (xy 11.942318 -370.069364) (xy 11.934918 -370.062524) (xy 11.916319 -370.054809)
			(xy 11.90625 -370.054378) (xy 5.771388 -370.054378) (xy 5.761319 -370.053952) (xy 5.74272 -370.046232)
			(xy 5.73532 -370.039392) (xy 5.193284 -369.497356) (xy 5.186435 -369.489959) (xy 5.178703 -369.47136)
			(xy 5.178298 -369.461288) (xy 5.178298 -364.527338) (xy 5.177863 -364.517273) (xy 5.170133 -364.498685)
			(xy 5.163312 -364.49127) (xy 4.88823 -364.216188) (xy 4.880832 -364.209343) (xy 4.862233 -364.20162)
			(xy 4.852162 -364.201202) (xy 2.758948 -364.201202) (xy 2.748882 -364.201635) (xy 2.730292 -364.209363)
			(xy 2.72288 -364.216188) (xy 2.199894 -364.739174) (xy 2.19306 -364.746577) (xy 2.185353 -364.765175)
			(xy 2.184908 -364.775242) (xy 2.184908 -372.011448) (xy 5.278118 -372.011448) (xy 5.282189 -371.955826)
			(xy 5.294315 -371.901389) (xy 5.314238 -371.849298) (xy 5.341534 -371.800663) (xy 5.37562 -371.75652)
			(xy 5.415769 -371.717811) (xy 5.461127 -371.68536) (xy 5.510727 -371.659859) (xy 5.563511 -371.641852)
			(xy 5.618354 -371.631722) (xy 5.674088 -371.629685) (xy 5.729525 -371.635785) (xy 5.783482 -371.649891)
			(xy 5.834811 -371.671703) (xy 5.882417 -371.700757) (xy 5.925285 -371.736432) (xy 5.962502 -371.777969)
			(xy 5.993275 -371.824482) (xy 6.016947 -371.874979) (xy 6.033015 -371.928386) (xy 6.041135 -371.983562)
			(xy 6.041644 -372.011448) (xy 6.041135 -372.039334) (xy 6.033015 -372.09451) (xy 6.016947 -372.147917)
			(xy 5.993275 -372.198414) (xy 5.962502 -372.244927) (xy 5.925285 -372.286464) (xy 5.882417 -372.322139)
			(xy 5.834811 -372.351193) (xy 5.783482 -372.373005) (xy 5.729525 -372.387111) (xy 5.674088 -372.393211)
			(xy 5.618354 -372.391174) (xy 5.563511 -372.381044) (xy 5.510727 -372.363037) (xy 5.461127 -372.337536)
			(xy 5.415769 -372.305085) (xy 5.37562 -372.266376) (xy 5.341534 -372.222233) (xy 5.314238 -372.173598)
			(xy 5.294315 -372.121507) (xy 5.282189 -372.06707) (xy 5.278118 -372.011448) (xy 2.184908 -372.011448)
			(xy 2.184908 -372.921784) (xy 3.759198 -372.921784) (xy 3.763269 -372.866162) (xy 3.775395 -372.811725)
			(xy 3.795318 -372.759634) (xy 3.822614 -372.710999) (xy 3.8567 -372.666856) (xy 3.896849 -372.628147)
			(xy 3.942207 -372.595696) (xy 3.991807 -372.570195) (xy 4.044591 -372.552188) (xy 4.099434 -372.542058)
			(xy 4.155168 -372.540021) (xy 4.210605 -372.546121) (xy 4.264562 -372.560227) (xy 4.315891 -372.582039)
			(xy 4.363497 -372.611093) (xy 4.406365 -372.646768) (xy 4.443582 -372.688305) (xy 4.474355 -372.734818)
			(xy 4.490116 -372.76844) (xy 8.137095 -372.76844) (xy 8.137096 -372.713934) (xy 8.144853 -372.659983)
			(xy 8.160209 -372.607686) (xy 8.182852 -372.558106) (xy 8.212321 -372.512253) (xy 8.248015 -372.47106)
			(xy 8.289208 -372.435367) (xy 8.335061 -372.405899) (xy 8.384642 -372.383257) (xy 8.43694 -372.367901)
			(xy 8.490891 -372.360145) (xy 8.518144 -372.359682) (xy 8.529091 -372.359764) (xy 8.550949 -372.361037)
			(xy 8.561832 -372.362222) (xy 8.57504 -372.363746) (xy 8.59917 -372.353586) (xy 8.669274 -372.26494)
			(xy 8.673592 -372.239286) (xy 8.66902 -372.226586) (xy 8.660348 -372.201553) (xy 8.648164 -372.149993)
			(xy 8.641997 -372.097373) (xy 8.641588 -372.070884) (xy 8.642047 -372.040904) (xy 8.649878 -371.981458)
			(xy 8.665403 -371.923543) (xy 8.688358 -371.868152) (xy 8.718348 -371.816231) (xy 8.754861 -371.768671)
			(xy 8.797271 -371.726286) (xy 8.844853 -371.6898) (xy 8.896791 -371.65984) (xy 8.952196 -371.636918)
			(xy 9.010119 -371.621426) (xy 9.06957 -371.613629) (xy 9.09955 -371.613176) (xy 9.96315 -371.613176)
			(xy 9.993124 -371.613667) (xy 10.052558 -371.621489) (xy 10.110465 -371.636999) (xy 10.165852 -371.659932)
			(xy 10.217773 -371.689896) (xy 10.265341 -371.726379) (xy 10.307742 -371.768756) (xy 10.344251 -371.816304)
			(xy 10.374244 -371.868208) (xy 10.397208 -371.923583) (xy 10.412751 -371.98148) (xy 10.420606 -372.040911)
			(xy 10.421112 -372.070884) (xy 10.420469 -372.105568) (xy 10.409971 -372.174139) (xy 10.389273 -372.240349)
			(xy 10.37463 -372.271798) (xy 10.369042 -372.282974) (xy 10.369804 -372.307612) (xy 10.421874 -372.4021)
			(xy 10.442448 -372.41607) (xy 10.45464 -372.41734) (xy 10.482311 -372.420865) (xy 10.536282 -372.434964)
			(xy 10.587623 -372.456773) (xy 10.635242 -372.485825) (xy 10.678123 -372.521502) (xy 10.715351 -372.563043)
			(xy 10.746133 -372.609562) (xy 10.769812 -372.660068) (xy 10.785885 -372.713484) (xy 10.794008 -372.768671)
			(xy 10.794492 -372.796562) (xy 10.794006 -372.823813) (xy 10.78625 -372.877761) (xy 10.770895 -372.930056)
			(xy 10.748253 -372.979633) (xy 10.718787 -373.025483) (xy 10.683096 -373.066674) (xy 10.641905 -373.102365)
			(xy 10.596055 -373.131831) (xy 10.546478 -373.154473) (xy 10.494183 -373.169828) (xy 10.440235 -373.177584)
			(xy 10.385733 -373.177584) (xy 10.331785 -373.169828) (xy 10.27949 -373.154473) (xy 10.229913 -373.131831)
			(xy 10.184063 -373.102365) (xy 10.142872 -373.066674) (xy 10.107181 -373.025483) (xy 10.077715 -372.979633)
			(xy 10.055073 -372.930056) (xy 10.039718 -372.877761) (xy 10.031962 -372.823813) (xy 10.031476 -372.796562)
			(xy 10.031897 -372.77066) (xy 10.038912 -372.719332) (xy 10.052807 -372.669426) (xy 10.073327 -372.621859)
			(xy 10.08634 -372.599458) (xy 10.091042 -372.590987) (xy 10.09425 -372.571892) (xy 10.090146 -372.55297)
			(xy 10.079317 -372.536919) (xy 10.063307 -372.52603) (xy 10.0444 -372.521855) (xy 10.034778 -372.523004)
			(xy 10.016987 -372.525624) (xy 9.981132 -372.528424) (xy 9.96315 -372.528592) (xy 9.09955 -372.528592)
			(xy 9.076017 -372.528344) (xy 9.029189 -372.523638) (xy 9.006078 -372.519194) (xy 8.993124 -372.5164)
			(xy 8.968232 -372.524274) (xy 8.890254 -372.606062) (xy 8.88365 -372.631462) (xy 8.887206 -372.644416)
			(xy 8.893019 -372.668186) (xy 8.899259 -372.716722) (xy 8.899652 -372.74119) (xy 8.899185 -372.768443)
			(xy 8.891428 -372.822394) (xy 8.876072 -372.874692) (xy 8.853429 -372.924272) (xy 8.823961 -372.970125)
			(xy 8.788267 -373.011318) (xy 8.747074 -373.047012) (xy 8.701221 -373.07648) (xy 8.651641 -373.099122)
			(xy 8.599343 -373.114478) (xy 8.545392 -373.122235) (xy 8.490886 -373.122235) (xy 8.436935 -373.114477)
			(xy 8.384637 -373.099121) (xy 8.335057 -373.076478) (xy 8.289204 -373.04701) (xy 8.248011 -373.011316)
			(xy 8.212318 -372.970123) (xy 8.18285 -372.92427) (xy 8.160208 -372.874689) (xy 8.144852 -372.822391)
			(xy 8.137095 -372.76844) (xy 4.490116 -372.76844) (xy 4.498027 -372.785315) (xy 4.514095 -372.838722)
			(xy 4.522215 -372.893898) (xy 4.522724 -372.921784) (xy 4.522215 -372.94967) (xy 4.514095 -373.004846)
			(xy 4.498027 -373.058253) (xy 4.474355 -373.10875) (xy 4.443582 -373.155263) (xy 4.406365 -373.1968)
			(xy 4.363497 -373.232475) (xy 4.315891 -373.261529) (xy 4.264562 -373.283341) (xy 4.210605 -373.297447)
			(xy 4.155168 -373.303547) (xy 4.099434 -373.30151) (xy 4.044591 -373.29138) (xy 3.991807 -373.273373)
			(xy 3.942207 -373.247872) (xy 3.896849 -373.215421) (xy 3.8567 -373.176712) (xy 3.822614 -373.132569)
			(xy 3.795318 -373.083934) (xy 3.775395 -373.031843) (xy 3.763269 -372.977406) (xy 3.759198 -372.921784)
			(xy 2.184908 -372.921784) (xy 2.184908 -375.083578) (xy 3.073906 -375.083578) (xy 3.077977 -375.027956)
			(xy 3.090103 -374.973519) (xy 3.110026 -374.921428) (xy 3.137322 -374.872793) (xy 3.171408 -374.82865)
			(xy 3.211557 -374.789941) (xy 3.256915 -374.75749) (xy 3.306515 -374.731989) (xy 3.359299 -374.713982)
			(xy 3.414142 -374.703852) (xy 3.469876 -374.701815) (xy 3.525313 -374.707915) (xy 3.57927 -374.722021)
			(xy 3.630599 -374.743833) (xy 3.678205 -374.772887) (xy 3.721073 -374.808562) (xy 3.75829 -374.850099)
			(xy 3.789063 -374.896612) (xy 3.812735 -374.947109) (xy 3.828803 -375.000516) (xy 3.836923 -375.055692)
			(xy 3.837432 -375.083578) (xy 3.836923 -375.111464) (xy 3.828803 -375.16664) (xy 3.812735 -375.220047)
			(xy 3.789063 -375.270544) (xy 3.75829 -375.317057) (xy 3.721073 -375.358594) (xy 3.678205 -375.394269)
			(xy 3.630599 -375.423323) (xy 3.57927 -375.445135) (xy 3.525313 -375.459241) (xy 3.469876 -375.465341)
			(xy 3.414142 -375.463304) (xy 3.359299 -375.453174) (xy 3.306515 -375.435167) (xy 3.256915 -375.409666)
			(xy 3.211557 -375.377215) (xy 3.171408 -375.338506) (xy 3.137322 -375.294363) (xy 3.110026 -375.245728)
			(xy 3.090103 -375.193637) (xy 3.077977 -375.1392) (xy 3.073906 -375.083578) (xy 2.184908 -375.083578)
			(xy 2.184908 -375.834148) (xy 5.090158 -375.834148) (xy 5.094229 -375.778526) (xy 5.106355 -375.724089)
			(xy 5.126278 -375.671998) (xy 5.153574 -375.623363) (xy 5.18766 -375.57922) (xy 5.227809 -375.540511)
			(xy 5.273167 -375.50806) (xy 5.322767 -375.482559) (xy 5.375551 -375.464552) (xy 5.430394 -375.454422)
			(xy 5.486128 -375.452385) (xy 5.541565 -375.458485) (xy 5.595522 -375.472591) (xy 5.646851 -375.494403)
			(xy 5.694457 -375.523457) (xy 5.737325 -375.559132) (xy 5.774542 -375.600669) (xy 5.805315 -375.647182)
			(xy 5.828987 -375.697679) (xy 5.845055 -375.751086) (xy 5.853175 -375.806262) (xy 5.853684 -375.834148)
			(xy 5.853175 -375.862034) (xy 5.845055 -375.91721) (xy 5.828987 -375.970617) (xy 5.805315 -376.021114)
			(xy 5.774542 -376.067627) (xy 5.737325 -376.109164) (xy 5.694457 -376.144839) (xy 5.646851 -376.173893)
			(xy 5.595522 -376.195705) (xy 5.541565 -376.209811) (xy 5.486128 -376.215911) (xy 5.430394 -376.213874)
			(xy 5.375551 -376.203744) (xy 5.322767 -376.185737) (xy 5.273167 -376.160236) (xy 5.227809 -376.127785)
			(xy 5.18766 -376.089076) (xy 5.153574 -376.044933) (xy 5.126278 -375.996298) (xy 5.106355 -375.944207)
			(xy 5.094229 -375.88977) (xy 5.090158 -375.834148) (xy 2.184908 -375.834148) (xy 2.184908 -377.517914)
			(xy 6.139178 -377.517914) (xy 6.143249 -377.462292) (xy 6.155375 -377.407855) (xy 6.175298 -377.355764)
			(xy 6.202594 -377.307129) (xy 6.23668 -377.262986) (xy 6.276829 -377.224277) (xy 6.322187 -377.191826)
			(xy 6.371787 -377.166325) (xy 6.424571 -377.148318) (xy 6.479414 -377.138188) (xy 6.535148 -377.136151)
			(xy 6.590585 -377.142251) (xy 6.644542 -377.156357) (xy 6.695871 -377.178169) (xy 6.743477 -377.207223)
			(xy 6.786345 -377.242898) (xy 6.823562 -377.284435) (xy 6.854335 -377.330948) (xy 6.878007 -377.381445)
			(xy 6.894075 -377.434852) (xy 6.902195 -377.490028) (xy 6.902704 -377.517914) (xy 6.902195 -377.5458)
			(xy 6.894075 -377.600976) (xy 6.878007 -377.654383) (xy 6.854335 -377.70488) (xy 6.823562 -377.751393)
			(xy 6.786345 -377.79293) (xy 6.743477 -377.828605) (xy 6.695871 -377.857659) (xy 6.644542 -377.879471)
			(xy 6.590585 -377.893577) (xy 6.535148 -377.899677) (xy 6.479414 -377.89764) (xy 6.424571 -377.88751)
			(xy 6.371787 -377.869503) (xy 6.322187 -377.844002) (xy 6.276829 -377.811551) (xy 6.23668 -377.772842)
			(xy 6.202594 -377.728699) (xy 6.175298 -377.680064) (xy 6.155375 -377.627973) (xy 6.143249 -377.573536)
			(xy 6.139178 -377.517914) (xy 2.184908 -377.517914) (xy 2.184908 -378.370592) (xy 5.090158 -378.370592)
			(xy 5.094229 -378.31497) (xy 5.106355 -378.260533) (xy 5.126278 -378.208442) (xy 5.153574 -378.159807)
			(xy 5.18766 -378.115664) (xy 5.227809 -378.076955) (xy 5.273167 -378.044504) (xy 5.322767 -378.019003)
			(xy 5.375551 -378.000996) (xy 5.430394 -377.990866) (xy 5.486128 -377.988829) (xy 5.541565 -377.994929)
			(xy 5.595522 -378.009035) (xy 5.646851 -378.030847) (xy 5.694457 -378.059901) (xy 5.737325 -378.095576)
			(xy 5.774542 -378.137113) (xy 5.805315 -378.183626) (xy 5.828987 -378.234123) (xy 5.845055 -378.28753)
			(xy 5.853175 -378.342706) (xy 5.853684 -378.370592) (xy 5.853175 -378.398478) (xy 5.845055 -378.453654)
			(xy 5.828987 -378.507061) (xy 5.805315 -378.557558) (xy 5.774542 -378.604071) (xy 5.737325 -378.645608)
			(xy 5.694457 -378.681283) (xy 5.646851 -378.710337) (xy 5.595522 -378.732149) (xy 5.541565 -378.746255)
			(xy 5.486128 -378.752355) (xy 5.430394 -378.750318) (xy 5.375551 -378.740188) (xy 5.322767 -378.722181)
			(xy 5.273167 -378.69668) (xy 5.227809 -378.664229) (xy 5.18766 -378.62552) (xy 5.153574 -378.581377)
			(xy 5.126278 -378.532742) (xy 5.106355 -378.480651) (xy 5.094229 -378.426214) (xy 5.090158 -378.370592)
			(xy 2.184908 -378.370592) (xy 2.184908 -379.144276) (xy 2.185303 -379.15351) (xy 2.191843 -379.170782)
			(xy 2.204083 -379.184612) (xy 2.212086 -379.189234) (xy 2.304542 -379.237494) (xy 2.332736 -379.235716)
			(xy 2.34442 -379.227588) (xy 2.368556 -379.211412) (xy 2.420698 -379.185781) (xy 2.476126 -379.168361)
			(xy 2.533555 -379.159558) (xy 2.562606 -379.159008) (xy 2.589859 -379.159471) (xy 2.643811 -379.167228)
			(xy 2.69611 -379.182584) (xy 2.745691 -379.205226) (xy 2.791545 -379.234694) (xy 2.832739 -379.270388)
			(xy 2.868433 -379.311581) (xy 2.897902 -379.357435) (xy 2.920545 -379.407016) (xy 2.935901 -379.459315)
			(xy 2.943659 -379.513267) (xy 2.943659 -379.540516) (xy 3.653788 -379.540516) (xy 3.657859 -379.484894)
			(xy 3.669985 -379.430457) (xy 3.689908 -379.378366) (xy 3.717204 -379.329731) (xy 3.75129 -379.285588)
			(xy 3.791439 -379.246879) (xy 3.836797 -379.214428) (xy 3.886397 -379.188927) (xy 3.939181 -379.17092)
			(xy 3.994024 -379.16079) (xy 4.049758 -379.158753) (xy 4.105195 -379.164853) (xy 4.159152 -379.178959)
			(xy 4.210481 -379.200771) (xy 4.258087 -379.229825) (xy 4.300955 -379.2655) (xy 4.338172 -379.307037)
			(xy 4.368945 -379.35355) (xy 4.392617 -379.404047) (xy 4.408685 -379.457454) (xy 4.416805 -379.51263)
			(xy 4.417314 -379.540516) (xy 4.41711 -379.551692) (xy 4.536692 -379.551692) (xy 4.540763 -379.49607)
			(xy 4.552889 -379.441633) (xy 4.572812 -379.389542) (xy 4.600108 -379.340907) (xy 4.634194 -379.296764)
			(xy 4.674343 -379.258055) (xy 4.719701 -379.225604) (xy 4.769301 -379.200103) (xy 4.822085 -379.182096)
			(xy 4.876928 -379.171966) (xy 4.932662 -379.169929) (xy 4.988099 -379.176029) (xy 5.042056 -379.190135)
			(xy 5.093385 -379.211947) (xy 5.140991 -379.241001) (xy 5.183859 -379.276676) (xy 5.221076 -379.318213)
			(xy 5.251849 -379.364726) (xy 5.275521 -379.415223) (xy 5.291589 -379.46863) (xy 5.299709 -379.523806)
			(xy 5.300218 -379.551692) (xy 5.299709 -379.579578) (xy 5.291589 -379.634754) (xy 5.275521 -379.688161)
			(xy 5.251849 -379.738658) (xy 5.221076 -379.785171) (xy 5.183859 -379.826708) (xy 5.140991 -379.862383)
			(xy 5.093385 -379.891437) (xy 5.042056 -379.913249) (xy 4.988099 -379.927355) (xy 4.932662 -379.933455)
			(xy 4.876928 -379.931418) (xy 4.822085 -379.921288) (xy 4.769301 -379.903281) (xy 4.719701 -379.87778)
			(xy 4.674343 -379.845329) (xy 4.634194 -379.80662) (xy 4.600108 -379.762477) (xy 4.572812 -379.713842)
			(xy 4.552889 -379.661751) (xy 4.540763 -379.607314) (xy 4.536692 -379.551692) (xy 4.41711 -379.551692)
			(xy 4.416805 -379.568402) (xy 4.408685 -379.623578) (xy 4.392617 -379.676985) (xy 4.368945 -379.727482)
			(xy 4.338172 -379.773995) (xy 4.300955 -379.815532) (xy 4.258087 -379.851207) (xy 4.210481 -379.880261)
			(xy 4.159152 -379.902073) (xy 4.105195 -379.916179) (xy 4.049758 -379.922279) (xy 3.994024 -379.920242)
			(xy 3.939181 -379.910112) (xy 3.886397 -379.892105) (xy 3.836797 -379.866604) (xy 3.791439 -379.834153)
			(xy 3.75129 -379.795444) (xy 3.717204 -379.751301) (xy 3.689908 -379.702666) (xy 3.669985 -379.650575)
			(xy 3.657859 -379.596138) (xy 3.653788 -379.540516) (xy 2.943659 -379.540516) (xy 2.943659 -379.567773)
			(xy 2.935901 -379.621725) (xy 2.920545 -379.674024) (xy 2.897902 -379.723605) (xy 2.868433 -379.769459)
			(xy 2.832739 -379.810652) (xy 2.791545 -379.846346) (xy 2.745691 -379.875814) (xy 2.69611 -379.898456)
			(xy 2.643811 -379.913812) (xy 2.589859 -379.921569) (xy 2.562606 -379.922024) (xy 2.533555 -379.921479)
			(xy 2.476126 -379.912668) (xy 2.420698 -379.89525) (xy 2.368552 -379.869626) (xy 2.34442 -379.853444)
			(xy 2.332736 -379.845316) (xy 2.304542 -379.843538) (xy 2.21234 -379.891798) (xy 2.205802 -379.895546)
			(xy 2.195091 -379.906136) (xy 2.191258 -379.912626) (xy 2.191004 -379.912626) (xy 2.188151 -379.918313)
			(xy 2.185056 -379.93065) (xy 2.184908 -379.93701) (xy 2.184908 -380.385574) (xy 2.185345 -380.395638)
			(xy 2.193079 -380.414222) (xy 2.199894 -380.421642) (xy 3.352038 -381.573786) (xy 3.359438 -381.580628)
			(xy 3.378036 -381.588351) (xy 3.388106 -381.588772) (xy 5.938774 -381.588772) (xy 5.948825 -381.589277)
			(xy 5.967387 -381.596996) (xy 5.974842 -381.603758) (xy 6.249924 -381.87884) (xy 6.256772 -381.886237)
			(xy 6.264504 -381.904836) (xy 6.26491 -381.914908) (xy 6.26491 -383.864866) (xy 7.795512 -383.864866)
			(xy 7.799583 -383.809244) (xy 7.811709 -383.754807) (xy 7.831632 -383.702716) (xy 7.858928 -383.654081)
			(xy 7.893014 -383.609938) (xy 7.933163 -383.571229) (xy 7.978521 -383.538778) (xy 8.028121 -383.513277)
			(xy 8.080905 -383.49527) (xy 8.135748 -383.48514) (xy 8.191482 -383.483103) (xy 8.246919 -383.489203)
			(xy 8.300876 -383.503309) (xy 8.352205 -383.525121) (xy 8.399811 -383.554175) (xy 8.442679 -383.58985)
			(xy 8.479896 -383.631387) (xy 8.510669 -383.6779) (xy 8.534341 -383.728397) (xy 8.550409 -383.781804)
			(xy 8.558529 -383.83698) (xy 8.559038 -383.864866) (xy 9.827512 -383.864866) (xy 9.831583 -383.809244)
			(xy 9.843709 -383.754807) (xy 9.863632 -383.702716) (xy 9.890928 -383.654081) (xy 9.925014 -383.609938)
			(xy 9.965163 -383.571229) (xy 10.010521 -383.538778) (xy 10.060121 -383.513277) (xy 10.112905 -383.49527)
			(xy 10.167748 -383.48514) (xy 10.223482 -383.483103) (xy 10.278919 -383.489203) (xy 10.332876 -383.503309)
			(xy 10.384205 -383.525121) (xy 10.431811 -383.554175) (xy 10.474679 -383.58985) (xy 10.511896 -383.631387)
			(xy 10.542669 -383.6779) (xy 10.566341 -383.728397) (xy 10.582409 -383.781804) (xy 10.590529 -383.83698)
			(xy 10.591038 -383.864866) (xy 10.843512 -383.864866) (xy 10.847583 -383.809244) (xy 10.859709 -383.754807)
			(xy 10.879632 -383.702716) (xy 10.906928 -383.654081) (xy 10.941014 -383.609938) (xy 10.981163 -383.571229)
			(xy 11.026521 -383.538778) (xy 11.076121 -383.513277) (xy 11.128905 -383.49527) (xy 11.183748 -383.48514)
			(xy 11.239482 -383.483103) (xy 11.294919 -383.489203) (xy 11.348876 -383.503309) (xy 11.400205 -383.525121)
			(xy 11.447811 -383.554175) (xy 11.490679 -383.58985) (xy 11.527896 -383.631387) (xy 11.558669 -383.6779)
			(xy 11.582341 -383.728397) (xy 11.598409 -383.781804) (xy 11.606529 -383.83698) (xy 11.607038 -383.864866)
			(xy 11.859512 -383.864866) (xy 11.863583 -383.809244) (xy 11.875709 -383.754807) (xy 11.895632 -383.702716)
			(xy 11.922928 -383.654081) (xy 11.957014 -383.609938) (xy 11.997163 -383.571229) (xy 12.042521 -383.538778)
			(xy 12.092121 -383.513277) (xy 12.144905 -383.49527) (xy 12.199748 -383.48514) (xy 12.255482 -383.483103)
			(xy 12.310919 -383.489203) (xy 12.364876 -383.503309) (xy 12.416205 -383.525121) (xy 12.463811 -383.554175)
			(xy 12.506679 -383.58985) (xy 12.543896 -383.631387) (xy 12.574669 -383.6779) (xy 12.598341 -383.728397)
			(xy 12.614409 -383.781804) (xy 12.622529 -383.83698) (xy 12.623038 -383.864866) (xy 12.622529 -383.892752)
			(xy 12.614409 -383.947928) (xy 12.598341 -384.001335) (xy 12.574669 -384.051832) (xy 12.543896 -384.098345)
			(xy 12.506679 -384.139882) (xy 12.463811 -384.175557) (xy 12.416205 -384.204611) (xy 12.364876 -384.226423)
			(xy 12.310919 -384.240529) (xy 12.255482 -384.246629) (xy 12.199748 -384.244592) (xy 12.144905 -384.234462)
			(xy 12.092121 -384.216455) (xy 12.042521 -384.190954) (xy 11.997163 -384.158503) (xy 11.957014 -384.119794)
			(xy 11.922928 -384.075651) (xy 11.895632 -384.027016) (xy 11.875709 -383.974925) (xy 11.863583 -383.920488)
			(xy 11.859512 -383.864866) (xy 11.607038 -383.864866) (xy 11.606529 -383.892752) (xy 11.598409 -383.947928)
			(xy 11.582341 -384.001335) (xy 11.558669 -384.051832) (xy 11.527896 -384.098345) (xy 11.490679 -384.139882)
			(xy 11.447811 -384.175557) (xy 11.400205 -384.204611) (xy 11.348876 -384.226423) (xy 11.294919 -384.240529)
			(xy 11.239482 -384.246629) (xy 11.183748 -384.244592) (xy 11.128905 -384.234462) (xy 11.076121 -384.216455)
			(xy 11.026521 -384.190954) (xy 10.981163 -384.158503) (xy 10.941014 -384.119794) (xy 10.906928 -384.075651)
			(xy 10.879632 -384.027016) (xy 10.859709 -383.974925) (xy 10.847583 -383.920488) (xy 10.843512 -383.864866)
			(xy 10.591038 -383.864866) (xy 10.590529 -383.892752) (xy 10.582409 -383.947928) (xy 10.566341 -384.001335)
			(xy 10.542669 -384.051832) (xy 10.511896 -384.098345) (xy 10.474679 -384.139882) (xy 10.431811 -384.175557)
			(xy 10.384205 -384.204611) (xy 10.332876 -384.226423) (xy 10.278919 -384.240529) (xy 10.223482 -384.246629)
			(xy 10.167748 -384.244592) (xy 10.112905 -384.234462) (xy 10.060121 -384.216455) (xy 10.010521 -384.190954)
			(xy 9.965163 -384.158503) (xy 9.925014 -384.119794) (xy 9.890928 -384.075651) (xy 9.863632 -384.027016)
			(xy 9.843709 -383.974925) (xy 9.831583 -383.920488) (xy 9.827512 -383.864866) (xy 8.559038 -383.864866)
			(xy 8.558529 -383.892752) (xy 8.550409 -383.947928) (xy 8.534341 -384.001335) (xy 8.510669 -384.051832)
			(xy 8.479896 -384.098345) (xy 8.442679 -384.139882) (xy 8.399811 -384.175557) (xy 8.352205 -384.204611)
			(xy 8.300876 -384.226423) (xy 8.246919 -384.240529) (xy 8.191482 -384.246629) (xy 8.135748 -384.244592)
			(xy 8.080905 -384.234462) (xy 8.028121 -384.216455) (xy 7.978521 -384.190954) (xy 7.933163 -384.158503)
			(xy 7.893014 -384.119794) (xy 7.858928 -384.075651) (xy 7.831632 -384.027016) (xy 7.811709 -383.974925)
			(xy 7.799583 -383.920488) (xy 7.795512 -383.864866) (xy 6.26491 -383.864866) (xy 6.26491 -384.141726)
			(xy 6.264483 -384.151794) (xy 6.256763 -384.170393) (xy 6.249924 -384.177794) (xy 6.012942 -384.414776)
			(xy 6.005541 -384.421616) (xy 5.986943 -384.429333) (xy 5.976874 -384.429762) (xy 4.532122 -384.429762)
			(xy 4.522059 -384.430201) (xy 4.503481 -384.437942) (xy 4.496054 -384.444748) (xy 4.144772 -384.79603)
			(xy 4.137922 -384.803427) (xy 4.130188 -384.822026) (xy 4.129786 -384.832098) (xy 4.129786 -385.480814)
			(xy 7.766048 -385.480814) (xy 7.770119 -385.425192) (xy 7.782245 -385.370755) (xy 7.802168 -385.318664)
			(xy 7.829464 -385.270029) (xy 7.86355 -385.225886) (xy 7.903699 -385.187177) (xy 7.949057 -385.154726)
			(xy 7.998657 -385.129225) (xy 8.051441 -385.111218) (xy 8.106284 -385.101088) (xy 8.162018 -385.099051)
			(xy 8.217455 -385.105151) (xy 8.271412 -385.119257) (xy 8.322741 -385.141069) (xy 8.370347 -385.170123)
			(xy 8.413215 -385.205798) (xy 8.450432 -385.247335) (xy 8.481205 -385.293848) (xy 8.504877 -385.344345)
			(xy 8.520945 -385.397752) (xy 8.529065 -385.452928) (xy 8.529574 -385.480814) (xy 8.529065 -385.5087)
			(xy 8.520945 -385.563876) (xy 8.504877 -385.617283) (xy 8.481205 -385.66778) (xy 8.450432 -385.714293)
			(xy 8.413215 -385.75583) (xy 8.370347 -385.791505) (xy 8.322741 -385.820559) (xy 8.271412 -385.842371)
			(xy 8.217455 -385.856477) (xy 8.162018 -385.862577) (xy 8.106284 -385.86054) (xy 8.051441 -385.85041)
			(xy 7.998657 -385.832403) (xy 7.949057 -385.806902) (xy 7.903699 -385.774451) (xy 7.86355 -385.735742)
			(xy 7.829464 -385.691599) (xy 7.802168 -385.642964) (xy 7.782245 -385.590873) (xy 7.770119 -385.536436)
			(xy 7.766048 -385.480814) (xy 4.129786 -385.480814) (xy 4.129786 -386.496814) (xy 7.766048 -386.496814)
			(xy 7.770119 -386.441192) (xy 7.782245 -386.386755) (xy 7.802168 -386.334664) (xy 7.829464 -386.286029)
			(xy 7.86355 -386.241886) (xy 7.903699 -386.203177) (xy 7.949057 -386.170726) (xy 7.998657 -386.145225)
			(xy 8.051441 -386.127218) (xy 8.106284 -386.117088) (xy 8.162018 -386.115051) (xy 8.217455 -386.121151)
			(xy 8.271412 -386.135257) (xy 8.322741 -386.157069) (xy 8.370347 -386.186123) (xy 8.413215 -386.221798)
			(xy 8.450432 -386.263335) (xy 8.481205 -386.309848) (xy 8.504877 -386.360345) (xy 8.520945 -386.413752)
			(xy 8.529065 -386.468928) (xy 8.529574 -386.496814) (xy 11.830048 -386.496814) (xy 11.834119 -386.441192)
			(xy 11.846245 -386.386755) (xy 11.866168 -386.334664) (xy 11.893464 -386.286029) (xy 11.92755 -386.241886)
			(xy 11.967699 -386.203177) (xy 12.013057 -386.170726) (xy 12.062657 -386.145225) (xy 12.115441 -386.127218)
			(xy 12.170284 -386.117088) (xy 12.226018 -386.115051) (xy 12.281455 -386.121151) (xy 12.335412 -386.135257)
			(xy 12.386741 -386.157069) (xy 12.434347 -386.186123) (xy 12.477215 -386.221798) (xy 12.514432 -386.263335)
			(xy 12.545205 -386.309848) (xy 12.568877 -386.360345) (xy 12.584945 -386.413752) (xy 12.593065 -386.468928)
			(xy 12.593574 -386.496814) (xy 12.593065 -386.5247) (xy 12.584945 -386.579876) (xy 12.568877 -386.633283)
			(xy 12.545205 -386.68378) (xy 12.514432 -386.730293) (xy 12.477215 -386.77183) (xy 12.434347 -386.807505)
			(xy 12.386741 -386.836559) (xy 12.335412 -386.858371) (xy 12.281455 -386.872477) (xy 12.226018 -386.878577)
			(xy 12.170284 -386.87654) (xy 12.115441 -386.86641) (xy 12.062657 -386.848403) (xy 12.013057 -386.822902)
			(xy 11.967699 -386.790451) (xy 11.92755 -386.751742) (xy 11.893464 -386.707599) (xy 11.866168 -386.658964)
			(xy 11.846245 -386.606873) (xy 11.834119 -386.552436) (xy 11.830048 -386.496814) (xy 8.529574 -386.496814)
			(xy 8.529065 -386.5247) (xy 8.520945 -386.579876) (xy 8.504877 -386.633283) (xy 8.481205 -386.68378)
			(xy 8.450432 -386.730293) (xy 8.413215 -386.77183) (xy 8.370347 -386.807505) (xy 8.322741 -386.836559)
			(xy 8.271412 -386.858371) (xy 8.217455 -386.872477) (xy 8.162018 -386.878577) (xy 8.106284 -386.87654)
			(xy 8.051441 -386.86641) (xy 7.998657 -386.848403) (xy 7.949057 -386.822902) (xy 7.903699 -386.790451)
			(xy 7.86355 -386.751742) (xy 7.829464 -386.707599) (xy 7.802168 -386.658964) (xy 7.782245 -386.606873)
			(xy 7.770119 -386.552436) (xy 7.766048 -386.496814) (xy 4.129786 -386.496814) (xy 4.129786 -386.601208)
			(xy 4.13021 -386.611278) (xy 4.137925 -386.629882) (xy 4.144772 -386.637276) (xy 4.36245 -386.854954)
			(xy 4.369849 -386.861798) (xy 4.388448 -386.869521) (xy 4.398518 -386.86994) (xy 5.843524 -386.86994)
			(xy 5.853591 -386.870369) (xy 5.872186 -386.878094) (xy 5.879592 -386.884926) (xy 6.116574 -387.121908)
			(xy 6.123422 -387.129306) (xy 6.131158 -387.147904) (xy 6.13156 -387.157976) (xy 6.13156 -387.512814)
			(xy 7.766048 -387.512814) (xy 7.770119 -387.457192) (xy 7.782245 -387.402755) (xy 7.802168 -387.350664)
			(xy 7.829464 -387.302029) (xy 7.86355 -387.257886) (xy 7.903699 -387.219177) (xy 7.949057 -387.186726)
			(xy 7.998657 -387.161225) (xy 8.051441 -387.143218) (xy 8.106284 -387.133088) (xy 8.162018 -387.131051)
			(xy 8.217455 -387.137151) (xy 8.271412 -387.151257) (xy 8.322741 -387.173069) (xy 8.370347 -387.202123)
			(xy 8.413215 -387.237798) (xy 8.450432 -387.279335) (xy 8.481205 -387.325848) (xy 8.504877 -387.376345)
			(xy 8.520945 -387.429752) (xy 8.529065 -387.484928) (xy 8.529574 -387.512814) (xy 11.830048 -387.512814)
			(xy 11.834119 -387.457192) (xy 11.846245 -387.402755) (xy 11.866168 -387.350664) (xy 11.893464 -387.302029)
			(xy 11.92755 -387.257886) (xy 11.967699 -387.219177) (xy 12.013057 -387.186726) (xy 12.062657 -387.161225)
			(xy 12.115441 -387.143218) (xy 12.170284 -387.133088) (xy 12.226018 -387.131051) (xy 12.281455 -387.137151)
			(xy 12.335412 -387.151257) (xy 12.386741 -387.173069) (xy 12.434347 -387.202123) (xy 12.477215 -387.237798)
			(xy 12.514432 -387.279335) (xy 12.545205 -387.325848) (xy 12.568877 -387.376345) (xy 12.584945 -387.429752)
			(xy 12.593065 -387.484928) (xy 12.593574 -387.512814) (xy 12.593065 -387.5407) (xy 12.584945 -387.595876)
			(xy 12.568877 -387.649283) (xy 12.545205 -387.69978) (xy 12.514432 -387.746293) (xy 12.477215 -387.78783)
			(xy 12.434347 -387.823505) (xy 12.386741 -387.852559) (xy 12.335412 -387.874371) (xy 12.281455 -387.888477)
			(xy 12.226018 -387.894577) (xy 12.170284 -387.89254) (xy 12.115441 -387.88241) (xy 12.062657 -387.864403)
			(xy 12.013057 -387.838902) (xy 11.967699 -387.806451) (xy 11.92755 -387.767742) (xy 11.893464 -387.723599)
			(xy 11.866168 -387.674964) (xy 11.846245 -387.622873) (xy 11.834119 -387.568436) (xy 11.830048 -387.512814)
			(xy 8.529574 -387.512814) (xy 8.529065 -387.5407) (xy 8.520945 -387.595876) (xy 8.504877 -387.649283)
			(xy 8.481205 -387.69978) (xy 8.450432 -387.746293) (xy 8.413215 -387.78783) (xy 8.370347 -387.823505)
			(xy 8.322741 -387.852559) (xy 8.271412 -387.874371) (xy 8.217455 -387.888477) (xy 8.162018 -387.894577)
			(xy 8.106284 -387.89254) (xy 8.051441 -387.88241) (xy 7.998657 -387.864403) (xy 7.949057 -387.838902)
			(xy 7.903699 -387.806451) (xy 7.86355 -387.767742) (xy 7.829464 -387.723599) (xy 7.802168 -387.674964)
			(xy 7.782245 -387.622873) (xy 7.770119 -387.568436) (xy 7.766048 -387.512814) (xy 6.13156 -387.512814)
			(xy 6.13156 -388.528814) (xy 11.830048 -388.528814) (xy 11.834119 -388.473192) (xy 11.846245 -388.418755)
			(xy 11.866168 -388.366664) (xy 11.893464 -388.318029) (xy 11.92755 -388.273886) (xy 11.967699 -388.235177)
			(xy 12.013057 -388.202726) (xy 12.062657 -388.177225) (xy 12.115441 -388.159218) (xy 12.170284 -388.149088)
			(xy 12.226018 -388.147051) (xy 12.281455 -388.153151) (xy 12.335412 -388.167257) (xy 12.386741 -388.189069)
			(xy 12.434347 -388.218123) (xy 12.477215 -388.253798) (xy 12.514432 -388.295335) (xy 12.545205 -388.341848)
			(xy 12.568877 -388.392345) (xy 12.584945 -388.445752) (xy 12.593065 -388.500928) (xy 12.593574 -388.528814)
			(xy 12.593065 -388.5567) (xy 12.584945 -388.611876) (xy 12.568877 -388.665283) (xy 12.545205 -388.71578)
			(xy 12.514432 -388.762293) (xy 12.477215 -388.80383) (xy 12.434347 -388.839505) (xy 12.386741 -388.868559)
			(xy 12.335412 -388.890371) (xy 12.281455 -388.904477) (xy 12.226018 -388.910577) (xy 12.170284 -388.90854)
			(xy 12.115441 -388.89841) (xy 12.062657 -388.880403) (xy 12.013057 -388.854902) (xy 11.967699 -388.822451)
			(xy 11.92755 -388.783742) (xy 11.893464 -388.739599) (xy 11.866168 -388.690964) (xy 11.846245 -388.638873)
			(xy 11.834119 -388.584436) (xy 11.830048 -388.528814) (xy 6.13156 -388.528814) (xy 6.13156 -388.908036)
			(xy 6.131129 -388.918102) (xy 6.123401 -388.936693) (xy 6.116574 -388.944104) (xy 5.908294 -389.152384)
			(xy 7.55218 -389.152384) (xy 7.556251 -389.096762) (xy 7.568377 -389.042325) (xy 7.5883 -388.990234)
			(xy 7.615596 -388.941599) (xy 7.649682 -388.897456) (xy 7.689831 -388.858747) (xy 7.735189 -388.826296)
			(xy 7.784789 -388.800795) (xy 7.837573 -388.782788) (xy 7.892416 -388.772658) (xy 7.94815 -388.770621)
			(xy 8.003587 -388.776721) (xy 8.057544 -388.790827) (xy 8.108873 -388.812639) (xy 8.156479 -388.841693)
			(xy 8.199347 -388.877368) (xy 8.236564 -388.918905) (xy 8.267337 -388.965418) (xy 8.291009 -389.015915)
			(xy 8.307077 -389.069322) (xy 8.315197 -389.124498) (xy 8.315706 -389.152384) (xy 8.56818 -389.152384)
			(xy 8.572251 -389.096762) (xy 8.584377 -389.042325) (xy 8.6043 -388.990234) (xy 8.631596 -388.941599)
			(xy 8.665682 -388.897456) (xy 8.705831 -388.858747) (xy 8.751189 -388.826296) (xy 8.800789 -388.800795)
			(xy 8.853573 -388.782788) (xy 8.908416 -388.772658) (xy 8.96415 -388.770621) (xy 9.019587 -388.776721)
			(xy 9.073544 -388.790827) (xy 9.124873 -388.812639) (xy 9.172479 -388.841693) (xy 9.215347 -388.877368)
			(xy 9.252564 -388.918905) (xy 9.283337 -388.965418) (xy 9.307009 -389.015915) (xy 9.323077 -389.069322)
			(xy 9.331197 -389.124498) (xy 9.331706 -389.152384) (xy 9.58418 -389.152384) (xy 9.588251 -389.096762)
			(xy 9.600377 -389.042325) (xy 9.6203 -388.990234) (xy 9.647596 -388.941599) (xy 9.681682 -388.897456)
			(xy 9.721831 -388.858747) (xy 9.767189 -388.826296) (xy 9.816789 -388.800795) (xy 9.869573 -388.782788)
			(xy 9.924416 -388.772658) (xy 9.98015 -388.770621) (xy 10.035587 -388.776721) (xy 10.089544 -388.790827)
			(xy 10.140873 -388.812639) (xy 10.188479 -388.841693) (xy 10.231347 -388.877368) (xy 10.268564 -388.918905)
			(xy 10.299337 -388.965418) (xy 10.323009 -389.015915) (xy 10.339077 -389.069322) (xy 10.347197 -389.124498)
			(xy 10.347706 -389.152384) (xy 10.347197 -389.18027) (xy 10.339077 -389.235446) (xy 10.323009 -389.288853)
			(xy 10.299337 -389.33935) (xy 10.268564 -389.385863) (xy 10.231347 -389.4274) (xy 10.188479 -389.463075)
			(xy 10.140873 -389.492129) (xy 10.089544 -389.513941) (xy 10.035587 -389.528047) (xy 9.98015 -389.534147)
			(xy 9.924416 -389.53211) (xy 9.869573 -389.52198) (xy 9.816789 -389.503973) (xy 9.767189 -389.478472)
			(xy 9.721831 -389.446021) (xy 9.681682 -389.407312) (xy 9.647596 -389.363169) (xy 9.6203 -389.314534)
			(xy 9.600377 -389.262443) (xy 9.588251 -389.208006) (xy 9.58418 -389.152384) (xy 9.331706 -389.152384)
			(xy 9.331197 -389.18027) (xy 9.323077 -389.235446) (xy 9.307009 -389.288853) (xy 9.283337 -389.33935)
			(xy 9.252564 -389.385863) (xy 9.215347 -389.4274) (xy 9.172479 -389.463075) (xy 9.124873 -389.492129)
			(xy 9.073544 -389.513941) (xy 9.019587 -389.528047) (xy 8.96415 -389.534147) (xy 8.908416 -389.53211)
			(xy 8.853573 -389.52198) (xy 8.800789 -389.503973) (xy 8.751189 -389.478472) (xy 8.705831 -389.446021)
			(xy 8.665682 -389.407312) (xy 8.631596 -389.363169) (xy 8.6043 -389.314534) (xy 8.584377 -389.262443)
			(xy 8.572251 -389.208006) (xy 8.56818 -389.152384) (xy 8.315706 -389.152384) (xy 8.315197 -389.18027)
			(xy 8.307077 -389.235446) (xy 8.291009 -389.288853) (xy 8.267337 -389.33935) (xy 8.236564 -389.385863)
			(xy 8.199347 -389.4274) (xy 8.156479 -389.463075) (xy 8.108873 -389.492129) (xy 8.057544 -389.513941)
			(xy 8.003587 -389.528047) (xy 7.94815 -389.534147) (xy 7.892416 -389.53211) (xy 7.837573 -389.52198)
			(xy 7.784789 -389.503973) (xy 7.735189 -389.478472) (xy 7.689831 -389.446021) (xy 7.649682 -389.407312)
			(xy 7.615596 -389.363169) (xy 7.5883 -389.314534) (xy 7.568377 -389.262443) (xy 7.556251 -389.208006)
			(xy 7.55218 -389.152384) (xy 5.908294 -389.152384) (xy 5.860542 -389.200136) (xy 5.853144 -389.20698)
			(xy 5.834545 -389.214704) (xy 5.824474 -389.215122) (xy 4.494022 -389.215122) (xy 4.483959 -389.21556)
			(xy 4.465377 -389.223297) (xy 4.457954 -389.230108) (xy 4.144772 -389.54329) (xy 4.137916 -389.550684)
			(xy 4.130167 -389.569283) (xy 4.129786 -389.579358) (xy 4.129786 -389.975852) (xy 4.130218 -389.985918)
			(xy 4.137944 -390.00451) (xy 4.144772 -390.01192) (xy 4.686554 -390.553702) (xy 4.693956 -390.56054)
			(xy 4.712554 -390.568254) (xy 4.722622 -390.568688)
		)
		(stroke
			(width 0)
			(type solid)
		)
		(fill yes)
		(layer "In5.Cu")
		(net "P1V2_USB_8042")
	)
	(gr_poly
		(pts
			(xy 242.5319 -210.513422) (xy 242.544064 -210.512732) (xy 242.565697 -210.501602) (xy 242.573302 -210.492086)
			(xy 242.589906 -210.469491) (xy 242.628654 -210.428963) (xy 242.672916 -210.394543) (xy 242.721739 -210.366971)
			(xy 242.774071 -210.346841) (xy 242.828787 -210.334587) (xy 242.884706 -210.330473) (xy 242.940625 -210.334587)
			(xy 242.995341 -210.346841) (xy 243.047673 -210.366971) (xy 243.096496 -210.394543) (xy 243.140758 -210.428963)
			(xy 243.179506 -210.469491) (xy 243.19611 -210.492086) (xy 243.203723 -210.501603) (xy 243.225345 -210.512766)
			(xy 243.237512 -210.513422) (xy 243.473732 -210.513422) (xy 243.4838 -210.512994) (xy 243.502398 -210.505274)
			(xy 243.5098 -210.498436) (xy 244.04574 -209.962496) (xy 244.052419 -209.955084) (xy 244.059994 -209.936649)
			(xy 244.060472 -209.926682) (xy 244.060472 -209.743548) (xy 244.060951 -209.710671) (xy 244.068346 -209.645334)
			(xy 244.083003 -209.581234) (xy 244.104738 -209.519176) (xy 244.133279 -209.459939) (xy 244.168268 -209.404266)
			(xy 244.209264 -209.352857) (xy 244.232176 -209.329274) (xy 244.993922 -208.567782) (xy 245.000959 -208.559946)
			(xy 245.008561 -208.54033) (xy 245.007694 -208.519309) (xy 245.003574 -208.509616) (xy 244.954552 -208.408524)
			(xy 244.926358 -208.39303) (xy 244.910102 -208.395062) (xy 244.898903 -208.396278) (xy 244.876409 -208.39755)
			(xy 244.865144 -208.397602) (xy 244.837891 -208.397142) (xy 244.783939 -208.389391) (xy 244.731639 -208.37404)
			(xy 244.682056 -208.351403) (xy 244.6362 -208.32194) (xy 244.595003 -208.28625) (xy 244.559306 -208.245061)
			(xy 244.529833 -208.19921) (xy 244.507186 -208.149632) (xy 244.491825 -208.097335) (xy 244.484064 -208.043384)
			(xy 244.484059 -207.988878) (xy 244.491812 -207.934926) (xy 244.507164 -207.882627) (xy 244.529803 -207.833045)
			(xy 244.559268 -207.78719) (xy 244.594959 -207.745994) (xy 244.63615 -207.710298) (xy 244.682001 -207.680827)
			(xy 244.73158 -207.658181) (xy 244.783878 -207.642823) (xy 244.837828 -207.635063) (xy 244.892334 -207.63506)
			(xy 244.946286 -207.642815) (xy 244.998585 -207.658168) (xy 245.048166 -207.680809) (xy 245.09402 -207.710276)
			(xy 245.135215 -207.745968) (xy 245.17091 -207.78716) (xy 245.200379 -207.833012) (xy 245.223023 -207.882592)
			(xy 245.23838 -207.93489) (xy 245.246138 -207.988841) (xy 245.246652 -208.016094) (xy 245.246198 -208.042301)
			(xy 245.238983 -208.094216) (xy 245.22473 -208.144656) (xy 245.203708 -208.192669) (xy 245.17631 -208.237354)
			(xy 245.160038 -208.257902) (xy 245.147592 -208.273142) (xy 245.149624 -208.312258) (xy 245.163594 -208.326228)
			(xy 245.171006 -208.332912) (xy 245.189439 -208.340509) (xy 245.209377 -208.340509) (xy 245.22781 -208.332912)
			(xy 245.235222 -208.326228) (xy 245.346982 -208.214468) (xy 245.353825 -208.207069) (xy 245.361551 -208.18847)
			(xy 245.361968 -208.1784) (xy 245.361968 -202.425808) (xy 245.362389 -202.415736) (xy 245.370098 -202.397127)
			(xy 245.376954 -202.38974) (xy 247.759982 -200.006712) (xy 247.765316 -199.9742) (xy 247.757696 -199.959468)
			(xy 247.744715 -199.932592) (xy 247.726354 -199.875803) (xy 247.717084 -199.816844) (xy 247.716548 -199.787002)
			(xy 247.717034 -199.75975) (xy 247.72479 -199.705799) (xy 247.740144 -199.653502) (xy 247.762785 -199.603921)
			(xy 247.79225 -199.558068) (xy 247.827941 -199.516874) (xy 247.869131 -199.481178) (xy 247.914981 -199.451707)
			(xy 247.964559 -199.42906) (xy 248.016854 -199.413699) (xy 248.070804 -199.405937) (xy 248.098056 -199.405494)
			(xy 248.106184 -199.405494) (xy 248.116598 -199.405748) (xy 248.13514 -199.398382) (xy 248.194576 -199.340216)
			(xy 248.201528 -199.332792) (xy 248.209395 -199.314055) (xy 248.209816 -199.303894) (xy 248.209816 -194.220084)
			(xy 248.210242 -194.210015) (xy 248.217963 -194.191417) (xy 248.224802 -194.184016) (xy 248.373392 -194.035426)
			(xy 248.380081 -194.028018) (xy 248.387674 -194.009582) (xy 248.388124 -193.999612) (xy 248.388124 -193.371724)
			(xy 248.388608 -193.345636) (xy 248.396771 -193.294102) (xy 248.4129 -193.244481) (xy 248.436597 -193.197997)
			(xy 248.467277 -193.155794) (xy 248.485406 -193.137028) (xy 249.682762 -191.939672) (xy 249.689608 -191.932274)
			(xy 249.697339 -191.913675) (xy 249.697748 -191.903604) (xy 249.697748 -190.330074) (xy 249.697523 -190.323036)
			(xy 249.69365 -190.309502) (xy 249.690128 -190.303404) (xy 249.67647 -190.280604) (xy 249.654907 -190.232028)
			(xy 249.640294 -190.18093) (xy 249.632915 -190.128297) (xy 249.632911 -190.07515) (xy 249.640284 -190.022517)
			(xy 249.654891 -189.971416) (xy 249.676448 -189.922838) (xy 249.690128 -189.900052) (xy 249.693635 -189.893947)
			(xy 249.69751 -189.880418) (xy 249.697748 -189.873382) (xy 249.697748 -189.715394) (xy 249.697442 -189.706905)
			(xy 249.691893 -189.690861) (xy 249.68138 -189.677532) (xy 249.67438 -189.672722) (xy 249.59183 -189.619382)
			(xy 249.565922 -189.617604) (xy 249.554238 -189.622938) (xy 249.529349 -189.633696) (xy 249.477293 -189.648868)
			(xy 249.423615 -189.656523) (xy 249.396504 -189.656974) (xy 249.369253 -189.656511) (xy 249.315307 -189.648755)
			(xy 249.263013 -189.633401) (xy 249.213437 -189.610761) (xy 249.167587 -189.581295) (xy 249.126398 -189.545605)
			(xy 249.090707 -189.504416) (xy 249.061241 -189.458567) (xy 249.038601 -189.408991) (xy 249.023246 -189.356697)
			(xy 249.015489 -189.302751) (xy 249.015489 -189.248249) (xy 249.023246 -189.194303) (xy 249.038601 -189.142009)
			(xy 249.061241 -189.092433) (xy 249.090707 -189.046584) (xy 249.126398 -189.005395) (xy 249.167587 -188.969705)
			(xy 249.213437 -188.940239) (xy 249.263013 -188.917599) (xy 249.315307 -188.902245) (xy 249.369253 -188.894489)
			(xy 249.396504 -188.893958) (xy 249.423615 -188.894414) (xy 249.477296 -188.902057) (xy 249.529351 -188.91723)
			(xy 249.554238 -188.927994) (xy 249.565922 -188.933328) (xy 249.59183 -188.93155) (xy 249.67438 -188.87821)
			(xy 249.681338 -188.873354) (xy 249.691826 -188.860028) (xy 249.697414 -188.844016) (xy 249.697748 -188.835538)
			(xy 249.697748 -183.778906) (xy 249.697453 -183.769969) (xy 249.6914 -183.753155) (xy 249.679927 -183.739455)
			(xy 249.672348 -183.73471) (xy 249.647845 -183.720014) (xy 249.603141 -183.684435) (xy 249.564245 -183.642584)
			(xy 249.53203 -183.595397) (xy 249.507216 -183.543932) (xy 249.49036 -183.489341) (xy 249.481838 -183.432845)
			(xy 249.481841 -183.375711) (xy 249.49037 -183.319216) (xy 249.507233 -183.264627) (xy 249.532052 -183.213164)
			(xy 249.564273 -183.165982) (xy 249.603173 -183.124135) (xy 249.647882 -183.088561) (xy 249.672348 -183.073802)
			(xy 249.679905 -183.069031) (xy 249.691364 -183.055331) (xy 249.697444 -183.038537) (xy 249.697748 -183.029606)
			(xy 249.697748 -168.96588) (xy 249.69732 -168.955813) (xy 249.689594 -168.937218) (xy 249.682762 -168.929812)
			(xy 247.4595 -166.70655) (xy 247.452104 -166.699698) (xy 247.433505 -166.691956) (xy 247.423432 -166.691564)
			(xy 239.761268 -166.691564) (xy 239.751202 -166.691995) (xy 239.732612 -166.699724) (xy 239.7252 -166.70655)
			(xy 239.391698 -167.040052) (xy 239.38486 -167.047453) (xy 239.377145 -167.066052) (xy 239.376712 -167.07612)
			(xy 239.376712 -169.505376) (xy 239.377149 -169.51544) (xy 239.384884 -169.534023) (xy 239.391698 -169.541444)
			(xy 239.870488 -170.020234) (xy 239.877883 -170.02709) (xy 239.896481 -170.034839) (xy 239.906556 -170.03522)
			(xy 241.258344 -170.03522) (xy 241.268411 -170.034789) (xy 241.287006 -170.027066) (xy 241.294412 -170.020234)
			(xy 242.076986 -169.23766) (xy 242.083336 -169.226992) (xy 242.085368 -169.22115) (xy 242.093803 -169.195592)
			(xy 242.116854 -169.146958) (xy 242.146511 -169.102046) (xy 242.182185 -169.061747) (xy 242.223168 -169.026861)
			(xy 242.268647 -168.998081) (xy 242.317719 -168.975976) (xy 242.36941 -168.960987) (xy 242.422694 -168.953411)
			(xy 242.449604 -168.952926) (xy 242.476856 -168.95339) (xy 242.530804 -168.961147) (xy 242.5831 -168.976504)
			(xy 242.632677 -168.999147) (xy 242.678528 -169.028616) (xy 242.719717 -169.06431) (xy 242.755407 -169.105503)
			(xy 242.784871 -169.151356) (xy 242.807509 -169.200936) (xy 242.822861 -169.253233) (xy 242.830613 -169.307182)
			(xy 242.831112 -169.334434) (xy 242.830654 -169.361347) (xy 242.823094 -169.41464) (xy 242.808114 -169.466339)
			(xy 242.786013 -169.515419) (xy 242.757229 -169.560902) (xy 242.722335 -169.601886) (xy 242.721355 -169.602753)
			(xy 244.268458 -169.602753) (xy 244.268458 -169.548247) (xy 244.276215 -169.494297) (xy 244.291571 -169.442)
			(xy 244.314213 -169.39242) (xy 244.34368 -169.346567) (xy 244.379374 -169.305375) (xy 244.420566 -169.269682)
			(xy 244.466418 -169.240214) (xy 244.515998 -169.217571) (xy 244.568295 -169.202215) (xy 244.622245 -169.194458)
			(xy 244.649498 -169.193972) (xy 244.677932 -169.194529) (xy 244.734174 -169.202952) (xy 244.788543 -169.219626)
			(xy 244.839837 -169.244183) (xy 244.886919 -169.276078) (xy 244.928748 -169.314606) (xy 244.964397 -169.358913)
			(xy 244.97919 -169.383202) (xy 244.986048 -169.395394) (xy 245.010432 -169.408856) (xy 245.12778 -169.4053)
			(xy 245.151402 -169.390314) (xy 245.157498 -169.377868) (xy 245.17222 -169.349883) (xy 245.208144 -169.297848)
			(xy 245.250889 -169.251254) (xy 245.299641 -169.210986) (xy 245.353471 -169.177813) (xy 245.411356 -169.152366)
			(xy 245.472192 -169.135129) (xy 245.534822 -169.12643) (xy 245.566438 -169.1259) (xy 246.430038 -169.1259)
			(xy 246.462743 -169.126502) (xy 246.52748 -169.135866) (xy 246.590228 -169.154341) (xy 246.649711 -169.181551)
			(xy 246.704719 -169.216944) (xy 246.754136 -169.259799) (xy 246.775986 -169.284142) (xy 246.782844 -169.292016)
			(xy 246.800878 -169.300906) (xy 246.89435 -169.306494) (xy 246.9134 -169.29989) (xy 246.92102 -169.292778)
			(xy 246.942185 -169.274325) (xy 246.98891 -169.243186) (xy 247.039691 -169.219223) (xy 247.093432 -169.202953)
			(xy 247.148977 -169.194726) (xy 247.177052 -169.194226) (xy 247.20431 -169.194618) (xy 247.258271 -169.20237)
			(xy 247.310579 -169.217723) (xy 247.36017 -169.240365) (xy 247.406033 -169.269834) (xy 247.447235 -169.305531)
			(xy 247.482937 -169.346729) (xy 247.512412 -169.392588) (xy 247.53506 -169.442176) (xy 247.55042 -169.494482)
			(xy 247.558179 -169.548443) (xy 247.558179 -169.602957) (xy 247.55042 -169.656918) (xy 247.53506 -169.709224)
			(xy 247.512412 -169.758812) (xy 247.482937 -169.804671) (xy 247.447235 -169.845869) (xy 247.406033 -169.881566)
			(xy 247.36017 -169.911035) (xy 247.310579 -169.933677) (xy 247.258271 -169.94903) (xy 247.20431 -169.956782)
			(xy 247.177052 -169.957242) (xy 247.149813 -169.956746) (xy 247.095892 -169.948984) (xy 247.043624 -169.933626)
			(xy 246.994075 -169.910983) (xy 246.948254 -169.881518) (xy 246.92737 -169.864024) (xy 246.919242 -169.857166)
			(xy 246.900192 -169.85107) (xy 246.806974 -169.85869) (xy 246.789194 -169.868088) (xy 246.78259 -169.875962)
			(xy 246.763933 -169.897852) (xy 246.722 -169.937222) (xy 246.675463 -169.971025) (xy 246.625057 -169.998729)
			(xy 246.571575 -170.019896) (xy 246.515863 -170.034194) (xy 246.458797 -170.041395) (xy 246.430038 -170.041824)
			(xy 245.566438 -170.041824) (xy 245.534305 -170.04122) (xy 245.470675 -170.032199) (xy 245.408931 -170.014371)
			(xy 245.350286 -169.988086) (xy 245.295892 -169.953861) (xy 245.246816 -169.912367) (xy 245.204023 -169.86442)
			(xy 245.168353 -169.810961) (xy 245.153942 -169.782236) (xy 245.147846 -169.76979) (xy 245.124478 -169.754296)
			(xy 245.007384 -169.748708) (xy 244.982746 -169.761662) (xy 244.975634 -169.7736) (xy 244.960663 -169.797201)
			(xy 244.924981 -169.840217) (xy 244.883407 -169.877568) (xy 244.836829 -169.908455) (xy 244.786243 -169.932218)
			(xy 244.732733 -169.948348) (xy 244.677442 -169.9565) (xy 244.649498 -169.956988) (xy 244.622245 -169.956542)
			(xy 244.568295 -169.948785) (xy 244.515998 -169.933429) (xy 244.466418 -169.910786) (xy 244.420566 -169.881318)
			(xy 244.379374 -169.845625) (xy 244.34368 -169.804433) (xy 244.314213 -169.75858) (xy 244.291571 -169.709)
			(xy 244.276215 -169.656703) (xy 244.268458 -169.602753) (xy 242.721355 -169.602753) (xy 242.682024 -169.637555)
			(xy 242.637098 -169.667201) (xy 242.588449 -169.690234) (xy 242.562888 -169.69867) (xy 242.557046 -169.700702)
			(xy 242.546378 -169.707052) (xy 242.304824 -169.948606) (xy 242.298048 -169.955996) (xy 242.290417 -169.97452)
			(xy 242.290472 -169.994555) (xy 242.293902 -170.003978) (xy 242.299744 -170.018202) (xy 242.325144 -170.03522)
			(xy 243.571522 -170.03522) (xy 243.58159 -170.035648) (xy 243.600187 -170.04337) (xy 243.60759 -170.050206)
			(xy 245.182898 -171.625514) (xy 245.189742 -171.632913) (xy 245.197472 -171.651511) (xy 245.197884 -171.661582)
			(xy 245.197884 -179.07127) (xy 245.198337 -179.081424) (xy 245.206202 -179.100148) (xy 245.213124 -179.107592)
			(xy 245.272052 -179.165504) (xy 245.290594 -179.173124) (xy 245.301008 -179.17287) (xy 245.306596 -179.17287)
			(xy 245.333851 -179.173333) (xy 245.387805 -179.18109) (xy 245.440107 -179.196446) (xy 245.48969 -179.21909)
			(xy 245.535546 -179.248559) (xy 245.576742 -179.284255) (xy 245.612438 -179.32545) (xy 245.641908 -179.371306)
			(xy 245.664552 -179.42089) (xy 245.67991 -179.473191) (xy 245.687667 -179.527145) (xy 245.687667 -179.581655)
			(xy 245.67991 -179.635609) (xy 245.664552 -179.68791) (xy 245.641908 -179.737494) (xy 245.612438 -179.78335)
			(xy 245.576742 -179.824545) (xy 245.535546 -179.860241) (xy 245.48969 -179.88971) (xy 245.440107 -179.912354)
			(xy 245.387805 -179.92771) (xy 245.333851 -179.935467) (xy 245.306596 -179.935886) (xy 245.301008 -179.935886)
			(xy 245.290594 -179.935632) (xy 245.272052 -179.943252) (xy 245.213124 -180.001164) (xy 245.206169 -180.008587)
			(xy 245.198295 -180.027323) (xy 245.197884 -180.037486) (xy 245.197884 -183.05145) (xy 245.217442 -183.07812)
			(xy 245.233698 -183.082946) (xy 245.259275 -183.091381) (xy 245.307945 -183.11444) (xy 245.35289 -183.144111)
			(xy 245.393217 -183.179807) (xy 245.428126 -183.220817) (xy 245.456924 -183.266327) (xy 245.479037 -183.315434)
			(xy 245.494027 -183.367161) (xy 245.501597 -183.420483) (xy 245.501595 -183.474339) (xy 245.494337 -183.525451)
			(xy 245.640591 -183.525451) (xy 245.640591 -183.470949) (xy 245.648348 -183.417003) (xy 245.663703 -183.36471)
			(xy 245.686343 -183.315134) (xy 245.715809 -183.269285) (xy 245.7515 -183.228096) (xy 245.79269 -183.192406)
			(xy 245.838539 -183.16294) (xy 245.888115 -183.1403) (xy 245.940409 -183.124946) (xy 245.994355 -183.117191)
			(xy 246.021606 -183.116728) (xy 246.047005 -183.117125) (xy 246.097355 -183.123868) (xy 246.146364 -183.137233)
			(xy 246.193166 -183.156984) (xy 246.236933 -183.182771) (xy 246.27689 -183.214139) (xy 246.29491 -183.232044)
			(xy 246.301514 -183.238648) (xy 246.31777 -183.246522) (xy 246.403114 -183.25338) (xy 246.420386 -183.248554)
			(xy 246.428006 -183.242966) (xy 246.452759 -183.225404) (xy 246.506672 -183.197538) (xy 246.564312 -183.178543)
			(xy 246.62423 -183.168899) (xy 246.654574 -183.16829) (xy 246.681863 -183.168741) (xy 246.735885 -183.176517)
			(xy 246.788246 -183.191913) (xy 246.837879 -183.214616) (xy 246.861076 -183.228996) (xy 246.869712 -183.234584)
			(xy 246.889524 -183.23814) (xy 246.979694 -183.218582) (xy 246.996204 -183.206898) (xy 247.001538 -183.198516)
			(xy 247.01666 -183.175784) (xy 247.052362 -183.134479) (xy 247.093585 -183.098683) (xy 247.139489 -183.069126)
			(xy 247.189135 -183.046412) (xy 247.241512 -183.031004) (xy 247.29555 -183.023217) (xy 247.322848 -183.022748)
			(xy 247.350094 -183.023325) (xy 247.40403 -183.031087) (xy 247.456313 -183.046444) (xy 247.505878 -183.069085)
			(xy 247.551717 -183.098549) (xy 247.592897 -183.134237) (xy 247.628579 -183.175421) (xy 247.658038 -183.221264)
			(xy 247.680673 -183.270832) (xy 247.696024 -183.323117) (xy 247.703778 -183.377054) (xy 247.703778 -183.431546)
			(xy 247.696024 -183.485483) (xy 247.680673 -183.537768) (xy 247.658038 -183.587336) (xy 247.628579 -183.633179)
			(xy 247.592897 -183.674363) (xy 247.551717 -183.710051) (xy 247.505878 -183.739515) (xy 247.456313 -183.762156)
			(xy 247.40403 -183.777513) (xy 247.350094 -183.785275) (xy 247.322848 -183.785764) (xy 247.295559 -183.785309)
			(xy 247.241537 -183.777536) (xy 247.189175 -183.762141) (xy 247.139543 -183.739439) (xy 247.116346 -183.725058)
			(xy 247.10771 -183.71947) (xy 247.087898 -183.715914) (xy 246.997728 -183.735472) (xy 246.981218 -183.747156)
			(xy 246.975884 -183.755538) (xy 246.960732 -183.778249) (xy 246.925037 -183.819557) (xy 246.88382 -183.855356)
			(xy 246.837921 -183.884916) (xy 246.788279 -183.907633) (xy 246.735906 -183.923045) (xy 246.681871 -183.930835)
			(xy 246.654574 -183.931306) (xy 246.629175 -183.930911) (xy 246.578825 -183.924167) (xy 246.529817 -183.910801)
			(xy 246.483015 -183.891049) (xy 246.439248 -183.865262) (xy 246.399291 -183.833894) (xy 246.38127 -183.81599)
			(xy 246.374666 -183.809386) (xy 246.35841 -183.801512) (xy 246.273066 -183.794654) (xy 246.255794 -183.79948)
			(xy 246.248174 -183.805068) (xy 246.22343 -183.822643) (xy 246.169513 -183.850505) (xy 246.111871 -183.869496)
			(xy 246.051951 -183.879136) (xy 246.021606 -183.879744) (xy 245.994355 -183.879209) (xy 245.940409 -183.871454)
			(xy 245.888115 -183.8561) (xy 245.838539 -183.83346) (xy 245.79269 -183.803994) (xy 245.7515 -183.768304)
			(xy 245.715809 -183.727115) (xy 245.686343 -183.681266) (xy 245.663703 -183.63169) (xy 245.648348 -183.579397)
			(xy 245.640591 -183.525451) (xy 245.494337 -183.525451) (xy 245.494023 -183.52766) (xy 245.479029 -183.579386)
			(xy 245.456913 -183.628492) (xy 245.428114 -183.674) (xy 245.393202 -183.715009) (xy 245.352873 -183.750702)
			(xy 245.307926 -183.780371) (xy 245.259255 -183.803426) (xy 245.233698 -183.811926) (xy 245.217442 -183.816752)
			(xy 245.197884 -183.843422) (xy 245.197884 -184.095136) (xy 245.198646 -184.099454) (xy 245.20126 -184.115583)
			(xy 245.20406 -184.14814) (xy 245.204234 -184.164478) (xy 245.204061 -184.180816) (xy 245.201262 -184.213373)
			(xy 245.198646 -184.229502) (xy 245.197884 -184.23382) (xy 245.197884 -185.27141) (xy 245.198308 -185.28148)
			(xy 245.206024 -185.300083) (xy 245.21287 -185.307478) (xy 245.305834 -185.400442) (xy 246.211088 -185.400442)
			(xy 246.215159 -185.34482) (xy 246.227285 -185.290383) (xy 246.247208 -185.238292) (xy 246.274504 -185.189657)
			(xy 246.30859 -185.145514) (xy 246.348739 -185.106805) (xy 246.394097 -185.074354) (xy 246.443697 -185.048853)
			(xy 246.496481 -185.030846) (xy 246.551324 -185.020716) (xy 246.607058 -185.018679) (xy 246.662495 -185.024779)
			(xy 246.716452 -185.038885) (xy 246.767781 -185.060697) (xy 246.815387 -185.089751) (xy 246.858255 -185.125426)
			(xy 246.895472 -185.166963) (xy 246.926245 -185.213476) (xy 246.949917 -185.263973) (xy 246.965985 -185.31738)
			(xy 246.974105 -185.372556) (xy 246.974614 -185.400442) (xy 246.974105 -185.428328) (xy 246.965985 -185.483504)
			(xy 246.949917 -185.536911) (xy 246.926245 -185.587408) (xy 246.908279 -185.614564) (xy 248.11939 -185.614564)
			(xy 248.123461 -185.558942) (xy 248.135587 -185.504505) (xy 248.15551 -185.452414) (xy 248.182806 -185.403779)
			(xy 248.216892 -185.359636) (xy 248.257041 -185.320927) (xy 248.302399 -185.288476) (xy 248.351999 -185.262975)
			(xy 248.404783 -185.244968) (xy 248.459626 -185.234838) (xy 248.51536 -185.232801) (xy 248.570797 -185.238901)
			(xy 248.624754 -185.253007) (xy 248.676083 -185.274819) (xy 248.723689 -185.303873) (xy 248.766557 -185.339548)
			(xy 248.803774 -185.381085) (xy 248.834547 -185.427598) (xy 248.858219 -185.478095) (xy 248.874287 -185.531502)
			(xy 248.882407 -185.586678) (xy 248.882916 -185.614564) (xy 248.882407 -185.64245) (xy 248.874287 -185.697626)
			(xy 248.858219 -185.751033) (xy 248.834547 -185.80153) (xy 248.803774 -185.848043) (xy 248.766557 -185.88958)
			(xy 248.723689 -185.925255) (xy 248.676083 -185.954309) (xy 248.624754 -185.976121) (xy 248.570797 -185.990227)
			(xy 248.51536 -185.996327) (xy 248.459626 -185.99429) (xy 248.404783 -185.98416) (xy 248.351999 -185.966153)
			(xy 248.302399 -185.940652) (xy 248.257041 -185.908201) (xy 248.216892 -185.869492) (xy 248.182806 -185.825349)
			(xy 248.15551 -185.776714) (xy 248.135587 -185.724623) (xy 248.123461 -185.670186) (xy 248.11939 -185.614564)
			(xy 246.908279 -185.614564) (xy 246.895472 -185.633921) (xy 246.858255 -185.675458) (xy 246.815387 -185.711133)
			(xy 246.767781 -185.740187) (xy 246.716452 -185.761999) (xy 246.662495 -185.776105) (xy 246.607058 -185.782205)
			(xy 246.551324 -185.780168) (xy 246.496481 -185.770038) (xy 246.443697 -185.752031) (xy 246.394097 -185.72653)
			(xy 246.348739 -185.694079) (xy 246.30859 -185.65537) (xy 246.274504 -185.611227) (xy 246.247208 -185.562592)
			(xy 246.227285 -185.510501) (xy 246.215159 -185.456064) (xy 246.211088 -185.400442) (xy 245.305834 -185.400442)
			(xy 245.594378 -185.688986) (xy 245.612495 -185.707765) (xy 245.643189 -185.74996) (xy 245.666899 -185.79644)
			(xy 245.683038 -185.846059) (xy 245.69121 -185.897593) (xy 245.69166 -185.923682) (xy 245.69166 -189.80912)
			(xy 246.874282 -189.80912) (xy 246.878353 -189.753498) (xy 246.890479 -189.699061) (xy 246.910402 -189.64697)
			(xy 246.937698 -189.598335) (xy 246.971784 -189.554192) (xy 247.011933 -189.515483) (xy 247.057291 -189.483032)
			(xy 247.106891 -189.457531) (xy 247.159675 -189.439524) (xy 247.214518 -189.429394) (xy 247.270252 -189.427357)
			(xy 247.325689 -189.433457) (xy 247.379646 -189.447563) (xy 247.430975 -189.469375) (xy 247.478581 -189.498429)
			(xy 247.521449 -189.534104) (xy 247.558666 -189.575641) (xy 247.589439 -189.622154) (xy 247.613111 -189.672651)
			(xy 247.629179 -189.726058) (xy 247.637299 -189.781234) (xy 247.637808 -189.80912) (xy 247.637299 -189.837006)
			(xy 247.635497 -189.849252) (xy 248.044968 -189.849252) (xy 248.049039 -189.79363) (xy 248.061165 -189.739193)
			(xy 248.081088 -189.687102) (xy 248.108384 -189.638467) (xy 248.14247 -189.594324) (xy 248.182619 -189.555615)
			(xy 248.227977 -189.523164) (xy 248.277577 -189.497663) (xy 248.330361 -189.479656) (xy 248.385204 -189.469526)
			(xy 248.440938 -189.467489) (xy 248.496375 -189.473589) (xy 248.550332 -189.487695) (xy 248.601661 -189.509507)
			(xy 248.649267 -189.538561) (xy 248.692135 -189.574236) (xy 248.729352 -189.615773) (xy 248.760125 -189.662286)
			(xy 248.783797 -189.712783) (xy 248.799865 -189.76619) (xy 248.807985 -189.821366) (xy 248.808494 -189.849252)
			(xy 248.807985 -189.877138) (xy 248.799865 -189.932314) (xy 248.783797 -189.985721) (xy 248.760125 -190.036218)
			(xy 248.729352 -190.082731) (xy 248.692135 -190.124268) (xy 248.649267 -190.159943) (xy 248.601661 -190.188997)
			(xy 248.550332 -190.210809) (xy 248.496375 -190.224915) (xy 248.440938 -190.231015) (xy 248.385204 -190.228978)
			(xy 248.330361 -190.218848) (xy 248.277577 -190.200841) (xy 248.227977 -190.17534) (xy 248.182619 -190.142889)
			(xy 248.14247 -190.10418) (xy 248.108384 -190.060037) (xy 248.081088 -190.011402) (xy 248.061165 -189.959311)
			(xy 248.049039 -189.904874) (xy 248.044968 -189.849252) (xy 247.635497 -189.849252) (xy 247.629179 -189.892182)
			(xy 247.613111 -189.945589) (xy 247.589439 -189.996086) (xy 247.558666 -190.042599) (xy 247.521449 -190.084136)
			(xy 247.478581 -190.119811) (xy 247.430975 -190.148865) (xy 247.379646 -190.170677) (xy 247.325689 -190.184783)
			(xy 247.270252 -190.190883) (xy 247.214518 -190.188846) (xy 247.159675 -190.178716) (xy 247.106891 -190.160709)
			(xy 247.057291 -190.135208) (xy 247.011933 -190.102757) (xy 246.971784 -190.064048) (xy 246.937698 -190.019905)
			(xy 246.910402 -189.97127) (xy 246.890479 -189.919179) (xy 246.878353 -189.864742) (xy 246.874282 -189.80912)
			(xy 245.69166 -189.80912) (xy 245.69166 -193.750946) (xy 245.694454 -193.762884) (xy 245.697248 -193.768472)
			(xy 245.711086 -193.795999) (xy 245.730671 -193.854412) (xy 245.740607 -193.915214) (xy 245.74119 -193.946018)
			(xy 245.740702 -193.973268) (xy 245.732944 -194.027213) (xy 245.717587 -194.079504) (xy 245.694945 -194.129078)
			(xy 245.665478 -194.174925) (xy 245.629786 -194.216111) (xy 245.588596 -194.251799) (xy 245.542746 -194.281262)
			(xy 245.49317 -194.3039) (xy 245.440877 -194.319251) (xy 245.386932 -194.327005) (xy 245.359682 -194.327526)
			(xy 245.347774 -194.32742) (xy 245.324008 -194.325893) (xy 245.312184 -194.324478) (xy 245.301262 -194.323208)
			(xy 245.280434 -194.329558) (xy 245.215156 -194.387216) (xy 245.207353 -194.39475) (xy 245.198399 -194.414483)
			(xy 245.197884 -194.425316) (xy 245.197884 -196.580506) (xy 245.197459 -196.590575) (xy 245.189742 -196.609177)
			(xy 245.182898 -196.616574) (xy 244.598444 -197.201028) (xy 245.01424 -197.201028) (xy 245.018311 -197.145406)
			(xy 245.030437 -197.090969) (xy 245.05036 -197.038878) (xy 245.077656 -196.990243) (xy 245.111742 -196.9461)
			(xy 245.151891 -196.907391) (xy 245.197249 -196.87494) (xy 245.246849 -196.849439) (xy 245.299633 -196.831432)
			(xy 245.354476 -196.821302) (xy 245.41021 -196.819265) (xy 245.465647 -196.825365) (xy 245.519604 -196.839471)
			(xy 245.570933 -196.861283) (xy 245.618539 -196.890337) (xy 245.661407 -196.926012) (xy 245.698624 -196.967549)
			(xy 245.729397 -197.014062) (xy 245.753069 -197.064559) (xy 245.769137 -197.117966) (xy 245.777257 -197.173142)
			(xy 245.777766 -197.201028) (xy 245.777257 -197.228914) (xy 245.769137 -197.28409) (xy 245.753069 -197.337497)
			(xy 245.729397 -197.387994) (xy 245.698624 -197.434507) (xy 245.661407 -197.476044) (xy 245.618539 -197.511719)
			(xy 245.570933 -197.540773) (xy 245.519604 -197.562585) (xy 245.465647 -197.576691) (xy 245.41021 -197.582791)
			(xy 245.354476 -197.580754) (xy 245.299633 -197.570624) (xy 245.246849 -197.552617) (xy 245.197249 -197.527116)
			(xy 245.151891 -197.494665) (xy 245.111742 -197.455956) (xy 245.077656 -197.411813) (xy 245.05036 -197.363178)
			(xy 245.030437 -197.311087) (xy 245.018311 -197.25665) (xy 245.01424 -197.201028) (xy 244.598444 -197.201028)
			(xy 243.58473 -198.214742) (xy 243.577364 -198.238872) (xy 243.57965 -198.251318) (xy 243.582869 -198.269114)
			(xy 243.586304 -198.305117) (xy 243.586508 -198.3232) (xy 243.586022 -198.350451) (xy 243.578266 -198.404399)
			(xy 243.562911 -198.456694) (xy 243.540269 -198.506271) (xy 243.510803 -198.552121) (xy 243.475112 -198.593312)
			(xy 243.433921 -198.629003) (xy 243.388071 -198.658469) (xy 243.338494 -198.681111) (xy 243.286199 -198.696466)
			(xy 243.232251 -198.704222) (xy 243.205 -198.704708) (xy 243.186918 -198.704482) (xy 243.150917 -198.701045)
			(xy 243.133118 -198.69785) (xy 243.120672 -198.695564) (xy 243.096542 -198.70293) (xy 242.858544 -198.940928)
			(xy 242.85187 -198.948342) (xy 242.844307 -198.966777) (xy 242.843812 -198.976742) (xy 242.843812 -199.058784)
			(xy 242.851432 -199.077326) (xy 242.858798 -199.084692) (xy 242.879648 -199.106293) (xy 242.914974 -199.154832)
			(xy 242.942264 -199.208303) (xy 242.960847 -199.265388) (xy 242.970262 -199.324678) (xy 242.970812 -199.354694)
			(xy 242.970349 -199.381947) (xy 242.962593 -199.435899) (xy 242.947237 -199.488198) (xy 242.924595 -199.537779)
			(xy 242.895127 -199.583633) (xy 242.859434 -199.624827) (xy 242.818241 -199.660521) (xy 242.772388 -199.68999)
			(xy 242.722807 -199.712634) (xy 242.670509 -199.727991) (xy 242.616557 -199.735748) (xy 242.589304 -199.736202)
			(xy 242.559288 -199.735641) (xy 242.499998 -199.726235) (xy 242.442914 -199.707654) (xy 242.389447 -199.680359)
			(xy 242.340918 -199.645022) (xy 242.319302 -199.624188) (xy 242.311936 -199.616822) (xy 242.293394 -199.609202)
			(xy 242.211352 -199.609202) (xy 242.201388 -199.609685) (xy 242.18296 -199.617268) (xy 242.175538 -199.623934)
			(xy 241.689636 -200.109836) (xy 241.682791 -200.117235) (xy 241.675064 -200.135833) (xy 241.67465 -200.145904)
			(xy 241.67465 -200.201276) (xy 241.68227 -200.220072) (xy 241.689636 -200.227184) (xy 241.7087 -200.2468)
			(xy 241.741585 -200.290511) (xy 241.76789 -200.338471) (xy 241.787074 -200.389696) (xy 241.789747 -200.401936)
			(xy 242.245132 -200.401936) (xy 242.249203 -200.346314) (xy 242.261329 -200.291877) (xy 242.281252 -200.239786)
			(xy 242.308548 -200.191151) (xy 242.342634 -200.147008) (xy 242.382783 -200.108299) (xy 242.428141 -200.075848)
			(xy 242.477741 -200.050347) (xy 242.530525 -200.03234) (xy 242.585368 -200.02221) (xy 242.641102 -200.020173)
			(xy 242.696539 -200.026273) (xy 242.750496 -200.040379) (xy 242.801825 -200.062191) (xy 242.849431 -200.091245)
			(xy 242.892299 -200.12692) (xy 242.929516 -200.168457) (xy 242.960289 -200.21497) (xy 242.983961 -200.265467)
			(xy 243.000029 -200.318874) (xy 243.008149 -200.37405) (xy 243.008658 -200.401936) (xy 243.008149 -200.429822)
			(xy 243.000029 -200.484998) (xy 242.983961 -200.538405) (xy 242.960289 -200.588902) (xy 242.929516 -200.635415)
			(xy 242.892299 -200.676952) (xy 242.849431 -200.712627) (xy 242.801825 -200.741681) (xy 242.750496 -200.763493)
			(xy 242.696539 -200.777599) (xy 242.641102 -200.783699) (xy 242.585368 -200.781662) (xy 242.530525 -200.771532)
			(xy 242.477741 -200.753525) (xy 242.428141 -200.728024) (xy 242.382783 -200.695573) (xy 242.342634 -200.656864)
			(xy 242.308548 -200.612721) (xy 242.281252 -200.564086) (xy 242.261329 -200.511995) (xy 242.249203 -200.457558)
			(xy 242.245132 -200.401936) (xy 241.789747 -200.401936) (xy 241.798744 -200.443136) (xy 241.802662 -200.497696)
			(xy 241.798746 -200.552255) (xy 241.787076 -200.605696) (xy 241.767893 -200.656922) (xy 241.74159 -200.704882)
			(xy 241.708706 -200.748593) (xy 241.689636 -200.768204) (xy 241.682786 -200.775601) (xy 241.675048 -200.794199)
			(xy 241.67465 -200.804272) (xy 241.67465 -201.659998) (xy 242.454936 -201.659998) (xy 242.459007 -201.604376)
			(xy 242.471133 -201.549939) (xy 242.491056 -201.497848) (xy 242.518352 -201.449213) (xy 242.552438 -201.40507)
			(xy 242.592587 -201.366361) (xy 242.637945 -201.33391) (xy 242.687545 -201.308409) (xy 242.740329 -201.290402)
			(xy 242.795172 -201.280272) (xy 242.850906 -201.278235) (xy 242.906343 -201.284335) (xy 242.9603 -201.298441)
			(xy 243.011629 -201.320253) (xy 243.059235 -201.349307) (xy 243.102103 -201.384982) (xy 243.13932 -201.426519)
			(xy 243.170093 -201.473032) (xy 243.193765 -201.523529) (xy 243.209833 -201.576936) (xy 243.217953 -201.632112)
			(xy 243.218462 -201.659998) (xy 243.217953 -201.687884) (xy 243.209833 -201.74306) (xy 243.193765 -201.796467)
			(xy 243.170093 -201.846964) (xy 243.13932 -201.893477) (xy 243.102103 -201.935014) (xy 243.059235 -201.970689)
			(xy 243.011629 -201.999743) (xy 242.9603 -202.021555) (xy 242.906343 -202.035661) (xy 242.850906 -202.041761)
			(xy 242.795172 -202.039724) (xy 242.740329 -202.029594) (xy 242.687545 -202.011587) (xy 242.637945 -201.986086)
			(xy 242.592587 -201.953635) (xy 242.552438 -201.914926) (xy 242.518352 -201.870783) (xy 242.491056 -201.822148)
			(xy 242.471133 -201.770057) (xy 242.459007 -201.71562) (xy 242.454936 -201.659998) (xy 241.67465 -201.659998)
			(xy 241.67465 -202.832462) (xy 242.81968 -202.832462) (xy 242.823751 -202.77684) (xy 242.835877 -202.722403)
			(xy 242.8558 -202.670312) (xy 242.883096 -202.621677) (xy 242.917182 -202.577534) (xy 242.957331 -202.538825)
			(xy 243.002689 -202.506374) (xy 243.052289 -202.480873) (xy 243.105073 -202.462866) (xy 243.159916 -202.452736)
			(xy 243.21565 -202.450699) (xy 243.271087 -202.456799) (xy 243.325044 -202.470905) (xy 243.376373 -202.492717)
			(xy 243.423979 -202.521771) (xy 243.466847 -202.557446) (xy 243.504064 -202.598983) (xy 243.534837 -202.645496)
			(xy 243.558509 -202.695993) (xy 243.574577 -202.7494) (xy 243.582697 -202.804576) (xy 243.583206 -202.832462)
			(xy 243.582697 -202.860348) (xy 243.574577 -202.915524) (xy 243.558509 -202.968931) (xy 243.534837 -203.019428)
			(xy 243.504064 -203.065941) (xy 243.466847 -203.107478) (xy 243.423979 -203.143153) (xy 243.376373 -203.172207)
			(xy 243.325044 -203.194019) (xy 243.271087 -203.208125) (xy 243.21565 -203.214225) (xy 243.159916 -203.212188)
			(xy 243.105073 -203.202058) (xy 243.052289 -203.184051) (xy 243.002689 -203.15855) (xy 242.957331 -203.126099)
			(xy 242.917182 -203.08739) (xy 242.883096 -203.043247) (xy 242.8558 -202.994612) (xy 242.835877 -202.942521)
			(xy 242.823751 -202.888084) (xy 242.81968 -202.832462) (xy 241.67465 -202.832462) (xy 241.67465 -204.780134)
			(xy 241.675075 -204.789835) (xy 241.682245 -204.807863) (xy 241.68862 -204.815186) (xy 241.744246 -204.873098)
			(xy 241.761772 -204.881226) (xy 241.771678 -204.88148) (xy 241.799386 -204.883199) (xy 241.853905 -204.89365)
			(xy 241.906336 -204.911891) (xy 241.95557 -204.937536) (xy 242.000568 -204.970044) (xy 242.040381 -205.00873)
			(xy 242.074168 -205.052776) (xy 242.101216 -205.101253) (xy 242.120615 -205.152244) (xy 244.491762 -205.152244)
			(xy 244.495833 -205.096622) (xy 244.507959 -205.042185) (xy 244.527882 -204.990094) (xy 244.555178 -204.941459)
			(xy 244.589264 -204.897316) (xy 244.629413 -204.858607) (xy 244.674771 -204.826156) (xy 244.724371 -204.800655)
			(xy 244.777155 -204.782648) (xy 244.831998 -204.772518) (xy 244.887732 -204.770481) (xy 244.943169 -204.776581)
			(xy 244.997126 -204.790687) (xy 245.048455 -204.812499) (xy 245.096061 -204.841553) (xy 245.138929 -204.877228)
			(xy 245.176146 -204.918765) (xy 245.206919 -204.965278) (xy 245.230591 -205.015775) (xy 245.246659 -205.069182)
			(xy 245.254779 -205.124358) (xy 245.255288 -205.152244) (xy 245.254779 -205.18013) (xy 245.246659 -205.235306)
			(xy 245.230591 -205.288713) (xy 245.206919 -205.33921) (xy 245.176146 -205.385723) (xy 245.138929 -205.42726)
			(xy 245.096061 -205.462935) (xy 245.048455 -205.491989) (xy 244.997126 -205.513801) (xy 244.943169 -205.527907)
			(xy 244.887732 -205.534007) (xy 244.831998 -205.53197) (xy 244.777155 -205.52184) (xy 244.724371 -205.503833)
			(xy 244.674771 -205.478332) (xy 244.629413 -205.445881) (xy 244.589264 -205.407172) (xy 244.555178 -205.363029)
			(xy 244.527882 -205.314394) (xy 244.507959 -205.262303) (xy 244.495833 -205.207866) (xy 244.491762 -205.152244)
			(xy 242.120615 -205.152244) (xy 242.120955 -205.153138) (xy 242.132967 -205.207336) (xy 242.137 -205.262701)
			(xy 242.132967 -205.318067) (xy 242.120954 -205.372265) (xy 242.101215 -205.424149) (xy 242.074166 -205.472626)
			(xy 242.040379 -205.516672) (xy 242.000566 -205.555358) (xy 241.955567 -205.587866) (xy 241.906333 -205.613511)
			(xy 241.853903 -205.631751) (xy 241.799383 -205.642201) (xy 241.771678 -205.643988) (xy 241.761772 -205.644242)
			(xy 241.744246 -205.65237) (xy 241.68862 -205.710282) (xy 241.682234 -205.717602) (xy 241.675039 -205.735628)
			(xy 241.67465 -205.745334) (xy 241.67465 -205.895194) (xy 241.699796 -205.923642) (xy 241.7191 -205.926182)
			(xy 241.746385 -205.930133) (xy 241.79951 -205.944872) (xy 241.84996 -205.967105) (xy 241.896683 -205.99637)
			(xy 241.938707 -206.032056) (xy 241.975155 -206.07342) (xy 242.005269 -206.119601) (xy 242.028421 -206.169636)
			(xy 242.044128 -206.222482) (xy 242.052064 -206.27704) (xy 242.052064 -206.332171) (xy 242.044126 -206.386728)
			(xy 242.028417 -206.439574) (xy 242.005264 -206.489608) (xy 241.996189 -206.503524) (xy 244.491762 -206.503524)
			(xy 244.495833 -206.447902) (xy 244.507959 -206.393465) (xy 244.527882 -206.341374) (xy 244.555178 -206.292739)
			(xy 244.589264 -206.248596) (xy 244.629413 -206.209887) (xy 244.674771 -206.177436) (xy 244.724371 -206.151935)
			(xy 244.777155 -206.133928) (xy 244.831998 -206.123798) (xy 244.887732 -206.121761) (xy 244.943169 -206.127861)
			(xy 244.997126 -206.141967) (xy 245.048455 -206.163779) (xy 245.096061 -206.192833) (xy 245.138929 -206.228508)
			(xy 245.176146 -206.270045) (xy 245.206919 -206.316558) (xy 245.230591 -206.367055) (xy 245.246659 -206.420462)
			(xy 245.254779 -206.475638) (xy 245.255288 -206.503524) (xy 245.254779 -206.53141) (xy 245.246659 -206.586586)
			(xy 245.230591 -206.639993) (xy 245.206919 -206.69049) (xy 245.176146 -206.737003) (xy 245.138929 -206.77854)
			(xy 245.096061 -206.814215) (xy 245.048455 -206.843269) (xy 244.997126 -206.865081) (xy 244.943169 -206.879187)
			(xy 244.887732 -206.885287) (xy 244.831998 -206.88325) (xy 244.777155 -206.87312) (xy 244.724371 -206.855113)
			(xy 244.674771 -206.829612) (xy 244.629413 -206.797161) (xy 244.589264 -206.758452) (xy 244.555178 -206.714309)
			(xy 244.527882 -206.665674) (xy 244.507959 -206.613583) (xy 244.495833 -206.559146) (xy 244.491762 -206.503524)
			(xy 241.996189 -206.503524) (xy 241.975149 -206.535788) (xy 241.938699 -206.577151) (xy 241.896675 -206.612836)
			(xy 241.849951 -206.6421) (xy 241.7995 -206.664332) (xy 241.746375 -206.679069) (xy 241.7191 -206.683102)
			(xy 241.699796 -206.685642) (xy 241.67465 -206.71409) (xy 241.67465 -207.517746) (xy 241.67514 -207.52719)
			(xy 241.682049 -207.544777) (xy 241.688112 -207.552036) (xy 241.74069 -207.609694) (xy 241.757708 -207.618076)
			(xy 241.76736 -207.619092) (xy 241.795502 -207.622093) (xy 241.850524 -207.635342) (xy 241.902985 -207.656573)
			(xy 241.951735 -207.685319) (xy 241.995704 -207.72095) (xy 242.033929 -207.762685) (xy 242.06557 -207.809607)
			(xy 242.089934 -207.860689) (xy 242.106486 -207.914808) (xy 242.114863 -207.970779) (xy 242.11534 -207.999076)
			(xy 242.11486 -208.026487) (xy 242.107001 -208.080742) (xy 242.091455 -208.133313) (xy 242.068544 -208.183118)
			(xy 242.038738 -208.229129) (xy 242.002653 -208.2704) (xy 241.961031 -208.306079) (xy 241.914729 -208.335432)
			(xy 241.864703 -208.357854) (xy 241.83848 -208.365852) (xy 241.821716 -208.370678) (xy 241.801396 -208.397602)
			(xy 241.801396 -210.352894) (xy 241.801932 -210.362882) (xy 241.809644 -210.381316) (xy 241.816382 -210.388708)
			(xy 241.92611 -210.498436) (xy 241.933506 -210.505288) (xy 241.952105 -210.513028) (xy 241.962178 -210.513422)
		)
		(stroke
			(width 0)
			(type solid)
		)
		(fill yes)
		(layer "In5.Cu")
		(net "P5V_AUX")
	)
	(gr_poly
		(pts
			(xy 384.43281 -300.88078) (xy 384.439478 -300.880585) (xy 384.452352 -300.877112) (xy 384.45821 -300.873922)
			(xy 384.463036 -300.871128) (xy 384.466338 -300.868588) (xy 384.488584 -300.851179) (xy 384.537782 -300.823428)
			(xy 384.59098 -300.80444) (xy 384.64663 -300.794769) (xy 384.674872 -300.794166) (xy 384.688462 -300.794338)
			(xy 384.715547 -300.79663) (xy 384.728974 -300.798738) (xy 384.741166 -300.80077) (xy 384.763772 -300.793658)
			(xy 384.840226 -300.72076) (xy 384.8481 -300.698408) (xy 384.84683 -300.68647) (xy 384.845777 -300.677362)
			(xy 384.844635 -300.659062) (xy 384.844544 -300.649894) (xy 384.84472 -300.635648) (xy 384.847389 -300.60728)
			(xy 384.849878 -300.593252) (xy 384.852164 -300.58106) (xy 384.844798 -300.55693) (xy 384.767582 -300.479714)
			(xy 384.743706 -300.472348) (xy 384.73126 -300.474634) (xy 384.717295 -300.477118) (xy 384.689055 -300.479788)
			(xy 384.674872 -300.479968) (xy 384.650056 -300.47948) (xy 384.601077 -300.471446) (xy 384.554044 -300.455595)
			(xy 384.510194 -300.432343) (xy 384.470684 -300.402304) (xy 384.436553 -300.366269) (xy 384.408701 -300.325187)
			(xy 384.387863 -300.280141) (xy 384.374586 -300.232317) (xy 384.369221 -300.182975) (xy 384.371909 -300.133415)
			(xy 384.382579 -300.084942) (xy 384.40095 -300.038835) (xy 384.426538 -299.996306) (xy 384.458669 -299.958477)
			(xy 384.496496 -299.926345) (xy 384.539024 -299.900755) (xy 384.585131 -299.882382) (xy 384.633603 -299.87171)
			(xy 384.683163 -299.869021) (xy 384.732505 -299.874384) (xy 384.78033 -299.887659) (xy 384.825377 -299.908496)
			(xy 384.86646 -299.936345) (xy 384.902496 -299.970475) (xy 384.932537 -300.009984) (xy 384.95579 -300.053833)
			(xy 384.971643 -300.100866) (xy 384.979679 -300.149844) (xy 384.98018 -300.17466) (xy 384.980002 -300.188906)
			(xy 384.977328 -300.217273) (xy 384.974846 -300.231302) (xy 384.97256 -300.243494) (xy 384.979926 -300.267624)
			(xy 385.057142 -300.34484) (xy 385.081018 -300.352206) (xy 385.093464 -300.34992) (xy 385.107429 -300.347437)
			(xy 385.135669 -300.34477) (xy 385.149852 -300.344586) (xy 385.163966 -300.344708) (xy 385.192079 -300.347253)
			(xy 385.205986 -300.349666) (xy 385.218686 -300.352206) (xy 385.242308 -300.34484) (xy 385.319524 -300.26737)
			(xy 385.32689 -300.243748) (xy 385.324604 -300.231302) (xy 385.322118 -300.217337) (xy 385.319445 -300.189097)
			(xy 385.31927 -300.174914) (xy 385.319792 -300.149659) (xy 385.328105 -300.099837) (xy 385.344506 -300.052063)
			(xy 385.368547 -300.00764) (xy 385.399571 -299.96778) (xy 385.436733 -299.93357) (xy 385.479019 -299.905944)
			(xy 385.525275 -299.885654) (xy 385.57424 -299.873254) (xy 385.624578 -299.869083) (xy 385.674916 -299.873254)
			(xy 385.723881 -299.885654) (xy 385.770137 -299.905944) (xy 385.812423 -299.93357) (xy 385.849585 -299.96778)
			(xy 385.880609 -300.00764) (xy 385.90465 -300.052063) (xy 385.921051 -300.099837) (xy 385.929364 -300.149659)
			(xy 385.929886 -300.174914) (xy 385.929699 -300.189096) (xy 385.927024 -300.217335) (xy 385.924552 -300.231302)
			(xy 385.922266 -300.243748) (xy 385.929632 -300.267624) (xy 386.006848 -300.34484) (xy 386.030978 -300.352206)
			(xy 386.04317 -300.34992) (xy 386.057198 -300.347429) (xy 386.085566 -300.344762) (xy 386.099812 -300.344586)
			(xy 386.123803 -300.345058) (xy 386.171193 -300.352565) (xy 386.216826 -300.367393) (xy 386.259578 -300.389178)
			(xy 386.298395 -300.417381) (xy 386.332323 -300.451309) (xy 386.360526 -300.490128) (xy 386.382309 -300.532879)
			(xy 386.397136 -300.578512) (xy 386.404643 -300.625903) (xy 386.40512 -300.649894) (xy 386.405028 -300.659062)
			(xy 386.403885 -300.677362) (xy 386.402834 -300.68647) (xy 386.401564 -300.698662) (xy 386.409438 -300.721014)
			(xy 386.485892 -300.793912) (xy 386.508498 -300.801024) (xy 386.520436 -300.798992) (xy 386.533924 -300.796861)
			(xy 386.561137 -300.794573) (xy 386.574792 -300.79442) (xy 386.645404 -300.79442) (xy 386.656098 -300.793861)
			(xy 386.675661 -300.78521) (xy 386.68325 -300.777656) (xy 386.740908 -300.713394) (xy 386.747512 -300.693074)
			(xy 386.746496 -300.682152) (xy 386.744718 -300.649894) (xy 386.74524 -300.624639) (xy 386.753553 -300.574817)
			(xy 386.769954 -300.527043) (xy 386.793995 -300.48262) (xy 386.825019 -300.44276) (xy 386.862181 -300.40855)
			(xy 386.904467 -300.380924) (xy 386.950723 -300.360634) (xy 386.999688 -300.348234) (xy 387.050026 -300.344063)
			(xy 387.100364 -300.348234) (xy 387.149329 -300.360634) (xy 387.195585 -300.380924) (xy 387.237871 -300.40855)
			(xy 387.275033 -300.44276) (xy 387.306057 -300.48262) (xy 387.330098 -300.527043) (xy 387.346499 -300.574817)
			(xy 387.354812 -300.624639) (xy 387.355334 -300.649894) (xy 387.353556 -300.682152) (xy 387.35254 -300.693074)
			(xy 387.359144 -300.713394) (xy 387.416802 -300.777656) (xy 387.424319 -300.785316) (xy 387.443924 -300.794)
			(xy 387.454648 -300.79442) (xy 387.52526 -300.79442) (xy 387.53885 -300.794591) (xy 387.565935 -300.796882)
			(xy 387.579362 -300.798992) (xy 387.5913 -300.80077) (xy 387.613906 -300.793912) (xy 387.69036 -300.72076)
			(xy 387.698234 -300.698662) (xy 387.696964 -300.68647) (xy 387.695911 -300.677362) (xy 387.694769 -300.659062)
			(xy 387.694678 -300.649894) (xy 387.6952 -300.624639) (xy 387.703513 -300.574817) (xy 387.719914 -300.527043)
			(xy 387.743955 -300.48262) (xy 387.774979 -300.44276) (xy 387.812141 -300.40855) (xy 387.854427 -300.380924)
			(xy 387.900683 -300.360634) (xy 387.949648 -300.348234) (xy 387.999986 -300.344063) (xy 388.050324 -300.348234)
			(xy 388.099289 -300.360634) (xy 388.145545 -300.380924) (xy 388.187831 -300.40855) (xy 388.224993 -300.44276)
			(xy 388.256017 -300.48262) (xy 388.280058 -300.527043) (xy 388.296459 -300.574817) (xy 388.304772 -300.624639)
			(xy 388.305294 -300.649894) (xy 388.305202 -300.659062) (xy 388.304058 -300.677362) (xy 388.303008 -300.68647)
			(xy 388.301738 -300.698408) (xy 388.309612 -300.72076) (xy 388.386066 -300.793658) (xy 388.408672 -300.80077)
			(xy 388.420864 -300.798738) (xy 388.43429 -300.796621) (xy 388.461375 -300.794336) (xy 388.474966 -300.794166)
			(xy 388.488556 -300.794337) (xy 388.515641 -300.796629) (xy 388.529068 -300.798738) (xy 388.54126 -300.80077)
			(xy 388.563866 -300.793658) (xy 388.64032 -300.72076) (xy 388.648194 -300.698408) (xy 388.646924 -300.68647)
			(xy 388.645871 -300.677362) (xy 388.644729 -300.659062) (xy 388.644638 -300.649894) (xy 388.64516 -300.624639)
			(xy 388.653473 -300.574817) (xy 388.669874 -300.527043) (xy 388.693915 -300.48262) (xy 388.724939 -300.44276)
			(xy 388.762101 -300.40855) (xy 388.804387 -300.380924) (xy 388.850643 -300.360634) (xy 388.899608 -300.348234)
			(xy 388.949946 -300.344063) (xy 389.000284 -300.348234) (xy 389.049249 -300.360634) (xy 389.095505 -300.380924)
			(xy 389.137791 -300.40855) (xy 389.174953 -300.44276) (xy 389.205977 -300.48262) (xy 389.230018 -300.527043)
			(xy 389.246419 -300.574817) (xy 389.254732 -300.624639) (xy 389.255254 -300.649894) (xy 389.255158 -300.658998)
			(xy 389.254017 -300.677172) (xy 389.252968 -300.686216) (xy 389.251698 -300.698154) (xy 389.259572 -300.720506)
			(xy 389.336026 -300.793404) (xy 389.358632 -300.800516) (xy 389.37057 -300.798484) (xy 389.384058 -300.796355)
			(xy 389.411272 -300.794067) (xy 389.424926 -300.793912) (xy 389.495284 -300.793912) (xy 389.505945 -300.793456)
			(xy 389.525419 -300.784779) (xy 389.532876 -300.777148) (xy 389.590788 -300.712886) (xy 389.597392 -300.692566)
			(xy 389.596376 -300.681644) (xy 389.594598 -300.649894) (xy 389.59512 -300.624639) (xy 389.603433 -300.574817)
			(xy 389.619834 -300.527043) (xy 389.643875 -300.48262) (xy 389.674899 -300.44276) (xy 389.712061 -300.40855)
			(xy 389.754347 -300.380924) (xy 389.800603 -300.360634) (xy 389.849568 -300.348234) (xy 389.899906 -300.344063)
			(xy 389.950244 -300.348234) (xy 389.999209 -300.360634) (xy 390.045465 -300.380924) (xy 390.087751 -300.40855)
			(xy 390.124913 -300.44276) (xy 390.155937 -300.48262) (xy 390.179978 -300.527043) (xy 390.196379 -300.574817)
			(xy 390.204692 -300.624639) (xy 390.205214 -300.649894) (xy 390.203436 -300.681644) (xy 390.20242 -300.692566)
			(xy 390.209024 -300.712886) (xy 390.266936 -300.777148) (xy 390.274482 -300.784653) (xy 390.293902 -300.793301)
			(xy 390.304528 -300.793912) (xy 390.374886 -300.793912) (xy 390.38854 -300.794075) (xy 390.415752 -300.796366)
			(xy 390.429242 -300.798484) (xy 390.44118 -300.800516) (xy 390.463786 -300.793404) (xy 390.54024 -300.720506)
			(xy 390.548114 -300.698154) (xy 390.546844 -300.686216) (xy 390.545796 -300.677172) (xy 390.544653 -300.658998)
			(xy 390.544558 -300.649894) (xy 390.545029 -300.625902) (xy 390.552536 -300.578509) (xy 390.567363 -300.532874)
			(xy 390.589147 -300.490119) (xy 390.617349 -300.451299) (xy 390.651278 -300.417368) (xy 390.690096 -300.389161)
			(xy 390.732848 -300.367374) (xy 390.778482 -300.352542) (xy 390.825874 -300.345031) (xy 390.849866 -300.344586)
			(xy 390.864049 -300.344771) (xy 390.892288 -300.347441) (xy 390.906254 -300.34992) (xy 390.9187 -300.352206)
			(xy 390.942322 -300.34484) (xy 391.019792 -300.26737) (xy 391.027158 -300.243748) (xy 391.024872 -300.231302)
			(xy 391.022386 -300.217337) (xy 391.019712 -300.189097) (xy 391.019538 -300.174914) (xy 391.019724 -300.160731)
			(xy 391.022396 -300.132492) (xy 391.024872 -300.118526) (xy 391.027158 -300.10608) (xy 391.019792 -300.082458)
			(xy 390.942322 -300.004988) (xy 390.9187 -299.997622) (xy 390.906254 -299.999908) (xy 390.892289 -300.002391)
			(xy 390.864049 -300.00506) (xy 390.849866 -300.005242) (xy 390.82461 -300.004718) (xy 390.774787 -299.996399)
			(xy 390.727012 -299.979993) (xy 390.68259 -299.955948) (xy 390.64273 -299.92492) (xy 390.608521 -299.887755)
			(xy 390.580895 -299.845466) (xy 390.560605 -299.799207) (xy 390.548206 -299.75024) (xy 390.544035 -299.6999)
			(xy 390.548206 -299.64956) (xy 390.560605 -299.600593) (xy 390.580895 -299.554334) (xy 390.608521 -299.512045)
			(xy 390.64273 -299.47488) (xy 390.68259 -299.443852) (xy 390.727012 -299.419807) (xy 390.774787 -299.403401)
			(xy 390.82461 -299.395082) (xy 390.849866 -299.394626) (xy 390.864049 -299.394811) (xy 390.892288 -299.397482)
			(xy 390.906254 -299.39996) (xy 390.9187 -299.402246) (xy 390.942576 -299.39488) (xy 391.019792 -299.317664)
			(xy 391.027158 -299.293534) (xy 391.024872 -299.281342) (xy 391.022375 -299.267315) (xy 391.019706 -299.238947)
			(xy 391.019538 -299.2247) (xy 391.020024 -299.199884) (xy 391.028053 -299.150905) (xy 391.0439 -299.10387)
			(xy 391.067148 -299.060019) (xy 391.097184 -299.020506) (xy 391.133216 -298.986373) (xy 391.174295 -298.958518)
			(xy 391.21934 -298.937676) (xy 391.267163 -298.924396) (xy 391.316504 -298.919028) (xy 391.366064 -298.921712)
			(xy 391.414537 -298.932379) (xy 391.460646 -298.950747) (xy 391.503176 -298.976332) (xy 391.541006 -299.008461)
			(xy 391.573141 -299.046287) (xy 391.598733 -299.088813) (xy 391.617108 -299.134919) (xy 391.627782 -299.18339)
			(xy 391.63004 -299.224954) (xy 391.969002 -299.224954) (xy 391.972962 -299.1759) (xy 391.984739 -299.128116)
			(xy 392.00403 -299.08284) (xy 392.030333 -299.041244) (xy 392.062968 -299.004407) (xy 392.101089 -298.973282)
			(xy 392.14371 -298.948675) (xy 392.189726 -298.931223) (xy 392.237945 -298.921379) (xy 392.28712 -298.919398)
			(xy 392.335975 -298.92533) (xy 392.383246 -298.939022) (xy 392.427708 -298.96012) (xy 392.468211 -298.988076)
			(xy 392.503704 -299.022168) (xy 392.533269 -299.061512) (xy 392.55614 -299.105089) (xy 392.571724 -299.15177)
			(xy 392.579619 -299.200347) (xy 392.580114 -299.224954) (xy 392.919216 -299.224954) (xy 392.923176 -299.1759)
			(xy 392.934953 -299.128116) (xy 392.954244 -299.08284) (xy 392.980547 -299.041244) (xy 393.013182 -299.004407)
			(xy 393.051303 -298.973282) (xy 393.093924 -298.948675) (xy 393.13994 -298.931223) (xy 393.188159 -298.921379)
			(xy 393.237334 -298.919398) (xy 393.286189 -298.92533) (xy 393.33346 -298.939022) (xy 393.377922 -298.96012)
			(xy 393.418425 -298.988076) (xy 393.453918 -299.022168) (xy 393.483483 -299.061512) (xy 393.506354 -299.105089)
			(xy 393.521938 -299.15177) (xy 393.529833 -299.200347) (xy 393.530328 -299.224954) (xy 393.869176 -299.224954)
			(xy 393.873136 -299.1759) (xy 393.884913 -299.128116) (xy 393.904204 -299.08284) (xy 393.930507 -299.041244)
			(xy 393.963142 -299.004407) (xy 394.001263 -298.973282) (xy 394.043884 -298.948675) (xy 394.0899 -298.931223)
			(xy 394.138119 -298.921379) (xy 394.187294 -298.919398) (xy 394.236149 -298.92533) (xy 394.28342 -298.939022)
			(xy 394.327882 -298.96012) (xy 394.368385 -298.988076) (xy 394.403878 -299.022168) (xy 394.433443 -299.061512)
			(xy 394.456314 -299.105089) (xy 394.471898 -299.15177) (xy 394.479793 -299.200347) (xy 394.480288 -299.224954)
			(xy 394.479793 -299.249561) (xy 394.471898 -299.298138) (xy 394.456314 -299.344819) (xy 394.433443 -299.388396)
			(xy 394.403878 -299.42774) (xy 394.368385 -299.461832) (xy 394.327882 -299.489788) (xy 394.28342 -299.510886)
			(xy 394.236149 -299.524578) (xy 394.187294 -299.53051) (xy 394.138119 -299.528529) (xy 394.0899 -299.518685)
			(xy 394.043884 -299.501233) (xy 394.001263 -299.476626) (xy 393.963142 -299.445501) (xy 393.930507 -299.408664)
			(xy 393.904204 -299.367068) (xy 393.884913 -299.321792) (xy 393.873136 -299.274008) (xy 393.869176 -299.224954)
			(xy 393.530328 -299.224954) (xy 393.529833 -299.249561) (xy 393.521938 -299.298138) (xy 393.506354 -299.344819)
			(xy 393.483483 -299.388396) (xy 393.453918 -299.42774) (xy 393.418425 -299.461832) (xy 393.377922 -299.489788)
			(xy 393.33346 -299.510886) (xy 393.286189 -299.524578) (xy 393.237334 -299.53051) (xy 393.188159 -299.528529)
			(xy 393.13994 -299.518685) (xy 393.093924 -299.501233) (xy 393.051303 -299.476626) (xy 393.013182 -299.445501)
			(xy 392.980547 -299.408664) (xy 392.954244 -299.367068) (xy 392.934953 -299.321792) (xy 392.923176 -299.274008)
			(xy 392.919216 -299.224954) (xy 392.580114 -299.224954) (xy 392.579619 -299.249561) (xy 392.571724 -299.298138)
			(xy 392.55614 -299.344819) (xy 392.533269 -299.388396) (xy 392.503704 -299.42774) (xy 392.468211 -299.461832)
			(xy 392.427708 -299.489788) (xy 392.383246 -299.510886) (xy 392.335975 -299.524578) (xy 392.28712 -299.53051)
			(xy 392.237945 -299.528529) (xy 392.189726 -299.518685) (xy 392.14371 -299.501233) (xy 392.101089 -299.476626)
			(xy 392.062968 -299.445501) (xy 392.030333 -299.408664) (xy 392.00403 -299.367068) (xy 391.984739 -299.321792)
			(xy 391.972962 -299.274008) (xy 391.969002 -299.224954) (xy 391.63004 -299.224954) (xy 391.630474 -299.23295)
			(xy 391.625113 -299.282292) (xy 391.61184 -299.330117) (xy 391.591005 -299.375165) (xy 391.563156 -299.416248)
			(xy 391.529028 -299.452286) (xy 391.48952 -299.482327) (xy 391.445672 -299.505581) (xy 391.39864 -299.521436)
			(xy 391.349662 -299.529473) (xy 391.324846 -299.530008) (xy 391.310663 -299.529824) (xy 391.282423 -299.527154)
			(xy 391.268458 -299.524674) (xy 391.256012 -299.522388) (xy 391.232136 -299.529754) (xy 391.15492 -299.60697)
			(xy 391.147554 -299.6311) (xy 391.14984 -299.643292) (xy 391.15234 -299.657319) (xy 391.155015 -299.685687)
			(xy 391.155174 -299.699934) (xy 391.15499 -299.714117) (xy 391.152323 -299.742357) (xy 391.14984 -299.756322)
			(xy 391.147554 -299.768768) (xy 391.15492 -299.79239) (xy 391.23239 -299.86986) (xy 391.256012 -299.877226)
			(xy 391.268458 -299.87494) (xy 391.282423 -299.872457) (xy 391.310663 -299.869789) (xy 391.324846 -299.869606)
			(xy 391.348834 -299.87008) (xy 391.39622 -299.877592) (xy 391.441847 -299.892424) (xy 391.484592 -299.91421)
			(xy 391.523403 -299.942414) (xy 391.557325 -299.976342) (xy 391.585522 -300.015159) (xy 391.607299 -300.057909)
			(xy 391.622122 -300.103539) (xy 391.629625 -300.150925) (xy 391.630154 -300.174914) (xy 391.629967 -300.189096)
			(xy 391.627293 -300.217335) (xy 391.62482 -300.231302) (xy 391.622534 -300.243748) (xy 391.6299 -300.26737)
			(xy 391.70737 -300.34484) (xy 391.730992 -300.352206) (xy 391.743438 -300.34992) (xy 391.757403 -300.347436)
			(xy 391.785643 -300.344766) (xy 391.799826 -300.344586) (xy 391.814008 -300.344774) (xy 391.842247 -300.34745)
			(xy 391.856214 -300.34992) (xy 391.86866 -300.352206) (xy 391.892282 -300.34484) (xy 391.969752 -300.26737)
			(xy 391.977118 -300.243748) (xy 391.974832 -300.231302) (xy 391.972346 -300.217337) (xy 391.969673 -300.189097)
			(xy 391.969498 -300.174914) (xy 391.969983 -300.150093) (xy 391.978012 -300.101106) (xy 391.99386 -300.054063)
			(xy 392.01711 -300.010203) (xy 392.04715 -299.970683) (xy 392.083188 -299.936544) (xy 392.124274 -299.908684)
			(xy 392.169326 -299.887839) (xy 392.217157 -299.874556) (xy 392.266507 -299.869187) (xy 392.316075 -299.871873)
			(xy 392.364556 -299.882543) (xy 392.410672 -299.900915) (xy 392.453208 -299.926506) (xy 392.491044 -299.958642)
			(xy 392.523182 -299.996475) (xy 392.548776 -300.03901) (xy 392.567151 -300.085125) (xy 392.577824 -300.133605)
			(xy 392.580065 -300.174914) (xy 392.919216 -300.174914) (xy 392.923176 -300.12586) (xy 392.934953 -300.078076)
			(xy 392.954244 -300.0328) (xy 392.980547 -299.991204) (xy 393.013182 -299.954367) (xy 393.051303 -299.923242)
			(xy 393.093924 -299.898635) (xy 393.13994 -299.881183) (xy 393.188159 -299.871339) (xy 393.237334 -299.869358)
			(xy 393.286189 -299.87529) (xy 393.33346 -299.888982) (xy 393.377922 -299.91008) (xy 393.418425 -299.938036)
			(xy 393.453918 -299.972128) (xy 393.483483 -300.011472) (xy 393.506354 -300.055049) (xy 393.521938 -300.10173)
			(xy 393.529833 -300.150307) (xy 393.530328 -300.174914) (xy 393.869176 -300.174914) (xy 393.873136 -300.12586)
			(xy 393.884913 -300.078076) (xy 393.904204 -300.0328) (xy 393.930507 -299.991204) (xy 393.963142 -299.954367)
			(xy 394.001263 -299.923242) (xy 394.043884 -299.898635) (xy 394.0899 -299.881183) (xy 394.138119 -299.871339)
			(xy 394.187294 -299.869358) (xy 394.236149 -299.87529) (xy 394.28342 -299.888982) (xy 394.327882 -299.91008)
			(xy 394.368385 -299.938036) (xy 394.403878 -299.972128) (xy 394.433443 -300.011472) (xy 394.456314 -300.055049)
			(xy 394.471898 -300.10173) (xy 394.479793 -300.150307) (xy 394.480288 -300.174914) (xy 394.479793 -300.199521)
			(xy 394.471898 -300.248098) (xy 394.456314 -300.294779) (xy 394.433443 -300.338356) (xy 394.403878 -300.3777)
			(xy 394.368385 -300.411792) (xy 394.327882 -300.439748) (xy 394.28342 -300.460846) (xy 394.236149 -300.474538)
			(xy 394.187294 -300.48047) (xy 394.138119 -300.478489) (xy 394.0899 -300.468645) (xy 394.043884 -300.451193)
			(xy 394.001263 -300.426586) (xy 393.963142 -300.395461) (xy 393.930507 -300.358624) (xy 393.904204 -300.317028)
			(xy 393.884913 -300.271752) (xy 393.873136 -300.223968) (xy 393.869176 -300.174914) (xy 393.530328 -300.174914)
			(xy 393.529833 -300.199521) (xy 393.521938 -300.248098) (xy 393.506354 -300.294779) (xy 393.483483 -300.338356)
			(xy 393.453918 -300.3777) (xy 393.418425 -300.411792) (xy 393.377922 -300.439748) (xy 393.33346 -300.460846)
			(xy 393.286189 -300.474538) (xy 393.237334 -300.48047) (xy 393.188159 -300.478489) (xy 393.13994 -300.468645)
			(xy 393.093924 -300.451193) (xy 393.051303 -300.426586) (xy 393.013182 -300.395461) (xy 392.980547 -300.358624)
			(xy 392.954244 -300.317028) (xy 392.934953 -300.271752) (xy 392.923176 -300.223968) (xy 392.919216 -300.174914)
			(xy 392.580065 -300.174914) (xy 392.580513 -300.183173) (xy 392.575147 -300.232523) (xy 392.561868 -300.280355)
			(xy 392.541026 -300.325409) (xy 392.513169 -300.366497) (xy 392.479032 -300.402537) (xy 392.439513 -300.432579)
			(xy 392.395656 -300.455832) (xy 392.348613 -300.471684) (xy 392.299626 -300.479716) (xy 392.274806 -300.480222)
			(xy 392.260624 -300.480036) (xy 392.232384 -300.477363) (xy 392.218418 -300.474888) (xy 392.205972 -300.472602)
			(xy 392.18235 -300.479968) (xy 392.10488 -300.557438) (xy 392.097514 -300.58106) (xy 392.0998 -300.593506)
			(xy 392.102285 -300.607471) (xy 392.104958 -300.635711) (xy 392.105134 -300.649894) (xy 392.105042 -300.659062)
			(xy 392.103899 -300.677362) (xy 392.102848 -300.68647) (xy 392.101578 -300.698408) (xy 392.109452 -300.72076)
			(xy 392.185906 -300.793658) (xy 392.208512 -300.80077) (xy 392.220704 -300.798738) (xy 392.23413 -300.796618)
			(xy 392.261215 -300.794329) (xy 392.274806 -300.794166) (xy 392.303047 -300.794782) (xy 392.358697 -300.804455)
			(xy 392.411898 -300.823433) (xy 392.461105 -300.851166) (xy 392.48334 -300.868588) (xy 392.486642 -300.871128)
			(xy 392.491468 -300.873922) (xy 392.497346 -300.877063) (xy 392.510208 -300.880532) (xy 392.516868 -300.88078)
			(xy 392.982958 -300.88078) (xy 392.989624 -300.880579) (xy 393.002492 -300.877096) (xy 393.008358 -300.873922)
			(xy 393.013184 -300.871128) (xy 393.016486 -300.868588) (xy 393.038733 -300.851183) (xy 393.087932 -300.823438)
			(xy 393.14113 -300.804458) (xy 393.19678 -300.794795) (xy 393.22502 -300.794166) (xy 393.253261 -300.794783)
			(xy 393.30891 -300.804458) (xy 393.362109 -300.823438) (xy 393.411315 -300.851172) (xy 393.433554 -300.868588)
			(xy 393.436856 -300.871128) (xy 393.441682 -300.873922) (xy 393.44756 -300.877062) (xy 393.460422 -300.880527)
			(xy 393.467082 -300.88078) (xy 393.932918 -300.88078) (xy 393.939585 -300.880584) (xy 393.952459 -300.87711)
			(xy 393.958318 -300.873922) (xy 393.963144 -300.871128) (xy 393.966446 -300.868588) (xy 393.988693 -300.85118)
			(xy 394.03789 -300.823429) (xy 394.091088 -300.804443) (xy 394.146739 -300.794773) (xy 394.17498 -300.794166)
			(xy 394.203219 -300.794788) (xy 394.258863 -300.804472) (xy 394.312056 -300.823459) (xy 394.361255 -300.851199)
			(xy 394.383514 -300.868588) (xy 394.386816 -300.871128) (xy 394.391642 -300.873922) (xy 394.397519 -300.877066)
			(xy 394.410381 -300.880542) (xy 394.417042 -300.88078) (xy 394.882878 -300.88078) (xy 394.889547 -300.880589)
			(xy 394.902425 -300.877124) (xy 394.908278 -300.873922) (xy 394.913104 -300.871128) (xy 394.916406 -300.868588)
			(xy 394.938652 -300.851177) (xy 394.987848 -300.823421) (xy 395.041046 -300.804428) (xy 395.096698 -300.794752)
			(xy 395.12494 -300.794166) (xy 395.153388 -300.795436) (xy 395.164818 -300.796452) (xy 395.185646 -300.788832)
			(xy 395.227302 -300.747176) (xy 395.234144 -300.739776) (xy 395.24187 -300.721178) (xy 395.242288 -300.711108)
			(xy 395.242288 -300.606968) (xy 395.24176 -300.5967) (xy 395.233633 -300.577835) (xy 395.22654 -300.570392)
			(xy 395.166342 -300.51248) (xy 395.147292 -300.505114) (xy 395.136878 -300.505368) (xy 395.12494 -300.505622)
			(xy 395.098948 -300.505142) (xy 395.047602 -300.497015) (xy 394.99816 -300.480956) (xy 394.951839 -300.457359)
			(xy 394.909781 -300.426806) (xy 394.87302 -300.39005) (xy 394.842462 -300.347995) (xy 394.818859 -300.301677)
			(xy 394.802794 -300.252237) (xy 394.794661 -300.200892) (xy 394.794661 -300.148908) (xy 394.802794 -300.097563)
			(xy 394.818859 -300.048123) (xy 394.842462 -300.001805) (xy 394.87302 -299.95975) (xy 394.909781 -299.922994)
			(xy 394.951839 -299.892441) (xy 394.99816 -299.868844) (xy 395.047602 -299.852785) (xy 395.098948 -299.844658)
			(xy 395.12494 -299.844206) (xy 395.136878 -299.84446) (xy 395.147292 -299.844714) (xy 395.166342 -299.837348)
			(xy 395.22654 -299.779436) (xy 395.233655 -299.77201) (xy 395.241767 -299.753133) (xy 395.242288 -299.74286)
			(xy 395.242288 -298.706794) (xy 395.241765 -298.696524) (xy 395.233644 -298.677652) (xy 395.22654 -298.670218)
			(xy 395.166596 -298.612306) (xy 395.147292 -298.60494) (xy 395.136878 -298.605194) (xy 395.125194 -298.605448)
			(xy 395.124686 -298.605448) (xy 395.095415 -298.604821) (xy 395.037785 -298.594524) (xy 394.982864 -298.574254)
			(xy 394.9573 -298.559982) (xy 394.951712 -298.55668) (xy 394.9319 -298.551092) (xy 394.91793 -298.54906)
			(xy 394.38199 -298.54906) (xy 394.36802 -298.551092) (xy 394.348208 -298.55668) (xy 394.34262 -298.559982)
			(xy 394.317058 -298.574261) (xy 394.26214 -298.594549) (xy 394.204507 -298.604848) (xy 394.175234 -298.605448)
			(xy 394.174726 -298.605448) (xy 394.145456 -298.604816) (xy 394.087831 -298.59451) (xy 394.032916 -298.574231)
			(xy 394.00734 -298.559982) (xy 394.001752 -298.55668) (xy 393.98194 -298.551092) (xy 393.96797 -298.54906)
			(xy 393.43203 -298.54906) (xy 393.41806 -298.551092) (xy 393.398248 -298.55668) (xy 393.39266 -298.559982)
			(xy 393.367097 -298.574257) (xy 393.312178 -298.594534) (xy 393.254546 -298.604823) (xy 393.225274 -298.605448)
			(xy 393.224766 -298.605448) (xy 393.195495 -298.60482) (xy 393.137867 -298.594519) (xy 393.082948 -298.574246)
			(xy 393.05738 -298.559982) (xy 393.051792 -298.55668) (xy 393.03198 -298.551092) (xy 393.01801 -298.54906)
			(xy 392.481816 -298.54906) (xy 392.467846 -298.551092) (xy 392.448034 -298.55668) (xy 392.442446 -298.559982)
			(xy 392.416883 -298.574255) (xy 392.361963 -298.594531) (xy 392.304332 -298.604817) (xy 392.27506 -298.605448)
			(xy 392.274552 -298.605448) (xy 392.245282 -298.604818) (xy 392.187654 -298.594516) (xy 392.132737 -298.574241)
			(xy 392.107166 -298.559982) (xy 392.101578 -298.55668) (xy 392.081766 -298.551092) (xy 392.067796 -298.54906)
			(xy 391.459212 -298.54906) (xy 391.449306 -298.553378) (xy 391.429643 -298.561779) (xy 391.388559 -298.573628)
			(xy 391.346225 -298.579641) (xy 391.324846 -298.580048) (xy 391.303464 -298.579676) (xy 391.261124 -298.573672)
			(xy 391.220041 -298.561804) (xy 391.200386 -298.553378) (xy 391.19048 -298.54906) (xy 390.581896 -298.54906)
			(xy 390.567926 -298.551092) (xy 390.548114 -298.55668) (xy 390.542526 -298.559982) (xy 390.516963 -298.574254)
			(xy 390.462043 -298.594526) (xy 390.404411 -298.604809) (xy 390.37514 -298.605448) (xy 390.374632 -298.605448)
			(xy 390.361042 -298.605277) (xy 390.333957 -298.602985) (xy 390.32053 -298.600876) (xy 390.308592 -298.599098)
			(xy 390.285986 -298.605956) (xy 390.209532 -298.679108) (xy 390.201658 -298.701206) (xy 390.202928 -298.713398)
			(xy 390.203976 -298.722442) (xy 390.205118 -298.740616) (xy 390.205214 -298.74972) (xy 390.204742 -298.77371)
			(xy 390.197233 -298.8211) (xy 390.182404 -298.866732) (xy 390.16062 -298.909482) (xy 390.132416 -298.948298)
			(xy 390.098488 -298.982225) (xy 390.05967 -299.010427) (xy 390.016919 -299.03221) (xy 389.971286 -299.047037)
			(xy 389.923896 -299.054543) (xy 389.899906 -299.055028) (xy 389.885724 -299.054842) (xy 389.857484 -299.052169)
			(xy 389.843518 -299.049694) (xy 389.831072 -299.047408) (xy 389.807196 -299.054774) (xy 389.72998 -299.13199)
			(xy 389.722614 -299.15612) (xy 389.7249 -299.168312) (xy 389.7274 -299.182339) (xy 389.730073 -299.210707)
			(xy 389.730234 -299.224954) (xy 389.729791 -299.24895) (xy 389.72229 -299.296353) (xy 389.707466 -299.341998)
			(xy 389.685684 -299.384763) (xy 389.657479 -299.423593) (xy 389.623548 -299.457533) (xy 389.584724 -299.485746)
			(xy 389.541965 -299.507539) (xy 389.496323 -299.522374) (xy 389.448922 -299.529886) (xy 389.424926 -299.530262)
			(xy 389.410743 -299.530077) (xy 389.382504 -299.527406) (xy 389.368538 -299.524928) (xy 389.356092 -299.522642)
			(xy 389.33247 -299.530008) (xy 389.255 -299.607478) (xy 389.247634 -299.6311) (xy 389.24992 -299.643546)
			(xy 389.252403 -299.657511) (xy 389.255072 -299.685751) (xy 389.255254 -299.699934) (xy 389.254766 -299.724759)
			(xy 389.246728 -299.773753) (xy 389.230869 -299.820802) (xy 389.207608 -299.864666) (xy 389.177556 -299.904188)
			(xy 389.141507 -299.938328) (xy 389.100409 -299.966186) (xy 389.055346 -299.987028) (xy 389.007504 -300.000304)
			(xy 388.958145 -300.005666) (xy 388.908568 -300.002972) (xy 388.860081 -299.992293) (xy 388.81396 -299.97391)
			(xy 388.771421 -299.948307) (xy 388.733584 -299.91616) (xy 388.701446 -299.878314) (xy 388.675855 -299.835768)
			(xy 388.657484 -299.789642) (xy 388.646817 -299.741152) (xy 388.644136 -299.691575) (xy 388.649511 -299.642217)
			(xy 388.6628 -299.594379) (xy 388.683654 -299.549321) (xy 388.711522 -299.508231) (xy 388.745672 -299.47219)
			(xy 388.785202 -299.442149) (xy 388.829071 -299.418899) (xy 388.876124 -299.403053) (xy 388.925121 -299.395028)
			(xy 388.949946 -299.394626) (xy 388.964129 -299.39481) (xy 388.992369 -299.397479) (xy 389.006334 -299.39996)
			(xy 389.01878 -299.402246) (xy 389.042402 -299.39488) (xy 389.119872 -299.31741) (xy 389.127238 -299.293788)
			(xy 389.124952 -299.281342) (xy 389.122469 -299.267377) (xy 389.119801 -299.239137) (xy 389.119618 -299.224954)
			(xy 389.119712 -299.215786) (xy 389.120858 -299.197486) (xy 389.121904 -299.188378) (xy 389.123174 -299.176186)
			(xy 389.1153 -299.154088) (xy 389.038846 -299.080936) (xy 389.01624 -299.074078) (xy 389.004302 -299.07611)
			(xy 388.990809 -299.078178) (xy 388.963596 -299.080343) (xy 388.949946 -299.080428) (xy 387.999986 -299.080428)
			(xy 387.973993 -299.079918) (xy 387.922648 -299.071787) (xy 387.873205 -299.055727) (xy 387.826881 -299.032134)
			(xy 387.784817 -299.001588) (xy 387.748046 -298.96484) (xy 387.717474 -298.922795) (xy 387.693852 -298.876486)
			(xy 387.677761 -298.827053) (xy 387.669599 -298.775712) (xy 387.669024 -298.74972) (xy 387.671056 -298.715176)
			(xy 387.672072 -298.703746) (xy 387.664452 -298.682156) (xy 387.59257 -298.610274) (xy 387.57098 -298.6024)
			(xy 387.559296 -298.60367) (xy 387.52526 -298.605448) (xy 387.524752 -298.605448) (xy 387.495482 -298.604818)
			(xy 387.437854 -298.594516) (xy 387.382937 -298.574241) (xy 387.357366 -298.559982) (xy 387.351778 -298.55668)
			(xy 387.331966 -298.551092) (xy 387.317996 -298.54906) (xy 386.781802 -298.54906) (xy 386.767832 -298.551092)
			(xy 386.74802 -298.55668) (xy 386.742432 -298.559982) (xy 386.716869 -298.574254) (xy 386.661949 -298.594527)
			(xy 386.604317 -298.604811) (xy 386.575046 -298.605448) (xy 386.574538 -298.605448) (xy 386.545268 -298.604817)
			(xy 386.487642 -298.594513) (xy 386.432725 -298.574236) (xy 386.407152 -298.559982) (xy 386.401564 -298.55668)
			(xy 386.381752 -298.551092) (xy 386.367782 -298.54906) (xy 385.831588 -298.54906) (xy 385.817618 -298.551092)
			(xy 385.797806 -298.55668) (xy 385.792218 -298.559982) (xy 385.766656 -298.574261) (xy 385.711738 -298.594548)
			(xy 385.654105 -298.604847) (xy 385.624832 -298.605448) (xy 385.624324 -298.605448) (xy 385.595054 -298.604816)
			(xy 385.537429 -298.594509) (xy 385.482514 -298.57423) (xy 385.456938 -298.559982) (xy 385.45135 -298.55668)
			(xy 385.431538 -298.551092) (xy 385.417568 -298.54906) (xy 384.80873 -298.54906) (xy 384.798824 -298.553378)
			(xy 384.779228 -298.561697) (xy 384.73831 -298.573441) (xy 384.696157 -298.579389) (xy 384.674872 -298.579794)
			(xy 384.653586 -298.579408) (xy 384.611432 -298.573458) (xy 384.570514 -298.561704) (xy 384.55092 -298.553378)
			(xy 384.541014 -298.54906) (xy 380.163832 -298.54906) (xy 380.153843 -298.549593) (xy 380.135408 -298.557305)
			(xy 380.128018 -298.564046) (xy 380.093982 -298.597828) (xy 380.088045 -298.604322) (xy 380.080579 -298.620241)
			(xy 380.078912 -298.637745) (xy 380.080774 -298.646342) (xy 380.10592 -298.744132) (xy 380.124462 -298.763436)
			(xy 380.137416 -298.767246) (xy 380.163509 -298.775316) (xy 380.213246 -298.797882) (xy 380.259258 -298.827307)
			(xy 380.300605 -298.862992) (xy 380.336443 -298.904206) (xy 380.366039 -298.950109) (xy 380.388789 -298.999762)
			(xy 380.404228 -299.052151) (xy 380.412041 -299.106206) (xy 380.412498 -299.133514) (xy 380.412011 -299.160764)
			(xy 380.404253 -299.21471) (xy 380.401319 -299.2247) (xy 383.734069 -299.2247) (xy 383.73824 -299.174365)
			(xy 383.750638 -299.125402) (xy 383.770925 -299.079148) (xy 383.798549 -299.036864) (xy 383.832755 -298.999703)
			(xy 383.872611 -298.968678) (xy 383.91703 -298.944636) (xy 383.9648 -298.928233) (xy 384.014618 -298.919916)
			(xy 384.039872 -298.919392) (xy 384.065268 -298.919898) (xy 384.115358 -298.928313) (xy 384.163365 -298.944897)
			(xy 384.207968 -298.969196) (xy 384.247936 -299.000538) (xy 384.265424 -299.01896) (xy 384.273044 -299.027342)
			(xy 384.29311 -299.035724) (xy 384.392424 -299.033184) (xy 384.411728 -299.023786) (xy 384.419094 -299.014896)
			(xy 384.434899 -298.996367) (xy 384.47099 -298.963668) (xy 384.511482 -298.936611) (xy 384.555502 -298.915779)
			(xy 384.602099 -298.901621) (xy 384.650268 -298.894444) (xy 384.674618 -298.893992) (xy 385.624578 -298.893992)
			(xy 385.650585 -298.894566) (xy 385.701958 -298.902699) (xy 385.751427 -298.91877) (xy 385.797772 -298.942381)
			(xy 385.839853 -298.972952) (xy 385.876634 -299.00973) (xy 385.907207 -299.051809) (xy 385.930822 -299.098153)
			(xy 385.946896 -299.14762) (xy 385.955033 -299.198993) (xy 385.955033 -299.233291) (xy 386.269089 -299.233291)
			(xy 386.271775 -299.183725) (xy 386.282444 -299.135247) (xy 386.300815 -299.089133) (xy 386.326404 -299.046598)
			(xy 386.358537 -299.008764) (xy 386.396368 -298.976626) (xy 386.438899 -298.951032) (xy 386.485011 -298.932655)
			(xy 386.533488 -298.92198) (xy 386.583053 -298.919288) (xy 386.632401 -298.924651) (xy 386.680232 -298.937925)
			(xy 386.725285 -298.958763) (xy 386.766373 -298.986615) (xy 386.802415 -299.020747) (xy 386.83246 -299.06026)
			(xy 386.855717 -299.104113) (xy 386.871573 -299.151151) (xy 386.87961 -299.200135) (xy 386.8801 -299.224954)
			(xy 386.879917 -299.239137) (xy 386.877249 -299.267377) (xy 386.874766 -299.281342) (xy 386.872579 -299.295304)
			(xy 386.875168 -299.323435) (xy 386.885364 -299.349782) (xy 386.902388 -299.372327) (xy 386.924937 -299.389346)
			(xy 386.951285 -299.399537) (xy 386.979417 -299.40212) (xy 386.993384 -299.39996) (xy 387.007414 -299.39748)
			(xy 387.03578 -299.394805) (xy 387.050026 -299.394626) (xy 387.074844 -299.395106) (xy 387.123825 -299.40314)
			(xy 387.170861 -299.418992) (xy 387.214713 -299.442244) (xy 387.254225 -299.472285) (xy 387.288358 -299.508322)
			(xy 387.316211 -299.549405) (xy 387.33705 -299.594454) (xy 387.350328 -299.642281) (xy 387.355693 -299.691625)
			(xy 387.355242 -299.699934) (xy 387.694182 -299.699934) (xy 387.698142 -299.65088) (xy 387.709919 -299.603096)
			(xy 387.72921 -299.55782) (xy 387.755513 -299.516224) (xy 387.788148 -299.479387) (xy 387.826269 -299.448262)
			(xy 387.86889 -299.423655) (xy 387.914906 -299.406203) (xy 387.963125 -299.396359) (xy 388.0123 -299.394378)
			(xy 388.061155 -299.40031) (xy 388.108426 -299.414002) (xy 388.152888 -299.4351) (xy 388.193391 -299.463056)
			(xy 388.228884 -299.497148) (xy 388.258449 -299.536492) (xy 388.28132 -299.580069) (xy 388.296904 -299.62675)
			(xy 388.304799 -299.675327) (xy 388.305294 -299.699934) (xy 388.304799 -299.724541) (xy 388.296904 -299.773118)
			(xy 388.28132 -299.819799) (xy 388.258449 -299.863376) (xy 388.228884 -299.90272) (xy 388.193391 -299.936812)
			(xy 388.152888 -299.964768) (xy 388.108426 -299.985866) (xy 388.061155 -299.999558) (xy 388.0123 -300.00549)
			(xy 387.963125 -300.003509) (xy 387.914906 -299.993665) (xy 387.86889 -299.976213) (xy 387.826269 -299.951606)
			(xy 387.788148 -299.920481) (xy 387.755513 -299.883644) (xy 387.72921 -299.842048) (xy 387.709919 -299.796772)
			(xy 387.698142 -299.748988) (xy 387.694182 -299.699934) (xy 387.355242 -299.699934) (xy 387.353005 -299.741188)
			(xy 387.342334 -299.789663) (xy 387.323962 -299.835773) (xy 387.298373 -299.878303) (xy 387.26624 -299.916134)
			(xy 387.22841 -299.948268) (xy 387.18588 -299.973859) (xy 387.13977 -299.992232) (xy 387.091296 -300.002904)
			(xy 387.041733 -300.005593) (xy 386.992389 -300.000229) (xy 386.944562 -299.986953) (xy 386.899512 -299.966115)
			(xy 386.858428 -299.938263) (xy 386.82239 -299.904131) (xy 386.792349 -299.864619) (xy 386.769095 -299.820768)
			(xy 386.753242 -299.773732) (xy 386.745206 -299.724752) (xy 386.744718 -299.699934) (xy 386.744899 -299.685751)
			(xy 386.747568 -299.657511) (xy 386.750052 -299.643546) (xy 386.75223 -299.629584) (xy 386.749639 -299.601455)
			(xy 386.739442 -299.575112) (xy 386.72242 -299.552569) (xy 386.699874 -299.53555) (xy 386.673529 -299.525358)
			(xy 386.6454 -299.522771) (xy 386.631434 -299.524928) (xy 386.617406 -299.527419) (xy 386.589038 -299.530087)
			(xy 386.574792 -299.530262) (xy 386.549973 -299.529814) (xy 386.500988 -299.521782) (xy 386.453948 -299.505932)
			(xy 386.410092 -299.48268) (xy 386.370575 -299.45264) (xy 386.336439 -299.416603) (xy 386.308582 -299.375518)
			(xy 386.287738 -299.330468) (xy 386.274458 -299.282639) (xy 386.269089 -299.233291) (xy 385.955033 -299.233291)
			(xy 385.955033 -299.251007) (xy 385.946896 -299.30238) (xy 385.930822 -299.351847) (xy 385.907207 -299.398191)
			(xy 385.876634 -299.44027) (xy 385.839853 -299.477048) (xy 385.797772 -299.507619) (xy 385.751427 -299.53123)
			(xy 385.701958 -299.547301) (xy 385.650585 -299.555434) (xy 385.624578 -299.555916) (xy 384.674618 -299.555916)
			(xy 384.650234 -299.555483) (xy 384.601997 -299.54831) (xy 384.555336 -299.53413) (xy 384.511263 -299.513252)
			(xy 384.470734 -299.486128) (xy 384.434627 -299.453346) (xy 384.41884 -299.434758) (xy 384.411728 -299.426122)
			(xy 384.39217 -299.41647) (xy 384.292856 -299.41393) (xy 384.27279 -299.422312) (xy 384.26517 -299.430694)
			(xy 384.247686 -299.449071) (xy 384.207755 -299.480345) (xy 384.163203 -299.504586) (xy 384.115255 -299.521125)
			(xy 384.065232 -299.529508) (xy 384.039872 -299.530008) (xy 384.014618 -299.529484) (xy 383.9648 -299.521167)
			(xy 383.91703 -299.504764) (xy 383.872611 -299.480722) (xy 383.832755 -299.449697) (xy 383.798549 -299.412536)
			(xy 383.770925 -299.370252) (xy 383.750638 -299.323998) (xy 383.73824 -299.275035) (xy 383.734069 -299.2247)
			(xy 380.401319 -299.2247) (xy 380.388896 -299.267002) (xy 380.366254 -299.316577) (xy 380.336787 -299.362425)
			(xy 380.301096 -299.403613) (xy 380.259906 -299.439302) (xy 380.214056 -299.468766) (xy 380.16448 -299.491405)
			(xy 380.112186 -299.506758) (xy 380.05824 -299.514512) (xy 380.03099 -299.515022) (xy 380.006522 -299.514629)
			(xy 379.957986 -299.508388) (xy 379.934216 -299.502576) (xy 379.931168 -299.501814) (xy 379.924818 -299.500798)
			(xy 379.914808 -299.499911) (xy 379.895422 -299.505144) (xy 379.887226 -299.510958) (xy 379.823472 -299.559726)
			(xy 379.814595 -299.567304) (xy 379.804256 -299.588203) (xy 379.80366 -299.599858) (xy 379.80366 -299.895514)
			(xy 381.921002 -299.895514) (xy 381.925073 -299.839892) (xy 381.937199 -299.785455) (xy 381.957122 -299.733364)
			(xy 381.984418 -299.684729) (xy 382.018504 -299.640586) (xy 382.058653 -299.601877) (xy 382.104011 -299.569426)
			(xy 382.153611 -299.543925) (xy 382.206395 -299.525918) (xy 382.261238 -299.515788) (xy 382.316972 -299.513751)
			(xy 382.372409 -299.519851) (xy 382.426366 -299.533957) (xy 382.477695 -299.555769) (xy 382.525301 -299.584823)
			(xy 382.568169 -299.620498) (xy 382.605386 -299.662035) (xy 382.636159 -299.708548) (xy 382.659831 -299.759045)
			(xy 382.675899 -299.812452) (xy 382.684019 -299.867628) (xy 382.684528 -299.895514) (xy 382.684019 -299.9234)
			(xy 382.675899 -299.978576) (xy 382.659831 -300.031983) (xy 382.636159 -300.08248) (xy 382.605386 -300.128993)
			(xy 382.568169 -300.17053) (xy 382.525301 -300.206205) (xy 382.477695 -300.235259) (xy 382.426366 -300.257071)
			(xy 382.372409 -300.271177) (xy 382.316972 -300.277277) (xy 382.261238 -300.27524) (xy 382.206395 -300.26511)
			(xy 382.153611 -300.247103) (xy 382.104011 -300.221602) (xy 382.058653 -300.189151) (xy 382.018504 -300.150442)
			(xy 381.984418 -300.106299) (xy 381.957122 -300.057664) (xy 381.937199 -300.005573) (xy 381.925073 -299.951136)
			(xy 381.921002 -299.895514) (xy 379.80366 -299.895514) (xy 379.80366 -300.60519) (xy 379.804197 -300.615177)
			(xy 379.811915 -300.633606) (xy 379.818646 -300.641004) (xy 380.043436 -300.865794) (xy 380.050783 -300.8726)
			(xy 380.069245 -300.88032) (xy 380.07925 -300.88078)
		)
		(stroke
			(width 0)
			(type solid)
		)
		(fill yes)
		(layer "In5.Cu")
		(net "PCEPLL1_VDDA18_PEX3")
	)
	(gr_poly
		(pts
			(xy 342.064848 -92.401644) (xy 342.074724 -92.40118) (xy 342.093018 -92.393734) (xy 342.100408 -92.387166)
			(xy 342.100662 -92.386912) (xy 343.86901 -90.618564) (xy 343.869518 -90.618056) (xy 343.876106 -90.610677)
			(xy 343.883565 -90.592378) (xy 343.883996 -90.582496) (xy 343.883996 -81.20761) (xy 343.883574 -81.197539)
			(xy 343.875862 -81.178932) (xy 343.86901 -81.171542) (xy 342.649556 -79.952088) (xy 342.642444 -79.944722)
			(xy 342.623648 -79.937102) (xy 329.216004 -79.937102) (xy 329.205934 -79.937525) (xy 329.187328 -79.945238)
			(xy 329.179936 -79.952088) (xy 329.027028 -80.104996) (xy 329.019662 -80.112108) (xy 329.012042 -80.130904)
			(xy 329.012042 -80.862753) (xy 331.324655 -80.862753) (xy 331.324655 -80.808247) (xy 331.332413 -80.754295)
			(xy 331.347769 -80.701996) (xy 331.370413 -80.652415) (xy 331.399882 -80.606561) (xy 331.435577 -80.565368)
			(xy 331.476771 -80.529675) (xy 331.522625 -80.500207) (xy 331.572207 -80.477565) (xy 331.624506 -80.46221)
			(xy 331.678459 -80.454455) (xy 331.705712 -80.453992) (xy 331.733082 -80.454453) (xy 331.787262 -80.462272)
			(xy 331.839765 -80.477763) (xy 331.889511 -80.500605) (xy 331.935478 -80.530331) (xy 331.95641 -80.547972)
			(xy 331.963522 -80.554068) (xy 331.98054 -80.560418) (xy 332.065884 -80.560418) (xy 332.082902 -80.554068)
			(xy 332.090014 -80.547972) (xy 332.110964 -80.530355) (xy 332.156932 -80.500641) (xy 332.206675 -80.477801)
			(xy 332.259172 -80.462305) (xy 332.313344 -80.45447) (xy 332.340712 -80.453992) (xy 332.367963 -80.454479)
			(xy 332.421909 -80.462237) (xy 332.474202 -80.477593) (xy 332.523778 -80.500235) (xy 332.569627 -80.529701)
			(xy 332.610816 -80.565393) (xy 332.646506 -80.606583) (xy 332.675971 -80.652432) (xy 332.698612 -80.702009)
			(xy 332.713966 -80.754303) (xy 332.720903 -80.802554) (xy 332.884457 -80.802554) (xy 332.884457 -80.748046)
			(xy 332.892215 -80.694093) (xy 332.907572 -80.641794) (xy 332.930217 -80.592212) (xy 332.959687 -80.546358)
			(xy 332.995383 -80.505165) (xy 333.036579 -80.469471) (xy 333.082435 -80.440004) (xy 333.132018 -80.417363)
			(xy 333.184319 -80.402009) (xy 333.238272 -80.394256) (xy 333.265526 -80.393794) (xy 333.292897 -80.394246)
			(xy 333.347076 -80.402068) (xy 333.39958 -80.41756) (xy 333.449326 -80.440405) (xy 333.495293 -80.470132)
			(xy 333.516224 -80.487774) (xy 333.523336 -80.49387) (xy 333.540354 -80.50022) (xy 333.625698 -80.50022)
			(xy 333.642716 -80.49387) (xy 333.649828 -80.487774) (xy 333.670773 -80.470151) (xy 333.716743 -80.440438)
			(xy 333.766487 -80.417599) (xy 333.818985 -80.402104) (xy 333.873158 -80.394271) (xy 333.900526 -80.393794)
			(xy 333.927776 -80.394278) (xy 333.981721 -80.402037) (xy 334.034013 -80.417395) (xy 334.083587 -80.440037)
			(xy 334.129435 -80.469504) (xy 334.170622 -80.505196) (xy 334.206311 -80.546386) (xy 334.235775 -80.592235)
			(xy 334.258415 -80.641811) (xy 334.273768 -80.694104) (xy 334.281524 -80.74805) (xy 334.281524 -80.80255)
			(xy 334.273768 -80.856496) (xy 334.258415 -80.908789) (xy 334.235775 -80.958365) (xy 334.206311 -81.004214)
			(xy 334.170622 -81.045404) (xy 334.129435 -81.081096) (xy 334.083587 -81.110563) (xy 334.034013 -81.133205)
			(xy 333.981721 -81.148563) (xy 333.927776 -81.156322) (xy 333.900526 -81.15681) (xy 333.873156 -81.156326)
			(xy 333.818978 -81.148512) (xy 333.766475 -81.133027) (xy 333.716728 -81.11019) (xy 333.67076 -81.080469)
			(xy 333.649828 -81.06283) (xy 333.642716 -81.056734) (xy 333.625698 -81.050384) (xy 333.540354 -81.050384)
			(xy 333.523336 -81.056734) (xy 333.516224 -81.06283) (xy 333.495298 -81.080476) (xy 333.449323 -81.110186)
			(xy 333.399574 -81.13302) (xy 333.347072 -81.148509) (xy 333.292895 -81.156336) (xy 333.265526 -81.15681)
			(xy 333.238272 -81.156344) (xy 333.184319 -81.148591) (xy 333.132018 -81.133237) (xy 333.082435 -81.110596)
			(xy 333.036579 -81.081129) (xy 332.995383 -81.045435) (xy 332.959687 -81.004242) (xy 332.930217 -80.958388)
			(xy 332.907572 -80.908806) (xy 332.892215 -80.856507) (xy 332.884457 -80.802554) (xy 332.720903 -80.802554)
			(xy 332.721722 -80.808249) (xy 332.721722 -80.862751) (xy 332.713966 -80.916697) (xy 332.698612 -80.968991)
			(xy 332.675971 -81.018568) (xy 332.646506 -81.064417) (xy 332.610816 -81.105607) (xy 332.569627 -81.141299)
			(xy 332.523778 -81.170765) (xy 332.474202 -81.193407) (xy 332.421909 -81.208763) (xy 332.367963 -81.216521)
			(xy 332.340712 -81.217008) (xy 332.313342 -81.216533) (xy 332.259164 -81.208717) (xy 332.206661 -81.19323)
			(xy 332.156914 -81.17039) (xy 332.110946 -81.140668) (xy 332.090014 -81.123028) (xy 332.082902 -81.116932)
			(xy 332.065884 -81.110582) (xy 331.98054 -81.110582) (xy 331.963522 -81.116932) (xy 331.95641 -81.123028)
			(xy 331.935489 -81.14068) (xy 331.889512 -81.170389) (xy 331.839762 -81.193222) (xy 331.787259 -81.20871)
			(xy 331.733082 -81.216535) (xy 331.705712 -81.217008) (xy 331.678459 -81.216545) (xy 331.624506 -81.20879)
			(xy 331.572207 -81.193435) (xy 331.522625 -81.170793) (xy 331.476771 -81.141325) (xy 331.435577 -81.105632)
			(xy 331.399882 -81.064439) (xy 331.370413 -81.018585) (xy 331.347769 -80.969004) (xy 331.332413 -80.916705)
			(xy 331.324655 -80.862753) (xy 329.012042 -80.862753) (xy 329.012042 -81.31175) (xy 329.012638 -81.322796)
			(xy 329.021978 -81.342823) (xy 329.030076 -81.350358) (xy 329.050887 -81.368589) (xy 329.087545 -81.410025)
			(xy 329.117838 -81.45632) (xy 329.141129 -81.506504) (xy 329.156932 -81.559524) (xy 329.164914 -81.61427)
			(xy 329.16491 -81.669595) (xy 329.156918 -81.724339) (xy 329.141106 -81.777357) (xy 329.117806 -81.827536)
			(xy 329.087506 -81.873826) (xy 329.050841 -81.915256) (xy 329.030076 -81.933542) (xy 329.021978 -81.94108)
			(xy 329.012625 -81.961102) (xy 329.012578 -81.96199) (xy 338.037168 -81.96199) (xy 338.041239 -81.906368)
			(xy 338.053365 -81.851931) (xy 338.073288 -81.79984) (xy 338.100584 -81.751205) (xy 338.13467 -81.707062)
			(xy 338.174819 -81.668353) (xy 338.220177 -81.635902) (xy 338.269777 -81.610401) (xy 338.322561 -81.592394)
			(xy 338.377404 -81.582264) (xy 338.433138 -81.580227) (xy 338.488575 -81.586327) (xy 338.542532 -81.600433)
			(xy 338.593861 -81.622245) (xy 338.641467 -81.651299) (xy 338.684335 -81.686974) (xy 338.721552 -81.728511)
			(xy 338.752325 -81.775024) (xy 338.775997 -81.825521) (xy 338.792065 -81.878928) (xy 338.798831 -81.924906)
			(xy 342.007442 -81.924906) (xy 342.011513 -81.869284) (xy 342.023639 -81.814847) (xy 342.043562 -81.762756)
			(xy 342.070858 -81.714121) (xy 342.104944 -81.669978) (xy 342.145093 -81.631269) (xy 342.190451 -81.598818)
			(xy 342.240051 -81.573317) (xy 342.292835 -81.55531) (xy 342.347678 -81.54518) (xy 342.403412 -81.543143)
			(xy 342.458849 -81.549243) (xy 342.512806 -81.563349) (xy 342.564135 -81.585161) (xy 342.611741 -81.614215)
			(xy 342.654609 -81.64989) (xy 342.691826 -81.691427) (xy 342.722599 -81.73794) (xy 342.746271 -81.788437)
			(xy 342.762339 -81.841844) (xy 342.770459 -81.89702) (xy 342.770968 -81.924906) (xy 342.770459 -81.952792)
			(xy 342.762339 -82.007968) (xy 342.746271 -82.061375) (xy 342.722599 -82.111872) (xy 342.691826 -82.158385)
			(xy 342.654609 -82.199922) (xy 342.611741 -82.235597) (xy 342.564135 -82.264651) (xy 342.512806 -82.286463)
			(xy 342.458849 -82.300569) (xy 342.403412 -82.306669) (xy 342.347678 -82.304632) (xy 342.292835 -82.294502)
			(xy 342.240051 -82.276495) (xy 342.190451 -82.250994) (xy 342.145093 -82.218543) (xy 342.104944 -82.179834)
			(xy 342.070858 -82.135691) (xy 342.043562 -82.087056) (xy 342.023639 -82.034965) (xy 342.011513 -81.980528)
			(xy 342.007442 -81.924906) (xy 338.798831 -81.924906) (xy 338.800185 -81.934104) (xy 338.800694 -81.96199)
			(xy 338.800185 -81.989876) (xy 338.792065 -82.045052) (xy 338.775997 -82.098459) (xy 338.752325 -82.148956)
			(xy 338.721552 -82.195469) (xy 338.684335 -82.237006) (xy 338.641467 -82.272681) (xy 338.593861 -82.301735)
			(xy 338.542532 -82.323547) (xy 338.488575 -82.337653) (xy 338.433138 -82.343753) (xy 338.377404 -82.341716)
			(xy 338.322561 -82.331586) (xy 338.269777 -82.313579) (xy 338.220177 -82.288078) (xy 338.174819 -82.255627)
			(xy 338.13467 -82.216918) (xy 338.100584 -82.172775) (xy 338.073288 -82.12414) (xy 338.053365 -82.072049)
			(xy 338.041239 -82.017612) (xy 338.037168 -81.96199) (xy 329.012578 -81.96199) (xy 329.012042 -81.97215)
			(xy 329.012042 -82.109056) (xy 329.014582 -82.120232) (xy 329.017376 -82.125566) (xy 329.030052 -82.152168)
			(xy 329.047953 -82.208308) (xy 329.056989 -82.266537) (xy 329.057508 -82.296) (xy 329.056957 -82.32546)
			(xy 329.047904 -82.383681) (xy 329.030028 -82.439824) (xy 329.017376 -82.466434) (xy 329.014582 -82.471768)
			(xy 329.012042 -82.482944) (xy 329.012042 -83.566) (xy 330.199492 -83.566) (xy 330.199991 -83.539569)
			(xy 330.207301 -83.487215) (xy 330.221769 -83.436371) (xy 330.243117 -83.388012) (xy 330.270935 -83.343062)
			(xy 330.304693 -83.302382) (xy 330.343742 -83.266752) (xy 330.387336 -83.236853) (xy 330.43464 -83.213258)
			(xy 330.484749 -83.196418) (xy 330.510642 -83.191096) (xy 330.521056 -83.189064) (xy 330.538074 -83.177634)
			(xy 330.589636 -83.098386) (xy 330.593192 -83.078066) (xy 330.590652 -83.067652) (xy 330.585857 -83.046)
			(xy 330.580768 -83.001943) (xy 330.580492 -82.979768) (xy 330.580978 -82.952517) (xy 330.588734 -82.898569)
			(xy 330.604089 -82.846274) (xy 330.626731 -82.796697) (xy 330.656197 -82.750847) (xy 330.691888 -82.709656)
			(xy 330.733079 -82.673965) (xy 330.778929 -82.644499) (xy 330.828506 -82.621857) (xy 330.880801 -82.606502)
			(xy 330.934749 -82.598746) (xy 330.989251 -82.598746) (xy 331.043199 -82.606502) (xy 331.095494 -82.621857)
			(xy 331.145071 -82.644499) (xy 331.190921 -82.673965) (xy 331.232112 -82.709656) (xy 331.267803 -82.750847)
			(xy 331.289883 -82.785204) (xy 340.274908 -82.785204) (xy 340.278979 -82.729582) (xy 340.291105 -82.675145)
			(xy 340.311028 -82.623054) (xy 340.338324 -82.574419) (xy 340.37241 -82.530276) (xy 340.412559 -82.491567)
			(xy 340.457917 -82.459116) (xy 340.507517 -82.433615) (xy 340.560301 -82.415608) (xy 340.615144 -82.405478)
			(xy 340.670878 -82.403441) (xy 340.726315 -82.409541) (xy 340.780272 -82.423647) (xy 340.831601 -82.445459)
			(xy 340.879207 -82.474513) (xy 340.922075 -82.510188) (xy 340.959292 -82.551725) (xy 340.990065 -82.598238)
			(xy 341.013737 -82.648735) (xy 341.029805 -82.702142) (xy 341.037925 -82.757318) (xy 341.038434 -82.785204)
			(xy 341.037925 -82.81309) (xy 341.029805 -82.868266) (xy 341.013737 -82.921673) (xy 340.990065 -82.97217)
			(xy 340.959292 -83.018683) (xy 340.922075 -83.06022) (xy 340.879207 -83.095895) (xy 340.831601 -83.124949)
			(xy 340.780272 -83.146761) (xy 340.726315 -83.160867) (xy 340.670878 -83.166967) (xy 340.615144 -83.16493)
			(xy 340.560301 -83.1548) (xy 340.507517 -83.136793) (xy 340.457917 -83.111292) (xy 340.412559 -83.078841)
			(xy 340.37241 -83.040132) (xy 340.338324 -82.995989) (xy 340.311028 -82.947354) (xy 340.291105 -82.895263)
			(xy 340.278979 -82.840826) (xy 340.274908 -82.785204) (xy 331.289883 -82.785204) (xy 331.297269 -82.796697)
			(xy 331.319911 -82.846274) (xy 331.335266 -82.898569) (xy 331.343022 -82.952517) (xy 331.343508 -82.979768)
			(xy 331.343071 -83.006201) (xy 331.335752 -83.058557) (xy 331.321275 -83.109402) (xy 331.29992 -83.157763)
			(xy 331.272094 -83.202712) (xy 331.23833 -83.243391) (xy 331.199274 -83.279021) (xy 331.155675 -83.308918)
			(xy 331.108366 -83.332512) (xy 331.058253 -83.34935) (xy 331.032358 -83.354672) (xy 331.021944 -83.356704)
			(xy 331.004926 -83.368134) (xy 330.953364 -83.447382) (xy 330.949808 -83.467702) (xy 330.952348 -83.478116)
			(xy 330.957138 -83.499769) (xy 330.962231 -83.543825) (xy 330.962508 -83.566) (xy 330.961492 -83.59394)
			(xy 330.96073 -83.603338) (xy 330.96581 -83.620864) (xy 331.017118 -83.68919) (xy 331.032358 -83.698842)
			(xy 331.041502 -83.700874) (xy 331.069618 -83.7074) (xy 331.123611 -83.727794) (xy 331.173917 -83.756088)
			(xy 331.219387 -83.791636) (xy 331.258983 -83.833629) (xy 331.291802 -83.881107) (xy 331.317095 -83.932986)
			(xy 331.334284 -83.988084) (xy 331.342978 -84.045142) (xy 331.343508 -84.074) (xy 331.343022 -84.101251)
			(xy 331.335266 -84.155199) (xy 331.319911 -84.207494) (xy 331.297269 -84.257071) (xy 331.267803 -84.302921)
			(xy 331.232112 -84.344112) (xy 331.190921 -84.379803) (xy 331.145071 -84.409269) (xy 331.095494 -84.431911)
			(xy 331.043199 -84.447266) (xy 330.989251 -84.455022) (xy 330.934749 -84.455022) (xy 330.880801 -84.447266)
			(xy 330.828506 -84.431911) (xy 330.778929 -84.409269) (xy 330.733079 -84.379803) (xy 330.691888 -84.344112)
			(xy 330.656197 -84.302921) (xy 330.626731 -84.257071) (xy 330.604089 -84.207494) (xy 330.588734 -84.155199)
			(xy 330.580978 -84.101251) (xy 330.580492 -84.074) (xy 330.581508 -84.04606) (xy 330.58227 -84.036662)
			(xy 330.57719 -84.019136) (xy 330.525882 -83.95081) (xy 330.510642 -83.941158) (xy 330.501498 -83.939126)
			(xy 330.473382 -83.9326) (xy 330.419389 -83.912206) (xy 330.369083 -83.883912) (xy 330.323613 -83.848364)
			(xy 330.284017 -83.806371) (xy 330.251198 -83.758893) (xy 330.225905 -83.707014) (xy 330.208716 -83.651916)
			(xy 330.200022 -83.594858) (xy 330.199492 -83.566) (xy 329.012042 -83.566) (xy 329.012042 -85.036251)
			(xy 332.927952 -85.036251) (xy 332.927952 -84.981749) (xy 332.935708 -84.927801) (xy 332.951062 -84.875506)
			(xy 332.973702 -84.825928) (xy 333.003166 -84.780076) (xy 333.038856 -84.738884) (xy 333.080044 -84.70319)
			(xy 333.125893 -84.673721) (xy 333.175468 -84.651076) (xy 333.227762 -84.635716) (xy 333.281709 -84.627955)
			(xy 333.30896 -84.627466) (xy 333.3377 -84.627962) (xy 333.394528 -84.636593) (xy 333.449419 -84.65365)
			(xy 333.50113 -84.678747) (xy 333.548492 -84.711317) (xy 333.569818 -84.73059) (xy 333.581319 -84.740714)
			(xy 333.608837 -84.754156) (xy 333.639104 -84.758835) (xy 333.669397 -84.754331) (xy 333.696993 -84.741049)
			(xy 333.719411 -84.720182) (xy 333.734634 -84.693607) (xy 333.738474 -84.678774) (xy 333.745269 -84.650944)
			(xy 333.766005 -84.597544) (xy 333.79449 -84.547843) (xy 333.830084 -84.502958) (xy 333.871987 -84.463897)
			(xy 333.919257 -84.431538) (xy 333.970833 -84.406608) (xy 334.025555 -84.389667) (xy 334.082196 -84.381096)
			(xy 334.110838 -84.380578) (xy 334.138086 -84.381095) (xy 334.192028 -84.388855) (xy 334.244316 -84.404213)
			(xy 334.293887 -84.426856) (xy 334.339731 -84.456322) (xy 334.380915 -84.492012) (xy 334.416601 -84.5332)
			(xy 334.446063 -84.579047) (xy 334.4687 -84.628619) (xy 334.484053 -84.680909) (xy 334.491808 -84.734852)
			(xy 334.491808 -84.789348) (xy 334.484053 -84.843291) (xy 334.4687 -84.895581) (xy 334.455659 -84.924138)
			(xy 335.867246 -84.924138) (xy 335.871317 -84.868516) (xy 335.883443 -84.814079) (xy 335.903366 -84.761988)
			(xy 335.930662 -84.713353) (xy 335.964748 -84.66921) (xy 336.004897 -84.630501) (xy 336.050255 -84.59805)
			(xy 336.099855 -84.572549) (xy 336.152639 -84.554542) (xy 336.207482 -84.544412) (xy 336.263216 -84.542375)
			(xy 336.318653 -84.548475) (xy 336.37261 -84.562581) (xy 336.423939 -84.584393) (xy 336.471545 -84.613447)
			(xy 336.514413 -84.649122) (xy 336.55163 -84.690659) (xy 336.582403 -84.737172) (xy 336.606075 -84.787669)
			(xy 336.622143 -84.841076) (xy 336.630263 -84.896252) (xy 336.630772 -84.924138) (xy 337.713572 -84.924138)
			(xy 337.717643 -84.868516) (xy 337.729769 -84.814079) (xy 337.749692 -84.761988) (xy 337.776988 -84.713353)
			(xy 337.811074 -84.66921) (xy 337.851223 -84.630501) (xy 337.896581 -84.59805) (xy 337.946181 -84.572549)
			(xy 337.998965 -84.554542) (xy 338.053808 -84.544412) (xy 338.109542 -84.542375) (xy 338.164979 -84.548475)
			(xy 338.218936 -84.562581) (xy 338.270265 -84.584393) (xy 338.317871 -84.613447) (xy 338.360739 -84.649122)
			(xy 338.397956 -84.690659) (xy 338.428729 -84.737172) (xy 338.452401 -84.787669) (xy 338.468469 -84.841076)
			(xy 338.476589 -84.896252) (xy 338.477098 -84.924138) (xy 339.565994 -84.924138) (xy 339.570065 -84.868516)
			(xy 339.582191 -84.814079) (xy 339.602114 -84.761988) (xy 339.62941 -84.713353) (xy 339.663496 -84.66921)
			(xy 339.703645 -84.630501) (xy 339.749003 -84.59805) (xy 339.798603 -84.572549) (xy 339.851387 -84.554542)
			(xy 339.90623 -84.544412) (xy 339.961964 -84.542375) (xy 340.017401 -84.548475) (xy 340.071358 -84.562581)
			(xy 340.122687 -84.584393) (xy 340.170293 -84.613447) (xy 340.213161 -84.649122) (xy 340.250378 -84.690659)
			(xy 340.281151 -84.737172) (xy 340.304823 -84.787669) (xy 340.320891 -84.841076) (xy 340.329011 -84.896252)
			(xy 340.32952 -84.924138) (xy 340.329011 -84.952024) (xy 340.320891 -85.0072) (xy 340.304823 -85.060607)
			(xy 340.281151 -85.111104) (xy 340.250378 -85.157617) (xy 340.213161 -85.199154) (xy 340.170293 -85.234829)
			(xy 340.122687 -85.263883) (xy 340.071358 -85.285695) (xy 340.017401 -85.299801) (xy 339.961964 -85.305901)
			(xy 339.90623 -85.303864) (xy 339.851387 -85.293734) (xy 339.798603 -85.275727) (xy 339.749003 -85.250226)
			(xy 339.703645 -85.217775) (xy 339.663496 -85.179066) (xy 339.62941 -85.134923) (xy 339.602114 -85.086288)
			(xy 339.582191 -85.034197) (xy 339.570065 -84.97976) (xy 339.565994 -84.924138) (xy 338.477098 -84.924138)
			(xy 338.476589 -84.952024) (xy 338.468469 -85.0072) (xy 338.452401 -85.060607) (xy 338.428729 -85.111104)
			(xy 338.397956 -85.157617) (xy 338.360739 -85.199154) (xy 338.317871 -85.234829) (xy 338.270265 -85.263883)
			(xy 338.218936 -85.285695) (xy 338.164979 -85.299801) (xy 338.109542 -85.305901) (xy 338.053808 -85.303864)
			(xy 337.998965 -85.293734) (xy 337.946181 -85.275727) (xy 337.896581 -85.250226) (xy 337.851223 -85.217775)
			(xy 337.811074 -85.179066) (xy 337.776988 -85.134923) (xy 337.749692 -85.086288) (xy 337.729769 -85.034197)
			(xy 337.717643 -84.97976) (xy 337.713572 -84.924138) (xy 336.630772 -84.924138) (xy 336.630263 -84.952024)
			(xy 336.622143 -85.0072) (xy 336.606075 -85.060607) (xy 336.582403 -85.111104) (xy 336.55163 -85.157617)
			(xy 336.514413 -85.199154) (xy 336.471545 -85.234829) (xy 336.423939 -85.263883) (xy 336.37261 -85.285695)
			(xy 336.318653 -85.299801) (xy 336.263216 -85.305901) (xy 336.207482 -85.303864) (xy 336.152639 -85.293734)
			(xy 336.099855 -85.275727) (xy 336.050255 -85.250226) (xy 336.004897 -85.217775) (xy 335.964748 -85.179066)
			(xy 335.930662 -85.134923) (xy 335.903366 -85.086288) (xy 335.883443 -85.034197) (xy 335.871317 -84.97976)
			(xy 335.867246 -84.924138) (xy 334.455659 -84.924138) (xy 334.446063 -84.945153) (xy 334.416601 -84.991)
			(xy 334.380915 -85.032188) (xy 334.339731 -85.067878) (xy 334.293887 -85.097344) (xy 334.244316 -85.119987)
			(xy 334.192028 -85.135345) (xy 334.138086 -85.143105) (xy 334.110838 -85.143594) (xy 334.082098 -85.14311)
			(xy 334.025268 -85.134478) (xy 333.970377 -85.117418) (xy 333.918666 -85.092318) (xy 333.871305 -85.059745)
			(xy 333.84998 -85.04047) (xy 333.838467 -85.030364) (xy 333.810952 -85.01693) (xy 333.780691 -85.012254)
			(xy 333.750404 -85.016757) (xy 333.722813 -85.030034) (xy 333.700396 -85.050892) (xy 333.685168 -85.077457)
			(xy 333.681324 -85.092286) (xy 333.674572 -85.120127) (xy 333.653828 -85.173527) (xy 333.625335 -85.223227)
			(xy 333.589735 -85.26811) (xy 333.547827 -85.307169) (xy 333.500552 -85.339526) (xy 333.448973 -85.364454)
			(xy 333.394247 -85.381394) (xy 333.337604 -85.389964) (xy 333.30896 -85.390482) (xy 333.281709 -85.390045)
			(xy 333.227762 -85.382284) (xy 333.175468 -85.366924) (xy 333.125893 -85.344279) (xy 333.080044 -85.31481)
			(xy 333.038856 -85.279116) (xy 333.003166 -85.237924) (xy 332.973702 -85.192072) (xy 332.951062 -85.142494)
			(xy 332.935708 -85.090199) (xy 332.927952 -85.036251) (xy 329.012042 -85.036251) (xy 329.012042 -86.290449)
			(xy 329.920604 -86.290449) (xy 329.920604 -86.235951) (xy 329.92836 -86.182007) (xy 329.943714 -86.129716)
			(xy 329.966354 -86.080142) (xy 329.995818 -86.034295) (xy 330.031507 -85.993107) (xy 330.072695 -85.957418)
			(xy 330.118542 -85.927954) (xy 330.168116 -85.905314) (xy 330.220407 -85.88996) (xy 330.274351 -85.882204)
			(xy 330.3016 -85.881718) (xy 330.327509 -85.882125) (xy 330.378849 -85.889162) (xy 330.428764 -85.90308)
			(xy 330.476338 -85.923622) (xy 330.520695 -85.950411) (xy 330.56102 -85.982955) (xy 330.596573 -86.020655)
			(xy 330.611988 -86.041484) (xy 330.617723 -86.048819) (xy 330.63323 -86.059102) (xy 330.642214 -86.06155)
			(xy 330.672694 -86.068154) (xy 330.681908 -86.069801) (xy 330.700409 -86.067048) (xy 330.708762 -86.06282)
			(xy 330.734776 -86.048549) (xy 330.789708 -86.026119) (xy 330.847074 -86.010962) (xy 330.905916 -86.003332)
			(xy 330.935584 -86.002876) (xy 330.965551 -86.003397) (xy 331.024971 -86.011218) (xy 331.082863 -86.026728)
			(xy 331.138235 -86.049661) (xy 331.19014 -86.079626) (xy 331.237689 -86.116109) (xy 331.28007 -86.158487)
			(xy 331.316556 -86.206034) (xy 331.346525 -86.257936) (xy 331.347349 -86.259924) (xy 333.146144 -86.259924)
			(xy 333.150215 -86.204302) (xy 333.162341 -86.149865) (xy 333.182264 -86.097774) (xy 333.20956 -86.049139)
			(xy 333.243646 -86.004996) (xy 333.283795 -85.966287) (xy 333.329153 -85.933836) (xy 333.378753 -85.908335)
			(xy 333.431537 -85.890328) (xy 333.48638 -85.880198) (xy 333.542114 -85.878161) (xy 333.597551 -85.884261)
			(xy 333.651508 -85.898367) (xy 333.702837 -85.920179) (xy 333.750443 -85.949233) (xy 333.793311 -85.984908)
			(xy 333.830528 -86.026445) (xy 333.861301 -86.072958) (xy 333.884973 -86.123455) (xy 333.901041 -86.176862)
			(xy 333.909161 -86.232038) (xy 333.90967 -86.259924) (xy 333.909161 -86.28781) (xy 333.901041 -86.342986)
			(xy 333.884973 -86.396393) (xy 333.861301 -86.44689) (xy 333.830528 -86.493403) (xy 333.793311 -86.53494)
			(xy 333.750443 -86.570615) (xy 333.702837 -86.599669) (xy 333.651508 -86.621481) (xy 333.597551 -86.635587)
			(xy 333.542114 -86.641687) (xy 333.48638 -86.63965) (xy 333.431537 -86.62952) (xy 333.378753 -86.611513)
			(xy 333.329153 -86.586012) (xy 333.283795 -86.553561) (xy 333.243646 -86.514852) (xy 333.20956 -86.470709)
			(xy 333.182264 -86.422074) (xy 333.162341 -86.369983) (xy 333.150215 -86.315546) (xy 333.146144 -86.259924)
			(xy 331.347349 -86.259924) (xy 331.369462 -86.313307) (xy 331.384976 -86.371197) (xy 331.392801 -86.430617)
			(xy 331.393292 -86.460584) (xy 331.393292 -86.77021) (xy 335.867246 -86.77021) (xy 335.871317 -86.714588)
			(xy 335.883443 -86.660151) (xy 335.903366 -86.60806) (xy 335.930662 -86.559425) (xy 335.964748 -86.515282)
			(xy 336.004897 -86.476573) (xy 336.050255 -86.444122) (xy 336.099855 -86.418621) (xy 336.152639 -86.400614)
			(xy 336.207482 -86.390484) (xy 336.263216 -86.388447) (xy 336.318653 -86.394547) (xy 336.37261 -86.408653)
			(xy 336.423939 -86.430465) (xy 336.471545 -86.459519) (xy 336.514413 -86.495194) (xy 336.55163 -86.536731)
			(xy 336.582403 -86.583244) (xy 336.606075 -86.633741) (xy 336.622143 -86.687148) (xy 336.630263 -86.742324)
			(xy 336.630716 -86.767162) (xy 339.539832 -86.767162) (xy 339.543903 -86.71154) (xy 339.556029 -86.657103)
			(xy 339.575952 -86.605012) (xy 339.603248 -86.556377) (xy 339.637334 -86.512234) (xy 339.677483 -86.473525)
			(xy 339.722841 -86.441074) (xy 339.772441 -86.415573) (xy 339.825225 -86.397566) (xy 339.880068 -86.387436)
			(xy 339.935802 -86.385399) (xy 339.991239 -86.391499) (xy 340.045196 -86.405605) (xy 340.096525 -86.427417)
			(xy 340.144131 -86.456471) (xy 340.186999 -86.492146) (xy 340.224216 -86.533683) (xy 340.244585 -86.56447)
			(xy 341.525604 -86.56447) (xy 341.529675 -86.508848) (xy 341.541801 -86.454411) (xy 341.561724 -86.40232)
			(xy 341.58902 -86.353685) (xy 341.623106 -86.309542) (xy 341.663255 -86.270833) (xy 341.708613 -86.238382)
			(xy 341.758213 -86.212881) (xy 341.810997 -86.194874) (xy 341.86584 -86.184744) (xy 341.921574 -86.182707)
			(xy 341.977011 -86.188807) (xy 342.030968 -86.202913) (xy 342.082297 -86.224725) (xy 342.129903 -86.253779)
			(xy 342.172771 -86.289454) (xy 342.209988 -86.330991) (xy 342.240761 -86.377504) (xy 342.264433 -86.428001)
			(xy 342.280501 -86.481408) (xy 342.288621 -86.536584) (xy 342.28913 -86.56447) (xy 342.288866 -86.578948)
			(xy 342.425526 -86.578948) (xy 342.429597 -86.523326) (xy 342.441723 -86.468889) (xy 342.461646 -86.416798)
			(xy 342.488942 -86.368163) (xy 342.523028 -86.32402) (xy 342.563177 -86.285311) (xy 342.608535 -86.25286)
			(xy 342.658135 -86.227359) (xy 342.710919 -86.209352) (xy 342.765762 -86.199222) (xy 342.821496 -86.197185)
			(xy 342.876933 -86.203285) (xy 342.93089 -86.217391) (xy 342.982219 -86.239203) (xy 343.029825 -86.268257)
			(xy 343.072693 -86.303932) (xy 343.10991 -86.345469) (xy 343.140683 -86.391982) (xy 343.164355 -86.442479)
			(xy 343.180423 -86.495886) (xy 343.188543 -86.551062) (xy 343.189052 -86.578948) (xy 343.188543 -86.606834)
			(xy 343.180423 -86.66201) (xy 343.164355 -86.715417) (xy 343.140683 -86.765914) (xy 343.10991 -86.812427)
			(xy 343.072693 -86.853964) (xy 343.029825 -86.889639) (xy 342.982219 -86.918693) (xy 342.93089 -86.940505)
			(xy 342.876933 -86.954611) (xy 342.821496 -86.960711) (xy 342.765762 -86.958674) (xy 342.710919 -86.948544)
			(xy 342.658135 -86.930537) (xy 342.608535 -86.905036) (xy 342.563177 -86.872585) (xy 342.523028 -86.833876)
			(xy 342.488942 -86.789733) (xy 342.461646 -86.741098) (xy 342.441723 -86.689007) (xy 342.429597 -86.63457)
			(xy 342.425526 -86.578948) (xy 342.288866 -86.578948) (xy 342.288621 -86.592356) (xy 342.280501 -86.647532)
			(xy 342.264433 -86.700939) (xy 342.240761 -86.751436) (xy 342.209988 -86.797949) (xy 342.172771 -86.839486)
			(xy 342.129903 -86.875161) (xy 342.082297 -86.904215) (xy 342.030968 -86.926027) (xy 341.977011 -86.940133)
			(xy 341.921574 -86.946233) (xy 341.86584 -86.944196) (xy 341.810997 -86.934066) (xy 341.758213 -86.916059)
			(xy 341.708613 -86.890558) (xy 341.663255 -86.858107) (xy 341.623106 -86.819398) (xy 341.58902 -86.775255)
			(xy 341.561724 -86.72662) (xy 341.541801 -86.674529) (xy 341.529675 -86.620092) (xy 341.525604 -86.56447)
			(xy 340.244585 -86.56447) (xy 340.254989 -86.580196) (xy 340.278661 -86.630693) (xy 340.294729 -86.6841)
			(xy 340.302849 -86.739276) (xy 340.303358 -86.767162) (xy 340.302849 -86.795048) (xy 340.294729 -86.850224)
			(xy 340.278661 -86.903631) (xy 340.254989 -86.954128) (xy 340.224216 -87.000641) (xy 340.186999 -87.042178)
			(xy 340.144131 -87.077853) (xy 340.096525 -87.106907) (xy 340.045196 -87.128719) (xy 339.991239 -87.142825)
			(xy 339.935802 -87.148925) (xy 339.880068 -87.146888) (xy 339.825225 -87.136758) (xy 339.772441 -87.118751)
			(xy 339.722841 -87.09325) (xy 339.677483 -87.060799) (xy 339.637334 -87.02209) (xy 339.603248 -86.977947)
			(xy 339.575952 -86.929312) (xy 339.556029 -86.877221) (xy 339.543903 -86.822784) (xy 339.539832 -86.767162)
			(xy 336.630716 -86.767162) (xy 336.630772 -86.77021) (xy 336.630263 -86.798096) (xy 336.622143 -86.853272)
			(xy 336.606075 -86.906679) (xy 336.582403 -86.957176) (xy 336.55163 -87.003689) (xy 336.514413 -87.045226)
			(xy 336.471545 -87.080901) (xy 336.423939 -87.109955) (xy 336.37261 -87.131767) (xy 336.318653 -87.145873)
			(xy 336.263216 -87.151973) (xy 336.207482 -87.149936) (xy 336.152639 -87.139806) (xy 336.099855 -87.121799)
			(xy 336.050255 -87.096298) (xy 336.004897 -87.063847) (xy 335.964748 -87.025138) (xy 335.930662 -86.980995)
			(xy 335.903366 -86.93236) (xy 335.883443 -86.880269) (xy 335.871317 -86.825832) (xy 335.867246 -86.77021)
			(xy 331.393292 -86.77021) (xy 331.393292 -87.324184) (xy 331.392824 -87.354153) (xy 331.385002 -87.413579)
			(xy 331.36949 -87.471476) (xy 331.346554 -87.526852) (xy 331.316585 -87.578761) (xy 331.280097 -87.626314)
			(xy 331.237714 -87.668697) (xy 331.190161 -87.705185) (xy 331.138252 -87.735154) (xy 331.082876 -87.75809)
			(xy 331.024979 -87.773602) (xy 330.965553 -87.781424) (xy 330.935584 -87.781892) (xy 330.905945 -87.781463)
			(xy 330.847162 -87.773834) (xy 330.789859 -87.758667) (xy 330.734998 -87.736217) (xy 330.709016 -87.721948)
			(xy 330.700604 -87.7177) (xy 330.681973 -87.714967) (xy 330.672694 -87.716614) (xy 330.642468 -87.723472)
			(xy 330.633482 -87.725918) (xy 330.617974 -87.736199) (xy 330.612242 -87.743538) (xy 330.596837 -87.764409)
			(xy 330.561273 -87.802173) (xy 330.520921 -87.83477) (xy 330.476524 -87.8616) (xy 330.428902 -87.882168)
			(xy 330.378933 -87.896095) (xy 330.327537 -87.903122) (xy 330.3016 -87.903558) (xy 330.274352 -87.902972)
			(xy 330.220412 -87.895216) (xy 330.168124 -87.879863) (xy 330.118553 -87.857225) (xy 330.072709 -87.827763)
			(xy 330.031524 -87.792076) (xy 329.995837 -87.750891) (xy 329.966375 -87.705047) (xy 329.943737 -87.655476)
			(xy 329.928384 -87.603188) (xy 329.920628 -87.549248) (xy 329.920628 -87.494752) (xy 329.928384 -87.440812)
			(xy 329.943737 -87.388524) (xy 329.966375 -87.338953) (xy 329.995837 -87.293109) (xy 330.031524 -87.251924)
			(xy 330.072709 -87.216237) (xy 330.118553 -87.186775) (xy 330.168124 -87.164137) (xy 330.220412 -87.148784)
			(xy 330.274352 -87.141028) (xy 330.3016 -87.140542) (xy 330.316393 -87.140675) (xy 330.345891 -87.142966)
			(xy 330.360528 -87.145114) (xy 330.37145 -87.146892) (xy 330.392786 -87.140796) (xy 330.460096 -87.083392)
			(xy 330.46812 -87.075821) (xy 330.477338 -87.055803) (xy 330.477876 -87.044784) (xy 330.477876 -86.740492)
			(xy 330.47735 -86.729471) (xy 330.468123 -86.709455) (xy 330.460096 -86.701884) (xy 330.392786 -86.64448)
			(xy 330.37145 -86.638384) (xy 330.360528 -86.640162) (xy 330.345891 -86.642306) (xy 330.316393 -86.644592)
			(xy 330.3016 -86.644734) (xy 330.274351 -86.644196) (xy 330.220407 -86.63644) (xy 330.168116 -86.621086)
			(xy 330.118542 -86.598446) (xy 330.072695 -86.568982) (xy 330.031507 -86.533293) (xy 329.995818 -86.492105)
			(xy 329.966354 -86.446258) (xy 329.943714 -86.396684) (xy 329.92836 -86.344393) (xy 329.920604 -86.290449)
			(xy 329.012042 -86.290449) (xy 329.012042 -88.419686) (xy 331.85303 -88.419686) (xy 331.857101 -88.364064)
			(xy 331.869227 -88.309627) (xy 331.88915 -88.257536) (xy 331.916446 -88.208901) (xy 331.950532 -88.164758)
			(xy 331.990681 -88.126049) (xy 332.036039 -88.093598) (xy 332.085639 -88.068097) (xy 332.138423 -88.05009)
			(xy 332.193266 -88.03996) (xy 332.249 -88.037923) (xy 332.304437 -88.044023) (xy 332.358394 -88.058129)
			(xy 332.409723 -88.079941) (xy 332.457329 -88.108995) (xy 332.500197 -88.14467) (xy 332.537414 -88.186207)
			(xy 332.568187 -88.23272) (xy 332.591859 -88.283217) (xy 332.607927 -88.336624) (xy 332.616047 -88.3918)
			(xy 332.616556 -88.419686) (xy 332.616047 -88.447572) (xy 332.607927 -88.502748) (xy 332.591859 -88.556155)
			(xy 332.568187 -88.606652) (xy 332.537414 -88.653165) (xy 332.500197 -88.694702) (xy 332.457329 -88.730377)
			(xy 332.409723 -88.759431) (xy 332.358394 -88.781243) (xy 332.304437 -88.795349) (xy 332.249 -88.801449)
			(xy 332.193266 -88.799412) (xy 332.138423 -88.789282) (xy 332.085639 -88.771275) (xy 332.036039 -88.745774)
			(xy 331.990681 -88.713323) (xy 331.950532 -88.674614) (xy 331.916446 -88.630471) (xy 331.88915 -88.581836)
			(xy 331.869227 -88.529745) (xy 331.857101 -88.475308) (xy 331.85303 -88.419686) (xy 329.012042 -88.419686)
			(xy 329.012042 -88.624918) (xy 329.012213 -88.632086) (xy 329.016084 -88.645883) (xy 329.019662 -88.652096)
			(xy 329.033414 -88.674934) (xy 329.055145 -88.723613) (xy 329.069891 -88.774843) (xy 329.077366 -88.827626)
			(xy 329.077828 -88.85428) (xy 329.077527 -88.871806) (xy 333.8863 -88.871806) (xy 333.890371 -88.816184)
			(xy 333.902497 -88.761747) (xy 333.92242 -88.709656) (xy 333.949716 -88.661021) (xy 333.983802 -88.616878)
			(xy 334.023951 -88.578169) (xy 334.069309 -88.545718) (xy 334.118909 -88.520217) (xy 334.171693 -88.50221)
			(xy 334.226536 -88.49208) (xy 334.28227 -88.490043) (xy 334.337707 -88.496143) (xy 334.391664 -88.510249)
			(xy 334.442993 -88.532061) (xy 334.490599 -88.561115) (xy 334.533467 -88.59679) (xy 334.547518 -88.612472)
			(xy 335.867246 -88.612472) (xy 335.871317 -88.55685) (xy 335.883443 -88.502413) (xy 335.903366 -88.450322)
			(xy 335.930662 -88.401687) (xy 335.964748 -88.357544) (xy 336.004897 -88.318835) (xy 336.050255 -88.286384)
			(xy 336.099855 -88.260883) (xy 336.152639 -88.242876) (xy 336.207482 -88.232746) (xy 336.263216 -88.230709)
			(xy 336.318653 -88.236809) (xy 336.37261 -88.250915) (xy 336.423939 -88.272727) (xy 336.471545 -88.301781)
			(xy 336.514413 -88.337456) (xy 336.55163 -88.378993) (xy 336.582403 -88.425506) (xy 336.606075 -88.476003)
			(xy 336.622143 -88.52941) (xy 336.630263 -88.584586) (xy 336.630772 -88.612472) (xy 337.713572 -88.612472)
			(xy 337.717643 -88.55685) (xy 337.729769 -88.502413) (xy 337.749692 -88.450322) (xy 337.776988 -88.401687)
			(xy 337.811074 -88.357544) (xy 337.851223 -88.318835) (xy 337.896581 -88.286384) (xy 337.946181 -88.260883)
			(xy 337.998965 -88.242876) (xy 338.053808 -88.232746) (xy 338.109542 -88.230709) (xy 338.164979 -88.236809)
			(xy 338.218936 -88.250915) (xy 338.270265 -88.272727) (xy 338.317871 -88.301781) (xy 338.360739 -88.337456)
			(xy 338.397956 -88.378993) (xy 338.428729 -88.425506) (xy 338.452401 -88.476003) (xy 338.468469 -88.52941)
			(xy 338.476589 -88.584586) (xy 338.476922 -88.60282) (xy 339.565994 -88.60282) (xy 339.570065 -88.547198)
			(xy 339.582191 -88.492761) (xy 339.602114 -88.44067) (xy 339.62941 -88.392035) (xy 339.663496 -88.347892)
			(xy 339.703645 -88.309183) (xy 339.749003 -88.276732) (xy 339.798603 -88.251231) (xy 339.851387 -88.233224)
			(xy 339.90623 -88.223094) (xy 339.961964 -88.221057) (xy 340.017401 -88.227157) (xy 340.071358 -88.241263)
			(xy 340.122687 -88.263075) (xy 340.170293 -88.292129) (xy 340.213161 -88.327804) (xy 340.250378 -88.369341)
			(xy 340.281151 -88.415854) (xy 340.304823 -88.466351) (xy 340.320891 -88.519758) (xy 340.329011 -88.574934)
			(xy 340.32952 -88.60282) (xy 340.329011 -88.630706) (xy 340.320891 -88.685882) (xy 340.304823 -88.739289)
			(xy 340.281151 -88.789786) (xy 340.250378 -88.836299) (xy 340.213161 -88.877836) (xy 340.170293 -88.913511)
			(xy 340.122687 -88.942565) (xy 340.071358 -88.964377) (xy 340.017401 -88.978483) (xy 339.961964 -88.984583)
			(xy 339.90623 -88.982546) (xy 339.851387 -88.972416) (xy 339.798603 -88.954409) (xy 339.749003 -88.928908)
			(xy 339.703645 -88.896457) (xy 339.663496 -88.857748) (xy 339.62941 -88.813605) (xy 339.602114 -88.76497)
			(xy 339.582191 -88.712879) (xy 339.570065 -88.658442) (xy 339.565994 -88.60282) (xy 338.476922 -88.60282)
			(xy 338.477098 -88.612472) (xy 338.476589 -88.640358) (xy 338.468469 -88.695534) (xy 338.452401 -88.748941)
			(xy 338.428729 -88.799438) (xy 338.397956 -88.845951) (xy 338.360739 -88.887488) (xy 338.317871 -88.923163)
			(xy 338.270265 -88.952217) (xy 338.218936 -88.974029) (xy 338.164979 -88.988135) (xy 338.109542 -88.994235)
			(xy 338.053808 -88.992198) (xy 337.998965 -88.982068) (xy 337.946181 -88.964061) (xy 337.896581 -88.93856)
			(xy 337.851223 -88.906109) (xy 337.811074 -88.8674) (xy 337.776988 -88.823257) (xy 337.749692 -88.774622)
			(xy 337.729769 -88.722531) (xy 337.717643 -88.668094) (xy 337.713572 -88.612472) (xy 336.630772 -88.612472)
			(xy 336.630263 -88.640358) (xy 336.622143 -88.695534) (xy 336.606075 -88.748941) (xy 336.582403 -88.799438)
			(xy 336.55163 -88.845951) (xy 336.514413 -88.887488) (xy 336.471545 -88.923163) (xy 336.423939 -88.952217)
			(xy 336.37261 -88.974029) (xy 336.318653 -88.988135) (xy 336.263216 -88.994235) (xy 336.207482 -88.992198)
			(xy 336.152639 -88.982068) (xy 336.099855 -88.964061) (xy 336.050255 -88.93856) (xy 336.004897 -88.906109)
			(xy 335.964748 -88.8674) (xy 335.930662 -88.823257) (xy 335.903366 -88.774622) (xy 335.883443 -88.722531)
			(xy 335.871317 -88.668094) (xy 335.867246 -88.612472) (xy 334.547518 -88.612472) (xy 334.570684 -88.638327)
			(xy 334.601457 -88.68484) (xy 334.625129 -88.735337) (xy 334.641197 -88.788744) (xy 334.649317 -88.84392)
			(xy 334.649826 -88.871806) (xy 334.649317 -88.899692) (xy 334.641197 -88.954868) (xy 334.625129 -89.008275)
			(xy 334.601457 -89.058772) (xy 334.570684 -89.105285) (xy 334.533467 -89.146822) (xy 334.490599 -89.182497)
			(xy 334.442993 -89.211551) (xy 334.391664 -89.233363) (xy 334.337707 -89.247469) (xy 334.28227 -89.253569)
			(xy 334.226536 -89.251532) (xy 334.171693 -89.241402) (xy 334.118909 -89.223395) (xy 334.069309 -89.197894)
			(xy 334.023951 -89.165443) (xy 333.983802 -89.126734) (xy 333.949716 -89.082591) (xy 333.92242 -89.033956)
			(xy 333.902497 -88.981865) (xy 333.890371 -88.927428) (xy 333.8863 -88.871806) (xy 329.077527 -88.871806)
			(xy 329.07737 -88.880937) (xy 329.069918 -88.933727) (xy 329.055182 -88.984963) (xy 329.033452 -89.033647)
			(xy 329.019662 -89.056464) (xy 329.016106 -89.062686) (xy 329.012235 -89.076478) (xy 329.012042 -89.083642)
			(xy 329.012042 -89.269316) (xy 329.807568 -89.269316) (xy 329.811639 -89.213694) (xy 329.823765 -89.159257)
			(xy 329.843688 -89.107166) (xy 329.870984 -89.058531) (xy 329.90507 -89.014388) (xy 329.945219 -88.975679)
			(xy 329.990577 -88.943228) (xy 330.040177 -88.917727) (xy 330.092961 -88.89972) (xy 330.147804 -88.88959)
			(xy 330.203538 -88.887553) (xy 330.258975 -88.893653) (xy 330.312932 -88.907759) (xy 330.364261 -88.929571)
			(xy 330.411867 -88.958625) (xy 330.454735 -88.9943) (xy 330.491952 -89.035837) (xy 330.522725 -89.08235)
			(xy 330.546397 -89.132847) (xy 330.562465 -89.186254) (xy 330.570585 -89.24143) (xy 330.571094 -89.269316)
			(xy 330.570585 -89.297202) (xy 330.562465 -89.352378) (xy 330.546397 -89.405785) (xy 330.522725 -89.456282)
			(xy 330.491952 -89.502795) (xy 330.454735 -89.544332) (xy 330.411867 -89.580007) (xy 330.364261 -89.609061)
			(xy 330.312932 -89.630873) (xy 330.258975 -89.644979) (xy 330.203538 -89.651079) (xy 330.147804 -89.649042)
			(xy 330.092961 -89.638912) (xy 330.040177 -89.620905) (xy 329.990577 -89.595404) (xy 329.945219 -89.562953)
			(xy 329.90507 -89.524244) (xy 329.870984 -89.480101) (xy 329.843688 -89.431466) (xy 329.823765 -89.379375)
			(xy 329.811639 -89.324938) (xy 329.807568 -89.269316) (xy 329.012042 -89.269316) (xy 329.012042 -90.66403)
			(xy 336.546188 -90.66403) (xy 336.550259 -90.608408) (xy 336.562385 -90.553971) (xy 336.582308 -90.50188)
			(xy 336.609604 -90.453245) (xy 336.64369 -90.409102) (xy 336.683839 -90.370393) (xy 336.729197 -90.337942)
			(xy 336.778797 -90.312441) (xy 336.831581 -90.294434) (xy 336.886424 -90.284304) (xy 336.942158 -90.282267)
			(xy 336.997595 -90.288367) (xy 337.051552 -90.302473) (xy 337.102881 -90.324285) (xy 337.150487 -90.353339)
			(xy 337.193355 -90.389014) (xy 337.230572 -90.430551) (xy 337.261345 -90.477064) (xy 337.285017 -90.527561)
			(xy 337.301085 -90.580968) (xy 337.309205 -90.636144) (xy 337.309714 -90.66403) (xy 337.309205 -90.691916)
			(xy 337.301085 -90.747092) (xy 337.285017 -90.800499) (xy 337.261345 -90.850996) (xy 337.230572 -90.897509)
			(xy 337.193355 -90.939046) (xy 337.150487 -90.974721) (xy 337.102881 -91.003775) (xy 337.051552 -91.025587)
			(xy 336.997595 -91.039693) (xy 336.942158 -91.045793) (xy 336.886424 -91.043756) (xy 336.831581 -91.033626)
			(xy 336.778797 -91.015619) (xy 336.729197 -90.990118) (xy 336.683839 -90.957667) (xy 336.64369 -90.918958)
			(xy 336.609604 -90.874815) (xy 336.582308 -90.82618) (xy 336.562385 -90.774089) (xy 336.550259 -90.719652)
			(xy 336.546188 -90.66403) (xy 329.012042 -90.66403) (xy 329.012042 -91.009216) (xy 329.0125 -91.019094)
			(xy 329.019937 -91.037399) (xy 329.02652 -91.044776) (xy 329.026774 -91.04503) (xy 329.380088 -91.398344)
			(xy 337.92617 -91.398344) (xy 337.930241 -91.342722) (xy 337.942367 -91.288285) (xy 337.96229 -91.236194)
			(xy 337.989586 -91.187559) (xy 338.023672 -91.143416) (xy 338.063821 -91.104707) (xy 338.109179 -91.072256)
			(xy 338.158779 -91.046755) (xy 338.211563 -91.028748) (xy 338.266406 -91.018618) (xy 338.32214 -91.016581)
			(xy 338.377577 -91.022681) (xy 338.431534 -91.036787) (xy 338.482863 -91.058599) (xy 338.530469 -91.087653)
			(xy 338.573337 -91.123328) (xy 338.610554 -91.164865) (xy 338.641327 -91.211378) (xy 338.664999 -91.261875)
			(xy 338.681067 -91.315282) (xy 338.689187 -91.370458) (xy 338.689696 -91.398344) (xy 338.689187 -91.42623)
			(xy 338.681067 -91.481406) (xy 338.664999 -91.534813) (xy 338.641327 -91.58531) (xy 338.610554 -91.631823)
			(xy 338.573337 -91.67336) (xy 338.530469 -91.709035) (xy 338.482863 -91.738089) (xy 338.431534 -91.759901)
			(xy 338.377577 -91.774007) (xy 338.32214 -91.780107) (xy 338.266406 -91.77807) (xy 338.211563 -91.76794)
			(xy 338.158779 -91.749933) (xy 338.109179 -91.724432) (xy 338.063821 -91.691981) (xy 338.023672 -91.653272)
			(xy 337.989586 -91.609129) (xy 337.96229 -91.560494) (xy 337.942367 -91.508403) (xy 337.930241 -91.453966)
			(xy 337.92617 -91.398344) (xy 329.380088 -91.398344) (xy 330.368402 -92.386658) (xy 330.36891 -92.387166)
			(xy 330.37629 -92.393754) (xy 330.394588 -92.401218) (xy 330.40447 -92.401644)
		)
		(stroke
			(width 0)
			(type solid)
		)
		(fill yes)
		(layer "In5.Cu")
		(net "P3V3_VDD_9ZXL0851_8_15")
	)
	(gr_poly
		(pts
			(xy 229.757732 -69.816218) (xy 229.767737 -69.815725) (xy 229.786221 -69.80806) (xy 229.800368 -69.793909)
			(xy 229.808028 -69.775423) (xy 229.808532 -69.765418) (xy 229.808532 -69.764656) (xy 229.808442 -69.715098)
			(xy 229.815611 -69.616247) (xy 229.831122 -69.518358) (xy 229.854865 -69.422134) (xy 229.886668 -69.328264)
			(xy 229.926304 -69.237424) (xy 229.973488 -69.150266) (xy 230.027881 -69.067415) (xy 230.089092 -68.989466)
			(xy 230.156683 -68.916979) (xy 230.230168 -68.850474) (xy 230.309019 -68.790429) (xy 230.39267 -68.737275)
			(xy 230.48052 -68.691393) (xy 230.57194 -68.653112) (xy 230.666271 -68.622709) (xy 230.762839 -68.6004)
			(xy 230.860948 -68.586347) (xy 230.959894 -68.58065) (xy 231.009444 -68.581524) (xy 231.009698 -68.581524)
			(xy 231.057036 -68.58027) (xy 231.151646 -68.584488) (xy 231.245605 -68.596346) (xy 231.338296 -68.615768)
			(xy 231.429112 -68.642625) (xy 231.517457 -68.676743) (xy 231.602752 -68.717896) (xy 231.684438 -68.765816)
			(xy 231.761979 -68.820188) (xy 231.834866 -68.880655) (xy 231.902622 -68.946821) (xy 231.964803 -69.018253)
			(xy 232.021 -69.094481) (xy 232.070845 -69.175006) (xy 232.114012 -69.2593) (xy 232.150217 -69.346811)
			(xy 232.179223 -69.436963) (xy 232.20084 -69.529167) (xy 232.214926 -69.622818) (xy 232.221388 -69.717302)
			(xy 232.221278 -69.764656) (xy 232.221278 -69.765418) (xy 232.221701 -69.774964) (xy 232.228735 -69.792715)
			(xy 232.241783 -69.806656) (xy 232.259029 -69.81485) (xy 232.268522 -69.815964) (xy 232.270808 -69.815964)
			(xy 232.272586 -69.816218) (xy 233.141012 -69.816218) (xy 233.150645 -69.815752) (xy 233.168531 -69.808574)
			(xy 233.17581 -69.802248) (xy 233.214164 -69.765926) (xy 233.217716 -69.762323) (xy 233.22348 -69.754012)
			(xy 233.225594 -69.749416) (xy 233.229404 -69.741034) (xy 233.229912 -69.730874) (xy 233.231233 -69.70422)
			(xy 233.240399 -69.651649) (xy 233.2568 -69.600866) (xy 233.280117 -69.552865) (xy 233.309894 -69.50858)
			(xy 233.345551 -69.468876) (xy 233.386392 -69.434527) (xy 233.43162 -69.406204) (xy 233.480354 -69.384458)
			(xy 233.531642 -69.369715) (xy 233.584484 -69.362261) (xy 233.611166 -69.361812) (xy 233.628946 -69.361812)
			(xy 233.65079 -69.362828) (xy 233.651552 -69.362828) (xy 233.657648 -69.362828) (xy 233.65841 -69.362828)
			(xy 233.686096 -69.361812) (xy 233.68635 -69.361812) (xy 233.715171 -69.362336) (xy 233.772158 -69.371003)
			(xy 233.827192 -69.388147) (xy 233.87902 -69.413378) (xy 233.92646 -69.44612) (xy 233.968432 -69.485629)
			(xy 234.003981 -69.531004) (xy 234.032297 -69.581212) (xy 234.052735 -69.63511) (xy 234.06483 -69.691469)
			(xy 234.067096 -69.720206) (xy 234.067096 -69.720714) (xy 234.067858 -69.730366) (xy 234.071922 -69.739002)
			(xy 234.074038 -69.743324) (xy 234.079658 -69.751133) (xy 234.083098 -69.754496) (xy 234.13339 -69.802248)
			(xy 234.139875 -69.807906) (xy 234.155582 -69.814917) (xy 234.164124 -69.815964) (xy 234.16641 -69.815964)
			(xy 234.168442 -69.816218) (xy 237.894368 -69.816218) (xy 237.902496 -69.815456) (xy 237.903004 -69.815456)
			(xy 237.910526 -69.813861) (xy 237.924224 -69.806895) (xy 237.929928 -69.80174) (xy 239.707928 -68.02374)
			(xy 239.712754 -68.018152) (xy 239.717418 -68.01141) (xy 239.72259 -67.995864) (xy 239.722914 -67.987672)
			(xy 239.722914 -61.319156) (xy 239.721644 -61.30798) (xy 239.718554 -61.29708) (xy 239.704571 -61.279289)
			(xy 239.69472 -61.27369) (xy 239.691672 -61.27242) (xy 239.666021 -61.261135) (xy 239.61806 -61.232151)
			(xy 239.574853 -61.196465) (xy 239.537328 -61.154845) (xy 239.506292 -61.108186) (xy 239.482412 -61.05749)
			(xy 239.466201 -61.003847) (xy 239.458009 -60.94841) (xy 239.45801 -60.892371) (xy 239.466205 -60.836935)
			(xy 239.482419 -60.783293) (xy 239.506301 -60.732598) (xy 239.537339 -60.68594) (xy 239.574866 -60.644322)
			(xy 239.618075 -60.608639) (xy 239.666038 -60.579657) (xy 239.691672 -60.568332) (xy 239.69472 -60.567062)
			(xy 239.70458 -60.561478) (xy 239.718553 -60.543675) (xy 239.721644 -60.532772) (xy 239.722914 -60.521596)
			(xy 239.722914 -60.35421) (xy 239.722493 -60.344139) (xy 239.714783 -60.32553) (xy 239.707928 -60.318142)
			(xy 238.420656 -59.03087) (xy 238.414345 -59.025056) (xy 238.398877 -59.017649) (xy 238.381832 -59.015763)
			(xy 238.373412 -59.017408) (xy 238.372904 -59.017408) (xy 238.350944 -59.022317) (xy 238.30625 -59.027535)
			(xy 238.28375 -59.027822) (xy 238.256763 -59.027352) (xy 238.203329 -59.01974) (xy 238.151501 -59.004675)
			(xy 238.102312 -58.982459) (xy 238.056744 -58.953533) (xy 238.015707 -58.918475) (xy 237.980018 -58.877985)
			(xy 237.950391 -58.83287) (xy 237.927415 -58.784031) (xy 237.91155 -58.732442) (xy 237.903112 -58.679132)
			(xy 237.902242 -58.652156) (xy 237.902242 -58.650378) (xy 237.901369 -58.64089) (xy 237.893525 -58.623542)
			(xy 237.887002 -58.616596) (xy 237.836456 -58.566558) (xy 237.83544 -58.565542) (xy 237.828152 -58.559251)
			(xy 237.810261 -58.552182) (xy 237.800642 -58.551826) (xy 234.138724 -58.551826) (xy 234.136946 -58.55208)
			(xy 234.134406 -58.55208) (xy 234.125021 -58.55307) (xy 234.107921 -58.561021) (xy 234.101132 -58.567574)
			(xy 234.050586 -58.620152) (xy 234.047013 -58.623986) (xy 234.041382 -58.632822) (xy 234.03941 -58.637678)
			(xy 234.035854 -58.64733) (xy 234.036362 -58.657744) (xy 234.036616 -58.673746) (xy 234.036616 -58.674254)
			(xy 234.036148 -58.701603) (xy 234.028337 -58.75574) (xy 234.012869 -58.808205) (xy 233.990061 -58.857921)
			(xy 233.960382 -58.903866) (xy 233.924441 -58.945098) (xy 233.904028 -58.963306) (xy 233.899964 -58.966862)
			(xy 233.89336 -58.975498) (xy 233.891074 -58.980324) (xy 233.888959 -58.985271) (xy 233.886642 -58.995774)
			(xy 233.886502 -59.001152) (xy 233.885486 -59.07786) (xy 233.885623 -59.083158) (xy 233.887797 -59.093529)
			(xy 233.889804 -59.098434) (xy 233.894122 -59.108594) (xy 233.902504 -59.11596) (xy 233.922084 -59.134125)
			(xy 233.956479 -59.174985) (xy 233.98484 -59.220242) (xy 234.006613 -59.269012) (xy 234.021372 -59.320341)
			(xy 234.028829 -59.373227) (xy 234.02925 -59.399932) (xy 234.028751 -59.427765) (xy 234.020674 -59.482841)
			(xy 234.004682 -59.536159) (xy 233.981114 -59.586589) (xy 233.950469 -59.63306) (xy 233.913399 -59.674586)
			(xy 233.892344 -59.692794) (xy 233.88834 -59.696335) (xy 233.881802 -59.704789) (xy 233.87939 -59.709558)
			(xy 233.864912 -59.739276) (xy 233.864912 -59.741054) (xy 233.867452 -59.822842) (xy 233.867827 -59.828828)
			(xy 233.871033 -59.840382) (xy 233.873802 -59.845702) (xy 233.876596 -59.850782) (xy 233.884724 -59.859418)
			(xy 233.889804 -59.862974) (xy 233.91139 -59.878303) (xy 233.950521 -59.913963) (xy 233.984352 -59.954686)
			(xy 234.012234 -59.999691) (xy 234.033634 -60.048115) (xy 234.04814 -60.099031) (xy 234.055475 -60.151463)
			(xy 234.05592 -60.177934) (xy 234.055432 -60.205184) (xy 234.047672 -60.259129) (xy 234.032314 -60.31142)
			(xy 234.009671 -60.360994) (xy 233.980204 -60.406841) (xy 233.944512 -60.448028) (xy 233.903323 -60.483717)
			(xy 233.857474 -60.513181) (xy 233.807899 -60.535821) (xy 233.755607 -60.551176) (xy 233.701662 -60.558933)
			(xy 233.674412 -60.559442) (xy 233.674158 -60.559442) (xy 233.646472 -60.558426) (xy 233.64571 -60.558426)
			(xy 233.639614 -60.558426) (xy 233.638852 -60.558426) (xy 233.611166 -60.559442) (xy 233.605832 -60.559442)
			(xy 233.604308 -60.559442) (xy 233.599228 -60.559442) (xy 233.571975 -60.558958) (xy 233.518022 -60.551205)
			(xy 233.465722 -60.535853) (xy 233.416139 -60.513214) (xy 233.370283 -60.483749) (xy 233.329086 -60.448058)
			(xy 233.293389 -60.406867) (xy 233.263916 -60.361015) (xy 233.241269 -60.311436) (xy 233.225908 -60.259139)
			(xy 233.218146 -60.205187) (xy 233.21772 -60.177934) (xy 233.21825 -60.148667) (xy 233.227183 -60.09082)
			(xy 233.244845 -60.035016) (xy 233.270823 -59.982563) (xy 233.304505 -59.934693) (xy 233.345103 -59.892527)
			(xy 233.368088 -59.874404) (xy 233.373168 -59.870594) (xy 233.380788 -59.860942) (xy 233.383582 -59.8551)
			(xy 233.385942 -59.849495) (xy 233.388255 -59.837559) (xy 233.388154 -59.831478) (xy 233.384344 -59.759596)
			(xy 233.383461 -59.750296) (xy 233.375898 -59.733233) (xy 233.369612 -59.726322) (xy 233.365294 -59.722004)
			(xy 233.357928 -59.715908) (xy 233.336134 -59.700629) (xy 233.2966 -59.664992) (xy 233.262408 -59.624202)
			(xy 233.234223 -59.579052) (xy 233.212593 -59.530421) (xy 233.197938 -59.479253) (xy 233.190543 -59.426545)
			(xy 233.190034 -59.399932) (xy 233.190531 -59.372192) (xy 233.198565 -59.317298) (xy 233.214468 -59.264147)
			(xy 233.237905 -59.213862) (xy 233.268381 -59.167502) (xy 233.305252 -59.126049) (xy 233.326178 -59.107832)
			(xy 233.32694 -59.107324) (xy 233.327702 -59.106562) (xy 233.331512 -59.102752) (xy 233.337978 -59.095659)
			(xy 233.34554 -59.078035) (xy 233.346244 -59.068462) (xy 233.348276 -59.002168) (xy 233.348231 -58.996613)
			(xy 233.346052 -58.985723) (xy 233.343958 -58.980578) (xy 233.33964 -58.970418) (xy 233.33075 -58.962798)
			(xy 233.310359 -58.944609) (xy 233.274482 -58.903397) (xy 233.244857 -58.857485) (xy 233.22209 -58.807814)
			(xy 233.206647 -58.755401) (xy 233.198846 -58.70132) (xy 233.198416 -58.674) (xy 233.199432 -58.647584)
			(xy 233.200194 -58.636662) (xy 233.196384 -58.626756) (xy 233.194478 -58.62191) (xy 233.188979 -58.613069)
			(xy 233.185462 -58.60923) (xy 233.14533 -58.56732) (xy 233.13788 -58.560265) (xy 233.119005 -58.552269)
			(xy 233.108754 -58.551826) (xy 232.323386 -58.551826) (xy 232.321608 -58.55208) (xy 232.319068 -58.55208)
			(xy 232.30713 -58.554366) (xy 232.299256 -58.557668) (xy 232.295862 -58.559543) (xy 232.289617 -58.564137)
			(xy 232.28681 -58.566812) (xy 232.23601 -58.617612) (xy 232.232962 -58.620914) (xy 232.227989 -58.627367)
			(xy 232.22203 -58.64252) (xy 232.221278 -58.650632) (xy 232.221278 -58.65368) (xy 232.220622 -58.702806)
			(xy 232.212074 -58.800689) (xy 232.195339 -58.897509) (xy 232.170535 -58.992583) (xy 232.137838 -59.085239)
			(xy 232.097478 -59.174822) (xy 232.04974 -59.260702) (xy 231.994961 -59.342271) (xy 231.933528 -59.418953)
			(xy 231.865874 -59.490207) (xy 231.792478 -59.555531) (xy 231.713857 -59.614463) (xy 231.630566 -59.666586)
			(xy 231.543194 -59.711534) (xy 231.452357 -59.748988) (xy 231.358696 -59.778685) (xy 231.262873 -59.800414)
			(xy 231.165565 -59.814022) (xy 231.067457 -59.819414) (xy 231.018334 -59.818524) (xy 231.015286 -59.818524)
			(xy 230.967299 -59.81959) (xy 230.871426 -59.814814) (xy 230.776268 -59.802192) (xy 230.682465 -59.781809)
			(xy 230.590649 -59.753802) (xy 230.50144 -59.718359) (xy 230.415438 -59.67572) (xy 230.333222 -59.626172)
			(xy 230.255346 -59.570048) (xy 230.182336 -59.507727) (xy 230.114682 -59.439629) (xy 230.05284 -59.366211)
			(xy 229.997228 -59.28797) (xy 229.94822 -59.205431) (xy 229.906145 -59.119151) (xy 229.871288 -59.029712)
			(xy 229.843883 -58.937715) (xy 229.824114 -58.84378) (xy 229.812116 -58.748541) (xy 229.807968 -58.652639)
			(xy 229.809294 -58.604658) (xy 229.809294 -58.602626) (xy 229.808879 -58.592602) (xy 229.801213 -58.574077)
			(xy 229.78704 -58.559898) (xy 229.768518 -58.552225) (xy 229.758494 -58.551826) (xy 229.710996 -58.551826)
			(xy 229.700927 -58.55225) (xy 229.682326 -58.559969) (xy 229.674928 -58.566812) (xy 228.19487 -60.04687)
			(xy 228.187835 -60.054543) (xy 228.180122 -60.073853) (xy 228.180766 -60.094638) (xy 228.18471 -60.104274)
			(xy 228.224842 -60.190888) (xy 228.228376 -60.197932) (xy 228.238986 -60.209572) (xy 228.24567 -60.213748)
			(xy 228.252274 -60.217558) (xy 228.267006 -60.22086) (xy 228.275388 -60.220098) (xy 228.3079 -60.218574)
			(xy 228.308408 -60.218574) (xy 228.341174 -60.220098) (xy 228.341682 -60.220098) (xy 228.347778 -60.220352)
			(xy 228.383338 -60.218574) (xy 228.410589 -60.219062) (xy 228.464535 -60.226824) (xy 228.516828 -60.242183)
			(xy 228.566402 -60.264827) (xy 228.61225 -60.294296) (xy 228.653438 -60.329989) (xy 228.689127 -60.37118)
			(xy 228.718591 -60.417031) (xy 228.74123 -60.466608) (xy 228.756584 -60.518902) (xy 228.76434 -60.572849)
			(xy 228.76434 -60.600082) (xy 231.00614 -60.600082) (xy 231.010211 -60.54446) (xy 231.022337 -60.490023)
			(xy 231.04226 -60.437932) (xy 231.069556 -60.389297) (xy 231.103642 -60.345154) (xy 231.143791 -60.306445)
			(xy 231.189149 -60.273994) (xy 231.238749 -60.248493) (xy 231.291533 -60.230486) (xy 231.346376 -60.220356)
			(xy 231.40211 -60.218319) (xy 231.457547 -60.224419) (xy 231.511504 -60.238525) (xy 231.562833 -60.260337)
			(xy 231.610439 -60.289391) (xy 231.653307 -60.325066) (xy 231.690524 -60.366603) (xy 231.721297 -60.413116)
			(xy 231.744969 -60.463613) (xy 231.761037 -60.51702) (xy 231.769157 -60.572196) (xy 231.769666 -60.600082)
			(xy 231.769157 -60.627968) (xy 231.761037 -60.683144) (xy 231.744969 -60.736551) (xy 231.721297 -60.787048)
			(xy 231.690524 -60.833561) (xy 231.653307 -60.875098) (xy 231.610439 -60.910773) (xy 231.562833 -60.939827)
			(xy 231.511504 -60.961639) (xy 231.457547 -60.975745) (xy 231.40211 -60.981845) (xy 231.346376 -60.979808)
			(xy 231.291533 -60.969678) (xy 231.238749 -60.951671) (xy 231.189149 -60.92617) (xy 231.143791 -60.893719)
			(xy 231.103642 -60.85501) (xy 231.069556 -60.810867) (xy 231.04226 -60.762232) (xy 231.022337 -60.710141)
			(xy 231.010211 -60.655704) (xy 231.00614 -60.600082) (xy 228.76434 -60.600082) (xy 228.76434 -60.627351)
			(xy 228.756584 -60.681298) (xy 228.74123 -60.733592) (xy 228.718591 -60.783169) (xy 228.689127 -60.82902)
			(xy 228.653438 -60.870211) (xy 228.61225 -60.905904) (xy 228.566402 -60.935373) (xy 228.516828 -60.958017)
			(xy 228.464535 -60.973376) (xy 228.410589 -60.981138) (xy 228.383338 -60.98159) (xy 228.347778 -60.979812)
			(xy 228.341682 -60.980066) (xy 228.341174 -60.980066) (xy 228.308154 -60.98159) (xy 228.280972 -60.981105)
			(xy 228.22716 -60.973381) (xy 228.17499 -60.958096) (xy 228.125518 -60.93556) (xy 228.079746 -60.906229)
			(xy 228.038601 -60.870697) (xy 228.002917 -60.829684) (xy 227.973417 -60.784021) (xy 227.950698 -60.734632)
			(xy 227.935221 -60.682519) (xy 227.93071 -60.655708) (xy 227.929694 -60.648596) (xy 227.924106 -60.63615)
			(xy 227.910644 -60.619894) (xy 227.905056 -60.617862) (xy 227.892864 -60.613798) (xy 227.887768 -60.61248)
			(xy 227.877271 -60.611716) (xy 227.872036 -60.612274) (xy 227.867718 -60.613036) (xy 227.862037 -60.614561)
			(xy 227.851521 -60.619823) (xy 227.84689 -60.62345) (xy 227.846636 -60.62345) (xy 227.826032 -60.639914)
			(xy 227.781153 -60.667615) (xy 227.732889 -60.688878) (xy 227.682159 -60.703299) (xy 227.629928 -60.710604)
			(xy 227.603558 -60.71108) (xy 227.60305 -60.71108) (xy 227.566728 -60.709556) (xy 227.559362 -60.709556)
			(xy 227.54971 -60.710318) (xy 227.540312 -60.710826) (xy 227.532184 -60.714382) (xy 227.527896 -60.716392)
			(xy 227.520095 -60.721759) (xy 227.51669 -60.72505) (xy 227.45192 -60.78982) (xy 227.447094 -60.795408)
			(xy 227.442421 -60.802147) (xy 227.437232 -60.817693) (xy 227.436934 -60.825888) (xy 227.436934 -61.33465)
			(xy 227.43753 -61.346405) (xy 227.447992 -61.367459) (xy 227.457 -61.375036) (xy 227.505768 -61.411866)
			(xy 227.509753 -61.414752) (xy 227.518578 -61.419101) (xy 227.523294 -61.420502) (xy 227.532692 -61.423042)
			(xy 227.542852 -61.421772) (xy 227.555241 -61.420237) (xy 227.580153 -61.418586) (xy 227.592636 -61.41847)
			(xy 227.625402 -61.419994) (xy 227.62591 -61.419994) (xy 227.631752 -61.420248) (xy 227.667058 -61.41847)
			(xy 227.66782 -61.41847) (xy 227.695071 -61.418957) (xy 227.749018 -61.426716) (xy 227.801311 -61.442072)
			(xy 227.850887 -61.464714) (xy 227.896737 -61.494181) (xy 227.937926 -61.529872) (xy 227.973618 -61.571062)
			(xy 228.003085 -61.616911) (xy 228.025727 -61.666487) (xy 228.041084 -61.71878) (xy 228.048843 -61.772727)
			(xy 228.049328 -61.799978) (xy 228.048887 -61.825363) (xy 228.042116 -61.875679) (xy 228.028744 -61.924657)
			(xy 228.009005 -61.971433) (xy 227.996496 -61.993526) (xy 227.994972 -61.99632) (xy 227.991416 -62.004702)
			(xy 227.991162 -62.00648) (xy 227.989384 -62.01918) (xy 227.989384 -62.060582) (xy 227.9898 -62.070607)
			(xy 227.997466 -62.089133) (xy 228.011639 -62.103314) (xy 228.030159 -62.110993) (xy 228.040184 -62.111382)
			(xy 228.04882 -62.111382) (xy 228.064822 -62.106048) (xy 228.07168 -62.10046) (xy 228.091971 -62.084992)
			(xy 228.135881 -62.059006) (xy 228.182861 -62.039102) (xy 228.232074 -62.025634) (xy 228.282643 -62.018843)
			(xy 228.308154 -62.018418) (xy 228.341174 -62.019942) (xy 228.341682 -62.019942) (xy 228.347778 -62.020196)
			(xy 228.383338 -62.018418) (xy 228.410586 -62.018907) (xy 228.464525 -62.026667) (xy 228.516812 -62.042025)
			(xy 228.566381 -62.064666) (xy 228.612223 -62.094132) (xy 228.653406 -62.129821) (xy 228.689091 -62.171007)
			(xy 228.718552 -62.216852) (xy 228.741189 -62.266424) (xy 228.756541 -62.318712) (xy 228.764296 -62.372652)
			(xy 228.764296 -62.399926) (xy 233.19054 -62.399926) (xy 233.194611 -62.344304) (xy 233.206737 -62.289867)
			(xy 233.22666 -62.237776) (xy 233.253956 -62.189141) (xy 233.288042 -62.144998) (xy 233.328191 -62.106289)
			(xy 233.373549 -62.073838) (xy 233.423149 -62.048337) (xy 233.475933 -62.03033) (xy 233.530776 -62.0202)
			(xy 233.58651 -62.018163) (xy 233.641947 -62.024263) (xy 233.695904 -62.038369) (xy 233.747233 -62.060181)
			(xy 233.794839 -62.089235) (xy 233.837707 -62.12491) (xy 233.874924 -62.166447) (xy 233.905697 -62.21296)
			(xy 233.929369 -62.263457) (xy 233.945437 -62.316864) (xy 233.951605 -62.358778) (xy 236.702344 -62.358778)
			(xy 236.706415 -62.303156) (xy 236.718541 -62.248719) (xy 236.738464 -62.196628) (xy 236.76576 -62.147993)
			(xy 236.799846 -62.10385) (xy 236.839995 -62.065141) (xy 236.885353 -62.03269) (xy 236.934953 -62.007189)
			(xy 236.987737 -61.989182) (xy 237.04258 -61.979052) (xy 237.098314 -61.977015) (xy 237.153751 -61.983115)
			(xy 237.207708 -61.997221) (xy 237.259037 -62.019033) (xy 237.306643 -62.048087) (xy 237.349511 -62.083762)
			(xy 237.386728 -62.125299) (xy 237.417501 -62.171812) (xy 237.441173 -62.222309) (xy 237.457241 -62.275716)
			(xy 237.465361 -62.330892) (xy 237.46587 -62.358778) (xy 237.465361 -62.386664) (xy 237.461989 -62.409578)
			(xy 238.418114 -62.409578) (xy 238.422185 -62.353956) (xy 238.434311 -62.299519) (xy 238.454234 -62.247428)
			(xy 238.48153 -62.198793) (xy 238.515616 -62.15465) (xy 238.555765 -62.115941) (xy 238.601123 -62.08349)
			(xy 238.650723 -62.057989) (xy 238.703507 -62.039982) (xy 238.75835 -62.029852) (xy 238.814084 -62.027815)
			(xy 238.869521 -62.033915) (xy 238.923478 -62.048021) (xy 238.974807 -62.069833) (xy 239.022413 -62.098887)
			(xy 239.065281 -62.134562) (xy 239.102498 -62.176099) (xy 239.133271 -62.222612) (xy 239.156943 -62.273109)
			(xy 239.173011 -62.326516) (xy 239.181131 -62.381692) (xy 239.18164 -62.409578) (xy 239.181131 -62.437464)
			(xy 239.173011 -62.49264) (xy 239.156943 -62.546047) (xy 239.133271 -62.596544) (xy 239.102498 -62.643057)
			(xy 239.065281 -62.684594) (xy 239.022413 -62.720269) (xy 238.974807 -62.749323) (xy 238.923478 -62.771135)
			(xy 238.869521 -62.785241) (xy 238.814084 -62.791341) (xy 238.75835 -62.789304) (xy 238.703507 -62.779174)
			(xy 238.650723 -62.761167) (xy 238.601123 -62.735666) (xy 238.555765 -62.703215) (xy 238.515616 -62.664506)
			(xy 238.48153 -62.620363) (xy 238.454234 -62.571728) (xy 238.434311 -62.519637) (xy 238.422185 -62.4652)
			(xy 238.418114 -62.409578) (xy 237.461989 -62.409578) (xy 237.457241 -62.44184) (xy 237.441173 -62.495247)
			(xy 237.417501 -62.545744) (xy 237.386728 -62.592257) (xy 237.349511 -62.633794) (xy 237.306643 -62.669469)
			(xy 237.259037 -62.698523) (xy 237.207708 -62.720335) (xy 237.153751 -62.734441) (xy 237.098314 -62.740541)
			(xy 237.04258 -62.738504) (xy 236.987737 -62.728374) (xy 236.934953 -62.710367) (xy 236.885353 -62.684866)
			(xy 236.839995 -62.652415) (xy 236.799846 -62.613706) (xy 236.76576 -62.569563) (xy 236.738464 -62.520928)
			(xy 236.718541 -62.468837) (xy 236.706415 -62.4144) (xy 236.702344 -62.358778) (xy 233.951605 -62.358778)
			(xy 233.953557 -62.37204) (xy 233.954066 -62.399926) (xy 233.953557 -62.427812) (xy 233.945437 -62.482988)
			(xy 233.929369 -62.536395) (xy 233.905697 -62.586892) (xy 233.874924 -62.633405) (xy 233.837707 -62.674942)
			(xy 233.794839 -62.710617) (xy 233.747233 -62.739671) (xy 233.695904 -62.761483) (xy 233.641947 -62.775589)
			(xy 233.58651 -62.781689) (xy 233.530776 -62.779652) (xy 233.475933 -62.769522) (xy 233.423149 -62.751515)
			(xy 233.373549 -62.726014) (xy 233.328191 -62.693563) (xy 233.288042 -62.654854) (xy 233.253956 -62.610711)
			(xy 233.22666 -62.562076) (xy 233.206737 -62.509985) (xy 233.194611 -62.455548) (xy 233.19054 -62.399926)
			(xy 228.764296 -62.399926) (xy 228.764296 -62.427148) (xy 228.756541 -62.481088) (xy 228.741189 -62.533376)
			(xy 228.718552 -62.582948) (xy 228.689091 -62.628793) (xy 228.653406 -62.669979) (xy 228.612223 -62.705668)
			(xy 228.566381 -62.735134) (xy 228.516812 -62.757775) (xy 228.464525 -62.773133) (xy 228.410586 -62.780893)
			(xy 228.383338 -62.781434) (xy 228.347778 -62.779656) (xy 228.341682 -62.77991) (xy 228.341174 -62.77991)
			(xy 228.308154 -62.781434) (xy 228.281022 -62.780952) (xy 228.227306 -62.773253) (xy 228.175224 -62.758017)
			(xy 228.125828 -62.735551) (xy 228.080115 -62.70631) (xy 228.059234 -62.688978) (xy 228.054662 -62.685168)
			(xy 228.044756 -62.679834) (xy 228.038914 -62.67831) (xy 228.033343 -62.677054) (xy 228.021929 -62.676796)
			(xy 228.016308 -62.677802) (xy 228.008688 -62.679326) (xy 228.00284 -62.680677) (xy 227.991933 -62.685677)
			(xy 227.987098 -62.689232) (xy 227.969826 -62.702948) (xy 227.965468 -62.706538) (xy 227.958294 -62.715256)
			(xy 227.955602 -62.72022) (xy 227.953824 -62.72403) (xy 227.942015 -62.745992) (xy 227.912676 -62.786309)
			(xy 227.895404 -62.804294) (xy 227.650294 -63.04915) (xy 227.622354 -63.07709) (xy 227.618798 -63.081154)
			(xy 227.613369 -63.088563) (xy 227.607645 -63.106004) (xy 227.607622 -63.11519) (xy 227.612956 -63.171832)
			(xy 227.615242 -63.1952) (xy 227.615904 -63.200818) (xy 227.619358 -63.211588) (xy 227.6221 -63.216536)
			(xy 227.622608 -63.217552) (xy 227.627434 -63.223902) (xy 227.632514 -63.229236) (xy 227.637086 -63.232538)
			(xy 227.637594 -63.232792) (xy 227.659096 -63.24813) (xy 227.698064 -63.28378) (xy 227.731748 -63.32446)
			(xy 227.759505 -63.369394) (xy 227.780806 -63.417724) (xy 227.790256 -63.450978) (xy 237.60633 -63.450978)
			(xy 237.610401 -63.395356) (xy 237.622527 -63.340919) (xy 237.64245 -63.288828) (xy 237.669746 -63.240193)
			(xy 237.703832 -63.19605) (xy 237.743981 -63.157341) (xy 237.789339 -63.12489) (xy 237.838939 -63.099389)
			(xy 237.891723 -63.081382) (xy 237.946566 -63.071252) (xy 238.0023 -63.069215) (xy 238.057737 -63.075315)
			(xy 238.111694 -63.089421) (xy 238.163023 -63.111233) (xy 238.210629 -63.140287) (xy 238.253497 -63.175962)
			(xy 238.290714 -63.217499) (xy 238.321487 -63.264012) (xy 238.345159 -63.314509) (xy 238.361227 -63.367916)
			(xy 238.369347 -63.423092) (xy 238.369856 -63.450978) (xy 238.369347 -63.478864) (xy 238.361227 -63.53404)
			(xy 238.345159 -63.587447) (xy 238.321487 -63.637944) (xy 238.290714 -63.684457) (xy 238.253497 -63.725994)
			(xy 238.210629 -63.761669) (xy 238.163023 -63.790723) (xy 238.111694 -63.812535) (xy 238.057737 -63.826641)
			(xy 238.0023 -63.832741) (xy 237.946566 -63.830704) (xy 237.891723 -63.820574) (xy 237.838939 -63.802567)
			(xy 237.789339 -63.777066) (xy 237.743981 -63.744615) (xy 237.703832 -63.705906) (xy 237.669746 -63.661763)
			(xy 237.64245 -63.613128) (xy 237.622527 -63.561037) (xy 237.610401 -63.5066) (xy 237.60633 -63.450978)
			(xy 227.790256 -63.450978) (xy 227.795244 -63.468528) (xy 227.802543 -63.520836) (xy 227.802948 -63.547244)
			(xy 227.80248 -63.574285) (xy 227.794847 -63.627827) (xy 227.779726 -63.679752) (xy 227.757421 -63.729021)
			(xy 227.728378 -63.774644) (xy 227.693181 -63.815706) (xy 227.652536 -63.851383) (xy 227.607258 -63.88096)
			(xy 227.558255 -63.903844) (xy 227.50651 -63.919574) (xy 227.47986 -63.92418) (xy 227.47097 -63.925704)
			(xy 227.46081 -63.931292) (xy 227.457711 -63.933327) (xy 227.452102 -63.938177) (xy 227.449634 -63.940944)
			(xy 227.449126 -63.941452) (xy 227.4448 -63.94682) (xy 227.438999 -63.959321) (xy 227.437696 -63.96609)
			(xy 227.436934 -63.974472) (xy 227.436934 -64.276224) (xy 227.856286 -64.276224) (xy 227.860357 -64.220602)
			(xy 227.872483 -64.166165) (xy 227.892406 -64.114074) (xy 227.919702 -64.065439) (xy 227.953788 -64.021296)
			(xy 227.993937 -63.982587) (xy 228.039295 -63.950136) (xy 228.088895 -63.924635) (xy 228.141679 -63.906628)
			(xy 228.196522 -63.896498) (xy 228.252256 -63.894461) (xy 228.307693 -63.900561) (xy 228.36165 -63.914667)
			(xy 228.412979 -63.936479) (xy 228.460585 -63.965533) (xy 228.503453 -64.001208) (xy 228.54067 -64.042745)
			(xy 228.571443 -64.089258) (xy 228.595115 -64.139755) (xy 228.611183 -64.193162) (xy 228.612193 -64.200024)
			(xy 231.00614 -64.200024) (xy 231.010211 -64.144402) (xy 231.022337 -64.089965) (xy 231.04226 -64.037874)
			(xy 231.069556 -63.989239) (xy 231.103642 -63.945096) (xy 231.143791 -63.906387) (xy 231.189149 -63.873936)
			(xy 231.238749 -63.848435) (xy 231.291533 -63.830428) (xy 231.346376 -63.820298) (xy 231.40211 -63.818261)
			(xy 231.457547 -63.824361) (xy 231.511504 -63.838467) (xy 231.562833 -63.860279) (xy 231.610439 -63.889333)
			(xy 231.653307 -63.925008) (xy 231.690524 -63.966545) (xy 231.721297 -64.013058) (xy 231.744969 -64.063555)
			(xy 231.761037 -64.116962) (xy 231.769157 -64.172138) (xy 231.769666 -64.200024) (xy 231.769157 -64.22791)
			(xy 231.761037 -64.283086) (xy 231.744969 -64.336493) (xy 231.721297 -64.38699) (xy 231.690524 -64.433503)
			(xy 231.653307 -64.47504) (xy 231.610439 -64.510715) (xy 231.562833 -64.539769) (xy 231.511504 -64.561581)
			(xy 231.457547 -64.575687) (xy 231.40211 -64.581787) (xy 231.346376 -64.57975) (xy 231.291533 -64.56962)
			(xy 231.238749 -64.551613) (xy 231.189149 -64.526112) (xy 231.143791 -64.493661) (xy 231.103642 -64.454952)
			(xy 231.069556 -64.410809) (xy 231.04226 -64.362174) (xy 231.022337 -64.310083) (xy 231.010211 -64.255646)
			(xy 231.00614 -64.200024) (xy 228.612193 -64.200024) (xy 228.619303 -64.248338) (xy 228.619812 -64.276224)
			(xy 228.619303 -64.30411) (xy 228.611183 -64.359286) (xy 228.595115 -64.412693) (xy 228.571443 -64.46319)
			(xy 228.54067 -64.509703) (xy 228.503453 -64.55124) (xy 228.460585 -64.586915) (xy 228.412979 -64.615969)
			(xy 228.36165 -64.637781) (xy 228.307693 -64.651887) (xy 228.252256 -64.657987) (xy 228.196522 -64.65595)
			(xy 228.141679 -64.64582) (xy 228.088895 -64.627813) (xy 228.039295 -64.602312) (xy 227.993937 -64.569861)
			(xy 227.953788 -64.531152) (xy 227.919702 -64.487009) (xy 227.892406 -64.438374) (xy 227.872483 -64.386283)
			(xy 227.860357 -64.331846) (xy 227.856286 -64.276224) (xy 227.436934 -64.276224) (xy 227.436934 -64.799972)
			(xy 233.19054 -64.799972) (xy 233.194611 -64.74435) (xy 233.206737 -64.689913) (xy 233.22666 -64.637822)
			(xy 233.253956 -64.589187) (xy 233.288042 -64.545044) (xy 233.328191 -64.506335) (xy 233.373549 -64.473884)
			(xy 233.423149 -64.448383) (xy 233.475933 -64.430376) (xy 233.530776 -64.420246) (xy 233.58651 -64.418209)
			(xy 233.641947 -64.424309) (xy 233.695904 -64.438415) (xy 233.747233 -64.460227) (xy 233.794839 -64.489281)
			(xy 233.837707 -64.524956) (xy 233.874924 -64.566493) (xy 233.905697 -64.613006) (xy 233.929369 -64.663503)
			(xy 233.945437 -64.71691) (xy 233.953557 -64.772086) (xy 233.954066 -64.799972) (xy 233.953557 -64.827858)
			(xy 233.945437 -64.883034) (xy 233.929369 -64.936441) (xy 233.905697 -64.986938) (xy 233.874924 -65.033451)
			(xy 233.837707 -65.074988) (xy 233.794839 -65.110663) (xy 233.747233 -65.139717) (xy 233.695904 -65.161529)
			(xy 233.641947 -65.175635) (xy 233.58651 -65.181735) (xy 233.530776 -65.179698) (xy 233.475933 -65.169568)
			(xy 233.423149 -65.151561) (xy 233.373549 -65.12606) (xy 233.328191 -65.093609) (xy 233.288042 -65.0549)
			(xy 233.253956 -65.010757) (xy 233.22666 -64.962122) (xy 233.206737 -64.910031) (xy 233.194611 -64.855594)
			(xy 233.19054 -64.799972) (xy 227.436934 -64.799972) (xy 227.436934 -65.096136) (xy 227.437188 -65.101216)
			(xy 227.438373 -65.109675) (xy 227.445561 -65.125159) (xy 227.45741 -65.137448) (xy 227.464874 -65.141602)
			(xy 227.47097 -65.144142) (xy 227.493576 -65.15227) (xy 227.494084 -65.15227) (xy 227.503736 -65.155572)
			(xy 227.510759 -65.157813) (xy 227.525474 -65.158595) (xy 227.532692 -65.157096) (xy 227.532946 -65.156842)
			(xy 227.539919 -65.154821) (xy 227.552435 -65.147481) (xy 227.557584 -65.142364) (xy 227.557838 -65.14211)
			(xy 227.575981 -65.122988) (xy 227.616618 -65.089415) (xy 227.661489 -65.061755) (xy 227.70974 -65.040532)
			(xy 227.760452 -65.026151) (xy 227.81266 -65.018886) (xy 227.839016 -65.018412) (xy 227.872036 -65.019936)
			(xy 227.872544 -65.019936) (xy 227.87864 -65.02019) (xy 227.9142 -65.018412) (xy 227.941452 -65.018875)
			(xy 227.995402 -65.026632) (xy 228.047699 -65.041989) (xy 228.097278 -65.064631) (xy 228.143129 -65.0941)
			(xy 228.18432 -65.129794) (xy 228.220012 -65.170987) (xy 228.249478 -65.21684) (xy 228.272118 -65.26642)
			(xy 228.287472 -65.318717) (xy 228.295226 -65.372668) (xy 228.295708 -65.39992) (xy 231.00614 -65.39992)
			(xy 231.010211 -65.344298) (xy 231.022337 -65.289861) (xy 231.04226 -65.23777) (xy 231.069556 -65.189135)
			(xy 231.103642 -65.144992) (xy 231.143791 -65.106283) (xy 231.189149 -65.073832) (xy 231.238749 -65.048331)
			(xy 231.291533 -65.030324) (xy 231.346376 -65.020194) (xy 231.40211 -65.018157) (xy 231.457547 -65.024257)
			(xy 231.511504 -65.038363) (xy 231.562833 -65.060175) (xy 231.610439 -65.089229) (xy 231.653307 -65.124904)
			(xy 231.690524 -65.166441) (xy 231.721297 -65.212954) (xy 231.744969 -65.263451) (xy 231.761037 -65.316858)
			(xy 231.769157 -65.372034) (xy 231.769666 -65.39992) (xy 231.769157 -65.427806) (xy 231.761037 -65.482982)
			(xy 231.744969 -65.536389) (xy 231.721297 -65.586886) (xy 231.690524 -65.633399) (xy 231.653307 -65.674936)
			(xy 231.610439 -65.710611) (xy 231.562833 -65.739665) (xy 231.511504 -65.761477) (xy 231.457547 -65.775583)
			(xy 231.40211 -65.781683) (xy 231.346376 -65.779646) (xy 231.291533 -65.769516) (xy 231.238749 -65.751509)
			(xy 231.189149 -65.726008) (xy 231.143791 -65.693557) (xy 231.103642 -65.654848) (xy 231.069556 -65.610705)
			(xy 231.04226 -65.56207) (xy 231.022337 -65.509979) (xy 231.010211 -65.455542) (xy 231.00614 -65.39992)
			(xy 228.295708 -65.39992) (xy 228.295337 -65.423275) (xy 228.289601 -65.469632) (xy 228.284278 -65.492376)
			(xy 228.28377 -65.494408) (xy 228.283516 -65.49644) (xy 228.2823 -65.506952) (xy 228.287565 -65.527423)
			(xy 228.293676 -65.536064) (xy 228.342952 -65.599056) (xy 228.350494 -65.607842) (xy 228.371265 -65.618021)
			(xy 228.38283 -65.618614) (xy 228.383338 -65.618614) (xy 228.410586 -65.619103) (xy 228.464526 -65.626863)
			(xy 228.516813 -65.642221) (xy 228.566383 -65.664863) (xy 228.612226 -65.694328) (xy 228.653409 -65.730018)
			(xy 228.689094 -65.771205) (xy 228.718555 -65.81705) (xy 228.741193 -65.866622) (xy 228.756545 -65.918911)
			(xy 228.7643 -65.972852) (xy 228.7643 -66.000122) (xy 233.19054 -66.000122) (xy 233.194611 -65.9445)
			(xy 233.206737 -65.890063) (xy 233.22666 -65.837972) (xy 233.253956 -65.789337) (xy 233.288042 -65.745194)
			(xy 233.328191 -65.706485) (xy 233.373549 -65.674034) (xy 233.423149 -65.648533) (xy 233.475933 -65.630526)
			(xy 233.530776 -65.620396) (xy 233.58651 -65.618359) (xy 233.641947 -65.624459) (xy 233.695904 -65.638565)
			(xy 233.747233 -65.660377) (xy 233.794839 -65.689431) (xy 233.837707 -65.725106) (xy 233.874924 -65.766643)
			(xy 233.905697 -65.813156) (xy 233.929369 -65.863653) (xy 233.945437 -65.91706) (xy 233.953557 -65.972236)
			(xy 233.954066 -66.000122) (xy 233.953557 -66.028008) (xy 233.945437 -66.083184) (xy 233.929369 -66.136591)
			(xy 233.905697 -66.187088) (xy 233.874924 -66.233601) (xy 233.837707 -66.275138) (xy 233.794839 -66.310813)
			(xy 233.747233 -66.339867) (xy 233.695904 -66.361679) (xy 233.641947 -66.375785) (xy 233.58651 -66.381885)
			(xy 233.530776 -66.379848) (xy 233.475933 -66.369718) (xy 233.423149 -66.351711) (xy 233.373549 -66.32621)
			(xy 233.328191 -66.293759) (xy 233.288042 -66.25505) (xy 233.253956 -66.210907) (xy 233.22666 -66.162272)
			(xy 233.206737 -66.110181) (xy 233.194611 -66.055744) (xy 233.19054 -66.000122) (xy 228.7643 -66.000122)
			(xy 228.7643 -66.027348) (xy 228.756545 -66.081289) (xy 228.741193 -66.133578) (xy 228.718555 -66.18315)
			(xy 228.689094 -66.228995) (xy 228.653409 -66.270182) (xy 228.612226 -66.305872) (xy 228.566383 -66.335337)
			(xy 228.516813 -66.357979) (xy 228.464526 -66.373337) (xy 228.410586 -66.381097) (xy 228.383338 -66.38163)
			(xy 228.347778 -66.379852) (xy 228.341682 -66.380106) (xy 228.341174 -66.380106) (xy 228.308154 -66.38163)
			(xy 228.280904 -66.381141) (xy 228.22696 -66.373379) (xy 228.17467 -66.358021) (xy 228.125097 -66.335377)
			(xy 228.079251 -66.30591) (xy 228.038064 -66.270219) (xy 228.002376 -66.22903) (xy 227.972911 -66.183182)
			(xy 227.950271 -66.133608) (xy 227.934916 -66.081316) (xy 227.927157 -66.027372) (xy 227.926646 -66.000122)
			(xy 227.926646 -65.99936) (xy 227.927307 -65.968582) (xy 227.937257 -65.907834) (xy 227.946458 -65.878456)
			(xy 227.94849 -65.870582) (xy 227.950522 -65.857882) (xy 227.950322 -65.850547) (xy 227.946191 -65.836475)
			(xy 227.942394 -65.830196) (xy 227.930964 -65.812924) (xy 227.927636 -65.808276) (xy 227.919306 -65.800452)
			(xy 227.914454 -65.79743) (xy 227.886006 -65.780412) (xy 227.884482 -65.780158) (xy 227.87864 -65.77965)
			(xy 227.872544 -65.779904) (xy 227.872036 -65.779904) (xy 227.839016 -65.781428) (xy 227.81269 -65.78098)
			(xy 227.760539 -65.773728) (xy 227.70988 -65.759374) (xy 227.661677 -65.738191) (xy 227.616844 -65.71058)
			(xy 227.576235 -65.677066) (xy 227.558092 -65.657984) (xy 227.557584 -65.657476) (xy 227.552451 -65.652337)
			(xy 227.539935 -65.644976) (xy 227.532946 -65.642998) (xy 227.532692 -65.642744) (xy 227.525474 -65.641256)
			(xy 227.510763 -65.642041) (xy 227.503736 -65.644268) (xy 227.49383 -65.64757) (xy 227.47097 -65.655698)
			(xy 227.464874 -65.658238) (xy 227.457385 -65.662362) (xy 227.445503 -65.674637) (xy 227.438351 -65.690154)
			(xy 227.437188 -65.698624) (xy 227.436934 -65.703704) (xy 227.436934 -66.940176) (xy 227.437029 -66.945194)
			(xy 227.438955 -66.955044) (xy 227.440744 -66.959734) (xy 227.44442 -66.967659) (xy 227.456143 -66.980592)
			(xy 227.471534 -66.988828) (xy 227.480114 -66.990468) (xy 227.482146 -66.990722) (xy 227.509829 -66.994235)
			(xy 227.563826 -67.008312) (xy 227.615196 -67.030104) (xy 227.662845 -67.059147) (xy 227.705754 -67.09482)
			(xy 227.74301 -67.136362) (xy 227.773818 -67.182889) (xy 227.79752 -67.233407) (xy 227.81361 -67.286838)
			(xy 227.821747 -67.342043) (xy 227.822252 -67.369944) (xy 227.822038 -67.389577) (xy 227.818093 -67.428643)
			(xy 227.814378 -67.447922) (xy 227.814124 -67.448938) (xy 227.813108 -67.458844) (xy 227.813108 -68.01993)
			(xy 227.813108 -68.020692) (xy 227.813587 -68.029606) (xy 227.819952 -68.046272) (xy 227.831636 -68.059753)
			(xy 227.83927 -68.06438) (xy 227.839778 -68.064634) (xy 227.879402 -68.08597) (xy 227.884914 -68.088742)
			(xy 227.896859 -68.091812) (xy 227.903024 -68.092066) (xy 227.915724 -68.09232) (xy 227.9269 -68.086732)
			(xy 227.927408 -68.086224) (xy 227.93071 -68.0847) (xy 227.934924 -68.082433) (xy 227.942472 -68.076552)
			(xy 227.945696 -68.073016) (xy 227.95865 -68.05803) (xy 227.961864 -68.054178) (xy 227.966852 -68.045477)
			(xy 227.968556 -68.040758) (xy 227.975414 -68.020184) (xy 227.977446 -68.010786) (xy 227.978173 -68.002861)
			(xy 227.97533 -67.987212) (xy 227.971858 -67.980052) (xy 227.957641 -67.952185) (xy 227.937495 -67.892962)
			(xy 227.927288 -67.831244) (xy 227.926646 -67.799966) (xy 227.927134 -67.772715) (xy 227.934894 -67.718769)
			(xy 227.950252 -67.666475) (xy 227.972894 -67.616899) (xy 228.002361 -67.57105) (xy 228.038052 -67.52986)
			(xy 228.07924 -67.494168) (xy 228.125089 -67.4647) (xy 228.174664 -67.442056) (xy 228.226957 -67.426697)
			(xy 228.280903 -67.418935) (xy 228.308154 -67.418458) (xy 228.341174 -67.419982) (xy 228.341682 -67.419982)
			(xy 228.347778 -67.420236) (xy 228.383338 -67.418458) (xy 228.410588 -67.418946) (xy 228.464534 -67.426707)
			(xy 228.516826 -67.442065) (xy 228.566401 -67.464708) (xy 228.612249 -67.494175) (xy 228.653437 -67.529866)
			(xy 228.689128 -67.571055) (xy 228.718594 -67.616903) (xy 228.741236 -67.666478) (xy 228.756594 -67.71877)
			(xy 228.764354 -67.772716) (xy 228.764846 -67.799966) (xy 231.00614 -67.799966) (xy 231.010211 -67.744344)
			(xy 231.022337 -67.689907) (xy 231.04226 -67.637816) (xy 231.069556 -67.589181) (xy 231.103642 -67.545038)
			(xy 231.143791 -67.506329) (xy 231.189149 -67.473878) (xy 231.238749 -67.448377) (xy 231.291533 -67.43037)
			(xy 231.346376 -67.42024) (xy 231.40211 -67.418203) (xy 231.457547 -67.424303) (xy 231.511504 -67.438409)
			(xy 231.562833 -67.460221) (xy 231.610439 -67.489275) (xy 231.653307 -67.52495) (xy 231.690524 -67.566487)
			(xy 231.721297 -67.613) (xy 231.744969 -67.663497) (xy 231.761037 -67.716904) (xy 231.769157 -67.77208)
			(xy 231.769666 -67.799966) (xy 231.769157 -67.827852) (xy 231.761037 -67.883028) (xy 231.744969 -67.936435)
			(xy 231.721297 -67.986932) (xy 231.690524 -68.033445) (xy 231.653307 -68.074982) (xy 231.610439 -68.110657)
			(xy 231.562833 -68.139711) (xy 231.511504 -68.161523) (xy 231.457547 -68.175629) (xy 231.40211 -68.181729)
			(xy 231.346376 -68.179692) (xy 231.291533 -68.169562) (xy 231.238749 -68.151555) (xy 231.189149 -68.126054)
			(xy 231.143791 -68.093603) (xy 231.103642 -68.054894) (xy 231.069556 -68.010751) (xy 231.04226 -67.962116)
			(xy 231.022337 -67.910025) (xy 231.010211 -67.855588) (xy 231.00614 -67.799966) (xy 228.764846 -67.799966)
			(xy 228.764308 -67.82896) (xy 228.755539 -67.886281) (xy 228.738196 -67.941615) (xy 228.71268 -67.993688)
			(xy 228.679578 -68.0413) (xy 228.639652 -68.083354) (xy 228.593823 -68.118883) (xy 228.568758 -68.133468)
			(xy 228.560122 -68.138294) (xy 228.55428 -68.145406) (xy 228.551323 -68.149125) (xy 228.546717 -68.157435)
			(xy 228.545136 -68.161916) (xy 228.5238 -68.227702) (xy 228.52262 -68.231597) (xy 228.521343 -68.239635)
			(xy 228.52126 -68.243704) (xy 228.524562 -68.259452) (xy 228.527864 -68.269358) (xy 228.538262 -68.293853)
			(xy 228.552941 -68.345001) (xy 228.560381 -68.397692) (xy 228.560884 -68.424298) (xy 228.560421 -68.45155)
			(xy 228.552664 -68.5055) (xy 228.537308 -68.557797) (xy 228.514665 -68.607376) (xy 228.485197 -68.653227)
			(xy 228.449503 -68.694418) (xy 228.40831 -68.73011) (xy 228.362456 -68.759576) (xy 228.312876 -68.782216)
			(xy 228.260579 -68.797569) (xy 228.206628 -68.805322) (xy 228.179376 -68.805806) (xy 228.143816 -68.804028)
			(xy 228.13772 -68.804282) (xy 228.137212 -68.804282) (xy 228.104192 -68.805806) (xy 228.07357 -68.805203)
			(xy 228.013114 -68.795421) (xy 227.955 -68.776094) (xy 227.900727 -68.747721) (xy 227.875846 -68.72986)
			(xy 227.875338 -68.729352) (xy 227.866448 -68.723002) (xy 227.85578 -68.720716) (xy 227.850357 -68.719718)
			(xy 227.839333 -68.71984) (xy 227.833936 -68.72097) (xy 227.813616 -68.725542) (xy 227.807879 -68.726978)
			(xy 227.797224 -68.732101) (xy 227.792534 -68.735702) (xy 227.78847 -68.739004) (xy 227.781358 -68.748148)
			(xy 227.778818 -68.753736) (xy 227.764419 -68.783216) (xy 227.726865 -68.837005) (xy 227.704142 -68.86067)
			(xy 227.45192 -69.112892) (xy 227.44507 -69.120289) (xy 227.43733 -69.138887) (xy 227.436934 -69.14896)
			(xy 227.436934 -69.330062) (xy 227.437103 -69.336071) (xy 227.439931 -69.347751) (xy 227.442522 -69.353176)
			(xy 227.44436 -69.356651) (xy 227.448951 -69.363033) (xy 227.451666 -69.365876) (xy 227.657152 -69.571362)
			(xy 227.659729 -69.57387) (xy 227.665466 -69.578204) (xy 227.668582 -69.579998) (xy 227.67417 -69.583046)
			(xy 227.679504 -69.58457) (xy 227.681028 -69.584824) (xy 227.709666 -69.592293) (xy 227.765741 -69.611242)
			(xy 227.793042 -69.62267) (xy 227.801678 -69.626226) (xy 227.813108 -69.625718) (xy 227.818836 -69.625255)
			(xy 227.829869 -69.622048) (xy 227.834952 -69.619368) (xy 227.905564 -69.579998) (xy 227.910556 -69.57702)
			(xy 227.91915 -69.569196) (xy 227.922582 -69.564504) (xy 227.929186 -69.555106) (xy 227.930964 -69.543168)
			(xy 227.935481 -69.516424) (xy 227.951084 -69.46448) (xy 227.973885 -69.415268) (xy 228.003424 -69.369781)
			(xy 228.039107 -69.328934) (xy 228.080213 -69.293551) (xy 228.125914 -69.264345) (xy 228.175291 -69.241904)
			(xy 228.227348 -69.22668) (xy 228.281036 -69.21898) (xy 228.308154 -69.218556) (xy 228.341174 -69.22008)
			(xy 228.341682 -69.22008) (xy 228.347778 -69.220334) (xy 228.383338 -69.218556) (xy 228.410588 -69.219044)
			(xy 228.464534 -69.226805) (xy 228.516826 -69.242163) (xy 228.566401 -69.264806) (xy 228.612249 -69.294273)
			(xy 228.653438 -69.329964) (xy 228.689129 -69.371152) (xy 228.718595 -69.417001) (xy 228.741238 -69.466576)
			(xy 228.756595 -69.518868) (xy 228.764356 -69.572814) (xy 228.764846 -69.600064) (xy 228.764498 -69.622896)
			(xy 228.759026 -69.668231) (xy 228.753924 -69.690488) (xy 228.75113 -69.701918) (xy 228.75367 -69.713348)
			(xy 228.75502 -69.718775) (xy 228.759767 -69.728899) (xy 228.763068 -69.733414) (xy 228.812344 -69.79666)
			(xy 228.818421 -69.803876) (xy 228.834602 -69.813548) (xy 228.84384 -69.815456) (xy 228.852222 -69.816218)
		)
		(stroke
			(width 0)
			(type solid)
		)
		(fill yes)
		(layer "In5.Cu")
		(net "P5V_AUX")
	)
	(gr_poly
		(pts
			(xy 404.677626 -269.051532) (xy 404.687695 -269.051105) (xy 404.706295 -269.043388) (xy 404.713694 -269.036546)
			(xy 405.00935 -268.74089) (xy 405.0162 -268.733493) (xy 405.023939 -268.714895) (xy 405.024336 -268.704822)
			(xy 405.024336 -265.55573) (xy 405.022558 -265.542014) (xy 384.497072 -192.136522) (xy 384.495149 -192.130267)
			(xy 384.488592 -192.118946) (xy 384.484118 -192.11417) (xy 383.358136 -190.988188) (xy 383.350738 -190.981342)
			(xy 383.332139 -190.973617) (xy 383.322068 -190.973202) (xy 380.017528 -190.973202) (xy 380.00813 -190.977266)
			(xy 379.98417 -190.987138) (xy 379.934252 -191.001046) (xy 379.88291 -191.008065) (xy 379.83109 -191.008065)
			(xy 379.779748 -191.001046) (xy 379.72983 -190.987138) (xy 379.70587 -190.977266) (xy 379.696472 -190.973202)
			(xy 378.395484 -190.973202) (xy 378.385415 -190.973628) (xy 378.366815 -190.981347) (xy 378.359416 -190.988188)
			(xy 377.38431 -191.963294) (xy 377.377497 -191.970638) (xy 377.369761 -191.989101) (xy 377.369324 -191.999108)
			(xy 377.369324 -192.249552) (xy 377.368858 -192.275629) (xy 377.360736 -192.327145) (xy 377.344653 -192.376756)
			(xy 377.321004 -192.423239) (xy 377.290374 -192.465449) (xy 377.272296 -192.484248) (xy 375.446544 -194.31)
			(xy 379.761748 -194.31) (xy 379.765819 -194.254378) (xy 379.777945 -194.199941) (xy 379.797868 -194.14785)
			(xy 379.825164 -194.099215) (xy 379.85925 -194.055072) (xy 379.899399 -194.016363) (xy 379.944757 -193.983912)
			(xy 379.994357 -193.958411) (xy 380.047141 -193.940404) (xy 380.101984 -193.930274) (xy 380.157718 -193.928237)
			(xy 380.213155 -193.934337) (xy 380.267112 -193.948443) (xy 380.318441 -193.970255) (xy 380.366047 -193.999309)
			(xy 380.408915 -194.034984) (xy 380.446132 -194.076521) (xy 380.476905 -194.123034) (xy 380.500577 -194.173531)
			(xy 380.516645 -194.226938) (xy 380.524765 -194.282114) (xy 380.525274 -194.31) (xy 380.524765 -194.337886)
			(xy 380.516645 -194.393062) (xy 380.500577 -194.446469) (xy 380.476905 -194.496966) (xy 380.446132 -194.543479)
			(xy 380.408915 -194.585016) (xy 380.366047 -194.620691) (xy 380.318441 -194.649745) (xy 380.267112 -194.671557)
			(xy 380.213155 -194.685663) (xy 380.157718 -194.691763) (xy 380.101984 -194.689726) (xy 380.047141 -194.679596)
			(xy 379.994357 -194.661589) (xy 379.944757 -194.636088) (xy 379.899399 -194.603637) (xy 379.85925 -194.564928)
			(xy 379.825164 -194.520785) (xy 379.797868 -194.47215) (xy 379.777945 -194.420059) (xy 379.765819 -194.365622)
			(xy 379.761748 -194.31) (xy 375.446544 -194.31) (xy 374.989852 -194.766692) (xy 374.983172 -194.774103)
			(xy 374.975594 -194.792539) (xy 374.97512 -194.802506) (xy 374.97512 -196.342) (xy 379.808738 -196.342)
			(xy 379.812809 -196.286378) (xy 379.824935 -196.231941) (xy 379.844858 -196.17985) (xy 379.872154 -196.131215)
			(xy 379.90624 -196.087072) (xy 379.946389 -196.048363) (xy 379.991747 -196.015912) (xy 380.041347 -195.990411)
			(xy 380.094131 -195.972404) (xy 380.148974 -195.962274) (xy 380.204708 -195.960237) (xy 380.260145 -195.966337)
			(xy 380.314102 -195.980443) (xy 380.365431 -196.002255) (xy 380.413037 -196.031309) (xy 380.455905 -196.066984)
			(xy 380.493122 -196.108521) (xy 380.523895 -196.155034) (xy 380.547567 -196.205531) (xy 380.563635 -196.258938)
			(xy 380.571755 -196.314114) (xy 380.572264 -196.342) (xy 380.571755 -196.369886) (xy 380.563635 -196.425062)
			(xy 380.547567 -196.478469) (xy 380.523895 -196.528966) (xy 380.493122 -196.575479) (xy 380.455905 -196.617016)
			(xy 380.413037 -196.652691) (xy 380.365431 -196.681745) (xy 380.314102 -196.703557) (xy 380.260145 -196.717663)
			(xy 380.204708 -196.723763) (xy 380.148974 -196.721726) (xy 380.094131 -196.711596) (xy 380.041347 -196.693589)
			(xy 379.991747 -196.668088) (xy 379.946389 -196.635637) (xy 379.90624 -196.596928) (xy 379.872154 -196.552785)
			(xy 379.844858 -196.50415) (xy 379.824935 -196.452059) (xy 379.812809 -196.397622) (xy 379.808738 -196.342)
			(xy 374.97512 -196.342) (xy 374.97512 -197.335394) (xy 378.916436 -197.335394) (xy 378.920507 -197.279772)
			(xy 378.932633 -197.225335) (xy 378.952556 -197.173244) (xy 378.979852 -197.124609) (xy 379.013938 -197.080466)
			(xy 379.054087 -197.041757) (xy 379.099445 -197.009306) (xy 379.149045 -196.983805) (xy 379.201829 -196.965798)
			(xy 379.256672 -196.955668) (xy 379.312406 -196.953631) (xy 379.367843 -196.959731) (xy 379.4218 -196.973837)
			(xy 379.473129 -196.995649) (xy 379.520735 -197.024703) (xy 379.563603 -197.060378) (xy 379.60082 -197.101915)
			(xy 379.631593 -197.148428) (xy 379.655265 -197.198925) (xy 379.671333 -197.252332) (xy 379.679453 -197.307508)
			(xy 379.679962 -197.335394) (xy 379.679549 -197.358) (xy 379.795784 -197.358) (xy 379.799855 -197.302378)
			(xy 379.811981 -197.247941) (xy 379.831904 -197.19585) (xy 379.8592 -197.147215) (xy 379.893286 -197.103072)
			(xy 379.933435 -197.064363) (xy 379.978793 -197.031912) (xy 380.028393 -197.006411) (xy 380.081177 -196.988404)
			(xy 380.13602 -196.978274) (xy 380.191754 -196.976237) (xy 380.247191 -196.982337) (xy 380.301148 -196.996443)
			(xy 380.352477 -197.018255) (xy 380.400083 -197.047309) (xy 380.442951 -197.082984) (xy 380.480168 -197.124521)
			(xy 380.510941 -197.171034) (xy 380.534613 -197.221531) (xy 380.550681 -197.274938) (xy 380.558801 -197.330114)
			(xy 380.55931 -197.358) (xy 380.558801 -197.385886) (xy 380.550681 -197.441062) (xy 380.534613 -197.494469)
			(xy 380.510941 -197.544966) (xy 380.480168 -197.591479) (xy 380.442951 -197.633016) (xy 380.400083 -197.668691)
			(xy 380.352477 -197.697745) (xy 380.301148 -197.719557) (xy 380.247191 -197.733663) (xy 380.191754 -197.739763)
			(xy 380.13602 -197.737726) (xy 380.081177 -197.727596) (xy 380.028393 -197.709589) (xy 379.978793 -197.684088)
			(xy 379.933435 -197.651637) (xy 379.893286 -197.612928) (xy 379.8592 -197.568785) (xy 379.831904 -197.52015)
			(xy 379.811981 -197.468059) (xy 379.799855 -197.413622) (xy 379.795784 -197.358) (xy 379.679549 -197.358)
			(xy 379.679453 -197.36328) (xy 379.671333 -197.418456) (xy 379.655265 -197.471863) (xy 379.631593 -197.52236)
			(xy 379.60082 -197.568873) (xy 379.563603 -197.61041) (xy 379.520735 -197.646085) (xy 379.473129 -197.675139)
			(xy 379.4218 -197.696951) (xy 379.367843 -197.711057) (xy 379.312406 -197.717157) (xy 379.256672 -197.71512)
			(xy 379.201829 -197.70499) (xy 379.149045 -197.686983) (xy 379.099445 -197.661482) (xy 379.054087 -197.629031)
			(xy 379.013938 -197.590322) (xy 378.979852 -197.546179) (xy 378.952556 -197.497544) (xy 378.932633 -197.445453)
			(xy 378.920507 -197.391016) (xy 378.916436 -197.335394) (xy 374.97512 -197.335394) (xy 374.97512 -198.374)
			(xy 379.855982 -198.374) (xy 379.860053 -198.318378) (xy 379.872179 -198.263941) (xy 379.892102 -198.21185)
			(xy 379.919398 -198.163215) (xy 379.953484 -198.119072) (xy 379.993633 -198.080363) (xy 380.038991 -198.047912)
			(xy 380.088591 -198.022411) (xy 380.141375 -198.004404) (xy 380.196218 -197.994274) (xy 380.251952 -197.992237)
			(xy 380.307389 -197.998337) (xy 380.361346 -198.012443) (xy 380.412675 -198.034255) (xy 380.460281 -198.063309)
			(xy 380.503149 -198.098984) (xy 380.540366 -198.140521) (xy 380.571139 -198.187034) (xy 380.594811 -198.237531)
			(xy 380.610879 -198.290938) (xy 380.618999 -198.346114) (xy 380.619508 -198.374) (xy 380.618999 -198.401886)
			(xy 380.610879 -198.457062) (xy 380.594811 -198.510469) (xy 380.571139 -198.560966) (xy 380.540366 -198.607479)
			(xy 380.503149 -198.649016) (xy 380.460281 -198.684691) (xy 380.412675 -198.713745) (xy 380.361346 -198.735557)
			(xy 380.307389 -198.749663) (xy 380.251952 -198.755763) (xy 380.196218 -198.753726) (xy 380.141375 -198.743596)
			(xy 380.088591 -198.725589) (xy 380.038991 -198.700088) (xy 379.993633 -198.667637) (xy 379.953484 -198.628928)
			(xy 379.919398 -198.584785) (xy 379.892102 -198.53615) (xy 379.872179 -198.484059) (xy 379.860053 -198.429622)
			(xy 379.855982 -198.374) (xy 374.97512 -198.374) (xy 374.97512 -199.39) (xy 379.794006 -199.39) (xy 379.798077 -199.334378)
			(xy 379.810203 -199.279941) (xy 379.830126 -199.22785) (xy 379.857422 -199.179215) (xy 379.891508 -199.135072)
			(xy 379.931657 -199.096363) (xy 379.977015 -199.063912) (xy 380.026615 -199.038411) (xy 380.079399 -199.020404)
			(xy 380.134242 -199.010274) (xy 380.189976 -199.008237) (xy 380.245413 -199.014337) (xy 380.29937 -199.028443)
			(xy 380.350699 -199.050255) (xy 380.398305 -199.079309) (xy 380.441173 -199.114984) (xy 380.47839 -199.156521)
			(xy 380.509163 -199.203034) (xy 380.532835 -199.253531) (xy 380.548903 -199.306938) (xy 380.557023 -199.362114)
			(xy 380.557532 -199.39) (xy 380.557023 -199.417886) (xy 380.548903 -199.473062) (xy 380.532835 -199.526469)
			(xy 380.509163 -199.576966) (xy 380.47839 -199.623479) (xy 380.441173 -199.665016) (xy 380.398305 -199.700691)
			(xy 380.350699 -199.729745) (xy 380.29937 -199.751557) (xy 380.245413 -199.765663) (xy 380.189976 -199.771763)
			(xy 380.134242 -199.769726) (xy 380.079399 -199.759596) (xy 380.026615 -199.741589) (xy 379.977015 -199.716088)
			(xy 379.931657 -199.683637) (xy 379.891508 -199.644928) (xy 379.857422 -199.600785) (xy 379.830126 -199.55215)
			(xy 379.810203 -199.500059) (xy 379.798077 -199.445622) (xy 379.794006 -199.39) (xy 374.97512 -199.39)
			(xy 374.97512 -200.099676) (xy 380.524764 -200.099676) (xy 380.528835 -200.044054) (xy 380.540961 -199.989617)
			(xy 380.560884 -199.937526) (xy 380.58818 -199.888891) (xy 380.622266 -199.844748) (xy 380.662415 -199.806039)
			(xy 380.707773 -199.773588) (xy 380.757373 -199.748087) (xy 380.810157 -199.73008) (xy 380.865 -199.71995)
			(xy 380.920734 -199.717913) (xy 380.976171 -199.724013) (xy 381.030128 -199.738119) (xy 381.081457 -199.759931)
			(xy 381.129063 -199.788985) (xy 381.171931 -199.82466) (xy 381.209148 -199.866197) (xy 381.239921 -199.91271)
			(xy 381.263593 -199.963207) (xy 381.279661 -200.016614) (xy 381.287781 -200.07179) (xy 381.28829 -200.099676)
			(xy 381.287781 -200.127562) (xy 381.279661 -200.182738) (xy 381.263593 -200.236145) (xy 381.239921 -200.286642)
			(xy 381.209148 -200.333155) (xy 381.171931 -200.374692) (xy 381.129063 -200.410367) (xy 381.081457 -200.439421)
			(xy 381.030128 -200.461233) (xy 380.976171 -200.475339) (xy 380.920734 -200.481439) (xy 380.865 -200.479402)
			(xy 380.810157 -200.469272) (xy 380.757373 -200.451265) (xy 380.707773 -200.425764) (xy 380.662415 -200.393313)
			(xy 380.622266 -200.354604) (xy 380.58818 -200.310461) (xy 380.560884 -200.261826) (xy 380.540961 -200.209735)
			(xy 380.528835 -200.155298) (xy 380.524764 -200.099676) (xy 374.97512 -200.099676) (xy 374.97512 -200.634092)
			(xy 379.021846 -200.634092) (xy 379.025917 -200.57847) (xy 379.038043 -200.524033) (xy 379.057966 -200.471942)
			(xy 379.085262 -200.423307) (xy 379.119348 -200.379164) (xy 379.159497 -200.340455) (xy 379.204855 -200.308004)
			(xy 379.254455 -200.282503) (xy 379.307239 -200.264496) (xy 379.362082 -200.254366) (xy 379.417816 -200.252329)
			(xy 379.473253 -200.258429) (xy 379.52721 -200.272535) (xy 379.578539 -200.294347) (xy 379.626145 -200.323401)
			(xy 379.669013 -200.359076) (xy 379.70623 -200.400613) (xy 379.737003 -200.447126) (xy 379.760675 -200.497623)
			(xy 379.776743 -200.55103) (xy 379.784863 -200.606206) (xy 379.785372 -200.634092) (xy 379.784863 -200.661978)
			(xy 379.776743 -200.717154) (xy 379.760675 -200.770561) (xy 379.737003 -200.821058) (xy 379.70623 -200.867571)
			(xy 379.669013 -200.909108) (xy 379.626145 -200.944783) (xy 379.578539 -200.973837) (xy 379.52721 -200.995649)
			(xy 379.473253 -201.009755) (xy 379.417816 -201.015855) (xy 379.362082 -201.013818) (xy 379.307239 -201.003688)
			(xy 379.254455 -200.985681) (xy 379.204855 -200.96018) (xy 379.159497 -200.927729) (xy 379.119348 -200.88902)
			(xy 379.085262 -200.844877) (xy 379.057966 -200.796242) (xy 379.038043 -200.744151) (xy 379.025917 -200.689714)
			(xy 379.021846 -200.634092) (xy 374.97512 -200.634092) (xy 374.97512 -201.284078) (xy 377.30506 -201.284078)
			(xy 377.309131 -201.228456) (xy 377.321257 -201.174019) (xy 377.34118 -201.121928) (xy 377.368476 -201.073293)
			(xy 377.402562 -201.02915) (xy 377.442711 -200.990441) (xy 377.488069 -200.95799) (xy 377.537669 -200.932489)
			(xy 377.590453 -200.914482) (xy 377.645296 -200.904352) (xy 377.70103 -200.902315) (xy 377.756467 -200.908415)
			(xy 377.810424 -200.922521) (xy 377.861753 -200.944333) (xy 377.909359 -200.973387) (xy 377.952227 -201.009062)
			(xy 377.989444 -201.050599) (xy 378.020217 -201.097112) (xy 378.043889 -201.147609) (xy 378.059957 -201.201016)
			(xy 378.068077 -201.256192) (xy 378.068586 -201.284078) (xy 378.068077 -201.311964) (xy 378.059957 -201.36714)
			(xy 378.043889 -201.420547) (xy 378.020217 -201.471044) (xy 377.989444 -201.517557) (xy 377.952227 -201.559094)
			(xy 377.909359 -201.594769) (xy 377.861753 -201.623823) (xy 377.810424 -201.645635) (xy 377.756467 -201.659741)
			(xy 377.70103 -201.665841) (xy 377.645296 -201.663804) (xy 377.590453 -201.653674) (xy 377.537669 -201.635667)
			(xy 377.488069 -201.610166) (xy 377.442711 -201.577715) (xy 377.402562 -201.539006) (xy 377.368476 -201.494863)
			(xy 377.34118 -201.446228) (xy 377.321257 -201.394137) (xy 377.309131 -201.3397) (xy 377.30506 -201.284078)
			(xy 374.97512 -201.284078) (xy 374.97512 -202.35418) (xy 379.391162 -202.35418) (xy 379.395233 -202.298558)
			(xy 379.407359 -202.244121) (xy 379.427282 -202.19203) (xy 379.454578 -202.143395) (xy 379.488664 -202.099252)
			(xy 379.528813 -202.060543) (xy 379.574171 -202.028092) (xy 379.623771 -202.002591) (xy 379.676555 -201.984584)
			(xy 379.731398 -201.974454) (xy 379.787132 -201.972417) (xy 379.842569 -201.978517) (xy 379.896526 -201.992623)
			(xy 379.947855 -202.014435) (xy 379.995461 -202.043489) (xy 380.038329 -202.079164) (xy 380.075546 -202.120701)
			(xy 380.106319 -202.167214) (xy 380.129991 -202.217711) (xy 380.146059 -202.271118) (xy 380.154179 -202.326294)
			(xy 380.154688 -202.35418) (xy 380.154179 -202.382066) (xy 380.151779 -202.398376) (xy 381.759712 -202.398376)
			(xy 381.763783 -202.342754) (xy 381.775909 -202.288317) (xy 381.795832 -202.236226) (xy 381.823128 -202.187591)
			(xy 381.857214 -202.143448) (xy 381.897363 -202.104739) (xy 381.942721 -202.072288) (xy 381.992321 -202.046787)
			(xy 382.045105 -202.02878) (xy 382.099948 -202.01865) (xy 382.155682 -202.016613) (xy 382.211119 -202.022713)
			(xy 382.265076 -202.036819) (xy 382.316405 -202.058631) (xy 382.364011 -202.087685) (xy 382.406879 -202.12336)
			(xy 382.444096 -202.164897) (xy 382.474869 -202.21141) (xy 382.498541 -202.261907) (xy 382.514609 -202.315314)
			(xy 382.522729 -202.37049) (xy 382.523238 -202.398376) (xy 382.522729 -202.426262) (xy 382.514609 -202.481438)
			(xy 382.498541 -202.534845) (xy 382.474869 -202.585342) (xy 382.444096 -202.631855) (xy 382.406879 -202.673392)
			(xy 382.364011 -202.709067) (xy 382.316405 -202.738121) (xy 382.265076 -202.759933) (xy 382.211119 -202.774039)
			(xy 382.155682 -202.780139) (xy 382.099948 -202.778102) (xy 382.045105 -202.767972) (xy 381.992321 -202.749965)
			(xy 381.942721 -202.724464) (xy 381.897363 -202.692013) (xy 381.857214 -202.653304) (xy 381.823128 -202.609161)
			(xy 381.795832 -202.560526) (xy 381.775909 -202.508435) (xy 381.763783 -202.453998) (xy 381.759712 -202.398376)
			(xy 380.151779 -202.398376) (xy 380.146059 -202.437242) (xy 380.129991 -202.490649) (xy 380.106319 -202.541146)
			(xy 380.075546 -202.587659) (xy 380.038329 -202.629196) (xy 379.995461 -202.664871) (xy 379.947855 -202.693925)
			(xy 379.896526 -202.715737) (xy 379.842569 -202.729843) (xy 379.787132 -202.735943) (xy 379.731398 -202.733906)
			(xy 379.676555 -202.723776) (xy 379.623771 -202.705769) (xy 379.574171 -202.680268) (xy 379.528813 -202.647817)
			(xy 379.488664 -202.609108) (xy 379.454578 -202.564965) (xy 379.427282 -202.51633) (xy 379.407359 -202.464239)
			(xy 379.395233 -202.409802) (xy 379.391162 -202.35418) (xy 374.97512 -202.35418) (xy 374.97512 -202.79995)
			(xy 378.439932 -202.79995) (xy 378.444003 -202.744328) (xy 378.456129 -202.689891) (xy 378.476052 -202.6378)
			(xy 378.503348 -202.589165) (xy 378.537434 -202.545022) (xy 378.577583 -202.506313) (xy 378.622941 -202.473862)
			(xy 378.672541 -202.448361) (xy 378.725325 -202.430354) (xy 378.780168 -202.420224) (xy 378.835902 -202.418187)
			(xy 378.891339 -202.424287) (xy 378.945296 -202.438393) (xy 378.996625 -202.460205) (xy 379.044231 -202.489259)
			(xy 379.087099 -202.524934) (xy 379.124316 -202.566471) (xy 379.155089 -202.612984) (xy 379.178761 -202.663481)
			(xy 379.194829 -202.716888) (xy 379.202949 -202.772064) (xy 379.203458 -202.79995) (xy 379.202949 -202.827836)
			(xy 379.194829 -202.883012) (xy 379.178761 -202.936419) (xy 379.155089 -202.986916) (xy 379.124316 -203.033429)
			(xy 379.087099 -203.074966) (xy 379.044231 -203.110641) (xy 378.996625 -203.139695) (xy 378.945296 -203.161507)
			(xy 378.891339 -203.175613) (xy 378.835902 -203.181713) (xy 378.780168 -203.179676) (xy 378.725325 -203.169546)
			(xy 378.672541 -203.151539) (xy 378.622941 -203.126038) (xy 378.577583 -203.093587) (xy 378.537434 -203.054878)
			(xy 378.503348 -203.010735) (xy 378.476052 -202.9621) (xy 378.456129 -202.910009) (xy 378.444003 -202.855572)
			(xy 378.439932 -202.79995) (xy 374.97512 -202.79995) (xy 374.97512 -205.590902) (xy 377.328682 -205.590902)
			(xy 377.332753 -205.53528) (xy 377.344879 -205.480843) (xy 377.364802 -205.428752) (xy 377.392098 -205.380117)
			(xy 377.426184 -205.335974) (xy 377.466333 -205.297265) (xy 377.511691 -205.264814) (xy 377.561291 -205.239313)
			(xy 377.614075 -205.221306) (xy 377.668918 -205.211176) (xy 377.724652 -205.209139) (xy 377.780089 -205.215239)
			(xy 377.834046 -205.229345) (xy 377.885375 -205.251157) (xy 377.932981 -205.280211) (xy 377.975849 -205.315886)
			(xy 378.013066 -205.357423) (xy 378.043839 -205.403936) (xy 378.067511 -205.454433) (xy 378.077008 -205.486)
			(xy 379.816612 -205.486) (xy 379.820683 -205.430378) (xy 379.832809 -205.375941) (xy 379.852732 -205.32385)
			(xy 379.880028 -205.275215) (xy 379.914114 -205.231072) (xy 379.954263 -205.192363) (xy 379.999621 -205.159912)
			(xy 380.049221 -205.134411) (xy 380.102005 -205.116404) (xy 380.156848 -205.106274) (xy 380.212582 -205.104237)
			(xy 380.268019 -205.110337) (xy 380.321976 -205.124443) (xy 380.373305 -205.146255) (xy 380.420911 -205.175309)
			(xy 380.463779 -205.210984) (xy 380.500996 -205.252521) (xy 380.531769 -205.299034) (xy 380.555441 -205.349531)
			(xy 380.571509 -205.402938) (xy 380.579629 -205.458114) (xy 380.580138 -205.486) (xy 380.579629 -205.513886)
			(xy 380.571509 -205.569062) (xy 380.555441 -205.622469) (xy 380.531769 -205.672966) (xy 380.500996 -205.719479)
			(xy 380.463779 -205.761016) (xy 380.420911 -205.796691) (xy 380.373305 -205.825745) (xy 380.321976 -205.847557)
			(xy 380.268019 -205.861663) (xy 380.212582 -205.867763) (xy 380.156848 -205.865726) (xy 380.102005 -205.855596)
			(xy 380.049221 -205.837589) (xy 379.999621 -205.812088) (xy 379.954263 -205.779637) (xy 379.914114 -205.740928)
			(xy 379.880028 -205.696785) (xy 379.852732 -205.64815) (xy 379.832809 -205.596059) (xy 379.820683 -205.541622)
			(xy 379.816612 -205.486) (xy 378.077008 -205.486) (xy 378.083579 -205.50784) (xy 378.091699 -205.563016)
			(xy 378.092208 -205.590902) (xy 378.091699 -205.618788) (xy 378.083579 -205.673964) (xy 378.067511 -205.727371)
			(xy 378.043839 -205.777868) (xy 378.013066 -205.824381) (xy 377.975849 -205.865918) (xy 377.932981 -205.901593)
			(xy 377.885375 -205.930647) (xy 377.834046 -205.952459) (xy 377.780089 -205.966565) (xy 377.724652 -205.972665)
			(xy 377.668918 -205.970628) (xy 377.614075 -205.960498) (xy 377.561291 -205.942491) (xy 377.511691 -205.91699)
			(xy 377.466333 -205.884539) (xy 377.426184 -205.84583) (xy 377.392098 -205.801687) (xy 377.364802 -205.753052)
			(xy 377.344879 -205.700961) (xy 377.332753 -205.646524) (xy 377.328682 -205.590902) (xy 374.97512 -205.590902)
			(xy 374.97512 -207.518) (xy 379.806706 -207.518) (xy 379.810777 -207.462378) (xy 379.822903 -207.407941)
			(xy 379.842826 -207.35585) (xy 379.870122 -207.307215) (xy 379.904208 -207.263072) (xy 379.944357 -207.224363)
			(xy 379.989715 -207.191912) (xy 380.039315 -207.166411) (xy 380.092099 -207.148404) (xy 380.146942 -207.138274)
			(xy 380.202676 -207.136237) (xy 380.258113 -207.142337) (xy 380.31207 -207.156443) (xy 380.363399 -207.178255)
			(xy 380.411005 -207.207309) (xy 380.453873 -207.242984) (xy 380.49109 -207.284521) (xy 380.521863 -207.331034)
			(xy 380.545535 -207.381531) (xy 380.561603 -207.434938) (xy 380.569723 -207.490114) (xy 380.570232 -207.518)
			(xy 380.569723 -207.545886) (xy 380.561603 -207.601062) (xy 380.545535 -207.654469) (xy 380.521863 -207.704966)
			(xy 380.49109 -207.751479) (xy 380.453873 -207.793016) (xy 380.411005 -207.828691) (xy 380.363399 -207.857745)
			(xy 380.31207 -207.879557) (xy 380.258113 -207.893663) (xy 380.202676 -207.899763) (xy 380.146942 -207.897726)
			(xy 380.092099 -207.887596) (xy 380.039315 -207.869589) (xy 379.989715 -207.844088) (xy 379.944357 -207.811637)
			(xy 379.904208 -207.772928) (xy 379.870122 -207.728785) (xy 379.842826 -207.68015) (xy 379.822903 -207.628059)
			(xy 379.810777 -207.573622) (xy 379.806706 -207.518) (xy 374.97512 -207.518) (xy 374.97512 -208.420052)
			(xy 378.864354 -208.420052) (xy 378.864354 -208.365548) (xy 378.87211 -208.3116) (xy 378.887464 -208.259305)
			(xy 378.910105 -208.209726) (xy 378.93957 -208.163875) (xy 378.97526 -208.122683) (xy 379.016449 -208.086989)
			(xy 379.062298 -208.05752) (xy 379.111875 -208.034876) (xy 379.164169 -208.019517) (xy 379.218117 -208.011756)
			(xy 379.245368 -208.011268) (xy 379.272317 -208.011677) (xy 379.325678 -208.019259) (xy 379.377441 -208.034276)
			(xy 379.426575 -208.056429) (xy 379.472102 -208.085277) (xy 379.513116 -208.120246) (xy 379.548799 -208.16064)
			(xy 379.578441 -208.205654) (xy 379.601453 -208.254391) (xy 379.609858 -208.28) (xy 379.614511 -208.293269)
			(xy 379.629862 -208.31681) (xy 379.651049 -208.335274) (xy 379.676468 -208.347263) (xy 379.704192 -208.351868)
			(xy 379.732122 -208.34874) (xy 379.75814 -208.338115) (xy 379.780277 -208.3208) (xy 379.788928 -208.309718)
			(xy 379.804341 -208.289161) (xy 379.839856 -208.252028) (xy 379.880034 -208.219999) (xy 379.924147 -208.193652)
			(xy 379.971397 -208.173464) (xy 380.020929 -208.1598) (xy 380.071847 -208.152909) (xy 380.097538 -208.152492)
			(xy 380.124787 -208.15298) (xy 380.178731 -208.160741) (xy 380.231021 -208.1761) (xy 380.280594 -208.198743)
			(xy 380.326439 -208.22821) (xy 380.367625 -208.263902) (xy 380.403312 -208.305091) (xy 380.432775 -208.35094)
			(xy 380.455414 -208.400514) (xy 380.470767 -208.452806) (xy 380.478522 -208.50675) (xy 380.478522 -208.56125)
			(xy 380.470767 -208.615194) (xy 380.455414 -208.667486) (xy 380.432775 -208.71706) (xy 380.403312 -208.762909)
			(xy 380.367625 -208.804098) (xy 380.326439 -208.83979) (xy 380.280594 -208.869257) (xy 380.231021 -208.8919)
			(xy 380.178731 -208.907259) (xy 380.124787 -208.91502) (xy 380.097538 -208.915508) (xy 380.070592 -208.91504)
			(xy 380.017235 -208.907461) (xy 379.965476 -208.892449) (xy 379.916345 -208.870302) (xy 379.87082 -208.841461)
			(xy 379.829807 -208.8065) (xy 379.794121 -208.766115) (xy 379.764475 -208.72111) (xy 379.741457 -208.672381)
			(xy 379.733048 -208.646776) (xy 379.728389 -208.633511) (xy 379.713037 -208.609974) (xy 379.69185 -208.591514)
			(xy 379.666433 -208.579527) (xy 379.638712 -208.574923) (xy 379.610785 -208.578049) (xy 379.584768 -208.588669)
			(xy 379.562631 -208.605979) (xy 379.553978 -208.617058) (xy 379.538554 -208.637607) (xy 379.503042 -208.674741)
			(xy 379.462867 -208.706772) (xy 379.418755 -208.733121) (xy 379.371507 -208.75331) (xy 379.321976 -208.766974)
			(xy 379.271059 -208.773867) (xy 379.245368 -208.774284) (xy 379.218117 -208.773844) (xy 379.164169 -208.766083)
			(xy 379.111875 -208.750724) (xy 379.062298 -208.72808) (xy 379.016449 -208.698611) (xy 378.97526 -208.662917)
			(xy 378.93957 -208.621725) (xy 378.910105 -208.575874) (xy 378.887464 -208.526295) (xy 378.87211 -208.474)
			(xy 378.864354 -208.420052) (xy 374.97512 -208.420052) (xy 374.97512 -209.042) (xy 374.974473 -209.070925)
			(xy 374.964399 -209.127891) (xy 374.94459 -209.182244) (xy 374.93067 -209.207608) (xy 374.927522 -209.213484)
			(xy 374.924038 -209.226346) (xy 374.923812 -209.233008) (xy 374.923812 -209.625184) (xy 377.160026 -209.625184)
			(xy 377.164097 -209.569562) (xy 377.176223 -209.515125) (xy 377.196146 -209.463034) (xy 377.223442 -209.414399)
			(xy 377.257528 -209.370256) (xy 377.297677 -209.331547) (xy 377.343035 -209.299096) (xy 377.392635 -209.273595)
			(xy 377.445419 -209.255588) (xy 377.500262 -209.245458) (xy 377.555996 -209.243421) (xy 377.611433 -209.249521)
			(xy 377.66539 -209.263627) (xy 377.716719 -209.285439) (xy 377.764325 -209.314493) (xy 377.807193 -209.350168)
			(xy 377.84441 -209.391705) (xy 377.875183 -209.438218) (xy 377.898855 -209.488715) (xy 377.914923 -209.542122)
			(xy 377.916082 -209.55) (xy 379.408942 -209.55) (xy 379.413013 -209.494378) (xy 379.425139 -209.439941)
			(xy 379.445062 -209.38785) (xy 379.472358 -209.339215) (xy 379.506444 -209.295072) (xy 379.546593 -209.256363)
			(xy 379.591951 -209.223912) (xy 379.641551 -209.198411) (xy 379.694335 -209.180404) (xy 379.749178 -209.170274)
			(xy 379.804912 -209.168237) (xy 379.860349 -209.174337) (xy 379.914306 -209.188443) (xy 379.965635 -209.210255)
			(xy 380.013241 -209.239309) (xy 380.056109 -209.274984) (xy 380.093326 -209.316521) (xy 380.124099 -209.363034)
			(xy 380.147771 -209.413531) (xy 380.163839 -209.466938) (xy 380.171959 -209.522114) (xy 380.172468 -209.55)
			(xy 380.171959 -209.577886) (xy 380.163839 -209.633062) (xy 380.147771 -209.686469) (xy 380.124099 -209.736966)
			(xy 380.093326 -209.783479) (xy 380.056109 -209.825016) (xy 380.013241 -209.860691) (xy 379.965635 -209.889745)
			(xy 379.914306 -209.911557) (xy 379.860349 -209.925663) (xy 379.804912 -209.931763) (xy 379.749178 -209.929726)
			(xy 379.694335 -209.919596) (xy 379.641551 -209.901589) (xy 379.591951 -209.876088) (xy 379.546593 -209.843637)
			(xy 379.506444 -209.804928) (xy 379.472358 -209.760785) (xy 379.445062 -209.71215) (xy 379.425139 -209.660059)
			(xy 379.413013 -209.605622) (xy 379.408942 -209.55) (xy 377.916082 -209.55) (xy 377.923043 -209.597298)
			(xy 377.923552 -209.625184) (xy 377.923043 -209.65307) (xy 377.914923 -209.708246) (xy 377.898855 -209.761653)
			(xy 377.875183 -209.81215) (xy 377.84441 -209.858663) (xy 377.807193 -209.9002) (xy 377.764325 -209.935875)
			(xy 377.716719 -209.964929) (xy 377.66539 -209.986741) (xy 377.611433 -210.000847) (xy 377.555996 -210.006947)
			(xy 377.500262 -210.00491) (xy 377.445419 -209.99478) (xy 377.392635 -209.976773) (xy 377.343035 -209.951272)
			(xy 377.297677 -209.918821) (xy 377.257528 -209.880112) (xy 377.223442 -209.835969) (xy 377.196146 -209.787334)
			(xy 377.176223 -209.735243) (xy 377.164097 -209.680806) (xy 377.160026 -209.625184) (xy 374.923812 -209.625184)
			(xy 374.923812 -209.736436) (xy 374.924295 -209.747183) (xy 374.933118 -209.766781) (xy 374.94083 -209.774282)
			(xy 375.004838 -209.832194) (xy 375.025158 -209.838798) (xy 375.03608 -209.837528) (xy 375.046021 -209.836562)
			(xy 375.06597 -209.835548) (xy 375.075958 -209.835496) (xy 375.103213 -209.835956) (xy 375.157167 -209.843708)
			(xy 375.20947 -209.859061) (xy 375.259055 -209.881701) (xy 375.304913 -209.911167) (xy 375.34611 -209.94686)
			(xy 375.381808 -209.988054) (xy 375.411279 -210.033908) (xy 375.433925 -210.083491) (xy 375.449283 -210.135791)
			(xy 375.457041 -210.189746) (xy 375.457041 -210.244254) (xy 375.449283 -210.298209) (xy 375.433925 -210.350509)
			(xy 375.411279 -210.400092) (xy 375.381808 -210.445946) (xy 375.34611 -210.48714) (xy 375.304913 -210.522833)
			(xy 375.259055 -210.552299) (xy 375.229048 -210.566) (xy 379.759716 -210.566) (xy 379.763787 -210.510378)
			(xy 379.775913 -210.455941) (xy 379.795836 -210.40385) (xy 379.823132 -210.355215) (xy 379.857218 -210.311072)
			(xy 379.897367 -210.272363) (xy 379.942725 -210.239912) (xy 379.992325 -210.214411) (xy 380.045109 -210.196404)
			(xy 380.099952 -210.186274) (xy 380.155686 -210.184237) (xy 380.211123 -210.190337) (xy 380.26508 -210.204443)
			(xy 380.316409 -210.226255) (xy 380.364015 -210.255309) (xy 380.406883 -210.290984) (xy 380.4441 -210.332521)
			(xy 380.474873 -210.379034) (xy 380.498545 -210.429531) (xy 380.514613 -210.482938) (xy 380.522733 -210.538114)
			(xy 380.523242 -210.566) (xy 380.522733 -210.593886) (xy 380.514613 -210.649062) (xy 380.498545 -210.702469)
			(xy 380.474873 -210.752966) (xy 380.4441 -210.799479) (xy 380.406883 -210.841016) (xy 380.364015 -210.876691)
			(xy 380.316409 -210.905745) (xy 380.26508 -210.927557) (xy 380.211123 -210.941663) (xy 380.155686 -210.947763)
			(xy 380.099952 -210.945726) (xy 380.045109 -210.935596) (xy 379.992325 -210.917589) (xy 379.942725 -210.892088)
			(xy 379.897367 -210.859637) (xy 379.857218 -210.820928) (xy 379.823132 -210.776785) (xy 379.795836 -210.72815)
			(xy 379.775913 -210.676059) (xy 379.763787 -210.621622) (xy 379.759716 -210.566) (xy 375.229048 -210.566)
			(xy 375.20947 -210.574939) (xy 375.157167 -210.590292) (xy 375.103213 -210.598044) (xy 375.075958 -210.598512)
			(xy 375.06597 -210.598459) (xy 375.046021 -210.597442) (xy 375.03608 -210.59648) (xy 375.025158 -210.59521)
			(xy 375.004838 -210.601814) (xy 374.94083 -210.659726) (xy 374.933208 -210.66729) (xy 374.924411 -210.686851)
			(xy 374.923812 -210.697572) (xy 374.923812 -211.810092) (xy 378.849634 -211.810092) (xy 378.853705 -211.75447)
			(xy 378.865831 -211.700033) (xy 378.885754 -211.647942) (xy 378.91305 -211.599307) (xy 378.947136 -211.555164)
			(xy 378.987285 -211.516455) (xy 379.032643 -211.484004) (xy 379.082243 -211.458503) (xy 379.135027 -211.440496)
			(xy 379.18987 -211.430366) (xy 379.245604 -211.428329) (xy 379.301041 -211.434429) (xy 379.354998 -211.448535)
			(xy 379.406327 -211.470347) (xy 379.453933 -211.499401) (xy 379.496801 -211.535076) (xy 379.534018 -211.576613)
			(xy 379.564791 -211.623126) (xy 379.588463 -211.673623) (xy 379.599107 -211.709) (xy 383.29184 -211.709)
			(xy 383.295911 -211.653378) (xy 383.308037 -211.598941) (xy 383.32796 -211.54685) (xy 383.355256 -211.498215)
			(xy 383.389342 -211.454072) (xy 383.429491 -211.415363) (xy 383.474849 -211.382912) (xy 383.524449 -211.357411)
			(xy 383.577233 -211.339404) (xy 383.632076 -211.329274) (xy 383.68781 -211.327237) (xy 383.743247 -211.333337)
			(xy 383.797204 -211.347443) (xy 383.848533 -211.369255) (xy 383.896139 -211.398309) (xy 383.939007 -211.433984)
			(xy 383.976224 -211.475521) (xy 384.006997 -211.522034) (xy 384.030669 -211.572531) (xy 384.046737 -211.625938)
			(xy 384.054857 -211.681114) (xy 384.055366 -211.709) (xy 384.054857 -211.736886) (xy 384.046737 -211.792062)
			(xy 384.030669 -211.845469) (xy 384.006997 -211.895966) (xy 383.976224 -211.942479) (xy 383.939007 -211.984016)
			(xy 383.896139 -212.019691) (xy 383.848533 -212.048745) (xy 383.797204 -212.070557) (xy 383.743247 -212.084663)
			(xy 383.68781 -212.090763) (xy 383.632076 -212.088726) (xy 383.577233 -212.078596) (xy 383.524449 -212.060589)
			(xy 383.474849 -212.035088) (xy 383.429491 -212.002637) (xy 383.389342 -211.963928) (xy 383.355256 -211.919785)
			(xy 383.32796 -211.87115) (xy 383.308037 -211.819059) (xy 383.295911 -211.764622) (xy 383.29184 -211.709)
			(xy 379.599107 -211.709) (xy 379.604531 -211.72703) (xy 379.612651 -211.782206) (xy 379.61316 -211.810092)
			(xy 379.612651 -211.837978) (xy 379.604531 -211.893154) (xy 379.588463 -211.946561) (xy 379.564791 -211.997058)
			(xy 379.534018 -212.043571) (xy 379.496801 -212.085108) (xy 379.453933 -212.120783) (xy 379.406327 -212.149837)
			(xy 379.354998 -212.171649) (xy 379.301041 -212.185755) (xy 379.245604 -212.191855) (xy 379.18987 -212.189818)
			(xy 379.135027 -212.179688) (xy 379.082243 -212.161681) (xy 379.032643 -212.13618) (xy 378.987285 -212.103729)
			(xy 378.947136 -212.06502) (xy 378.91305 -212.020877) (xy 378.885754 -211.972242) (xy 378.865831 -211.920151)
			(xy 378.853705 -211.865714) (xy 378.849634 -211.810092) (xy 374.923812 -211.810092) (xy 374.923812 -212.116416)
			(xy 374.924353 -212.126402) (xy 374.932071 -212.144829) (xy 374.938798 -212.15223) (xy 375.246646 -212.460078)
			(xy 377.30506 -212.460078) (xy 377.309131 -212.404456) (xy 377.321257 -212.350019) (xy 377.34118 -212.297928)
			(xy 377.368476 -212.249293) (xy 377.402562 -212.20515) (xy 377.442711 -212.166441) (xy 377.488069 -212.13399)
			(xy 377.537669 -212.108489) (xy 377.590453 -212.090482) (xy 377.645296 -212.080352) (xy 377.70103 -212.078315)
			(xy 377.756467 -212.084415) (xy 377.810424 -212.098521) (xy 377.861753 -212.120333) (xy 377.909359 -212.149387)
			(xy 377.952227 -212.185062) (xy 377.989444 -212.226599) (xy 378.020217 -212.273112) (xy 378.043889 -212.323609)
			(xy 378.059957 -212.377016) (xy 378.068077 -212.432192) (xy 378.068586 -212.460078) (xy 378.068077 -212.487964)
			(xy 378.059957 -212.54314) (xy 378.043889 -212.596547) (xy 378.020217 -212.647044) (xy 377.998217 -212.680296)
			(xy 378.744732 -212.680296) (xy 378.748803 -212.624674) (xy 378.760929 -212.570237) (xy 378.780852 -212.518146)
			(xy 378.808148 -212.469511) (xy 378.842234 -212.425368) (xy 378.882383 -212.386659) (xy 378.927741 -212.354208)
			(xy 378.977341 -212.328707) (xy 379.030125 -212.3107) (xy 379.084968 -212.30057) (xy 379.140702 -212.298533)
			(xy 379.196139 -212.304633) (xy 379.250096 -212.318739) (xy 379.301425 -212.340551) (xy 379.349031 -212.369605)
			(xy 379.391899 -212.40528) (xy 379.429116 -212.446817) (xy 379.459889 -212.49333) (xy 379.483561 -212.543827)
			(xy 379.499629 -212.597234) (xy 379.507749 -212.65241) (xy 379.508258 -212.680296) (xy 379.507749 -212.708182)
			(xy 379.499629 -212.763358) (xy 379.483561 -212.816765) (xy 379.459889 -212.867262) (xy 379.429116 -212.913775)
			(xy 379.391899 -212.955312) (xy 379.349031 -212.990987) (xy 379.301425 -213.020041) (xy 379.250096 -213.041853)
			(xy 379.196139 -213.055959) (xy 379.140702 -213.062059) (xy 379.084968 -213.060022) (xy 379.030125 -213.049892)
			(xy 378.977341 -213.031885) (xy 378.927741 -213.006384) (xy 378.882383 -212.973933) (xy 378.842234 -212.935224)
			(xy 378.808148 -212.891081) (xy 378.780852 -212.842446) (xy 378.760929 -212.790355) (xy 378.748803 -212.735918)
			(xy 378.744732 -212.680296) (xy 377.998217 -212.680296) (xy 377.989444 -212.693557) (xy 377.952227 -212.735094)
			(xy 377.909359 -212.770769) (xy 377.861753 -212.799823) (xy 377.810424 -212.821635) (xy 377.756467 -212.835741)
			(xy 377.70103 -212.841841) (xy 377.645296 -212.839804) (xy 377.590453 -212.829674) (xy 377.537669 -212.811667)
			(xy 377.488069 -212.786166) (xy 377.442711 -212.753715) (xy 377.402562 -212.715006) (xy 377.368476 -212.670863)
			(xy 377.34118 -212.622228) (xy 377.321257 -212.570137) (xy 377.309131 -212.5157) (xy 377.30506 -212.460078)
			(xy 375.246646 -212.460078) (xy 376.762518 -213.97595) (xy 378.439932 -213.97595) (xy 378.444003 -213.920328)
			(xy 378.456129 -213.865891) (xy 378.476052 -213.8138) (xy 378.503348 -213.765165) (xy 378.537434 -213.721022)
			(xy 378.577583 -213.682313) (xy 378.622941 -213.649862) (xy 378.672541 -213.624361) (xy 378.725325 -213.606354)
			(xy 378.780168 -213.596224) (xy 378.835902 -213.594187) (xy 378.891339 -213.600287) (xy 378.945296 -213.614393)
			(xy 378.996625 -213.636205) (xy 379.044231 -213.665259) (xy 379.087099 -213.700934) (xy 379.124316 -213.742471)
			(xy 379.155089 -213.788984) (xy 379.178761 -213.839481) (xy 379.194829 -213.892888) (xy 379.202949 -213.948064)
			(xy 379.203458 -213.97595) (xy 379.202949 -214.003836) (xy 379.194829 -214.059012) (xy 379.178761 -214.112419)
			(xy 379.155089 -214.162916) (xy 379.124316 -214.209429) (xy 379.087099 -214.250966) (xy 379.044231 -214.286641)
			(xy 378.996625 -214.315695) (xy 378.945296 -214.337507) (xy 378.891339 -214.351613) (xy 378.835902 -214.357713)
			(xy 378.780168 -214.355676) (xy 378.725325 -214.345546) (xy 378.672541 -214.327539) (xy 378.622941 -214.302038)
			(xy 378.577583 -214.269587) (xy 378.537434 -214.230878) (xy 378.503348 -214.186735) (xy 378.476052 -214.1381)
			(xy 378.456129 -214.086009) (xy 378.444003 -214.031572) (xy 378.439932 -213.97595) (xy 376.762518 -213.97595)
			(xy 378.546614 -215.760046) (xy 378.553957 -215.76686) (xy 378.57242 -215.774596) (xy 378.582428 -215.775032)
			(xy 381.801116 -215.775032) (xy 381.827194 -215.775495) (xy 381.878714 -215.783611) (xy 381.92833 -215.799689)
			(xy 381.974819 -215.823332) (xy 382.017036 -215.853957) (xy 382.035812 -215.87206) (xy 389.935974 -223.772222)
			(xy 389.954089 -223.791001) (xy 389.984779 -223.833197) (xy 390.008484 -223.879678) (xy 390.024618 -223.929297)
			(xy 390.032785 -223.98083) (xy 390.033256 -224.006918) (xy 390.033256 -229.37724) (xy 392.719558 -229.37724)
			(xy 392.723629 -229.321618) (xy 392.735755 -229.267181) (xy 392.755678 -229.21509) (xy 392.782974 -229.166455)
			(xy 392.81706 -229.122312) (xy 392.857209 -229.083603) (xy 392.902567 -229.051152) (xy 392.952167 -229.025651)
			(xy 393.004951 -229.007644) (xy 393.059794 -228.997514) (xy 393.115528 -228.995477) (xy 393.170965 -229.001577)
			(xy 393.224922 -229.015683) (xy 393.276251 -229.037495) (xy 393.323857 -229.066549) (xy 393.366725 -229.102224)
			(xy 393.403942 -229.143761) (xy 393.434715 -229.190274) (xy 393.458387 -229.240771) (xy 393.474455 -229.294178)
			(xy 393.482575 -229.349354) (xy 393.483084 -229.37724) (xy 393.482575 -229.405126) (xy 393.474455 -229.460302)
			(xy 393.458387 -229.513709) (xy 393.434715 -229.564206) (xy 393.403942 -229.610719) (xy 393.366725 -229.652256)
			(xy 393.323857 -229.687931) (xy 393.276251 -229.716985) (xy 393.224922 -229.738797) (xy 393.170965 -229.752903)
			(xy 393.115528 -229.759003) (xy 393.059794 -229.756966) (xy 393.004951 -229.746836) (xy 392.952167 -229.728829)
			(xy 392.902567 -229.703328) (xy 392.857209 -229.670877) (xy 392.81706 -229.632168) (xy 392.782974 -229.588025)
			(xy 392.755678 -229.53939) (xy 392.735755 -229.487299) (xy 392.723629 -229.432862) (xy 392.719558 -229.37724)
			(xy 390.033256 -229.37724) (xy 390.033256 -230.8479) (xy 390.033729 -230.857868) (xy 390.041295 -230.876314)
			(xy 390.047988 -230.883714) (xy 390.853422 -231.689148) (xy 390.860835 -231.695823) (xy 390.879271 -231.70339)
			(xy 390.889236 -231.70388) (xy 392.811762 -231.70388) (xy 392.820975 -231.703537) (xy 392.838229 -231.697085)
			(xy 392.85205 -231.684907) (xy 392.85672 -231.676956) (xy 392.905488 -231.585262) (xy 392.903964 -231.557322)
			(xy 392.89609 -231.545638) (xy 392.880666 -231.521881) (xy 392.856257 -231.470772) (xy 392.83968 -231.416613)
			(xy 392.8313 -231.360598) (xy 392.830812 -231.332278) (xy 392.831298 -231.305027) (xy 392.839054 -231.251079)
			(xy 392.854409 -231.198784) (xy 392.877051 -231.149207) (xy 392.906517 -231.103357) (xy 392.942208 -231.062166)
			(xy 392.983399 -231.026475) (xy 393.029249 -230.997009) (xy 393.078826 -230.974367) (xy 393.131121 -230.959012)
			(xy 393.185069 -230.951256) (xy 393.239571 -230.951256) (xy 393.293519 -230.959012) (xy 393.345814 -230.974367)
			(xy 393.395391 -230.997009) (xy 393.441241 -231.026475) (xy 393.482432 -231.062166) (xy 393.518123 -231.103357)
			(xy 393.547589 -231.149207) (xy 393.570231 -231.198784) (xy 393.585586 -231.251079) (xy 393.593342 -231.305027)
			(xy 393.593828 -231.332278) (xy 393.593238 -231.362698) (xy 393.583586 -231.422767) (xy 393.564524 -231.480543)
			(xy 393.536534 -231.534562) (xy 393.518898 -231.559354) (xy 393.511532 -231.56926) (xy 393.507722 -231.593898)
			(xy 393.542266 -231.696514) (xy 393.5603 -231.713786) (xy 393.572238 -231.717342) (xy 393.598772 -231.72562)
			(xy 393.648831 -231.749769) (xy 393.694169 -231.781917) (xy 393.714224 -231.801162) (xy 394.077444 -232.164382)
			(xy 394.095531 -232.183173) (xy 394.126163 -232.225384) (xy 394.149812 -232.271869) (xy 394.165894 -232.321482)
			(xy 394.174013 -232.373) (xy 394.174472 -232.399078) (xy 394.174472 -236.877098) (xy 394.174003 -236.903174)
			(xy 394.165875 -236.954687) (xy 394.149788 -237.004295) (xy 394.126139 -237.050775) (xy 394.095508 -237.092983)
			(xy 394.077444 -237.111794) (xy 391.33272 -239.856518) (xy 391.329231 -239.86013) (xy 391.323608 -239.86845)
			(xy 391.321544 -239.873028) (xy 390.426755 -242.033552) (xy 393.613384 -242.033552) (xy 393.617455 -241.97793)
			(xy 393.629581 -241.923493) (xy 393.649504 -241.871402) (xy 393.6768 -241.822767) (xy 393.710886 -241.778624)
			(xy 393.751035 -241.739915) (xy 393.796393 -241.707464) (xy 393.845993 -241.681963) (xy 393.898777 -241.663956)
			(xy 393.95362 -241.653826) (xy 394.009354 -241.651789) (xy 394.064791 -241.657889) (xy 394.118748 -241.671995)
			(xy 394.170077 -241.693807) (xy 394.217683 -241.722861) (xy 394.260551 -241.758536) (xy 394.297768 -241.800073)
			(xy 394.328541 -241.846586) (xy 394.352213 -241.897083) (xy 394.368281 -241.95049) (xy 394.376401 -242.005666)
			(xy 394.37691 -242.033552) (xy 394.376401 -242.061438) (xy 394.368281 -242.116614) (xy 394.352213 -242.170021)
			(xy 394.328541 -242.220518) (xy 394.297768 -242.267031) (xy 394.260551 -242.308568) (xy 394.217683 -242.344243)
			(xy 394.170077 -242.373297) (xy 394.118748 -242.395109) (xy 394.064791 -242.409215) (xy 394.009354 -242.415315)
			(xy 393.95362 -242.413278) (xy 393.898777 -242.403148) (xy 393.845993 -242.385141) (xy 393.796393 -242.35964)
			(xy 393.751035 -242.327189) (xy 393.710886 -242.28848) (xy 393.6768 -242.244337) (xy 393.649504 -242.195702)
			(xy 393.629581 -242.143611) (xy 393.617455 -242.089174) (xy 393.613384 -242.033552) (xy 390.426755 -242.033552)
			(xy 389.93318 -243.22532) (xy 389.931339 -243.230001) (xy 389.929299 -243.239851) (xy 389.929116 -243.244878)
			(xy 389.929116 -246.3419) (xy 393.825982 -246.3419) (xy 393.830053 -246.286278) (xy 393.842179 -246.231841)
			(xy 393.862102 -246.17975) (xy 393.889398 -246.131115) (xy 393.923484 -246.086972) (xy 393.963633 -246.048263)
			(xy 394.008991 -246.015812) (xy 394.058591 -245.990311) (xy 394.111375 -245.972304) (xy 394.166218 -245.962174)
			(xy 394.221952 -245.960137) (xy 394.277389 -245.966237) (xy 394.331346 -245.980343) (xy 394.382675 -246.002155)
			(xy 394.430281 -246.031209) (xy 394.473149 -246.066884) (xy 394.510366 -246.108421) (xy 394.541139 -246.154934)
			(xy 394.564811 -246.205431) (xy 394.580879 -246.258838) (xy 394.588999 -246.314014) (xy 394.589508 -246.3419)
			(xy 394.588999 -246.369786) (xy 394.580879 -246.424962) (xy 394.564811 -246.478369) (xy 394.541139 -246.528866)
			(xy 394.510366 -246.575379) (xy 394.473149 -246.616916) (xy 394.430281 -246.652591) (xy 394.382675 -246.681645)
			(xy 394.331346 -246.703457) (xy 394.277389 -246.717563) (xy 394.221952 -246.723663) (xy 394.166218 -246.721626)
			(xy 394.111375 -246.711496) (xy 394.058591 -246.693489) (xy 394.008991 -246.667988) (xy 393.963633 -246.635537)
			(xy 393.923484 -246.596828) (xy 393.889398 -246.552685) (xy 393.862102 -246.50405) (xy 393.842179 -246.451959)
			(xy 393.830053 -246.397522) (xy 393.825982 -246.3419) (xy 389.929116 -246.3419) (xy 389.929116 -251.741432)
			(xy 389.928463 -251.771636) (xy 389.917597 -251.831059) (xy 389.907526 -251.859542) (xy 389.904224 -251.868178)
			(xy 389.904224 -268.564106) (xy 389.904649 -268.574175) (xy 389.912367 -268.592776) (xy 389.91921 -268.600174)
			(xy 390.355582 -269.036546) (xy 390.362982 -269.043386) (xy 390.381581 -269.051099) (xy 390.39165 -269.051532)
		)
		(stroke
			(width 0)
			(type solid)
		)
		(fill yes)
		(layer "In5.Cu")
		(net "GND")
	)
	(gr_poly
		(pts
			(xy 230.915972 -321.442588) (xy 230.92283 -321.441572) (xy 230.934503 -321.438174) (xy 230.953068 -321.42253)
			(xy 230.95839 -321.4116) (xy 232.300272 -318.172084) (xy 232.302812 -318.159384) (xy 232.303066 -318.155574)
			(xy 232.303066 -313.672474) (xy 232.303496 -313.662407) (xy 232.311224 -313.643816) (xy 232.318052 -313.636406)
			(xy 232.326434 -313.628024) (xy 232.331424 -313.622526) (xy 232.338276 -313.609361) (xy 232.339896 -313.602116)
			(xy 232.340912 -313.592464) (xy 232.340912 -311.76087) (xy 232.340658 -311.756806) (xy 232.339059 -311.74494)
			(xy 232.326614 -311.724521) (xy 232.316782 -311.71769) (xy 232.264458 -311.686448) (xy 232.254494 -311.681149)
			(xy 232.232066 -311.67891) (xy 232.210838 -311.686487) (xy 232.202482 -311.694068) (xy 231.252522 -312.644028)
			(xy 231.245678 -312.651427) (xy 231.23795 -312.670025) (xy 231.237536 -312.680096) (xy 231.237536 -312.911236)
			(xy 231.237699 -312.917103) (xy 231.24039 -312.928523) (xy 231.24287 -312.933842) (xy 231.243124 -312.93435)
			(xy 231.256957 -312.961878) (xy 231.276531 -313.020292) (xy 231.286456 -313.081093) (xy 231.287066 -313.111896)
			(xy 231.28658 -313.139147) (xy 231.278824 -313.193095) (xy 231.263469 -313.24539) (xy 231.240827 -313.294967)
			(xy 231.211361 -313.340817) (xy 231.17567 -313.382008) (xy 231.134479 -313.417699) (xy 231.088629 -313.447165)
			(xy 231.039052 -313.469807) (xy 230.986757 -313.485162) (xy 230.932809 -313.492918) (xy 230.878307 -313.492918)
			(xy 230.824359 -313.485162) (xy 230.772064 -313.469807) (xy 230.722487 -313.447165) (xy 230.676637 -313.417699)
			(xy 230.635446 -313.382008) (xy 230.599755 -313.340817) (xy 230.570289 -313.294967) (xy 230.547647 -313.24539)
			(xy 230.532292 -313.193095) (xy 230.524536 -313.139147) (xy 230.52405 -313.111896) (xy 230.524689 -313.081192)
			(xy 230.53457 -313.020583) (xy 230.554028 -312.962339) (xy 230.567738 -312.934858) (xy 230.568246 -312.933842)
			(xy 230.57104 -312.928508) (xy 230.57358 -312.917332) (xy 230.57358 -312.5216) (xy 230.574066 -312.495513)
			(xy 230.582234 -312.443982) (xy 230.598367 -312.394365) (xy 230.622069 -312.347886) (xy 230.652755 -312.30569)
			(xy 230.670862 -312.286904) (xy 231.03459 -311.923176) (xy 231.040488 -311.916716) (xy 231.047902 -311.900887)
			(xy 231.04956 -311.883486) (xy 231.047798 -311.874916) (xy 231.022906 -311.777126) (xy 231.00411 -311.757822)
			(xy 230.997252 -311.75579) (xy 230.970781 -311.747973) (xy 230.920253 -311.725766) (xy 230.873453 -311.696509)
			(xy 230.831358 -311.660813) (xy 230.794847 -311.619422) (xy 230.764683 -311.573202) (xy 230.741494 -311.523117)
			(xy 230.725766 -311.470213) (xy 230.717826 -311.415594) (xy 230.717344 -311.387998) (xy 230.717807 -311.361157)
			(xy 230.725344 -311.308007) (xy 230.740254 -311.256437) (xy 230.762244 -311.207465) (xy 230.790879 -311.162058)
			(xy 230.825594 -311.121111) (xy 230.865705 -311.085433) (xy 230.910419 -311.055728) (xy 230.958855 -311.032582)
			(xy 230.984298 -311.024016) (xy 230.996998 -311.020206) (xy 231.015286 -311.000902) (xy 231.042972 -310.891174)
			(xy 231.036114 -310.866028) (xy 231.026716 -310.856376) (xy 231.006671 -310.834902) (xy 230.972754 -310.786942)
			(xy 230.946591 -310.734348) (xy 230.928801 -310.678365) (xy 230.919803 -310.620317) (xy 230.919274 -310.590946)
			(xy 230.91976 -310.563695) (xy 230.927516 -310.509747) (xy 230.942871 -310.457452) (xy 230.965513 -310.407875)
			(xy 230.994979 -310.362025) (xy 231.03067 -310.320834) (xy 231.071861 -310.285143) (xy 231.117711 -310.255677)
			(xy 231.167288 -310.233035) (xy 231.219583 -310.21768) (xy 231.273531 -310.209924) (xy 231.328033 -310.209924)
			(xy 231.381981 -310.21768) (xy 231.434276 -310.233035) (xy 231.483853 -310.255677) (xy 231.529703 -310.285143)
			(xy 231.570894 -310.320834) (xy 231.606585 -310.362025) (xy 231.636051 -310.407875) (xy 231.658693 -310.457452)
			(xy 231.674048 -310.509747) (xy 231.681804 -310.563695) (xy 231.68229 -310.590946) (xy 231.681786 -310.619079)
			(xy 231.673521 -310.674734) (xy 231.657178 -310.728573) (xy 231.633109 -310.779431) (xy 231.601837 -310.826205)
			(xy 231.564039 -310.867884) (xy 231.54259 -310.886094) (xy 231.530144 -310.896254) (xy 231.521508 -310.926988)
			(xy 231.559354 -311.032398) (xy 231.563336 -311.042052) (xy 231.577569 -311.057304) (xy 231.596678 -311.065675)
			(xy 231.607106 -311.06618) (xy 231.884982 -311.06618) (xy 231.892094 -311.065672) (xy 232.340404 -310.617362)
			(xy 232.340912 -310.61025) (xy 232.340912 -310.537352) (xy 232.340416 -310.52735) (xy 232.332748 -310.508873)
			(xy 232.318597 -310.494732) (xy 232.300114 -310.487077) (xy 232.290112 -310.486552) (xy 232.278428 -310.486552)
			(xy 232.268014 -310.491632) (xy 232.241918 -310.503723) (xy 232.187002 -310.520804) (xy 232.130146 -310.529464)
			(xy 232.10139 -310.529986) (xy 232.101136 -310.529986) (xy 232.073883 -310.529525) (xy 232.019931 -310.521773)
			(xy 231.967632 -310.506421) (xy 231.91805 -310.483782) (xy 231.872195 -310.454316) (xy 231.831001 -310.418625)
			(xy 231.795305 -310.377433) (xy 231.765836 -310.331581) (xy 231.743192 -310.282002) (xy 231.727835 -310.229704)
			(xy 231.720077 -310.175753) (xy 231.720077 -310.121247) (xy 231.727835 -310.067296) (xy 231.743192 -310.014998)
			(xy 231.765836 -309.965419) (xy 231.795305 -309.919567) (xy 231.831001 -309.878375) (xy 231.872195 -309.842684)
			(xy 231.91805 -309.813218) (xy 231.967632 -309.790579) (xy 232.019931 -309.775227) (xy 232.073883 -309.767475)
			(xy 232.101136 -309.76697) (xy 232.128779 -309.767478) (xy 232.18348 -309.77551) (xy 232.210102 -309.782972)
			(xy 232.21061 -309.782972) (xy 232.22204 -309.786274) (xy 232.245408 -309.78221) (xy 232.320338 -309.72633)
			(xy 232.329522 -309.718768) (xy 232.340252 -309.697569) (xy 232.340912 -309.68569) (xy 232.340912 -309.421276)
			(xy 232.340748 -309.415266) (xy 232.33793 -309.40358) (xy 232.335324 -309.398162) (xy 232.333484 -309.394688)
			(xy 232.32889 -309.388309) (xy 232.32618 -309.385462) (xy 232.318052 -309.377334) (xy 232.31121 -309.369934)
			(xy 232.303492 -309.351336) (xy 232.303066 -309.341266) (xy 232.303066 -308.99608) (xy 232.302705 -308.987064)
			(xy 232.296459 -308.970148) (xy 232.290874 -308.96306) (xy 232.285032 -308.956202) (xy 232.26903 -308.947312)
			(xy 232.259886 -308.946042) (xy 232.233183 -308.941483) (xy 232.181331 -308.925811) (xy 232.132216 -308.902962)
			(xy 232.086827 -308.873396) (xy 232.046076 -308.837706) (xy 232.010784 -308.796612) (xy 231.981658 -308.750939)
			(xy 231.959286 -308.701605) (xy 231.944117 -308.649603) (xy 231.936456 -308.595978) (xy 231.936457 -308.541808)
			(xy 231.94412 -308.488183) (xy 231.959291 -308.436182) (xy 231.981665 -308.386849) (xy 232.010792 -308.341176)
			(xy 232.046087 -308.300083) (xy 232.086838 -308.264396) (xy 232.132229 -308.234831) (xy 232.181344 -308.211984)
			(xy 232.233198 -308.196313) (xy 232.259886 -308.191662) (xy 232.268885 -308.189959) (xy 232.284899 -308.181104)
			(xy 232.291128 -308.17439) (xy 232.296716 -308.167786) (xy 232.303066 -308.150768) (xy 232.303066 -307.9115)
			(xy 232.302708 -307.902483) (xy 232.296467 -307.885562) (xy 232.290874 -307.87848) (xy 232.285032 -307.871622)
			(xy 232.26903 -307.862732) (xy 232.259886 -307.861462) (xy 232.233182 -307.856903) (xy 232.181326 -307.841231)
			(xy 232.132209 -307.818381) (xy 232.086817 -307.788813) (xy 232.046064 -307.753122) (xy 232.010769 -307.712026)
			(xy 231.981642 -307.666351) (xy 231.959269 -307.617014) (xy 231.944098 -307.56501) (xy 231.936437 -307.511382)
			(xy 231.936437 -307.45721) (xy 231.9441 -307.403582) (xy 231.959272 -307.351578) (xy 231.981646 -307.302242)
			(xy 232.010775 -307.256567) (xy 232.04607 -307.215472) (xy 232.086824 -307.179782) (xy 232.132216 -307.150215)
			(xy 232.181334 -307.127366) (xy 232.23319 -307.111695) (xy 232.259886 -307.107082) (xy 232.268885 -307.10538)
			(xy 232.284903 -307.096527) (xy 232.291128 -307.08981) (xy 232.296716 -307.083206) (xy 232.303066 -307.066188)
			(xy 232.303066 -291.450522) (xy 232.303505 -291.44046) (xy 232.311247 -291.421882) (xy 232.318052 -291.414454)
			(xy 232.461562 -291.270944) (xy 232.468404 -291.263544) (xy 232.476124 -291.244946) (xy 232.476548 -291.234876)
			(xy 232.476548 -281.450288) (xy 232.476121 -281.44022) (xy 232.468398 -281.421624) (xy 232.461562 -281.41422)
			(xy 232.024428 -280.977086) (xy 232.002283 -280.953881) (xy 231.966475 -280.900672) (xy 231.953308 -280.871422)
			(xy 231.949498 -280.862278) (xy 231.52354 -280.43632) (xy 231.516702 -280.428919) (xy 231.50899 -280.41032)
			(xy 231.508554 -280.400252) (xy 231.508554 -277.341076) (xy 231.508125 -277.331009) (xy 231.500399 -277.312415)
			(xy 231.493568 -277.305008) (xy 231.048814 -276.860254) (xy 231.017064 -276.85492) (xy 231.002332 -276.862286)
			(xy 230.976166 -276.874448) (xy 230.921086 -276.891636) (xy 230.864049 -276.900352) (xy 230.8352 -276.900894)
			(xy 230.834946 -276.900894) (xy 230.805395 -276.900342) (xy 230.746999 -276.891229) (xy 230.690709 -276.873215)
			(xy 230.637872 -276.846731) (xy 230.589755 -276.812412) (xy 230.547509 -276.771079) (xy 230.529384 -276.747732)
			(xy 230.521785 -276.738618) (xy 230.500594 -276.728001) (xy 230.488744 -276.727412) (xy 227.96373 -276.727412)
			(xy 227.953666 -276.727848) (xy 227.935081 -276.735582) (xy 227.927662 -276.742398) (xy 227.671376 -276.998684)
			(xy 227.664535 -277.006083) (xy 227.656819 -277.024683) (xy 227.65639 -277.034752) (xy 227.65639 -278.543512)
			(xy 227.656722 -278.551386) (xy 230.453438 -278.551386) (xy 230.454004 -278.522471) (xy 230.462721 -278.465301)
			(xy 230.479969 -278.410103) (xy 230.505351 -278.35814) (xy 230.538287 -278.310605) (xy 230.578022 -278.268587)
			(xy 230.600504 -278.250396) (xy 230.609304 -278.242781) (xy 230.619491 -278.221886) (xy 230.620062 -278.210264)
			(xy 230.620062 -278.130508) (xy 230.619517 -278.118876) (xy 230.609334 -278.097966) (xy 230.600504 -278.090376)
			(xy 230.57801 -278.072198) (xy 230.538275 -278.030175) (xy 230.505337 -277.982638) (xy 230.479951 -277.930674)
			(xy 230.462697 -277.875474) (xy 230.453971 -277.818303) (xy 230.453438 -277.789386) (xy 230.453924 -277.762135)
			(xy 230.46168 -277.708187) (xy 230.477035 -277.655892) (xy 230.499677 -277.606315) (xy 230.529143 -277.560465)
			(xy 230.564834 -277.519274) (xy 230.606025 -277.483583) (xy 230.651875 -277.454117) (xy 230.701452 -277.431475)
			(xy 230.753747 -277.41612) (xy 230.807695 -277.408364) (xy 230.862197 -277.408364) (xy 230.916145 -277.41612)
			(xy 230.96844 -277.431475) (xy 231.018017 -277.454117) (xy 231.063867 -277.483583) (xy 231.105058 -277.519274)
			(xy 231.140749 -277.560465) (xy 231.170215 -277.606315) (xy 231.192857 -277.655892) (xy 231.208212 -277.708187)
			(xy 231.215968 -277.762135) (xy 231.216454 -277.789386) (xy 231.215943 -277.818303) (xy 231.207215 -277.875476)
			(xy 231.189957 -277.930675) (xy 231.164564 -277.982638) (xy 231.131618 -278.030171) (xy 231.091875 -278.072187)
			(xy 231.069388 -278.090376) (xy 231.0606 -278.098001) (xy 231.050406 -278.118888) (xy 231.04983 -278.130508)
			(xy 231.04983 -278.210264) (xy 231.050336 -278.2219) (xy 231.060547 -278.24281) (xy 231.069388 -278.250396)
			(xy 231.091867 -278.268592) (xy 231.131603 -278.310611) (xy 231.164543 -278.358144) (xy 231.189932 -278.410105)
			(xy 231.207189 -278.465301) (xy 231.215919 -278.52247) (xy 231.216454 -278.551386) (xy 231.215968 -278.578637)
			(xy 231.208212 -278.632585) (xy 231.192857 -278.68488) (xy 231.170215 -278.734457) (xy 231.140749 -278.780307)
			(xy 231.105058 -278.821498) (xy 231.063867 -278.857189) (xy 231.018017 -278.886655) (xy 230.96844 -278.909297)
			(xy 230.916145 -278.924652) (xy 230.862197 -278.932408) (xy 230.807695 -278.932408) (xy 230.753747 -278.924652)
			(xy 230.701452 -278.909297) (xy 230.651875 -278.886655) (xy 230.606025 -278.857189) (xy 230.564834 -278.821498)
			(xy 230.529143 -278.780307) (xy 230.499677 -278.734457) (xy 230.477035 -278.68488) (xy 230.46168 -278.632585)
			(xy 230.453924 -278.578637) (xy 230.453438 -278.551386) (xy 227.656722 -278.551386) (xy 227.656815 -278.553582)
			(xy 227.664531 -278.572184) (xy 227.671376 -278.57958) (xy 228.471222 -279.379426) (xy 228.478073 -279.386822)
			(xy 228.48581 -279.405421) (xy 228.486208 -279.415494) (xy 228.486208 -279.567386) (xy 230.452928 -279.567386)
			(xy 230.456999 -279.511764) (xy 230.469125 -279.457327) (xy 230.489048 -279.405236) (xy 230.516344 -279.356601)
			(xy 230.55043 -279.312458) (xy 230.590579 -279.273749) (xy 230.635937 -279.241298) (xy 230.685537 -279.215797)
			(xy 230.738321 -279.19779) (xy 230.793164 -279.18766) (xy 230.848898 -279.185623) (xy 230.904335 -279.191723)
			(xy 230.958292 -279.205829) (xy 231.009621 -279.227641) (xy 231.057227 -279.256695) (xy 231.100095 -279.29237)
			(xy 231.137312 -279.333907) (xy 231.168085 -279.38042) (xy 231.191757 -279.430917) (xy 231.207825 -279.484324)
			(xy 231.215945 -279.5395) (xy 231.216454 -279.567386) (xy 231.215945 -279.595272) (xy 231.207825 -279.650448)
			(xy 231.191757 -279.703855) (xy 231.168085 -279.754352) (xy 231.137312 -279.800865) (xy 231.100095 -279.842402)
			(xy 231.057227 -279.878077) (xy 231.009621 -279.907131) (xy 230.958292 -279.928943) (xy 230.904335 -279.943049)
			(xy 230.848898 -279.949149) (xy 230.793164 -279.947112) (xy 230.738321 -279.936982) (xy 230.685537 -279.918975)
			(xy 230.635937 -279.893474) (xy 230.590579 -279.861023) (xy 230.55043 -279.822314) (xy 230.516344 -279.778171)
			(xy 230.489048 -279.729536) (xy 230.469125 -279.677445) (xy 230.456999 -279.623008) (xy 230.452928 -279.567386)
			(xy 228.486208 -279.567386) (xy 228.486208 -280.500582) (xy 228.815644 -280.500582) (xy 228.819715 -280.44496)
			(xy 228.831841 -280.390523) (xy 228.851764 -280.338432) (xy 228.87906 -280.289797) (xy 228.913146 -280.245654)
			(xy 228.953295 -280.206945) (xy 228.998653 -280.174494) (xy 229.048253 -280.148993) (xy 229.101037 -280.130986)
			(xy 229.15588 -280.120856) (xy 229.211614 -280.118819) (xy 229.267051 -280.124919) (xy 229.321008 -280.139025)
			(xy 229.372337 -280.160837) (xy 229.419943 -280.189891) (xy 229.462811 -280.225566) (xy 229.500028 -280.267103)
			(xy 229.530801 -280.313616) (xy 229.554473 -280.364113) (xy 229.570541 -280.41752) (xy 229.578661 -280.472696)
			(xy 229.57917 -280.500582) (xy 229.578661 -280.528468) (xy 229.570541 -280.583644) (xy 229.554473 -280.637051)
			(xy 229.530801 -280.687548) (xy 229.500028 -280.734061) (xy 229.462811 -280.775598) (xy 229.419943 -280.811273)
			(xy 229.372337 -280.840327) (xy 229.321008 -280.862139) (xy 229.267051 -280.876245) (xy 229.211614 -280.882345)
			(xy 229.15588 -280.880308) (xy 229.101037 -280.870178) (xy 229.048253 -280.852171) (xy 228.998653 -280.82667)
			(xy 228.953295 -280.794219) (xy 228.913146 -280.75551) (xy 228.87906 -280.711367) (xy 228.851764 -280.662732)
			(xy 228.831841 -280.610641) (xy 228.819715 -280.556204) (xy 228.815644 -280.500582) (xy 228.486208 -280.500582)
			(xy 228.486208 -287.864042) (xy 228.486639 -287.874109) (xy 228.494365 -287.892701) (xy 228.501194 -287.90011)
			(xy 228.725222 -288.124138) (xy 228.732071 -288.131535) (xy 228.739804 -288.150134) (xy 228.740208 -288.160206)
			(xy 228.740208 -290.03752) (xy 228.739782 -290.047589) (xy 228.732063 -290.066189) (xy 228.725222 -290.073588)
			(xy 228.501194 -290.297616) (xy 228.494351 -290.305016) (xy 228.486623 -290.323614) (xy 228.486208 -290.333684)
			(xy 228.486208 -290.37661) (xy 228.485784 -290.38668) (xy 228.478067 -290.405282) (xy 228.471222 -290.412678)
			(xy 228.398324 -290.485576) (xy 228.391824 -290.492591) (xy 228.38412 -290.510081) (xy 228.383338 -290.519612)
			(xy 228.380798 -290.588954) (xy 228.380798 -290.598411) (xy 228.386933 -290.616285) (xy 228.392736 -290.623752)
			(xy 228.39299 -290.624006) (xy 228.410346 -290.64487) (xy 228.439594 -290.690583) (xy 228.462063 -290.739983)
			(xy 228.477299 -290.79207) (xy 228.484992 -290.845791) (xy 228.485446 -290.872926) (xy 228.484958 -290.900177)
			(xy 228.477199 -290.954124) (xy 228.461842 -291.006418) (xy 228.4392 -291.055994) (xy 228.409734 -291.101844)
			(xy 228.374043 -291.143034) (xy 228.332854 -291.178726) (xy 228.287005 -291.208194) (xy 228.237429 -291.230838)
			(xy 228.185136 -291.246197) (xy 228.131189 -291.253958) (xy 228.103938 -291.254434) (xy 228.07657 -291.253958)
			(xy 228.022397 -291.246125) (xy 227.9699 -291.230629) (xy 227.920157 -291.207788) (xy 227.87419 -291.178071)
			(xy 227.85324 -291.160454) (xy 227.852986 -291.160454) (xy 227.852986 -291.1602) (xy 227.845898 -291.154617)
			(xy 227.828981 -291.14838) (xy 227.819966 -291.148008) (xy 227.75291 -291.148008) (xy 227.743893 -291.148366)
			(xy 227.726975 -291.154611) (xy 227.71989 -291.1602) (xy 227.719636 -291.160454) (xy 227.698704 -291.178094)
			(xy 227.652737 -291.207816) (xy 227.60299 -291.230654) (xy 227.550487 -291.246137) (xy 227.496308 -291.253948)
			(xy 227.468938 -291.254434) (xy 227.442459 -291.253984) (xy 227.390008 -291.246665) (xy 227.339074 -291.232162)
			(xy 227.290635 -291.210754) (xy 227.245622 -291.182853) (xy 227.2049 -291.148994) (xy 227.169253 -291.109829)
			(xy 227.139364 -291.066111) (xy 227.11581 -291.018678) (xy 227.099042 -290.968444) (xy 227.089382 -290.916374)
			(xy 227.087684 -290.889944) (xy 227.08743 -290.880292) (xy 227.079302 -290.862258) (xy 227.02139 -290.806886)
			(xy 227.014071 -290.800498) (xy 226.996044 -290.793303) (xy 226.986338 -290.792916) (xy 221.12859 -290.792916)
			(xy 221.11852 -290.792492) (xy 221.099917 -290.784776) (xy 221.092522 -290.77793) (xy 219.749624 -289.435032)
			(xy 219.742786 -289.427631) (xy 219.735072 -289.409032) (xy 219.734638 -289.398964) (xy 219.734638 -283.247846)
			(xy 219.734203 -283.237782) (xy 219.726468 -283.219197) (xy 219.719652 -283.211778) (xy 219.077794 -282.56992)
			(xy 219.070396 -282.563072) (xy 219.051798 -282.555337) (xy 219.041726 -282.554934) (xy 218.36253 -282.554934)
			(xy 218.343988 -282.562554) (xy 218.341702 -282.56484) (xy 214.307928 -282.56484) (xy 214.302266 -282.565006)
			(xy 214.291235 -282.567566) (xy 214.286084 -282.56992) (xy 214.25639 -282.583641) (xy 214.19461 -282.605141)
			(xy 214.130817 -282.619614) (xy 214.065807 -282.626879) (xy 214.0331 -282.627324) (xy 212.66023 -282.627324)
			(xy 212.650166 -282.62776) (xy 212.631582 -282.635495) (xy 212.624162 -282.64231) (xy 212.084158 -283.182314)
			(xy 212.077307 -283.18971) (xy 212.069569 -283.208309) (xy 212.069172 -283.218382) (xy 212.069172 -283.741622)
			(xy 212.068732 -283.774478) (xy 212.061383 -283.839778) (xy 212.046769 -283.903844) (xy 212.025073 -283.965871)
			(xy 211.996568 -284.025079) (xy 211.961613 -284.080723) (xy 211.920648 -284.132102) (xy 211.897722 -284.155642)
			(xy 211.559902 -284.493462) (xy 211.536337 -284.516357) (xy 211.484952 -284.557305) (xy 211.429308 -284.592248)
			(xy 211.370105 -284.620745) (xy 211.308084 -284.642439) (xy 211.244026 -284.657059) (xy 211.178735 -284.664419)
			(xy 211.145882 -284.664912) (xy 210.833716 -284.664912) (xy 210.822014 -284.665498) (xy 210.801028 -284.675859)
			(xy 210.786804 -284.694445) (xy 210.783932 -284.705806) (xy 210.778445 -284.731493) (xy 210.761352 -284.78116)
			(xy 210.737603 -284.82801) (xy 210.707648 -284.871157) (xy 210.672053 -284.909783) (xy 210.631493 -284.943158)
			(xy 210.586736 -284.970649) (xy 210.538628 -284.991735) (xy 210.488082 -285.006018) (xy 210.436053 -285.013227)
			(xy 210.40979 -285.013654) (xy 210.382538 -285.013168) (xy 210.328589 -285.00541) (xy 210.276293 -284.990055)
			(xy 210.226714 -284.967414) (xy 210.180861 -284.937948) (xy 210.139669 -284.902257) (xy 210.103974 -284.861067)
			(xy 210.074504 -284.815218) (xy 210.051858 -284.765641) (xy 210.036498 -284.713346) (xy 210.028735 -284.659398)
			(xy 210.028282 -284.632146) (xy 210.029017 -284.5982) (xy 210.041018 -284.531378) (xy 210.052158 -284.499304)
			(xy 210.046316 -284.493462) (xy 209.86115 -284.308296) (xy 209.838255 -284.284731) (xy 209.797306 -284.233346)
			(xy 209.762364 -284.177703) (xy 209.733866 -284.118499) (xy 209.712172 -284.056479) (xy 209.697553 -283.99242)
			(xy 209.690193 -283.927129) (xy 209.6897 -283.894276) (xy 209.6897 -283.527754) (xy 209.690203 -283.493164)
			(xy 209.698344 -283.424466) (xy 209.714521 -283.357204) (xy 209.738508 -283.292316) (xy 209.76997 -283.230705)
			(xy 209.808471 -283.173229) (xy 209.853473 -283.120688) (xy 209.90435 -283.073813) (xy 209.960395 -283.033256)
			(xy 210.020826 -282.999584) (xy 210.084803 -282.973263) (xy 210.151434 -282.954661) (xy 210.219793 -282.944037)
			(xy 210.254342 -282.942284) (xy 210.263853 -282.941562) (xy 210.28135 -282.934) (xy 210.288378 -282.927552)
			(xy 210.309714 -282.906216) (xy 210.316557 -282.898817) (xy 210.324274 -282.880218) (xy 210.3247 -282.870148)
			(xy 210.3247 -282.80741) (xy 210.325083 -282.777153) (xy 210.331323 -282.716962) (xy 210.337146 -282.687268)
			(xy 210.339432 -282.675838) (xy 210.334098 -282.653994) (xy 210.276948 -282.583636) (xy 210.269329 -282.575243)
			(xy 210.248895 -282.565498) (xy 210.237578 -282.56484) (xy 210.083654 -282.56484) (xy 210.073867 -282.565286)
			(xy 210.055709 -282.572599) (xy 210.048348 -282.579064) (xy 209.378804 -283.225494) (xy 209.371754 -283.232946)
			(xy 209.36377 -283.251821) (xy 209.36331 -283.26207) (xy 209.36331 -286.005524) (xy 209.363738 -286.015592)
			(xy 209.371459 -286.034189) (xy 209.378296 -286.041592) (xy 210.193128 -286.856424) (xy 210.19359 -286.8663)
			(xy 210.201037 -286.884595) (xy 210.207606 -286.891984) (xy 211.408772 -288.09315) (xy 211.415613 -288.10055)
			(xy 211.423334 -288.119148) (xy 211.423758 -288.129218) (xy 211.423758 -291.639549) (xy 220.096598 -291.639549)
			(xy 220.096598 -291.585051) (xy 220.104354 -291.531107) (xy 220.119708 -291.478816) (xy 220.142347 -291.429242)
			(xy 220.17181 -291.383395) (xy 220.207499 -291.342207) (xy 220.248685 -291.306518) (xy 220.294532 -291.277052)
			(xy 220.344105 -291.254412) (xy 220.396395 -291.239057) (xy 220.450339 -291.231299) (xy 220.477588 -291.230812)
			(xy 220.504958 -291.231282) (xy 220.559137 -291.239099) (xy 220.61164 -291.254587) (xy 220.661387 -291.277427)
			(xy 220.707354 -291.307151) (xy 220.728286 -291.324792) (xy 220.72854 -291.325046) (xy 220.735636 -291.330619)
			(xy 220.752546 -291.336873) (xy 220.76156 -291.337238) (xy 220.828616 -291.337238) (xy 220.837633 -291.336881)
			(xy 220.854549 -291.330632) (xy 220.861636 -291.325046) (xy 220.861636 -291.324792) (xy 220.86189 -291.324792)
			(xy 220.882814 -291.307143) (xy 220.928789 -291.277433) (xy 220.978539 -291.254599) (xy 221.031041 -291.23911)
			(xy 221.085218 -291.231285) (xy 221.112588 -291.230812) (xy 221.139843 -291.231234) (xy 221.193798 -291.23899)
			(xy 221.2461 -291.254346) (xy 221.295684 -291.276989) (xy 221.341541 -291.306458) (xy 221.382738 -291.342154)
			(xy 221.418435 -291.383349) (xy 221.447905 -291.429205) (xy 221.47055 -291.478789) (xy 221.485907 -291.53109)
			(xy 221.493665 -291.585045) (xy 221.493665 -291.639555) (xy 221.485907 -291.69351) (xy 221.47055 -291.745811)
			(xy 221.447905 -291.795395) (xy 221.418435 -291.841251) (xy 221.382738 -291.882446) (xy 221.341541 -291.918142)
			(xy 221.295684 -291.947611) (xy 221.2461 -291.970254) (xy 221.193798 -291.98561) (xy 221.139843 -291.993366)
			(xy 221.112588 -291.993828) (xy 221.085217 -291.993387) (xy 221.031036 -291.985565) (xy 220.978532 -291.970072)
			(xy 220.928785 -291.947224) (xy 220.88282 -291.917493) (xy 220.86189 -291.899848) (xy 220.861636 -291.899594)
			(xy 220.854544 -291.894016) (xy 220.837631 -291.887764) (xy 220.828616 -291.887402) (xy 220.76156 -291.887402)
			(xy 220.752541 -291.88774) (xy 220.735624 -291.894001) (xy 220.72854 -291.899594) (xy 220.72854 -291.899848)
			(xy 220.728286 -291.899848) (xy 220.707326 -291.917452) (xy 220.661361 -291.947171) (xy 220.611621 -291.970015)
			(xy 220.559126 -291.985514) (xy 220.504955 -291.99335) (xy 220.477588 -291.993828) (xy 220.450339 -291.993301)
			(xy 220.396395 -291.985543) (xy 220.344105 -291.970188) (xy 220.294532 -291.947548) (xy 220.248685 -291.918082)
			(xy 220.207499 -291.882393) (xy 220.17181 -291.841205) (xy 220.142347 -291.795358) (xy 220.119708 -291.745784)
			(xy 220.104354 -291.693493) (xy 220.096598 -291.639549) (xy 211.423758 -291.639549) (xy 211.423758 -306.744116)
			(xy 221.949516 -306.744116) (xy 221.953587 -306.688494) (xy 221.965713 -306.634057) (xy 221.985636 -306.581966)
			(xy 222.012932 -306.533331) (xy 222.047018 -306.489188) (xy 222.087167 -306.450479) (xy 222.132525 -306.418028)
			(xy 222.182125 -306.392527) (xy 222.234909 -306.37452) (xy 222.289752 -306.36439) (xy 222.345486 -306.362353)
			(xy 222.400923 -306.368453) (xy 222.45488 -306.382559) (xy 222.506209 -306.404371) (xy 222.553815 -306.433425)
			(xy 222.596683 -306.4691) (xy 222.6339 -306.510637) (xy 222.664673 -306.55715) (xy 222.688345 -306.607647)
			(xy 222.704413 -306.661054) (xy 222.712533 -306.71623) (xy 222.713042 -306.744116) (xy 222.712533 -306.772002)
			(xy 222.71032 -306.787042) (xy 229.223568 -306.787042) (xy 229.227639 -306.73142) (xy 229.239765 -306.676983)
			(xy 229.259688 -306.624892) (xy 229.286984 -306.576257) (xy 229.32107 -306.532114) (xy 229.361219 -306.493405)
			(xy 229.406577 -306.460954) (xy 229.456177 -306.435453) (xy 229.508961 -306.417446) (xy 229.563804 -306.407316)
			(xy 229.619538 -306.405279) (xy 229.674975 -306.411379) (xy 229.728932 -306.425485) (xy 229.780261 -306.447297)
			(xy 229.827867 -306.476351) (xy 229.870735 -306.512026) (xy 229.907952 -306.553563) (xy 229.938725 -306.600076)
			(xy 229.962397 -306.650573) (xy 229.978465 -306.70398) (xy 229.986585 -306.759156) (xy 229.987094 -306.787042)
			(xy 229.986585 -306.814928) (xy 229.978465 -306.870104) (xy 229.962397 -306.923511) (xy 229.938725 -306.974008)
			(xy 229.907952 -307.020521) (xy 229.870735 -307.062058) (xy 229.827867 -307.097733) (xy 229.780261 -307.126787)
			(xy 229.728932 -307.148599) (xy 229.674975 -307.162705) (xy 229.619538 -307.168805) (xy 229.563804 -307.166768)
			(xy 229.508961 -307.156638) (xy 229.456177 -307.138631) (xy 229.406577 -307.11313) (xy 229.361219 -307.080679)
			(xy 229.32107 -307.04197) (xy 229.286984 -306.997827) (xy 229.259688 -306.949192) (xy 229.239765 -306.897101)
			(xy 229.227639 -306.842664) (xy 229.223568 -306.787042) (xy 222.71032 -306.787042) (xy 222.704413 -306.827178)
			(xy 222.688345 -306.880585) (xy 222.664673 -306.931082) (xy 222.6339 -306.977595) (xy 222.596683 -307.019132)
			(xy 222.553815 -307.054807) (xy 222.506209 -307.083861) (xy 222.45488 -307.105673) (xy 222.400923 -307.119779)
			(xy 222.345486 -307.125879) (xy 222.289752 -307.123842) (xy 222.234909 -307.113712) (xy 222.182125 -307.095705)
			(xy 222.132525 -307.070204) (xy 222.087167 -307.037753) (xy 222.047018 -306.999044) (xy 222.012932 -306.954901)
			(xy 221.985636 -306.906266) (xy 221.965713 -306.854175) (xy 221.953587 -306.799738) (xy 221.949516 -306.744116)
			(xy 211.423758 -306.744116) (xy 211.423758 -307.053996) (xy 211.424774 -307.063648) (xy 211.426403 -307.070891)
			(xy 211.433248 -307.084057) (xy 211.438236 -307.089556) (xy 211.795106 -307.446426) (xy 226.875084 -307.446426)
			(xy 226.879155 -307.390804) (xy 226.891281 -307.336367) (xy 226.911204 -307.284276) (xy 226.9385 -307.235641)
			(xy 226.972586 -307.191498) (xy 227.012735 -307.152789) (xy 227.058093 -307.120338) (xy 227.107693 -307.094837)
			(xy 227.160477 -307.07683) (xy 227.21532 -307.0667) (xy 227.271054 -307.064663) (xy 227.326491 -307.070763)
			(xy 227.380448 -307.084869) (xy 227.431777 -307.106681) (xy 227.479383 -307.135735) (xy 227.522251 -307.17141)
			(xy 227.559468 -307.212947) (xy 227.590241 -307.25946) (xy 227.613913 -307.309957) (xy 227.629981 -307.363364)
			(xy 227.638101 -307.41854) (xy 227.63861 -307.446426) (xy 227.638101 -307.474312) (xy 227.629981 -307.529488)
			(xy 227.613913 -307.582895) (xy 227.590241 -307.633392) (xy 227.559468 -307.679905) (xy 227.522251 -307.721442)
			(xy 227.479383 -307.757117) (xy 227.431777 -307.786171) (xy 227.380448 -307.807983) (xy 227.326491 -307.822089)
			(xy 227.271054 -307.828189) (xy 227.21532 -307.826152) (xy 227.160477 -307.816022) (xy 227.107693 -307.798015)
			(xy 227.058093 -307.772514) (xy 227.012735 -307.740063) (xy 226.972586 -307.701354) (xy 226.9385 -307.657211)
			(xy 226.911204 -307.608576) (xy 226.891281 -307.556485) (xy 226.879155 -307.502048) (xy 226.875084 -307.446426)
			(xy 211.795106 -307.446426) (xy 212.096096 -307.747416) (xy 212.101594 -307.752406) (xy 212.114759 -307.759255)
			(xy 212.122004 -307.760878) (xy 212.131656 -307.761894) (xy 217.961972 -307.761894) (xy 217.972037 -307.76233)
			(xy 217.990623 -307.770062) (xy 217.99804 -307.77688) (xy 218.22156 -308.0004) (xy 218.22791 -308.00802)
			(xy 218.252548 -308.044596) (xy 218.256358 -308.047644) (xy 218.268042 -308.05247) (xy 218.344927 -308.084434)
			(xy 218.495791 -308.154939) (xy 218.642998 -308.232791) (xy 218.786191 -308.317801) (xy 218.913647 -308.402228)
			(xy 227.932994 -308.402228) (xy 227.937065 -308.346606) (xy 227.949191 -308.292169) (xy 227.969114 -308.240078)
			(xy 227.99641 -308.191443) (xy 228.030496 -308.1473) (xy 228.070645 -308.108591) (xy 228.116003 -308.07614)
			(xy 228.165603 -308.050639) (xy 228.218387 -308.032632) (xy 228.27323 -308.022502) (xy 228.328964 -308.020465)
			(xy 228.384401 -308.026565) (xy 228.438358 -308.040671) (xy 228.489687 -308.062483) (xy 228.537293 -308.091537)
			(xy 228.580161 -308.127212) (xy 228.617378 -308.168749) (xy 228.648151 -308.215262) (xy 228.671823 -308.265759)
			(xy 228.687891 -308.319166) (xy 228.696011 -308.374342) (xy 228.69652 -308.402228) (xy 228.696011 -308.430114)
			(xy 228.687891 -308.48529) (xy 228.671823 -308.538697) (xy 228.648151 -308.589194) (xy 228.617378 -308.635707)
			(xy 228.580161 -308.677244) (xy 228.537293 -308.712919) (xy 228.489687 -308.741973) (xy 228.438358 -308.763785)
			(xy 228.384401 -308.777891) (xy 228.328964 -308.783991) (xy 228.27323 -308.781954) (xy 228.218387 -308.771824)
			(xy 228.165603 -308.753817) (xy 228.116003 -308.728316) (xy 228.070645 -308.695865) (xy 228.030496 -308.657156)
			(xy 227.99641 -308.613013) (xy 227.969114 -308.564378) (xy 227.949191 -308.512287) (xy 227.937065 -308.45785)
			(xy 227.932994 -308.402228) (xy 218.913647 -308.402228) (xy 218.925022 -308.409763) (xy 219.059153 -308.508454)
			(xy 219.188259 -308.613632) (xy 219.312026 -308.725044) (xy 219.430154 -308.842419) (xy 219.542355 -308.965471)
			(xy 219.585858 -309.018178) (xy 229.941118 -309.018178) (xy 229.945189 -308.962556) (xy 229.957315 -308.908119)
			(xy 229.977238 -308.856028) (xy 230.004534 -308.807393) (xy 230.03862 -308.76325) (xy 230.078769 -308.724541)
			(xy 230.124127 -308.69209) (xy 230.173727 -308.666589) (xy 230.226511 -308.648582) (xy 230.281354 -308.638452)
			(xy 230.337088 -308.636415) (xy 230.392525 -308.642515) (xy 230.446482 -308.656621) (xy 230.497811 -308.678433)
			(xy 230.545417 -308.707487) (xy 230.588285 -308.743162) (xy 230.625502 -308.784699) (xy 230.656275 -308.831212)
			(xy 230.679947 -308.881709) (xy 230.696015 -308.935116) (xy 230.704135 -308.990292) (xy 230.704644 -309.018178)
			(xy 230.704135 -309.046064) (xy 230.696015 -309.10124) (xy 230.679947 -309.154647) (xy 230.656275 -309.205144)
			(xy 230.625502 -309.251657) (xy 230.588285 -309.293194) (xy 230.545417 -309.328869) (xy 230.497811 -309.357923)
			(xy 230.446482 -309.379735) (xy 230.392525 -309.393841) (xy 230.337088 -309.399941) (xy 230.281354 -309.397904)
			(xy 230.226511 -309.387774) (xy 230.173727 -309.369767) (xy 230.124127 -309.344266) (xy 230.078769 -309.311815)
			(xy 230.03862 -309.273106) (xy 230.004534 -309.228963) (xy 229.977238 -309.180328) (xy 229.957315 -309.128237)
			(xy 229.945189 -309.0738) (xy 229.941118 -309.018178) (xy 219.585858 -309.018178) (xy 219.648358 -309.093901)
			(xy 219.747904 -309.227399) (xy 219.840752 -309.365638) (xy 219.926676 -309.508284) (xy 220.005468 -309.654991)
			(xy 220.076937 -309.805401) (xy 220.119812 -309.908448) (xy 226.32111 -309.908448) (xy 226.325181 -309.852826)
			(xy 226.337307 -309.798389) (xy 226.35723 -309.746298) (xy 226.384526 -309.697663) (xy 226.418612 -309.65352)
			(xy 226.458761 -309.614811) (xy 226.504119 -309.58236) (xy 226.553719 -309.556859) (xy 226.606503 -309.538852)
			(xy 226.661346 -309.528722) (xy 226.71708 -309.526685) (xy 226.772517 -309.532785) (xy 226.826474 -309.546891)
			(xy 226.877803 -309.568703) (xy 226.925409 -309.597757) (xy 226.968277 -309.633432) (xy 227.005494 -309.674969)
			(xy 227.036267 -309.721482) (xy 227.047351 -309.745126) (xy 228.036626 -309.745126) (xy 228.040697 -309.689504)
			(xy 228.052823 -309.635067) (xy 228.072746 -309.582976) (xy 228.100042 -309.534341) (xy 228.134128 -309.490198)
			(xy 228.174277 -309.451489) (xy 228.219635 -309.419038) (xy 228.269235 -309.393537) (xy 228.322019 -309.37553)
			(xy 228.376862 -309.3654) (xy 228.432596 -309.363363) (xy 228.488033 -309.369463) (xy 228.54199 -309.383569)
			(xy 228.593319 -309.405381) (xy 228.640925 -309.434435) (xy 228.683793 -309.47011) (xy 228.72101 -309.511647)
			(xy 228.751783 -309.55816) (xy 228.775455 -309.608657) (xy 228.791523 -309.662064) (xy 228.799643 -309.71724)
			(xy 228.800152 -309.745126) (xy 228.799643 -309.773012) (xy 228.791523 -309.828188) (xy 228.775455 -309.881595)
			(xy 228.751783 -309.932092) (xy 228.72101 -309.978605) (xy 228.683793 -310.020142) (xy 228.640925 -310.055817)
			(xy 228.593319 -310.084871) (xy 228.54199 -310.106683) (xy 228.488033 -310.120789) (xy 228.432596 -310.126889)
			(xy 228.376862 -310.124852) (xy 228.322019 -310.114722) (xy 228.269235 -310.096715) (xy 228.219635 -310.071214)
			(xy 228.174277 -310.038763) (xy 228.134128 -310.000054) (xy 228.100042 -309.955911) (xy 228.072746 -309.907276)
			(xy 228.052823 -309.855185) (xy 228.040697 -309.800748) (xy 228.036626 -309.745126) (xy 227.047351 -309.745126)
			(xy 227.059939 -309.771979) (xy 227.076007 -309.825386) (xy 227.084127 -309.880562) (xy 227.084636 -309.908448)
			(xy 227.084127 -309.936334) (xy 227.076007 -309.99151) (xy 227.059939 -310.044917) (xy 227.036267 -310.095414)
			(xy 227.005494 -310.141927) (xy 226.968277 -310.183464) (xy 226.925409 -310.219139) (xy 226.877803 -310.248193)
			(xy 226.826474 -310.270005) (xy 226.772517 -310.284111) (xy 226.71708 -310.290211) (xy 226.661346 -310.288174)
			(xy 226.606503 -310.278044) (xy 226.553719 -310.260037) (xy 226.504119 -310.234536) (xy 226.458761 -310.202085)
			(xy 226.418612 -310.163376) (xy 226.384526 -310.119233) (xy 226.35723 -310.070598) (xy 226.337307 -310.018507)
			(xy 226.325181 -309.96407) (xy 226.32111 -309.908448) (xy 220.119812 -309.908448) (xy 220.140908 -309.959149)
			(xy 220.197226 -310.115863) (xy 220.245755 -310.275161) (xy 220.286377 -310.436657) (xy 220.318992 -310.599958)
			(xy 220.343523 -310.764667) (xy 220.359908 -310.930385) (xy 220.368109 -311.096709) (xy 220.368622 -311.179972)
			(xy 220.36841 -311.215786) (xy 227.498908 -311.215786) (xy 227.502979 -311.160164) (xy 227.515105 -311.105727)
			(xy 227.535028 -311.053636) (xy 227.562324 -311.005001) (xy 227.59641 -310.960858) (xy 227.636559 -310.922149)
			(xy 227.681917 -310.889698) (xy 227.731517 -310.864197) (xy 227.784301 -310.84619) (xy 227.839144 -310.83606)
			(xy 227.894878 -310.834023) (xy 227.950315 -310.840123) (xy 228.004272 -310.854229) (xy 228.055601 -310.876041)
			(xy 228.103207 -310.905095) (xy 228.146075 -310.94077) (xy 228.183292 -310.982307) (xy 228.214065 -311.02882)
			(xy 228.237737 -311.079317) (xy 228.253805 -311.132724) (xy 228.261925 -311.1879) (xy 228.262434 -311.215786)
			(xy 228.261925 -311.243672) (xy 228.253805 -311.298848) (xy 228.237737 -311.352255) (xy 228.214065 -311.402752)
			(xy 228.183292 -311.449265) (xy 228.146075 -311.490802) (xy 228.103207 -311.526477) (xy 228.055601 -311.555531)
			(xy 228.025463 -311.568338) (xy 229.820468 -311.568338) (xy 229.824539 -311.512716) (xy 229.836665 -311.458279)
			(xy 229.856588 -311.406188) (xy 229.883884 -311.357553) (xy 229.91797 -311.31341) (xy 229.958119 -311.274701)
			(xy 230.003477 -311.24225) (xy 230.053077 -311.216749) (xy 230.105861 -311.198742) (xy 230.160704 -311.188612)
			(xy 230.216438 -311.186575) (xy 230.271875 -311.192675) (xy 230.325832 -311.206781) (xy 230.377161 -311.228593)
			(xy 230.424767 -311.257647) (xy 230.467635 -311.293322) (xy 230.504852 -311.334859) (xy 230.535625 -311.381372)
			(xy 230.559297 -311.431869) (xy 230.575365 -311.485276) (xy 230.583485 -311.540452) (xy 230.583994 -311.568338)
			(xy 230.583485 -311.596224) (xy 230.575365 -311.6514) (xy 230.559297 -311.704807) (xy 230.535625 -311.755304)
			(xy 230.504852 -311.801817) (xy 230.467635 -311.843354) (xy 230.424767 -311.879029) (xy 230.377161 -311.908083)
			(xy 230.325832 -311.929895) (xy 230.271875 -311.944001) (xy 230.216438 -311.950101) (xy 230.160704 -311.948064)
			(xy 230.105861 -311.937934) (xy 230.053077 -311.919927) (xy 230.003477 -311.894426) (xy 229.958119 -311.861975)
			(xy 229.91797 -311.823266) (xy 229.883884 -311.779123) (xy 229.856588 -311.730488) (xy 229.836665 -311.678397)
			(xy 229.824539 -311.62396) (xy 229.820468 -311.568338) (xy 228.025463 -311.568338) (xy 228.004272 -311.577343)
			(xy 227.950315 -311.591449) (xy 227.894878 -311.597549) (xy 227.839144 -311.595512) (xy 227.784301 -311.585382)
			(xy 227.731517 -311.567375) (xy 227.681917 -311.541874) (xy 227.636559 -311.509423) (xy 227.59641 -311.470714)
			(xy 227.562324 -311.426571) (xy 227.535028 -311.377936) (xy 227.515105 -311.325845) (xy 227.502979 -311.271408)
			(xy 227.498908 -311.215786) (xy 220.36841 -311.215786) (xy 220.368148 -311.260131) (xy 220.360541 -311.420268)
			(xy 220.345348 -311.579864) (xy 220.322602 -311.73856) (xy 220.292356 -311.895999) (xy 220.254676 -312.051826)
			(xy 220.209649 -312.205691) (xy 220.157374 -312.357246) (xy 220.097971 -312.506153) (xy 220.031572 -312.652074)
			(xy 219.958327 -312.794681) (xy 219.878401 -312.933655) (xy 219.791974 -313.068681) (xy 219.69924 -313.199457)
			(xy 219.600408 -313.325687) (xy 219.4957 -313.447087) (xy 219.385352 -313.563385) (xy 219.269613 -313.674319)
			(xy 219.148743 -313.779638) (xy 219.023014 -313.879106) (xy 218.95816 -313.92622) (xy 218.929632 -313.946621)
			(xy 218.871843 -313.986375) (xy 218.84259 -314.005722) (xy 218.77471 -314.049731) (xy 218.635386 -314.131985)
			(xy 218.492286 -314.207479) (xy 218.345739 -314.276042) (xy 218.27109 -314.30722) (xy 218.263978 -314.310268)
			(xy 218.258644 -314.314586) (xy 218.255677 -314.317018) (xy 218.250453 -314.322635) (xy 218.24823 -314.325762)
			(xy 218.234006 -314.346844) (xy 218.22918 -314.355734) (xy 218.227802 -314.359031) (xy 218.225884 -314.365914)
			(xy 218.22537 -314.36945) (xy 218.225116 -314.375546) (xy 218.225116 -320.816732) (xy 224.888044 -320.816732)
			(xy 224.888518 -320.789362) (xy 224.896332 -320.735183) (xy 224.911819 -320.682679) (xy 224.934659 -320.632932)
			(xy 224.964383 -320.586966) (xy 224.982024 -320.566034) (xy 224.982278 -320.56578) (xy 224.987888 -320.55871)
			(xy 224.994119 -320.54178) (xy 224.99447 -320.53276) (xy 224.99447 -320.465704) (xy 224.994118 -320.456686)
			(xy 224.987868 -320.439769) (xy 224.982278 -320.432684) (xy 224.982024 -320.432684) (xy 224.982024 -320.43243)
			(xy 224.964389 -320.411494) (xy 224.934676 -320.365523) (xy 224.911839 -320.315776) (xy 224.896347 -320.263276)
			(xy 224.888518 -320.209101) (xy 224.888044 -320.181732) (xy 224.888608 -320.154484) (xy 224.896359 -320.100541)
			(xy 224.911707 -320.048251) (xy 224.934341 -319.998677) (xy 224.9638 -319.952829) (xy 224.999483 -319.91164)
			(xy 225.040665 -319.875948) (xy 225.086507 -319.84648) (xy 225.136076 -319.823835) (xy 225.188363 -319.808476)
			(xy 225.242304 -319.800714) (xy 225.269552 -319.800224) (xy 225.296921 -319.800712) (xy 225.3511 -319.808524)
			(xy 225.403603 -319.824007) (xy 225.45335 -319.846844) (xy 225.499318 -319.876565) (xy 225.52025 -319.894204)
			(xy 225.520504 -319.894458) (xy 225.52758 -319.900059) (xy 225.544505 -319.906296) (xy 225.553524 -319.90665)
			(xy 225.62058 -319.90665) (xy 225.629597 -319.906294) (xy 225.646515 -319.900047) (xy 225.6536 -319.894458)
			(xy 225.6536 -319.894204) (xy 225.653854 -319.894204) (xy 225.674787 -319.876563) (xy 225.720755 -319.846839)
			(xy 225.770501 -319.823993) (xy 225.823003 -319.808497) (xy 225.877181 -319.800668) (xy 225.931923 -319.800668)
			(xy 225.986101 -319.808497) (xy 226.038603 -319.823993) (xy 226.088349 -319.846839) (xy 226.134317 -319.876563)
			(xy 226.15525 -319.894204) (xy 226.155504 -319.894458) (xy 226.16258 -319.900059) (xy 226.179505 -319.906296)
			(xy 226.188524 -319.90665) (xy 226.25558 -319.90665) (xy 226.264597 -319.906294) (xy 226.281515 -319.900047)
			(xy 226.2886 -319.894458) (xy 226.2886 -319.894204) (xy 226.288854 -319.894204) (xy 226.309793 -319.876574)
			(xy 226.355764 -319.84686) (xy 226.40551 -319.824023) (xy 226.458009 -319.80853) (xy 226.512183 -319.800699)
			(xy 226.539552 -319.800224) (xy 226.566805 -319.8007) (xy 226.620757 -319.808451) (xy 226.673057 -319.823803)
			(xy 226.722639 -319.846442) (xy 226.768494 -319.875908) (xy 226.809688 -319.911601) (xy 226.845382 -319.952793)
			(xy 226.87485 -319.998647) (xy 226.897492 -320.048228) (xy 226.912845 -320.100527) (xy 226.920599 -320.154479)
			(xy 226.92106 -320.181732) (xy 226.920622 -320.209103) (xy 226.912799 -320.263284) (xy 226.897304 -320.315788)
			(xy 226.874456 -320.365534) (xy 226.844725 -320.4115) (xy 226.82708 -320.43243) (xy 226.826826 -320.432684)
			(xy 226.821231 -320.439765) (xy 226.814991 -320.456686) (xy 226.814634 -320.465704) (xy 226.814634 -320.53276)
			(xy 226.815003 -320.541776) (xy 226.821241 -320.558693) (xy 226.826826 -320.56578) (xy 226.82708 -320.56578)
			(xy 226.82708 -320.566034) (xy 226.844699 -320.586983) (xy 226.874414 -320.632951) (xy 226.897254 -320.682694)
			(xy 226.91275 -320.735191) (xy 226.920583 -320.789364) (xy 226.92106 -320.816732) (xy 226.920675 -320.843988)
			(xy 226.912912 -320.897944) (xy 226.89755 -320.950246) (xy 226.8749 -320.99983) (xy 226.845424 -321.045685)
			(xy 226.809722 -321.086879) (xy 226.768521 -321.122572) (xy 226.72266 -321.152038) (xy 226.673071 -321.174678)
			(xy 226.620766 -321.190029) (xy 226.566808 -321.19778) (xy 226.539552 -321.19824) (xy 226.512182 -321.197758)
			(xy 226.458003 -321.189946) (xy 226.4055 -321.174462) (xy 226.355752 -321.151623) (xy 226.309786 -321.121901)
			(xy 226.288854 -321.10426) (xy 226.2886 -321.104006) (xy 226.281517 -321.098414) (xy 226.264598 -321.09217)
			(xy 226.25558 -321.091814) (xy 226.188524 -321.091814) (xy 226.179508 -321.092179) (xy 226.162591 -321.098421)
			(xy 226.155504 -321.104006) (xy 226.15525 -321.10426) (xy 226.134317 -321.121901) (xy 226.088349 -321.151625)
			(xy 226.038603 -321.174471) (xy 225.986101 -321.189967) (xy 225.931923 -321.197796) (xy 225.877181 -321.197796)
			(xy 225.823003 -321.189967) (xy 225.770501 -321.174471) (xy 225.720755 -321.151625) (xy 225.674787 -321.121901)
			(xy 225.653854 -321.10426) (xy 225.6536 -321.104006) (xy 225.646517 -321.098414) (xy 225.629598 -321.09217)
			(xy 225.62058 -321.091814) (xy 225.553524 -321.091814) (xy 225.544508 -321.092179) (xy 225.527591 -321.098421)
			(xy 225.520504 -321.104006) (xy 225.520504 -321.10426) (xy 225.52025 -321.10426) (xy 225.499305 -321.121883)
			(xy 225.453336 -321.151599) (xy 225.403592 -321.174438) (xy 225.351094 -321.189933) (xy 225.29692 -321.197764)
			(xy 225.269552 -321.19824) (xy 225.242301 -321.197767) (xy 225.188355 -321.190005) (xy 225.136062 -321.174645)
			(xy 225.086486 -321.152001) (xy 225.040638 -321.122532) (xy 224.999449 -321.08684) (xy 224.963758 -321.04565)
			(xy 224.934292 -320.9998) (xy 224.911649 -320.950223) (xy 224.896292 -320.89793) (xy 224.888532 -320.843983)
			(xy 224.888044 -320.816732) (xy 218.225116 -320.816732) (xy 218.225116 -321.122548) (xy 218.226132 -321.132454)
			(xy 218.227834 -321.139614) (xy 218.234665 -321.152643) (xy 218.239594 -321.158108) (xy 218.50985 -321.428364)
			(xy 218.515353 -321.433344) (xy 218.528522 -321.440173) (xy 218.535758 -321.441826) (xy 218.54541 -321.442842)
			(xy 230.911654 -321.442842)
		)
		(stroke
			(width 0)
			(type solid)
		)
		(fill yes)
		(layer "In5.Cu")
		(net "GND")
	)
	(gr_poly
		(pts
			(xy 103.099616 -90.319098) (xy 103.106424 -90.318877) (xy 103.119553 -90.315266) (xy 103.125524 -90.311986)
			(xy 103.131319 -90.308281) (xy 103.140842 -90.298363) (xy 103.14432 -90.292428) (xy 103.186738 -90.213688)
			(xy 103.189761 -90.207527) (xy 103.192725 -90.194133) (xy 103.19258 -90.187272) (xy 103.192072 -90.173302)
			(xy 103.184452 -90.161618) (xy 103.169616 -90.138166) (xy 103.146154 -90.087878) (xy 103.130233 -90.03472)
			(xy 103.12219 -89.979814) (xy 103.121714 -89.952068) (xy 103.1222 -89.924817) (xy 103.129956 -89.870869)
			(xy 103.145311 -89.818574) (xy 103.167953 -89.768997) (xy 103.197419 -89.723147) (xy 103.23311 -89.681956)
			(xy 103.274301 -89.646265) (xy 103.320151 -89.616799) (xy 103.369728 -89.594157) (xy 103.422023 -89.578802)
			(xy 103.475971 -89.571046) (xy 103.530473 -89.571046) (xy 103.584421 -89.578802) (xy 103.636716 -89.594157)
			(xy 103.686293 -89.616799) (xy 103.732143 -89.646265) (xy 103.773334 -89.681956) (xy 103.809025 -89.723147)
			(xy 103.838491 -89.768997) (xy 103.861133 -89.818574) (xy 103.876488 -89.870869) (xy 103.884244 -89.924817)
			(xy 103.88473 -89.952068) (xy 103.884226 -89.979812) (xy 103.876177 -90.034712) (xy 103.860257 -90.087866)
			(xy 103.836804 -90.138154) (xy 103.821992 -90.161618) (xy 103.818182 -90.16746) (xy 103.814118 -90.18016)
			(xy 103.813864 -90.187272) (xy 103.813742 -90.194132) (xy 103.816691 -90.207526) (xy 103.819706 -90.213688)
			(xy 103.862124 -90.292428) (xy 103.865588 -90.298372) (xy 103.875118 -90.308288) (xy 103.88092 -90.311986)
			(xy 103.886887 -90.315275) (xy 103.900018 -90.318888) (xy 103.906828 -90.319098) (xy 104.12603 -90.319098)
			(xy 104.130175 -90.319003) (xy 104.138347 -90.3176) (xy 104.142286 -90.316304) (xy 104.164892 -90.308684)
			(xy 104.171242 -90.304112) (xy 104.195084 -90.287438) (xy 104.246777 -90.260747) (xy 104.301927 -90.242225)
			(xy 104.359252 -90.232301) (xy 104.417419 -90.231205) (xy 104.446324 -90.234516) (xy 104.477546 -90.239284)
			(xy 104.537924 -90.257803) (xy 104.594423 -90.286024) (xy 104.620314 -90.304112) (xy 104.626664 -90.308684)
			(xy 104.64927 -90.316304) (xy 104.653217 -90.317567) (xy 104.661384 -90.318968) (xy 104.665526 -90.319098)
			(xy 107.756706 -90.319098) (xy 107.767065 -90.318557) (xy 107.786073 -90.3103) (xy 107.793536 -90.303096)
			(xy 107.844082 -90.249756) (xy 107.847351 -90.246159) (xy 107.852589 -90.237972) (xy 107.854496 -90.2335)
			(xy 107.85856 -90.223086) (xy 107.858052 -90.212164) (xy 107.858052 -90.21064) (xy 107.857544 -90.190066)
			(xy 107.85803 -90.162815) (xy 107.865786 -90.108867) (xy 107.881141 -90.056572) (xy 107.903783 -90.006995)
			(xy 107.933249 -89.961145) (xy 107.96894 -89.919954) (xy 108.010131 -89.884263) (xy 108.055981 -89.854797)
			(xy 108.105558 -89.832155) (xy 108.157853 -89.8168) (xy 108.211801 -89.809044) (xy 108.266303 -89.809044)
			(xy 108.320251 -89.8168) (xy 108.372546 -89.832155) (xy 108.422123 -89.854797) (xy 108.467973 -89.884263)
			(xy 108.509164 -89.919954) (xy 108.544855 -89.961145) (xy 108.574321 -90.006995) (xy 108.596963 -90.056572)
			(xy 108.612318 -90.108867) (xy 108.620074 -90.162815) (xy 108.62056 -90.190066) (xy 108.620052 -90.21064)
			(xy 108.620052 -90.212164) (xy 108.619544 -90.223086) (xy 108.623608 -90.2335) (xy 108.625508 -90.237974)
			(xy 108.630755 -90.246156) (xy 108.634022 -90.249756) (xy 108.684822 -90.30335) (xy 108.692299 -90.310507)
			(xy 108.711312 -90.318635) (xy 108.721652 -90.319098) (xy 111.464344 -90.319098) (xy 111.474346 -90.318602)
			(xy 111.492822 -90.310935) (xy 111.506961 -90.296783) (xy 111.514611 -90.2783) (xy 111.515144 -90.268298)
			(xy 111.515144 -90.264488) (xy 111.51563 -90.237237) (xy 111.523386 -90.183289) (xy 111.538741 -90.130994)
			(xy 111.561383 -90.081417) (xy 111.590849 -90.035567) (xy 111.62654 -89.994376) (xy 111.667731 -89.958685)
			(xy 111.713581 -89.929219) (xy 111.763158 -89.906577) (xy 111.815453 -89.891222) (xy 111.869401 -89.883466)
			(xy 111.923903 -89.883466) (xy 111.977851 -89.891222) (xy 112.030146 -89.906577) (xy 112.079723 -89.929219)
			(xy 112.125573 -89.958685) (xy 112.166764 -89.994376) (xy 112.202455 -90.035567) (xy 112.231921 -90.081417)
			(xy 112.254563 -90.130994) (xy 112.269918 -90.183289) (xy 112.277674 -90.237237) (xy 112.27816 -90.264488)
			(xy 112.27816 -90.268298) (xy 112.278647 -90.278309) (xy 112.286305 -90.296808) (xy 112.300457 -90.310972)
			(xy 112.31895 -90.318645) (xy 112.32896 -90.319098) (xy 116.689632 -90.319098) (xy 116.6997 -90.318669)
			(xy 116.718295 -90.310946) (xy 116.7257 -90.304112) (xy 117.004846 -90.024966) (xy 117.006116 -90.023696)
			(xy 117.012996 -90.015493) (xy 117.019971 -89.995278) (xy 117.019578 -89.98458) (xy 117.01272 -89.90711)
			(xy 117.01208 -89.901927) (xy 117.009 -89.89195) (xy 117.006624 -89.887298) (xy 117.003576 -89.881456)
			(xy 116.995956 -89.87282) (xy 116.990876 -89.869518) (xy 116.969636 -89.854149) (xy 116.931172 -89.818523)
			(xy 116.897945 -89.777968) (xy 116.870582 -89.733248) (xy 116.849595 -89.685203) (xy 116.835382 -89.634739)
			(xy 116.828208 -89.582804) (xy 116.827808 -89.55659) (xy 116.828292 -89.529044) (xy 116.836216 -89.474525)
			(xy 116.851898 -89.421712) (xy 116.875012 -89.371703) (xy 116.905077 -89.325538) (xy 116.941468 -89.284176)
			(xy 116.983429 -89.248478) (xy 117.030088 -89.219184) (xy 117.080474 -89.196905) (xy 117.13354 -89.182104)
			(xy 117.160802 -89.17813) (xy 117.161056 -89.17813) (xy 117.170093 -89.176549) (xy 117.186263 -89.167915)
			(xy 117.198367 -89.154147) (xy 117.204857 -89.137003) (xy 117.205252 -89.127838) (xy 117.205252 -88.726518)
			(xy 117.204864 -88.71735) (xy 117.198396 -88.700192) (xy 117.186287 -88.686423) (xy 117.170095 -88.677816)
			(xy 117.161056 -88.676226) (xy 117.160802 -88.676226) (xy 117.133541 -88.672244) (xy 117.080471 -88.657454)
			(xy 117.03008 -88.635184) (xy 116.983416 -88.605898) (xy 116.94145 -88.570205) (xy 116.905054 -88.528846)
			(xy 116.874985 -88.482683) (xy 116.851869 -88.432675) (xy 116.836186 -88.379862) (xy 116.828263 -88.325342)
			(xy 116.828263 -88.270249) (xy 116.836188 -88.21573) (xy 116.851872 -88.162917) (xy 116.874989 -88.112909)
			(xy 116.905059 -88.066747) (xy 116.941456 -88.025389) (xy 116.983423 -87.989697) (xy 117.030087 -87.960412)
			(xy 117.080479 -87.938143) (xy 117.133549 -87.923354) (xy 117.160802 -87.919306) (xy 117.161056 -87.919306)
			(xy 117.170091 -87.917725) (xy 117.186257 -87.909089) (xy 117.198355 -87.89532) (xy 117.204838 -87.878177)
			(xy 117.205252 -87.869014) (xy 117.205252 -87.86241) (xy 117.204833 -87.852391) (xy 117.197164 -87.833879)
			(xy 117.182989 -87.819715) (xy 117.164471 -87.812059) (xy 117.154452 -87.81161) (xy 117.150896 -87.81161)
			(xy 117.147086 -87.812118) (xy 117.130732 -87.814363) (xy 117.097807 -87.816781) (xy 117.0813 -87.816944)
			(xy 117.051654 -87.816466) (xy 116.992861 -87.808784) (xy 116.935556 -87.793561) (xy 116.880701 -87.771054)
			(xy 116.854732 -87.756746) (xy 116.84635 -87.752409) (xy 116.827689 -87.749679) (xy 116.81841 -87.751412)
			(xy 116.788184 -87.75827) (xy 116.779204 -87.760723) (xy 116.763707 -87.771014) (xy 116.757958 -87.778336)
			(xy 116.742531 -87.799177) (xy 116.706951 -87.836895) (xy 116.66659 -87.869447) (xy 116.622192 -87.896233)
			(xy 116.574577 -87.91676) (xy 116.52462 -87.93065) (xy 116.473242 -87.937647) (xy 116.447316 -87.938102)
			(xy 116.420063 -87.93764) (xy 116.366111 -87.929885) (xy 116.313812 -87.91453) (xy 116.264231 -87.891889)
			(xy 116.218376 -87.862422) (xy 116.177182 -87.826729) (xy 116.141488 -87.785537) (xy 116.112019 -87.739683)
			(xy 116.089375 -87.690103) (xy 116.074019 -87.637805) (xy 116.066261 -87.583853) (xy 116.066261 -87.529347)
			(xy 116.074019 -87.475395) (xy 116.089375 -87.423097) (xy 116.112019 -87.373517) (xy 116.141488 -87.327663)
			(xy 116.177182 -87.286471) (xy 116.218376 -87.250778) (xy 116.264231 -87.221311) (xy 116.313812 -87.19867)
			(xy 116.366111 -87.183315) (xy 116.420063 -87.17556) (xy 116.447316 -87.175086) (xy 116.462109 -87.175229)
			(xy 116.491606 -87.177516) (xy 116.506244 -87.179658) (xy 116.517166 -87.181436) (xy 116.538502 -87.17534)
			(xy 116.605812 -87.117936) (xy 116.61384 -87.110366) (xy 116.623072 -87.090349) (xy 116.623592 -87.079328)
			(xy 116.623592 -86.775036) (xy 116.623058 -86.764014) (xy 116.613848 -86.743989) (xy 116.605812 -86.736428)
			(xy 116.538502 -86.679024) (xy 116.517166 -86.672928) (xy 116.506244 -86.674706) (xy 116.491607 -86.676855)
			(xy 116.462109 -86.679146) (xy 116.447316 -86.679278) (xy 116.443506 -86.679278) (xy 116.416433 -86.678535)
			(xy 116.362897 -86.670342) (xy 116.311057 -86.654661) (xy 116.261957 -86.631806) (xy 116.216583 -86.602236)
			(xy 116.175846 -86.566546) (xy 116.140567 -86.525454) (xy 116.111453 -86.479786) (xy 116.089091 -86.430459)
			(xy 116.07393 -86.378465) (xy 116.066275 -86.32485) (xy 116.065808 -86.29777) (xy 116.066296 -86.270521)
			(xy 116.074056 -86.216577) (xy 116.089414 -86.164287) (xy 116.112057 -86.114715) (xy 116.141525 -86.068869)
			(xy 116.177216 -86.027684) (xy 116.218406 -85.991997) (xy 116.264255 -85.962535) (xy 116.31383 -85.939898)
			(xy 116.366122 -85.924547) (xy 116.420067 -85.916793) (xy 116.447316 -85.916262) (xy 116.473241 -85.916697)
			(xy 116.524615 -85.923714) (xy 116.574568 -85.937617) (xy 116.62218 -85.958149) (xy 116.666577 -85.984935)
			(xy 116.706941 -86.01748) (xy 116.742532 -86.055187) (xy 116.757958 -86.076028) (xy 116.763689 -86.083369)
			(xy 116.779196 -86.093652) (xy 116.788184 -86.096094) (xy 116.81841 -86.102952) (xy 116.827689 -86.104596)
			(xy 116.846316 -86.101857) (xy 116.854732 -86.097618) (xy 116.880717 -86.083344) (xy 116.935577 -86.060865)
			(xy 116.992875 -86.045637) (xy 117.051657 -86.037914) (xy 117.0813 -86.03742) (xy 117.097807 -86.037587)
			(xy 117.130732 -86.040002) (xy 117.147086 -86.042246) (xy 117.150896 -86.042754) (xy 117.154452 -86.042754)
			(xy 117.164476 -86.042342) (xy 117.183002 -86.034679) (xy 117.197178 -86.020503) (xy 117.204842 -86.001978)
			(xy 117.205252 -85.991954) (xy 117.205252 -85.98535) (xy 117.20487 -85.976178) (xy 117.198407 -85.95901)
			(xy 117.186298 -85.945232) (xy 117.170103 -85.936618) (xy 117.161056 -85.935058) (xy 117.160802 -85.935058)
			(xy 117.133538 -85.931076) (xy 117.080464 -85.916285) (xy 117.030069 -85.894014) (xy 116.983401 -85.864726)
			(xy 116.941431 -85.82903) (xy 116.905031 -85.787669) (xy 116.874959 -85.741502) (xy 116.851841 -85.69149)
			(xy 116.836156 -85.638672) (xy 116.828231 -85.584148) (xy 116.828231 -85.529051) (xy 116.836156 -85.474527)
			(xy 116.851841 -85.42171) (xy 116.87496 -85.371698) (xy 116.905031 -85.325531) (xy 116.941431 -85.284169)
			(xy 116.983401 -85.248473) (xy 117.030069 -85.219185) (xy 117.080464 -85.196914) (xy 117.133539 -85.182124)
			(xy 117.160802 -85.178138) (xy 117.161056 -85.178138) (xy 117.170093 -85.176557) (xy 117.186265 -85.167923)
			(xy 117.198371 -85.154155) (xy 117.204864 -85.137011) (xy 117.205252 -85.127846) (xy 117.205252 -84.726526)
			(xy 117.204866 -84.717357) (xy 117.198399 -84.700196) (xy 117.18629 -84.686425) (xy 117.170097 -84.677817)
			(xy 117.161056 -84.676234) (xy 117.160802 -84.676234) (xy 117.13354 -84.672252) (xy 117.080469 -84.657462)
			(xy 117.030077 -84.635192) (xy 116.983412 -84.605905) (xy 116.941445 -84.570211) (xy 116.905048 -84.528852)
			(xy 116.874979 -84.482688) (xy 116.851862 -84.432679) (xy 116.836179 -84.379864) (xy 116.828255 -84.325344)
			(xy 116.828255 -84.27025) (xy 116.83618 -84.215729) (xy 116.851864 -84.162915) (xy 116.874982 -84.112906)
			(xy 116.905052 -84.066743) (xy 116.94145 -84.025384) (xy 116.983418 -83.989691) (xy 117.030083 -83.960405)
			(xy 117.080475 -83.938136) (xy 117.133547 -83.923346) (xy 117.160802 -83.919314) (xy 117.161056 -83.919314)
			(xy 117.170091 -83.917733) (xy 117.186259 -83.909098) (xy 117.198359 -83.895329) (xy 117.204844 -83.878186)
			(xy 117.205252 -83.869022) (xy 117.205252 -83.862418) (xy 117.204835 -83.852398) (xy 117.197166 -83.833883)
			(xy 117.182992 -83.819717) (xy 117.164472 -83.812059) (xy 117.154452 -83.811618) (xy 117.150896 -83.811618)
			(xy 117.147086 -83.812126) (xy 117.130732 -83.814371) (xy 117.097807 -83.816789) (xy 117.0813 -83.816952)
			(xy 117.051654 -83.816474) (xy 116.992861 -83.808792) (xy 116.935556 -83.79357) (xy 116.8807 -83.771063)
			(xy 116.854732 -83.756754) (xy 116.84635 -83.752416) (xy 116.827688 -83.749686) (xy 116.81841 -83.75142)
			(xy 116.788184 -83.758278) (xy 116.779204 -83.760732) (xy 116.763709 -83.771023) (xy 116.757958 -83.778344)
			(xy 116.742531 -83.799185) (xy 116.70695 -83.836902) (xy 116.666589 -83.869453) (xy 116.622192 -83.896239)
			(xy 116.574576 -83.916765) (xy 116.524619 -83.930655) (xy 116.473242 -83.937652) (xy 116.447316 -83.93811)
			(xy 116.420062 -83.937648) (xy 116.366109 -83.929893) (xy 116.313809 -83.914538) (xy 116.264227 -83.891896)
			(xy 116.218372 -83.862428) (xy 116.177177 -83.826735) (xy 116.141481 -83.785541) (xy 116.112012 -83.739687)
			(xy 116.089368 -83.690106) (xy 116.074011 -83.637806) (xy 116.066253 -83.583854) (xy 116.066253 -83.529346)
			(xy 116.074011 -83.475394) (xy 116.089368 -83.423094) (xy 116.112012 -83.373513) (xy 116.141481 -83.327659)
			(xy 116.177177 -83.286465) (xy 116.218372 -83.250772) (xy 116.264227 -83.221304) (xy 116.313809 -83.198662)
			(xy 116.366109 -83.183307) (xy 116.420062 -83.175552) (xy 116.447316 -83.175094) (xy 116.462109 -83.175237)
			(xy 116.491606 -83.177524) (xy 116.506244 -83.179666) (xy 116.517166 -83.181444) (xy 116.538502 -83.175348)
			(xy 116.605812 -83.117944) (xy 116.613842 -83.110374) (xy 116.623077 -83.090358) (xy 116.623592 -83.079336)
			(xy 116.623592 -82.873342) (xy 116.623062 -82.863351) (xy 116.615358 -82.844909) (xy 116.608606 -82.837528)
			(xy 116.465096 -82.694018) (xy 116.461727 -82.69082) (xy 116.454059 -82.685581) (xy 116.449856 -82.683604)
			(xy 116.440712 -82.67954) (xy 116.43106 -82.679032) (xy 116.402749 -82.677307) (xy 116.347065 -82.666532)
			(xy 116.293589 -82.647633) (xy 116.2435 -82.621027) (xy 116.197901 -82.5873) (xy 116.157796 -82.547195)
			(xy 116.12407 -82.501595) (xy 116.097464 -82.451505) (xy 116.078567 -82.398029) (xy 116.067793 -82.342345)
			(xy 116.066062 -82.314034) (xy 116.065554 -82.304636) (xy 116.06149 -82.295238) (xy 116.059513 -82.291035)
			(xy 116.054269 -82.283371) (xy 116.051076 -82.279998) (xy 115.261644 -81.490566) (xy 115.254532 -81.4832)
			(xy 115.235736 -81.47558) (xy 111.236506 -81.47558) (xy 111.226269 -81.476052) (xy 111.207415 -81.484036)
			(xy 111.19314 -81.498715) (xy 111.189008 -81.508092) (xy 111.149384 -81.61147) (xy 111.15675 -81.64195)
			(xy 111.168434 -81.652618) (xy 111.187944 -81.670768) (xy 111.222209 -81.711577) (xy 111.250453 -81.756763)
			(xy 111.272126 -81.805443) (xy 111.286805 -81.856668) (xy 111.294205 -81.909438) (xy 111.294672 -81.936082)
			(xy 111.294186 -81.963333) (xy 111.28643 -82.017281) (xy 111.271075 -82.069576) (xy 111.248433 -82.119153)
			(xy 111.218967 -82.165003) (xy 111.183276 -82.206194) (xy 111.142085 -82.241885) (xy 111.096235 -82.271351)
			(xy 111.046658 -82.293993) (xy 110.994363 -82.309348) (xy 110.940415 -82.317104) (xy 110.885913 -82.317104)
			(xy 110.831965 -82.309348) (xy 110.77967 -82.293993) (xy 110.730093 -82.271351) (xy 110.684243 -82.241885)
			(xy 110.643052 -82.206194) (xy 110.607361 -82.165003) (xy 110.577895 -82.119153) (xy 110.555253 -82.069576)
			(xy 110.539898 -82.017281) (xy 110.532142 -81.963333) (xy 110.531656 -81.936082) (xy 110.532101 -81.909439)
			(xy 110.53952 -81.856671) (xy 110.55421 -81.80545) (xy 110.575887 -81.756771) (xy 110.604128 -81.711584)
			(xy 110.638383 -81.670767) (xy 110.657894 -81.652618) (xy 110.669578 -81.64195) (xy 110.676944 -81.61147)
			(xy 110.63732 -81.508346) (xy 110.634526 -81.50225) (xy 110.634272 -81.501996) (xy 110.62958 -81.49423)
			(xy 110.615865 -81.482369) (xy 110.598886 -81.476004) (xy 110.589822 -81.47558) (xy 109.07776 -81.47558)
			(xy 109.069275 -81.475892) (xy 109.053242 -81.481451) (xy 109.039926 -81.49197) (xy 109.035088 -81.498948)
			(xy 108.982002 -81.582006) (xy 108.980224 -81.607914) (xy 108.985558 -81.619598) (xy 108.996619 -81.64472)
			(xy 109.012224 -81.697346) (xy 109.020121 -81.751665) (xy 109.02061 -81.77911) (xy 109.020124 -81.806361)
			(xy 109.012368 -81.860309) (xy 108.997013 -81.912604) (xy 108.974371 -81.962181) (xy 108.944905 -82.008031)
			(xy 108.909214 -82.049222) (xy 108.868023 -82.084913) (xy 108.822173 -82.114379) (xy 108.772596 -82.137021)
			(xy 108.720301 -82.152376) (xy 108.666353 -82.160132) (xy 108.611851 -82.160132) (xy 108.557903 -82.152376)
			(xy 108.505608 -82.137021) (xy 108.456031 -82.114379) (xy 108.410181 -82.084913) (xy 108.36899 -82.049222)
			(xy 108.333299 -82.008031) (xy 108.303833 -81.962181) (xy 108.281191 -81.912604) (xy 108.265836 -81.860309)
			(xy 108.25808 -81.806361) (xy 108.257594 -81.77911) (xy 108.258091 -81.751666) (xy 108.265994 -81.697349)
			(xy 108.281596 -81.644724) (xy 108.292646 -81.619598) (xy 108.29798 -81.607914) (xy 108.296202 -81.582006)
			(xy 108.243116 -81.498948) (xy 108.238262 -81.491987) (xy 108.224937 -81.48149) (xy 108.208924 -81.475898)
			(xy 108.200444 -81.47558) (xy 106.279442 -81.47558) (xy 106.269451 -81.476109) (xy 106.251006 -81.48381)
			(xy 106.243628 -81.490566) (xy 106.189018 -81.545176) (xy 106.170832 -81.562633) (xy 106.130034 -81.59224)
			(xy 106.085117 -81.61512) (xy 106.037181 -81.630713) (xy 105.9874 -81.638638) (xy 105.962196 -81.639156)
			(xy 100.582984 -81.639156) (xy 100.572916 -81.639584) (xy 100.554321 -81.647308) (xy 100.546916 -81.654142)
			(xy 99.949 -82.252058) (xy 99.941634 -82.25917) (xy 99.934014 -82.277966) (xy 99.934014 -82.565494)
			(xy 111.707166 -82.565494) (xy 111.711237 -82.509872) (xy 111.723363 -82.455435) (xy 111.743286 -82.403344)
			(xy 111.770582 -82.354709) (xy 111.804668 -82.310566) (xy 111.844817 -82.271857) (xy 111.890175 -82.239406)
			(xy 111.939775 -82.213905) (xy 111.992559 -82.195898) (xy 112.047402 -82.185768) (xy 112.103136 -82.183731)
			(xy 112.158573 -82.189831) (xy 112.21253 -82.203937) (xy 112.263859 -82.225749) (xy 112.311465 -82.254803)
			(xy 112.354333 -82.290478) (xy 112.39155 -82.332015) (xy 112.422323 -82.378528) (xy 112.445995 -82.429025)
			(xy 112.462063 -82.482432) (xy 112.470183 -82.537608) (xy 112.470692 -82.565494) (xy 112.470183 -82.59338)
			(xy 112.462063 -82.648556) (xy 112.445995 -82.701963) (xy 112.422323 -82.75246) (xy 112.39155 -82.798973)
			(xy 112.354333 -82.84051) (xy 112.311465 -82.876185) (xy 112.263859 -82.905239) (xy 112.21253 -82.927051)
			(xy 112.158573 -82.941157) (xy 112.103136 -82.947257) (xy 112.047402 -82.94522) (xy 111.992559 -82.93509)
			(xy 111.939775 -82.917083) (xy 111.890175 -82.891582) (xy 111.844817 -82.859131) (xy 111.804668 -82.820422)
			(xy 111.770582 -82.776279) (xy 111.743286 -82.727644) (xy 111.723363 -82.675553) (xy 111.711237 -82.621116)
			(xy 111.707166 -82.565494) (xy 99.934014 -82.565494) (xy 99.934014 -84.78985) (xy 100.952572 -84.78985)
			(xy 100.952572 -84.73535) (xy 100.960327 -84.681406) (xy 100.97568 -84.629114) (xy 100.998318 -84.579539)
			(xy 101.027781 -84.53369) (xy 101.063468 -84.4925) (xy 101.104653 -84.456808) (xy 101.150499 -84.42734)
			(xy 101.200071 -84.404696) (xy 101.252361 -84.389337) (xy 101.306304 -84.381575) (xy 101.333554 -84.381086)
			(xy 101.364288 -84.382356) (xy 101.375972 -84.383372) (xy 101.397054 -84.375244) (xy 101.467666 -84.301838)
			(xy 101.474778 -84.280502) (xy 101.473508 -84.269072) (xy 101.472211 -84.25775) (xy 101.470812 -84.235002)
			(xy 101.470714 -84.223606) (xy 101.471171 -84.196355) (xy 101.478927 -84.142406) (xy 101.494281 -84.090111)
			(xy 101.516922 -84.040533) (xy 101.546387 -83.994682) (xy 101.582078 -83.95349) (xy 101.623268 -83.917798)
			(xy 101.669118 -83.88833) (xy 101.718695 -83.865687) (xy 101.770989 -83.850331) (xy 101.824937 -83.842573)
			(xy 101.87944 -83.842571) (xy 101.933388 -83.850326) (xy 101.985684 -83.865679) (xy 102.035262 -83.888319)
			(xy 102.081114 -83.917784) (xy 102.122306 -83.953474) (xy 102.157999 -83.994663) (xy 102.187468 -84.040513)
			(xy 102.210111 -84.09009) (xy 102.225468 -84.142384) (xy 102.233227 -84.196332) (xy 102.233229 -84.250835)
			(xy 102.233227 -84.250849) (xy 103.671384 -84.250849) (xy 103.671384 -84.196351) (xy 103.679139 -84.142406)
			(xy 103.694493 -84.090115) (xy 103.717131 -84.04054) (xy 103.746594 -83.994692) (xy 103.782282 -83.953503)
			(xy 103.823468 -83.917812) (xy 103.869314 -83.888346) (xy 103.918887 -83.865703) (xy 103.971177 -83.850346)
			(xy 104.025121 -83.842586) (xy 104.05237 -83.842098) (xy 104.081108 -83.842641) (xy 104.137935 -83.851259)
			(xy 104.192825 -83.868304) (xy 104.244537 -83.893392) (xy 104.291901 -83.925953) (xy 104.313228 -83.945222)
			(xy 104.32473 -83.955342) (xy 104.352249 -83.968777) (xy 104.382513 -83.973452) (xy 104.412802 -83.968947)
			(xy 104.440396 -83.955667) (xy 104.462814 -83.934805) (xy 104.478041 -83.908237) (xy 104.481884 -83.893406)
			(xy 104.488623 -83.865561) (xy 104.509369 -83.812161) (xy 104.537863 -83.762461) (xy 104.573465 -83.717578)
			(xy 104.615375 -83.678519) (xy 104.662651 -83.646163) (xy 104.714232 -83.621235) (xy 104.76896 -83.604297)
			(xy 104.825604 -83.595727) (xy 104.854248 -83.59521) (xy 104.881498 -83.595663) (xy 104.935443 -83.603426)
			(xy 104.987735 -83.618786) (xy 105.037308 -83.64143) (xy 105.083155 -83.670899) (xy 105.124341 -83.706593)
			(xy 105.160029 -83.747784) (xy 105.189493 -83.793634) (xy 105.212131 -83.84321) (xy 105.227485 -83.895504)
			(xy 105.23524 -83.94945) (xy 105.23524 -84.00395) (xy 105.227485 -84.057896) (xy 105.212131 -84.11019)
			(xy 105.19908 -84.13877) (xy 106.610656 -84.13877) (xy 106.614727 -84.083148) (xy 106.626853 -84.028711)
			(xy 106.646776 -83.97662) (xy 106.674072 -83.927985) (xy 106.708158 -83.883842) (xy 106.748307 -83.845133)
			(xy 106.793665 -83.812682) (xy 106.843265 -83.787181) (xy 106.896049 -83.769174) (xy 106.950892 -83.759044)
			(xy 107.006626 -83.757007) (xy 107.062063 -83.763107) (xy 107.11602 -83.777213) (xy 107.167349 -83.799025)
			(xy 107.214955 -83.828079) (xy 107.257823 -83.863754) (xy 107.29504 -83.905291) (xy 107.325813 -83.951804)
			(xy 107.349485 -84.002301) (xy 107.365553 -84.055708) (xy 107.373673 -84.110884) (xy 107.374182 -84.13877)
			(xy 108.446568 -84.13877) (xy 108.450639 -84.083148) (xy 108.462765 -84.028711) (xy 108.482688 -83.97662)
			(xy 108.509984 -83.927985) (xy 108.54407 -83.883842) (xy 108.584219 -83.845133) (xy 108.629577 -83.812682)
			(xy 108.679177 -83.787181) (xy 108.731961 -83.769174) (xy 108.786804 -83.759044) (xy 108.842538 -83.757007)
			(xy 108.897975 -83.763107) (xy 108.951932 -83.777213) (xy 109.003261 -83.799025) (xy 109.050867 -83.828079)
			(xy 109.093735 -83.863754) (xy 109.130952 -83.905291) (xy 109.161725 -83.951804) (xy 109.185397 -84.002301)
			(xy 109.201465 -84.055708) (xy 109.209585 -84.110884) (xy 109.210094 -84.13877) (xy 110.309404 -84.13877)
			(xy 110.313475 -84.083148) (xy 110.325601 -84.028711) (xy 110.345524 -83.97662) (xy 110.37282 -83.927985)
			(xy 110.406906 -83.883842) (xy 110.447055 -83.845133) (xy 110.492413 -83.812682) (xy 110.542013 -83.787181)
			(xy 110.594797 -83.769174) (xy 110.64964 -83.759044) (xy 110.705374 -83.757007) (xy 110.760811 -83.763107)
			(xy 110.814768 -83.777213) (xy 110.866097 -83.799025) (xy 110.913703 -83.828079) (xy 110.956571 -83.863754)
			(xy 110.993788 -83.905291) (xy 111.024561 -83.951804) (xy 111.048233 -84.002301) (xy 111.064301 -84.055708)
			(xy 111.072421 -84.110884) (xy 111.07293 -84.13877) (xy 111.072421 -84.166656) (xy 111.064301 -84.221832)
			(xy 111.048233 -84.275239) (xy 111.024561 -84.325736) (xy 110.993788 -84.372249) (xy 110.956571 -84.413786)
			(xy 110.913703 -84.449461) (xy 110.866097 -84.478515) (xy 110.814768 -84.500327) (xy 110.760811 -84.514433)
			(xy 110.705374 -84.520533) (xy 110.64964 -84.518496) (xy 110.594797 -84.508366) (xy 110.542013 -84.490359)
			(xy 110.492413 -84.464858) (xy 110.447055 -84.432407) (xy 110.406906 -84.393698) (xy 110.37282 -84.349555)
			(xy 110.345524 -84.30092) (xy 110.325601 -84.248829) (xy 110.313475 -84.194392) (xy 110.309404 -84.13877)
			(xy 109.210094 -84.13877) (xy 109.209585 -84.166656) (xy 109.201465 -84.221832) (xy 109.185397 -84.275239)
			(xy 109.161725 -84.325736) (xy 109.130952 -84.372249) (xy 109.093735 -84.413786) (xy 109.050867 -84.449461)
			(xy 109.003261 -84.478515) (xy 108.951932 -84.500327) (xy 108.897975 -84.514433) (xy 108.842538 -84.520533)
			(xy 108.786804 -84.518496) (xy 108.731961 -84.508366) (xy 108.679177 -84.490359) (xy 108.629577 -84.464858)
			(xy 108.584219 -84.432407) (xy 108.54407 -84.393698) (xy 108.509984 -84.349555) (xy 108.482688 -84.30092)
			(xy 108.462765 -84.248829) (xy 108.450639 -84.194392) (xy 108.446568 -84.13877) (xy 107.374182 -84.13877)
			(xy 107.373673 -84.166656) (xy 107.365553 -84.221832) (xy 107.349485 -84.275239) (xy 107.325813 -84.325736)
			(xy 107.29504 -84.372249) (xy 107.257823 -84.413786) (xy 107.214955 -84.449461) (xy 107.167349 -84.478515)
			(xy 107.11602 -84.500327) (xy 107.062063 -84.514433) (xy 107.006626 -84.520533) (xy 106.950892 -84.518496)
			(xy 106.896049 -84.508366) (xy 106.843265 -84.490359) (xy 106.793665 -84.464858) (xy 106.748307 -84.432407)
			(xy 106.708158 -84.393698) (xy 106.674072 -84.349555) (xy 106.646776 -84.30092) (xy 106.626853 -84.248829)
			(xy 106.614727 -84.194392) (xy 106.610656 -84.13877) (xy 105.19908 -84.13877) (xy 105.189493 -84.159766)
			(xy 105.160029 -84.205616) (xy 105.124341 -84.246807) (xy 105.083155 -84.282501) (xy 105.037308 -84.31197)
			(xy 104.987735 -84.334614) (xy 104.935443 -84.349974) (xy 104.881498 -84.357737) (xy 104.854248 -84.358226)
			(xy 104.825508 -84.357727) (xy 104.76868 -84.349097) (xy 104.713789 -84.332041) (xy 104.662078 -84.306944)
			(xy 104.614716 -84.274375) (xy 104.59339 -84.255102) (xy 104.581879 -84.244992) (xy 104.554363 -84.231551)
			(xy 104.524099 -84.226871) (xy 104.493809 -84.231373) (xy 104.466215 -84.244653) (xy 104.443798 -84.265516)
			(xy 104.428575 -84.292087) (xy 104.424734 -84.306918) (xy 104.417926 -84.334745) (xy 104.397192 -84.388145)
			(xy 104.368708 -84.437845) (xy 104.333116 -84.48273) (xy 104.291215 -84.521791) (xy 104.243947 -84.55415)
			(xy 104.192372 -84.579081) (xy 104.137651 -84.596023) (xy 104.081012 -84.604595) (xy 104.05237 -84.605114)
			(xy 104.025121 -84.604614) (xy 103.971177 -84.596854) (xy 103.918887 -84.581497) (xy 103.869314 -84.558854)
			(xy 103.823468 -84.529388) (xy 103.782282 -84.493697) (xy 103.746594 -84.452508) (xy 103.717131 -84.40666)
			(xy 103.694493 -84.357085) (xy 103.679139 -84.304794) (xy 103.671384 -84.250849) (xy 102.233227 -84.250849)
			(xy 102.225475 -84.304783) (xy 102.210122 -84.357079) (xy 102.187484 -84.406658) (xy 102.158019 -84.45251)
			(xy 102.12233 -84.493702) (xy 102.081141 -84.529396) (xy 102.035292 -84.558865) (xy 101.985715 -84.581509)
			(xy 101.933421 -84.596867) (xy 101.879473 -84.604627) (xy 101.852222 -84.605114) (xy 101.821488 -84.603844)
			(xy 101.809804 -84.602828) (xy 101.788722 -84.610956) (xy 101.71811 -84.684362) (xy 101.710998 -84.705698)
			(xy 101.712268 -84.717128) (xy 101.713473 -84.727502) (xy 101.714869 -84.748342) (xy 101.715062 -84.758784)
			(xy 101.715062 -84.769452) (xy 101.723698 -84.788502) (xy 101.793802 -84.853018) (xy 101.813614 -84.859876)
			(xy 101.824028 -84.859114) (xy 101.852222 -84.858098) (xy 101.879473 -84.858573) (xy 101.933419 -84.866332)
			(xy 101.985712 -84.88169) (xy 102.035287 -84.904333) (xy 102.081135 -84.9338) (xy 102.122324 -84.969492)
			(xy 102.158013 -85.010682) (xy 102.187478 -85.056532) (xy 102.210118 -85.106109) (xy 102.225472 -85.158403)
			(xy 102.233228 -85.212349) (xy 102.233228 -85.266851) (xy 102.225472 -85.320797) (xy 102.210118 -85.373091)
			(xy 102.187478 -85.422668) (xy 102.158013 -85.468518) (xy 102.122324 -85.509708) (xy 102.081135 -85.5454)
			(xy 102.08031 -85.54593) (xy 103.779826 -85.54593) (xy 103.783897 -85.490308) (xy 103.796023 -85.435871)
			(xy 103.815946 -85.38378) (xy 103.843242 -85.335145) (xy 103.877328 -85.291002) (xy 103.917477 -85.252293)
			(xy 103.962835 -85.219842) (xy 104.012435 -85.194341) (xy 104.065219 -85.176334) (xy 104.120062 -85.166204)
			(xy 104.175796 -85.164167) (xy 104.231233 -85.170267) (xy 104.28519 -85.184373) (xy 104.336519 -85.206185)
			(xy 104.384125 -85.235239) (xy 104.426993 -85.270914) (xy 104.46421 -85.312451) (xy 104.494983 -85.358964)
			(xy 104.518655 -85.409461) (xy 104.534723 -85.462868) (xy 104.542843 -85.518044) (xy 104.543352 -85.54593)
			(xy 104.542843 -85.573816) (xy 104.534723 -85.628992) (xy 104.518655 -85.682399) (xy 104.494983 -85.732896)
			(xy 104.46421 -85.779409) (xy 104.426993 -85.820946) (xy 104.384125 -85.856621) (xy 104.336519 -85.885675)
			(xy 104.28519 -85.907487) (xy 104.231233 -85.921593) (xy 104.175796 -85.927693) (xy 104.120062 -85.925656)
			(xy 104.065219 -85.915526) (xy 104.012435 -85.897519) (xy 103.962835 -85.872018) (xy 103.917477 -85.839567)
			(xy 103.877328 -85.800858) (xy 103.843242 -85.756715) (xy 103.815946 -85.70808) (xy 103.796023 -85.655989)
			(xy 103.783897 -85.601552) (xy 103.779826 -85.54593) (xy 102.08031 -85.54593) (xy 102.035287 -85.574867)
			(xy 101.985712 -85.59751) (xy 101.933419 -85.612868) (xy 101.879473 -85.620627) (xy 101.852222 -85.621114)
			(xy 101.825143 -85.620633) (xy 101.771529 -85.612977) (xy 101.719537 -85.597816) (xy 101.670212 -85.575455)
			(xy 101.624544 -85.546343) (xy 101.583453 -85.511065) (xy 101.547763 -85.47033) (xy 101.518193 -85.424958)
			(xy 101.495336 -85.37586) (xy 101.479653 -85.324023) (xy 101.471458 -85.270489) (xy 101.470714 -85.243416)
			(xy 101.470714 -85.232748) (xy 101.462078 -85.213698) (xy 101.391974 -85.149182) (xy 101.372162 -85.142324)
			(xy 101.361748 -85.143086) (xy 101.333554 -85.144102) (xy 101.306304 -85.143625) (xy 101.252361 -85.135863)
			(xy 101.200071 -85.120504) (xy 101.150499 -85.09786) (xy 101.104653 -85.068392) (xy 101.063468 -85.0327)
			(xy 101.027781 -84.99151) (xy 100.998318 -84.945661) (xy 100.97568 -84.896086) (xy 100.960327 -84.843794)
			(xy 100.952572 -84.78985) (xy 99.934014 -84.78985) (xy 99.934014 -85.443314) (xy 99.93503 -85.452712)
			(xy 99.93757 -85.466682) (xy 99.947476 -85.491828) (xy 99.953318 -85.498432) (xy 99.97694 -85.528404)
			(xy 99.982668 -85.53575) (xy 99.998173 -85.546043) (xy 100.007166 -85.54847) (xy 100.037392 -85.555328)
			(xy 100.046672 -85.556975) (xy 100.065303 -85.554244) (xy 100.073714 -85.549994) (xy 100.099699 -85.535722)
			(xy 100.15456 -85.51325) (xy 100.211859 -85.49803) (xy 100.27064 -85.490315) (xy 100.300282 -85.489796)
			(xy 100.330268 -85.490285) (xy 100.389727 -85.49811) (xy 100.447657 -85.513629) (xy 100.503065 -85.536577)
			(xy 100.555004 -85.56656) (xy 100.602585 -85.603066) (xy 100.644995 -85.64547) (xy 100.681507 -85.693046)
			(xy 100.711497 -85.744981) (xy 100.734451 -85.800386) (xy 100.749978 -85.858314) (xy 100.757811 -85.917772)
			(xy 100.758244 -85.947758) (xy 100.758244 -85.984842) (xy 106.610656 -85.984842) (xy 106.614727 -85.92922)
			(xy 106.626853 -85.874783) (xy 106.646776 -85.822692) (xy 106.674072 -85.774057) (xy 106.708158 -85.729914)
			(xy 106.748307 -85.691205) (xy 106.793665 -85.658754) (xy 106.843265 -85.633253) (xy 106.896049 -85.615246)
			(xy 106.950892 -85.605116) (xy 107.006626 -85.603079) (xy 107.062063 -85.609179) (xy 107.11602 -85.623285)
			(xy 107.167349 -85.645097) (xy 107.214955 -85.674151) (xy 107.257823 -85.709826) (xy 107.29504 -85.751363)
			(xy 107.325813 -85.797876) (xy 107.329787 -85.806354) (xy 112.269957 -85.806354) (xy 112.269957 -85.751846)
			(xy 112.277715 -85.697892) (xy 112.293073 -85.645592) (xy 112.315717 -85.59601) (xy 112.345188 -85.550156)
			(xy 112.380885 -85.508963) (xy 112.422082 -85.473269) (xy 112.467938 -85.443802) (xy 112.517522 -85.421162)
			(xy 112.569824 -85.405808) (xy 112.623778 -85.398055) (xy 112.651032 -85.397594) (xy 112.678396 -85.398103)
			(xy 112.732566 -85.405903) (xy 112.785065 -85.421366) (xy 112.834814 -85.444174) (xy 112.880791 -85.473861)
			(xy 112.922053 -85.509815) (xy 112.957751 -85.551297) (xy 112.97285 -85.574124) (xy 112.980505 -85.585403)
			(xy 113.000689 -85.603712) (xy 113.025001 -85.616022) (xy 113.051705 -85.621454) (xy 113.078894 -85.619621)
			(xy 113.104626 -85.610653) (xy 113.127066 -85.595191) (xy 113.136172 -85.585046) (xy 113.154392 -85.564206)
			(xy 113.195801 -85.527471) (xy 113.242087 -85.497111) (xy 113.292276 -85.473762) (xy 113.345315 -85.457917)
			(xy 113.400087 -85.449907) (xy 113.427764 -85.44941) (xy 113.45502 -85.449834) (xy 113.508977 -85.457588)
			(xy 113.561282 -85.472941) (xy 113.610869 -85.495583) (xy 113.656729 -85.525051) (xy 113.697928 -85.560747)
			(xy 113.733627 -85.601942) (xy 113.7631 -85.647799) (xy 113.785746 -85.697384) (xy 113.801105 -85.749687)
			(xy 113.808863 -85.803644) (xy 113.808863 -85.858156) (xy 113.801105 -85.912113) (xy 113.785746 -85.964416)
			(xy 113.7631 -86.014001) (xy 113.733627 -86.059858) (xy 113.697928 -86.101053) (xy 113.656729 -86.136749)
			(xy 113.610869 -86.166217) (xy 113.561282 -86.188859) (xy 113.508977 -86.204212) (xy 113.45502 -86.211966)
			(xy 113.427764 -86.212426) (xy 113.400398 -86.211957) (xy 113.346225 -86.204155) (xy 113.293723 -86.188688)
			(xy 113.243973 -86.165873) (xy 113.197996 -86.13618) (xy 113.156736 -86.100218) (xy 113.121042 -86.058727)
			(xy 113.105946 -86.035896) (xy 113.098295 -86.024613) (xy 113.078112 -86.006301) (xy 113.053799 -85.993988)
			(xy 113.027093 -85.988555) (xy 112.999902 -85.99039) (xy 112.974168 -85.999361) (xy 112.951729 -86.014827)
			(xy 112.942624 -86.024974) (xy 112.924388 -86.0458) (xy 112.882984 -86.082539) (xy 112.836703 -86.112904)
			(xy 112.786516 -86.136255) (xy 112.733479 -86.152103) (xy 112.678709 -86.160113) (xy 112.651032 -86.16061)
			(xy 112.623778 -86.160145) (xy 112.569824 -86.152392) (xy 112.517522 -86.137038) (xy 112.467938 -86.114398)
			(xy 112.422081 -86.084931) (xy 112.380885 -86.049237) (xy 112.345188 -86.008044) (xy 112.315717 -85.96219)
			(xy 112.293073 -85.912608) (xy 112.277715 -85.860308) (xy 112.269957 -85.806354) (xy 107.329787 -85.806354)
			(xy 107.349485 -85.848373) (xy 107.365553 -85.90178) (xy 107.373673 -85.956956) (xy 107.374182 -85.984842)
			(xy 107.373673 -86.012728) (xy 107.365553 -86.067904) (xy 107.349485 -86.121311) (xy 107.325813 -86.171808)
			(xy 107.29504 -86.218321) (xy 107.257823 -86.259858) (xy 107.214955 -86.295533) (xy 107.167349 -86.324587)
			(xy 107.11602 -86.346399) (xy 107.062063 -86.360505) (xy 107.006626 -86.366605) (xy 106.950892 -86.364568)
			(xy 106.896049 -86.354438) (xy 106.843265 -86.336431) (xy 106.793665 -86.31093) (xy 106.748307 -86.278479)
			(xy 106.708158 -86.23977) (xy 106.674072 -86.195627) (xy 106.646776 -86.146992) (xy 106.626853 -86.094901)
			(xy 106.614727 -86.040464) (xy 106.610656 -85.984842) (xy 100.758244 -85.984842) (xy 100.758244 -86.811358)
			(xy 100.757794 -86.84021) (xy 100.750494 -86.89745) (xy 100.736016 -86.953308) (xy 100.725732 -86.980268)
			(xy 100.720398 -86.99373) (xy 100.725224 -87.021416) (xy 100.803202 -87.111332) (xy 100.829872 -87.119968)
			(xy 100.843842 -87.116412) (xy 100.865801 -87.1115) (xy 100.910496 -87.106275) (xy 100.932996 -87.105998)
			(xy 100.960247 -87.106483) (xy 101.014194 -87.114239) (xy 101.066488 -87.129594) (xy 101.116064 -87.152234)
			(xy 101.161914 -87.181699) (xy 101.203104 -87.21739) (xy 101.238796 -87.258579) (xy 101.268262 -87.304428)
			(xy 101.290903 -87.354004) (xy 101.306259 -87.406298) (xy 101.314016 -87.460245) (xy 101.314017 -87.514746)
			(xy 101.307088 -87.562944) (xy 103.932734 -87.562944) (xy 103.936805 -87.507322) (xy 103.948931 -87.452885)
			(xy 103.968854 -87.400794) (xy 103.99615 -87.352159) (xy 104.030236 -87.308016) (xy 104.070385 -87.269307)
			(xy 104.115743 -87.236856) (xy 104.165343 -87.211355) (xy 104.218127 -87.193348) (xy 104.27297 -87.183218)
			(xy 104.328704 -87.181181) (xy 104.384141 -87.187281) (xy 104.438098 -87.201387) (xy 104.489427 -87.223199)
			(xy 104.537033 -87.252253) (xy 104.579901 -87.287928) (xy 104.617118 -87.329465) (xy 104.647891 -87.375978)
			(xy 104.671563 -87.426475) (xy 104.687631 -87.479882) (xy 104.695751 -87.535058) (xy 104.69626 -87.562944)
			(xy 104.695751 -87.59083) (xy 104.687631 -87.646006) (xy 104.671563 -87.699413) (xy 104.647891 -87.74991)
			(xy 104.617118 -87.796423) (xy 104.579901 -87.83796) (xy 104.537033 -87.873635) (xy 104.489427 -87.902689)
			(xy 104.438098 -87.924501) (xy 104.384141 -87.938607) (xy 104.328704 -87.944707) (xy 104.27297 -87.94267)
			(xy 104.218127 -87.93254) (xy 104.165343 -87.914533) (xy 104.115743 -87.889032) (xy 104.070385 -87.856581)
			(xy 104.030236 -87.817872) (xy 103.99615 -87.773729) (xy 103.968854 -87.725094) (xy 103.948931 -87.673003)
			(xy 103.936805 -87.618566) (xy 103.932734 -87.562944) (xy 101.307088 -87.562944) (xy 101.306261 -87.568693)
			(xy 101.290907 -87.620987) (xy 101.268266 -87.670564) (xy 101.238801 -87.716414) (xy 101.203111 -87.757604)
			(xy 101.161922 -87.793295) (xy 101.116073 -87.822762) (xy 101.066497 -87.845403) (xy 101.014203 -87.860759)
			(xy 100.960256 -87.868516) (xy 100.905755 -87.868517) (xy 100.851808 -87.860761) (xy 100.799513 -87.845407)
			(xy 100.749937 -87.822767) (xy 100.704087 -87.793302) (xy 100.662897 -87.757611) (xy 100.627205 -87.716422)
			(xy 100.597739 -87.670573) (xy 100.575097 -87.620997) (xy 100.559741 -87.568703) (xy 100.551984 -87.514757)
			(xy 100.551488 -87.487506) (xy 100.552014 -87.45867) (xy 100.560687 -87.401655) (xy 100.56876 -87.373968)
			(xy 100.573078 -87.360252) (xy 100.56622 -87.333074) (xy 100.481638 -87.249254) (xy 100.454206 -87.24265)
			(xy 100.44049 -87.247222) (xy 100.406353 -87.257508) (xy 100.335928 -87.268607) (xy 100.300282 -87.26932)
			(xy 100.270636 -87.268841) (xy 100.211844 -87.261156) (xy 100.154541 -87.245931) (xy 100.099688 -87.223421)
			(xy 100.073714 -87.209122) (xy 100.065333 -87.204772) (xy 100.046665 -87.202014) (xy 100.037392 -87.203788)
			(xy 100.007166 -87.210646) (xy 99.998186 -87.2131) (xy 99.982691 -87.223391) (xy 99.97694 -87.230712)
			(xy 99.953318 -87.260684) (xy 99.947476 -87.267288) (xy 99.93757 -87.292434) (xy 99.934014 -87.301324)
			(xy 99.934014 -88.086438) (xy 104.62971 -88.086438) (xy 104.633781 -88.030816) (xy 104.645907 -87.976379)
			(xy 104.66583 -87.924288) (xy 104.693126 -87.875653) (xy 104.727212 -87.83151) (xy 104.767361 -87.792801)
			(xy 104.812719 -87.76035) (xy 104.862319 -87.734849) (xy 104.915103 -87.716842) (xy 104.969946 -87.706712)
			(xy 105.02568 -87.704675) (xy 105.081117 -87.710775) (xy 105.135074 -87.724881) (xy 105.186403 -87.746693)
			(xy 105.234009 -87.775747) (xy 105.276877 -87.811422) (xy 105.290928 -87.827104) (xy 106.610656 -87.827104)
			(xy 106.614727 -87.771482) (xy 106.626853 -87.717045) (xy 106.646776 -87.664954) (xy 106.674072 -87.616319)
			(xy 106.708158 -87.572176) (xy 106.748307 -87.533467) (xy 106.793665 -87.501016) (xy 106.843265 -87.475515)
			(xy 106.896049 -87.457508) (xy 106.950892 -87.447378) (xy 107.006626 -87.445341) (xy 107.062063 -87.451441)
			(xy 107.11602 -87.465547) (xy 107.167349 -87.487359) (xy 107.214955 -87.516413) (xy 107.257823 -87.552088)
			(xy 107.29504 -87.593625) (xy 107.325813 -87.640138) (xy 107.349485 -87.690635) (xy 107.365553 -87.744042)
			(xy 107.373673 -87.799218) (xy 107.374182 -87.827104) (xy 108.456982 -87.827104) (xy 108.461053 -87.771482)
			(xy 108.473179 -87.717045) (xy 108.493102 -87.664954) (xy 108.520398 -87.616319) (xy 108.554484 -87.572176)
			(xy 108.594633 -87.533467) (xy 108.639991 -87.501016) (xy 108.689591 -87.475515) (xy 108.742375 -87.457508)
			(xy 108.797218 -87.447378) (xy 108.852952 -87.445341) (xy 108.908389 -87.451441) (xy 108.962346 -87.465547)
			(xy 109.013675 -87.487359) (xy 109.061281 -87.516413) (xy 109.104149 -87.552088) (xy 109.141366 -87.593625)
			(xy 109.172139 -87.640138) (xy 109.195811 -87.690635) (xy 109.211879 -87.744042) (xy 109.219999 -87.799218)
			(xy 109.220332 -87.817452) (xy 110.309404 -87.817452) (xy 110.313475 -87.76183) (xy 110.325601 -87.707393)
			(xy 110.345524 -87.655302) (xy 110.37282 -87.606667) (xy 110.406906 -87.562524) (xy 110.447055 -87.523815)
			(xy 110.492413 -87.491364) (xy 110.542013 -87.465863) (xy 110.594797 -87.447856) (xy 110.64964 -87.437726)
			(xy 110.705374 -87.435689) (xy 110.760811 -87.441789) (xy 110.814768 -87.455895) (xy 110.866097 -87.477707)
			(xy 110.913703 -87.506761) (xy 110.956571 -87.542436) (xy 110.993788 -87.583973) (xy 111.024561 -87.630486)
			(xy 111.048233 -87.680983) (xy 111.064301 -87.73439) (xy 111.072421 -87.789566) (xy 111.07293 -87.817452)
			(xy 111.072421 -87.845338) (xy 111.064301 -87.900514) (xy 111.048233 -87.953921) (xy 111.024561 -88.004418)
			(xy 110.993788 -88.050931) (xy 110.956571 -88.092468) (xy 110.913703 -88.128143) (xy 110.866097 -88.157197)
			(xy 110.814768 -88.179009) (xy 110.760811 -88.193115) (xy 110.705374 -88.199215) (xy 110.64964 -88.197178)
			(xy 110.594797 -88.187048) (xy 110.542013 -88.169041) (xy 110.492413 -88.14354) (xy 110.447055 -88.111089)
			(xy 110.406906 -88.07238) (xy 110.37282 -88.028237) (xy 110.345524 -87.979602) (xy 110.325601 -87.927511)
			(xy 110.313475 -87.873074) (xy 110.309404 -87.817452) (xy 109.220332 -87.817452) (xy 109.220508 -87.827104)
			(xy 109.219999 -87.85499) (xy 109.211879 -87.910166) (xy 109.195811 -87.963573) (xy 109.172139 -88.01407)
			(xy 109.141366 -88.060583) (xy 109.104149 -88.10212) (xy 109.061281 -88.137795) (xy 109.013675 -88.166849)
			(xy 108.962346 -88.188661) (xy 108.908389 -88.202767) (xy 108.852952 -88.208867) (xy 108.797218 -88.20683)
			(xy 108.742375 -88.1967) (xy 108.689591 -88.178693) (xy 108.639991 -88.153192) (xy 108.594633 -88.120741)
			(xy 108.554484 -88.082032) (xy 108.520398 -88.037889) (xy 108.493102 -87.989254) (xy 108.473179 -87.937163)
			(xy 108.461053 -87.882726) (xy 108.456982 -87.827104) (xy 107.374182 -87.827104) (xy 107.373673 -87.85499)
			(xy 107.365553 -87.910166) (xy 107.349485 -87.963573) (xy 107.325813 -88.01407) (xy 107.29504 -88.060583)
			(xy 107.257823 -88.10212) (xy 107.214955 -88.137795) (xy 107.167349 -88.166849) (xy 107.11602 -88.188661)
			(xy 107.062063 -88.202767) (xy 107.006626 -88.208867) (xy 106.950892 -88.20683) (xy 106.896049 -88.1967)
			(xy 106.843265 -88.178693) (xy 106.793665 -88.153192) (xy 106.748307 -88.120741) (xy 106.708158 -88.082032)
			(xy 106.674072 -88.037889) (xy 106.646776 -87.989254) (xy 106.626853 -87.937163) (xy 106.614727 -87.882726)
			(xy 106.610656 -87.827104) (xy 105.290928 -87.827104) (xy 105.314094 -87.852959) (xy 105.344867 -87.899472)
			(xy 105.368539 -87.949969) (xy 105.384607 -88.003376) (xy 105.392727 -88.058552) (xy 105.393236 -88.086438)
			(xy 105.392727 -88.114324) (xy 105.384607 -88.1695) (xy 105.368539 -88.222907) (xy 105.344867 -88.273404)
			(xy 105.314094 -88.319917) (xy 105.276877 -88.361454) (xy 105.234009 -88.397129) (xy 105.186403 -88.426183)
			(xy 105.135074 -88.447995) (xy 105.081117 -88.462101) (xy 105.02568 -88.468201) (xy 104.969946 -88.466164)
			(xy 104.915103 -88.456034) (xy 104.862319 -88.438027) (xy 104.812719 -88.412526) (xy 104.767361 -88.380075)
			(xy 104.727212 -88.341366) (xy 104.693126 -88.297223) (xy 104.66583 -88.248588) (xy 104.645907 -88.196497)
			(xy 104.633781 -88.14206) (xy 104.62971 -88.086438) (xy 99.934014 -88.086438) (xy 99.934014 -88.774524)
			(xy 99.934475 -88.7844) (xy 99.941922 -88.802696) (xy 99.948492 -88.810084) (xy 99.948746 -88.810338)
			(xy 101.44252 -90.304112) (xy 101.443028 -90.30462) (xy 101.450406 -90.31121) (xy 101.468706 -90.318674)
			(xy 101.478588 -90.319098)
		)
		(stroke
			(width 0)
			(type solid)
		)
		(fill yes)
		(layer "In5.Cu")
		(net "P3V3_VDD_9ZXL0851_0_7")
	)
	(gr_poly
		(pts
			(xy 26.984198 -301.42815) (xy 26.989153 -301.428032) (xy 26.998875 -301.426115) (xy 27.003502 -301.42434)
			(xy 28.021026 -301.0027) (xy 28.025589 -301.000692) (xy 28.033903 -300.995192) (xy 28.037536 -300.991778)
			(xy 29.038296 -299.991018) (xy 29.045694 -299.984169) (xy 29.064292 -299.97643) (xy 29.074364 -299.976032)
			(xy 31.20771 -299.976032) (xy 31.217431 -299.975547) (xy 31.235449 -299.968231) (xy 31.242762 -299.961808)
			(xy 31.300674 -299.906436) (xy 31.308802 -299.88891) (xy 31.309056 -299.87875) (xy 31.310873 -299.849532)
			(xy 31.322343 -299.792128) (xy 31.342445 -299.737149) (xy 31.370707 -299.685885) (xy 31.406466 -299.639538)
			(xy 31.448884 -299.599195) (xy 31.472632 -299.582078) (xy 31.482538 -299.575474) (xy 31.493714 -299.555154)
			(xy 31.499302 -299.451268) (xy 31.490158 -299.429678) (xy 31.481268 -299.421804) (xy 31.460959 -299.40362)
			(xy 31.425235 -299.362445) (xy 31.39574 -299.316602) (xy 31.373075 -299.267025) (xy 31.357703 -299.214726)
			(xy 31.349936 -299.16077) (xy 31.349442 -299.133514) (xy 31.349928 -299.106263) (xy 31.357684 -299.052315)
			(xy 31.373039 -299.00002) (xy 31.395681 -298.950443) (xy 31.425147 -298.904593) (xy 31.460838 -298.863402)
			(xy 31.502029 -298.827711) (xy 31.547879 -298.798245) (xy 31.597456 -298.775603) (xy 31.649751 -298.760248)
			(xy 31.703699 -298.752492) (xy 31.758201 -298.752492) (xy 31.812149 -298.760248) (xy 31.864444 -298.775603)
			(xy 31.914021 -298.798245) (xy 31.959871 -298.827711) (xy 32.001062 -298.863402) (xy 32.036753 -298.904593)
			(xy 32.066219 -298.950443) (xy 32.088861 -299.00002) (xy 32.104216 -299.052315) (xy 32.111972 -299.106263)
			(xy 32.112458 -299.133514) (xy 32.112019 -299.159791) (xy 32.104808 -299.211848) (xy 32.090525 -299.262423)
			(xy 32.069439 -299.310562) (xy 32.04195 -299.355353) (xy 32.008576 -299.39595) (xy 31.969949 -299.431585)
			(xy 31.948628 -299.44695) (xy 31.938722 -299.453554) (xy 31.927546 -299.473874) (xy 31.921958 -299.57776)
			(xy 31.931102 -299.59935) (xy 31.939992 -299.607224) (xy 31.959278 -299.624461) (xy 31.993482 -299.663261)
			(xy 32.022127 -299.70633) (xy 32.044686 -299.752875) (xy 32.060745 -299.802043) (xy 32.070009 -299.852931)
			(xy 32.071564 -299.87875) (xy 32.071818 -299.88891) (xy 32.079946 -299.906436) (xy 32.137858 -299.961808)
			(xy 32.145159 -299.968246) (xy 32.163186 -299.975546) (xy 32.17291 -299.976032) (xy 32.798766 -299.976032)
			(xy 32.809965 -299.97545) (xy 32.830256 -299.965965) (xy 32.837882 -299.957744) (xy 32.895032 -299.889164)
			(xy 32.900874 -299.86732) (xy 32.898588 -299.856144) (xy 32.895714 -299.839145) (xy 32.892662 -299.804803)
			(xy 32.892492 -299.787564) (xy 32.89298 -299.760314) (xy 32.900741 -299.706371) (xy 32.916099 -299.65408)
			(xy 32.938742 -299.604507) (xy 32.96821 -299.558662) (xy 33.003901 -299.517476) (xy 33.04509 -299.481788)
			(xy 33.090939 -299.452325) (xy 33.140514 -299.429687) (xy 33.192806 -299.414333) (xy 33.24675 -299.406578)
			(xy 33.274 -299.406056) (xy 33.30236 -299.406575) (xy 33.358454 -299.414974) (xy 33.412686 -299.431587)
			(xy 33.46386 -299.456047) (xy 33.510848 -299.487815) (xy 33.532064 -299.50664) (xy 33.53943 -299.513498)
			(xy 33.557464 -299.520356) (xy 33.637982 -299.518578) (xy 33.64771 -299.5179) (xy 33.665604 -299.510194)
			(xy 33.67278 -299.503592) (xy 34.061146 -299.115226) (xy 34.067987 -299.107826) (xy 34.075703 -299.089227)
			(xy 34.076132 -299.079158) (xy 34.076132 -279.67813) (xy 34.075628 -279.668079) (xy 34.06791 -279.649515)
			(xy 34.061146 -279.642062) (xy 33.77692 -279.357836) (xy 33.769513 -279.351145) (xy 33.751077 -279.34355)
			(xy 33.741106 -279.343104) (xy 28.083764 -279.343104) (xy 28.050886 -279.342626) (xy 27.985547 -279.335233)
			(xy 27.921445 -279.320579) (xy 27.859385 -279.298847) (xy 27.800144 -279.27031) (xy 27.744467 -279.235326)
			(xy 27.693052 -279.194334) (xy 27.66949 -279.1714) (xy 27.547824 -279.049734) (xy 27.540423 -279.042896)
			(xy 27.521824 -279.035184) (xy 27.511756 -279.034748) (xy 22.661372 -279.034748) (xy 22.651388 -279.035292)
			(xy 22.632968 -279.043018) (xy 22.625558 -279.049734) (xy 21.430234 -280.244804) (xy 21.42342 -280.252148)
			(xy 21.415684 -280.270611) (xy 21.415248 -280.280618) (xy 21.415248 -280.693114) (xy 31.338012 -280.693114)
			(xy 31.338555 -280.663732) (xy 31.347584 -280.605665) (xy 31.365415 -280.54967) (xy 31.391626 -280.497075)
			(xy 31.425597 -280.449124) (xy 31.466521 -280.406952) (xy 31.48965 -280.388822) (xy 31.499048 -280.381456)
			(xy 31.509462 -280.360882) (xy 31.510986 -280.256996) (xy 31.50108 -280.235914) (xy 31.491936 -280.228548)
			(xy 31.470088 -280.210342) (xy 31.431546 -280.168524) (xy 31.399638 -280.121449) (xy 31.375071 -280.070159)
			(xy 31.358388 -280.015791) (xy 31.34996 -279.959549) (xy 31.349442 -279.931114) (xy 31.349928 -279.903863)
			(xy 31.357684 -279.849915) (xy 31.373039 -279.79762) (xy 31.395681 -279.748043) (xy 31.425147 -279.702193)
			(xy 31.460838 -279.661002) (xy 31.502029 -279.625311) (xy 31.547879 -279.595845) (xy 31.597456 -279.573203)
			(xy 31.649751 -279.557848) (xy 31.703699 -279.550092) (xy 31.758201 -279.550092) (xy 31.812149 -279.557848)
			(xy 31.864444 -279.573203) (xy 31.914021 -279.595845) (xy 31.959871 -279.625311) (xy 32.001062 -279.661002)
			(xy 32.036753 -279.702193) (xy 32.066219 -279.748043) (xy 32.088861 -279.79762) (xy 32.104216 -279.849915)
			(xy 32.111972 -279.903863) (xy 32.112458 -279.931114) (xy 32.111907 -279.960496) (xy 32.102876 -280.018561)
			(xy 32.085044 -280.074554) (xy 32.058835 -280.127149) (xy 32.024867 -280.1751) (xy 31.983946 -280.217274)
			(xy 31.96082 -280.235406) (xy 31.951422 -280.242772) (xy 31.941008 -280.263346) (xy 31.939484 -280.367232)
			(xy 31.94939 -280.388314) (xy 31.958534 -280.39568) (xy 31.980362 -280.413909) (xy 32.018902 -280.455724)
			(xy 32.05081 -280.502795) (xy 32.07538 -280.55408) (xy 32.092068 -280.608443) (xy 32.100505 -280.664681)
			(xy 32.101028 -280.693114) (xy 32.734502 -280.693114) (xy 32.738573 -280.637492) (xy 32.750699 -280.583055)
			(xy 32.770622 -280.530964) (xy 32.797918 -280.482329) (xy 32.832004 -280.438186) (xy 32.872153 -280.399477)
			(xy 32.917511 -280.367026) (xy 32.967111 -280.341525) (xy 33.019895 -280.323518) (xy 33.074738 -280.313388)
			(xy 33.130472 -280.311351) (xy 33.185909 -280.317451) (xy 33.239866 -280.331557) (xy 33.291195 -280.353369)
			(xy 33.338801 -280.382423) (xy 33.381669 -280.418098) (xy 33.418886 -280.459635) (xy 33.449659 -280.506148)
			(xy 33.473331 -280.556645) (xy 33.489399 -280.610052) (xy 33.497519 -280.665228) (xy 33.498028 -280.693114)
			(xy 33.497519 -280.721) (xy 33.489399 -280.776176) (xy 33.473331 -280.829583) (xy 33.449659 -280.88008)
			(xy 33.418886 -280.926593) (xy 33.381669 -280.96813) (xy 33.338801 -281.003805) (xy 33.291195 -281.032859)
			(xy 33.239866 -281.054671) (xy 33.185909 -281.068777) (xy 33.130472 -281.074877) (xy 33.074738 -281.07284)
			(xy 33.019895 -281.06271) (xy 32.967111 -281.044703) (xy 32.917511 -281.019202) (xy 32.872153 -280.986751)
			(xy 32.832004 -280.948042) (xy 32.797918 -280.903899) (xy 32.770622 -280.855264) (xy 32.750699 -280.803173)
			(xy 32.738573 -280.748736) (xy 32.734502 -280.693114) (xy 32.101028 -280.693114) (xy 32.100542 -280.720365)
			(xy 32.092786 -280.774313) (xy 32.077431 -280.826608) (xy 32.054789 -280.876185) (xy 32.025323 -280.922035)
			(xy 31.989632 -280.963226) (xy 31.948441 -280.998917) (xy 31.902591 -281.028383) (xy 31.853014 -281.051025)
			(xy 31.800719 -281.06638) (xy 31.746771 -281.074136) (xy 31.692269 -281.074136) (xy 31.638321 -281.06638)
			(xy 31.586026 -281.051025) (xy 31.536449 -281.028383) (xy 31.490599 -280.998917) (xy 31.449408 -280.963226)
			(xy 31.413717 -280.922035) (xy 31.384251 -280.876185) (xy 31.361609 -280.826608) (xy 31.346254 -280.774313)
			(xy 31.338498 -280.720365) (xy 31.338012 -280.693114) (xy 21.415248 -280.693114) (xy 21.415248 -281.829256)
			(xy 25.811478 -281.829256) (xy 25.815549 -281.773634) (xy 25.827675 -281.719197) (xy 25.847598 -281.667106)
			(xy 25.874894 -281.618471) (xy 25.90898 -281.574328) (xy 25.949129 -281.535619) (xy 25.994487 -281.503168)
			(xy 26.044087 -281.477667) (xy 26.096871 -281.45966) (xy 26.151714 -281.44953) (xy 26.207448 -281.447493)
			(xy 26.262885 -281.453593) (xy 26.316842 -281.467699) (xy 26.368171 -281.489511) (xy 26.415777 -281.518565)
			(xy 26.458645 -281.55424) (xy 26.495862 -281.595777) (xy 26.526635 -281.64229) (xy 26.550307 -281.692787)
			(xy 26.566375 -281.746194) (xy 26.574495 -281.80137) (xy 26.575004 -281.829256) (xy 27.296616 -281.829256)
			(xy 27.300687 -281.773634) (xy 27.312813 -281.719197) (xy 27.332736 -281.667106) (xy 27.360032 -281.618471)
			(xy 27.394118 -281.574328) (xy 27.434267 -281.535619) (xy 27.479625 -281.503168) (xy 27.529225 -281.477667)
			(xy 27.582009 -281.45966) (xy 27.636852 -281.44953) (xy 27.692586 -281.447493) (xy 27.748023 -281.453593)
			(xy 27.80198 -281.467699) (xy 27.853309 -281.489511) (xy 27.900915 -281.518565) (xy 27.943783 -281.55424)
			(xy 27.981 -281.595777) (xy 28.011773 -281.64229) (xy 28.035445 -281.692787) (xy 28.051513 -281.746194)
			(xy 28.059633 -281.80137) (xy 28.060142 -281.829256) (xy 28.059633 -281.857142) (xy 28.051513 -281.912318)
			(xy 28.035445 -281.965725) (xy 28.011773 -282.016222) (xy 27.981 -282.062735) (xy 27.943783 -282.104272)
			(xy 27.900915 -282.139947) (xy 27.853309 -282.169001) (xy 27.80198 -282.190813) (xy 27.748023 -282.204919)
			(xy 27.692586 -282.211019) (xy 27.636852 -282.208982) (xy 27.582009 -282.198852) (xy 27.529225 -282.180845)
			(xy 27.479625 -282.155344) (xy 27.434267 -282.122893) (xy 27.394118 -282.084184) (xy 27.360032 -282.040041)
			(xy 27.332736 -281.991406) (xy 27.312813 -281.939315) (xy 27.300687 -281.884878) (xy 27.296616 -281.829256)
			(xy 26.575004 -281.829256) (xy 26.574495 -281.857142) (xy 26.566375 -281.912318) (xy 26.550307 -281.965725)
			(xy 26.526635 -282.016222) (xy 26.495862 -282.062735) (xy 26.458645 -282.104272) (xy 26.415777 -282.139947)
			(xy 26.368171 -282.169001) (xy 26.316842 -282.190813) (xy 26.262885 -282.204919) (xy 26.207448 -282.211019)
			(xy 26.151714 -282.208982) (xy 26.096871 -282.198852) (xy 26.044087 -282.180845) (xy 25.994487 -282.155344)
			(xy 25.949129 -282.122893) (xy 25.90898 -282.084184) (xy 25.874894 -282.040041) (xy 25.847598 -281.991406)
			(xy 25.827675 -281.939315) (xy 25.815549 -281.884878) (xy 25.811478 -281.829256) (xy 21.415248 -281.829256)
			(xy 21.415248 -283.893514) (xy 31.338012 -283.893514) (xy 31.338555 -283.864132) (xy 31.347584 -283.806065)
			(xy 31.365415 -283.75007) (xy 31.391626 -283.697475) (xy 31.425597 -283.649524) (xy 31.466521 -283.607352)
			(xy 31.48965 -283.589222) (xy 31.499048 -283.581856) (xy 31.509462 -283.561282) (xy 31.510986 -283.457396)
			(xy 31.50108 -283.436314) (xy 31.491936 -283.428948) (xy 31.470088 -283.410742) (xy 31.431546 -283.368924)
			(xy 31.399638 -283.321849) (xy 31.375071 -283.270559) (xy 31.358388 -283.216191) (xy 31.34996 -283.159949)
			(xy 31.349442 -283.131514) (xy 31.349928 -283.104263) (xy 31.357684 -283.050315) (xy 31.373039 -282.99802)
			(xy 31.395681 -282.948443) (xy 31.425147 -282.902593) (xy 31.460838 -282.861402) (xy 31.502029 -282.825711)
			(xy 31.547879 -282.796245) (xy 31.597456 -282.773603) (xy 31.649751 -282.758248) (xy 31.703699 -282.750492)
			(xy 31.758201 -282.750492) (xy 31.812149 -282.758248) (xy 31.864444 -282.773603) (xy 31.914021 -282.796245)
			(xy 31.959871 -282.825711) (xy 32.001062 -282.861402) (xy 32.036753 -282.902593) (xy 32.066219 -282.948443)
			(xy 32.088861 -282.99802) (xy 32.104216 -283.050315) (xy 32.111972 -283.104263) (xy 32.112458 -283.131514)
			(xy 32.111907 -283.160896) (xy 32.102876 -283.218961) (xy 32.085044 -283.274954) (xy 32.058835 -283.327549)
			(xy 32.024867 -283.3755) (xy 31.983946 -283.417674) (xy 31.96082 -283.435806) (xy 31.951422 -283.443172)
			(xy 31.941008 -283.463746) (xy 31.939484 -283.567632) (xy 31.94939 -283.588714) (xy 31.958534 -283.59608)
			(xy 31.980362 -283.614309) (xy 32.018902 -283.656124) (xy 32.05081 -283.703195) (xy 32.07538 -283.75448)
			(xy 32.092068 -283.808843) (xy 32.100505 -283.865081) (xy 32.101028 -283.893514) (xy 32.734502 -283.893514)
			(xy 32.738573 -283.837892) (xy 32.750699 -283.783455) (xy 32.770622 -283.731364) (xy 32.797918 -283.682729)
			(xy 32.832004 -283.638586) (xy 32.872153 -283.599877) (xy 32.917511 -283.567426) (xy 32.967111 -283.541925)
			(xy 33.019895 -283.523918) (xy 33.074738 -283.513788) (xy 33.130472 -283.511751) (xy 33.185909 -283.517851)
			(xy 33.239866 -283.531957) (xy 33.291195 -283.553769) (xy 33.338801 -283.582823) (xy 33.381669 -283.618498)
			(xy 33.418886 -283.660035) (xy 33.449659 -283.706548) (xy 33.473331 -283.757045) (xy 33.489399 -283.810452)
			(xy 33.497519 -283.865628) (xy 33.498028 -283.893514) (xy 33.497519 -283.9214) (xy 33.489399 -283.976576)
			(xy 33.473331 -284.029983) (xy 33.449659 -284.08048) (xy 33.418886 -284.126993) (xy 33.381669 -284.16853)
			(xy 33.338801 -284.204205) (xy 33.291195 -284.233259) (xy 33.239866 -284.255071) (xy 33.185909 -284.269177)
			(xy 33.130472 -284.275277) (xy 33.074738 -284.27324) (xy 33.019895 -284.26311) (xy 32.967111 -284.245103)
			(xy 32.917511 -284.219602) (xy 32.872153 -284.187151) (xy 32.832004 -284.148442) (xy 32.797918 -284.104299)
			(xy 32.770622 -284.055664) (xy 32.750699 -284.003573) (xy 32.738573 -283.949136) (xy 32.734502 -283.893514)
			(xy 32.101028 -283.893514) (xy 32.100542 -283.920765) (xy 32.092786 -283.974713) (xy 32.077431 -284.027008)
			(xy 32.054789 -284.076585) (xy 32.025323 -284.122435) (xy 31.989632 -284.163626) (xy 31.948441 -284.199317)
			(xy 31.902591 -284.228783) (xy 31.853014 -284.251425) (xy 31.800719 -284.26678) (xy 31.746771 -284.274536)
			(xy 31.692269 -284.274536) (xy 31.638321 -284.26678) (xy 31.586026 -284.251425) (xy 31.536449 -284.228783)
			(xy 31.490599 -284.199317) (xy 31.449408 -284.163626) (xy 31.413717 -284.122435) (xy 31.384251 -284.076585)
			(xy 31.361609 -284.027008) (xy 31.346254 -283.974713) (xy 31.338498 -283.920765) (xy 31.338012 -283.893514)
			(xy 21.415248 -283.893514) (xy 21.415248 -285.029656) (xy 25.811478 -285.029656) (xy 25.815549 -284.974034)
			(xy 25.827675 -284.919597) (xy 25.847598 -284.867506) (xy 25.874894 -284.818871) (xy 25.90898 -284.774728)
			(xy 25.949129 -284.736019) (xy 25.994487 -284.703568) (xy 26.044087 -284.678067) (xy 26.096871 -284.66006)
			(xy 26.151714 -284.64993) (xy 26.207448 -284.647893) (xy 26.262885 -284.653993) (xy 26.316842 -284.668099)
			(xy 26.368171 -284.689911) (xy 26.415777 -284.718965) (xy 26.458645 -284.75464) (xy 26.495862 -284.796177)
			(xy 26.526635 -284.84269) (xy 26.550307 -284.893187) (xy 26.566375 -284.946594) (xy 26.574495 -285.00177)
			(xy 26.575004 -285.029656) (xy 27.296616 -285.029656) (xy 27.300687 -284.974034) (xy 27.312813 -284.919597)
			(xy 27.332736 -284.867506) (xy 27.360032 -284.818871) (xy 27.394118 -284.774728) (xy 27.434267 -284.736019)
			(xy 27.479625 -284.703568) (xy 27.529225 -284.678067) (xy 27.582009 -284.66006) (xy 27.636852 -284.64993)
			(xy 27.692586 -284.647893) (xy 27.748023 -284.653993) (xy 27.80198 -284.668099) (xy 27.853309 -284.689911)
			(xy 27.900915 -284.718965) (xy 27.943783 -284.75464) (xy 27.981 -284.796177) (xy 28.011773 -284.84269)
			(xy 28.035445 -284.893187) (xy 28.051513 -284.946594) (xy 28.059633 -285.00177) (xy 28.060142 -285.029656)
			(xy 28.059633 -285.057542) (xy 28.051513 -285.112718) (xy 28.035445 -285.166125) (xy 28.011773 -285.216622)
			(xy 27.981 -285.263135) (xy 27.943783 -285.304672) (xy 27.900915 -285.340347) (xy 27.853309 -285.369401)
			(xy 27.80198 -285.391213) (xy 27.748023 -285.405319) (xy 27.692586 -285.411419) (xy 27.636852 -285.409382)
			(xy 27.582009 -285.399252) (xy 27.529225 -285.381245) (xy 27.479625 -285.355744) (xy 27.434267 -285.323293)
			(xy 27.394118 -285.284584) (xy 27.360032 -285.240441) (xy 27.332736 -285.191806) (xy 27.312813 -285.139715)
			(xy 27.300687 -285.085278) (xy 27.296616 -285.029656) (xy 26.575004 -285.029656) (xy 26.574495 -285.057542)
			(xy 26.566375 -285.112718) (xy 26.550307 -285.166125) (xy 26.526635 -285.216622) (xy 26.495862 -285.263135)
			(xy 26.458645 -285.304672) (xy 26.415777 -285.340347) (xy 26.368171 -285.369401) (xy 26.316842 -285.391213)
			(xy 26.262885 -285.405319) (xy 26.207448 -285.411419) (xy 26.151714 -285.409382) (xy 26.096871 -285.399252)
			(xy 26.044087 -285.381245) (xy 25.994487 -285.355744) (xy 25.949129 -285.323293) (xy 25.90898 -285.284584)
			(xy 25.874894 -285.240441) (xy 25.847598 -285.191806) (xy 25.827675 -285.139715) (xy 25.815549 -285.085278)
			(xy 25.811478 -285.029656) (xy 21.415248 -285.029656) (xy 21.415248 -287.093914) (xy 31.338012 -287.093914)
			(xy 31.338555 -287.064532) (xy 31.347584 -287.006465) (xy 31.365415 -286.95047) (xy 31.391626 -286.897875)
			(xy 31.425597 -286.849924) (xy 31.466521 -286.807752) (xy 31.48965 -286.789622) (xy 31.499048 -286.782256)
			(xy 31.509462 -286.761682) (xy 31.510986 -286.657796) (xy 31.50108 -286.636714) (xy 31.491936 -286.629348)
			(xy 31.470088 -286.611142) (xy 31.431546 -286.569324) (xy 31.399638 -286.522249) (xy 31.375071 -286.470959)
			(xy 31.358388 -286.416591) (xy 31.34996 -286.360349) (xy 31.349442 -286.331914) (xy 31.349928 -286.304663)
			(xy 31.357684 -286.250715) (xy 31.373039 -286.19842) (xy 31.395681 -286.148843) (xy 31.425147 -286.102993)
			(xy 31.460838 -286.061802) (xy 31.502029 -286.026111) (xy 31.547879 -285.996645) (xy 31.597456 -285.974003)
			(xy 31.649751 -285.958648) (xy 31.703699 -285.950892) (xy 31.758201 -285.950892) (xy 31.812149 -285.958648)
			(xy 31.864444 -285.974003) (xy 31.914021 -285.996645) (xy 31.959871 -286.026111) (xy 32.001062 -286.061802)
			(xy 32.036753 -286.102993) (xy 32.066219 -286.148843) (xy 32.088861 -286.19842) (xy 32.104216 -286.250715)
			(xy 32.111972 -286.304663) (xy 32.112458 -286.331914) (xy 32.111907 -286.361296) (xy 32.102876 -286.419361)
			(xy 32.085044 -286.475354) (xy 32.058835 -286.527949) (xy 32.024867 -286.5759) (xy 31.983946 -286.618074)
			(xy 31.96082 -286.636206) (xy 31.951422 -286.643572) (xy 31.941008 -286.664146) (xy 31.939484 -286.768032)
			(xy 31.94939 -286.789114) (xy 31.958534 -286.79648) (xy 31.980362 -286.814709) (xy 32.018902 -286.856524)
			(xy 32.05081 -286.903595) (xy 32.07538 -286.95488) (xy 32.092068 -287.009243) (xy 32.100505 -287.065481)
			(xy 32.101028 -287.093914) (xy 32.734502 -287.093914) (xy 32.738573 -287.038292) (xy 32.750699 -286.983855)
			(xy 32.770622 -286.931764) (xy 32.797918 -286.883129) (xy 32.832004 -286.838986) (xy 32.872153 -286.800277)
			(xy 32.917511 -286.767826) (xy 32.967111 -286.742325) (xy 33.019895 -286.724318) (xy 33.074738 -286.714188)
			(xy 33.130472 -286.712151) (xy 33.185909 -286.718251) (xy 33.239866 -286.732357) (xy 33.291195 -286.754169)
			(xy 33.338801 -286.783223) (xy 33.381669 -286.818898) (xy 33.418886 -286.860435) (xy 33.449659 -286.906948)
			(xy 33.473331 -286.957445) (xy 33.489399 -287.010852) (xy 33.497519 -287.066028) (xy 33.498028 -287.093914)
			(xy 33.497519 -287.1218) (xy 33.489399 -287.176976) (xy 33.473331 -287.230383) (xy 33.449659 -287.28088)
			(xy 33.418886 -287.327393) (xy 33.381669 -287.36893) (xy 33.338801 -287.404605) (xy 33.291195 -287.433659)
			(xy 33.239866 -287.455471) (xy 33.185909 -287.469577) (xy 33.130472 -287.475677) (xy 33.074738 -287.47364)
			(xy 33.019895 -287.46351) (xy 32.967111 -287.445503) (xy 32.917511 -287.420002) (xy 32.872153 -287.387551)
			(xy 32.832004 -287.348842) (xy 32.797918 -287.304699) (xy 32.770622 -287.256064) (xy 32.750699 -287.203973)
			(xy 32.738573 -287.149536) (xy 32.734502 -287.093914) (xy 32.101028 -287.093914) (xy 32.100542 -287.121165)
			(xy 32.092786 -287.175113) (xy 32.077431 -287.227408) (xy 32.054789 -287.276985) (xy 32.025323 -287.322835)
			(xy 31.989632 -287.364026) (xy 31.948441 -287.399717) (xy 31.902591 -287.429183) (xy 31.853014 -287.451825)
			(xy 31.800719 -287.46718) (xy 31.746771 -287.474936) (xy 31.692269 -287.474936) (xy 31.638321 -287.46718)
			(xy 31.586026 -287.451825) (xy 31.536449 -287.429183) (xy 31.490599 -287.399717) (xy 31.449408 -287.364026)
			(xy 31.413717 -287.322835) (xy 31.384251 -287.276985) (xy 31.361609 -287.227408) (xy 31.346254 -287.175113)
			(xy 31.338498 -287.121165) (xy 31.338012 -287.093914) (xy 21.415248 -287.093914) (xy 21.415248 -288.230056)
			(xy 25.811478 -288.230056) (xy 25.815549 -288.174434) (xy 25.827675 -288.119997) (xy 25.847598 -288.067906)
			(xy 25.874894 -288.019271) (xy 25.90898 -287.975128) (xy 25.949129 -287.936419) (xy 25.994487 -287.903968)
			(xy 26.044087 -287.878467) (xy 26.096871 -287.86046) (xy 26.151714 -287.85033) (xy 26.207448 -287.848293)
			(xy 26.262885 -287.854393) (xy 26.316842 -287.868499) (xy 26.368171 -287.890311) (xy 26.415777 -287.919365)
			(xy 26.458645 -287.95504) (xy 26.495862 -287.996577) (xy 26.526635 -288.04309) (xy 26.550307 -288.093587)
			(xy 26.566375 -288.146994) (xy 26.574495 -288.20217) (xy 26.575004 -288.230056) (xy 27.296616 -288.230056)
			(xy 27.300687 -288.174434) (xy 27.312813 -288.119997) (xy 27.332736 -288.067906) (xy 27.360032 -288.019271)
			(xy 27.394118 -287.975128) (xy 27.434267 -287.936419) (xy 27.479625 -287.903968) (xy 27.529225 -287.878467)
			(xy 27.582009 -287.86046) (xy 27.636852 -287.85033) (xy 27.692586 -287.848293) (xy 27.748023 -287.854393)
			(xy 27.80198 -287.868499) (xy 27.853309 -287.890311) (xy 27.900915 -287.919365) (xy 27.943783 -287.95504)
			(xy 27.981 -287.996577) (xy 28.011773 -288.04309) (xy 28.035445 -288.093587) (xy 28.051513 -288.146994)
			(xy 28.059633 -288.20217) (xy 28.060142 -288.230056) (xy 28.059633 -288.257942) (xy 28.051513 -288.313118)
			(xy 28.035445 -288.366525) (xy 28.011773 -288.417022) (xy 27.981 -288.463535) (xy 27.943783 -288.505072)
			(xy 27.900915 -288.540747) (xy 27.853309 -288.569801) (xy 27.80198 -288.591613) (xy 27.748023 -288.605719)
			(xy 27.692586 -288.611819) (xy 27.636852 -288.609782) (xy 27.582009 -288.599652) (xy 27.529225 -288.581645)
			(xy 27.479625 -288.556144) (xy 27.434267 -288.523693) (xy 27.394118 -288.484984) (xy 27.360032 -288.440841)
			(xy 27.332736 -288.392206) (xy 27.312813 -288.340115) (xy 27.300687 -288.285678) (xy 27.296616 -288.230056)
			(xy 26.575004 -288.230056) (xy 26.574495 -288.257942) (xy 26.566375 -288.313118) (xy 26.550307 -288.366525)
			(xy 26.526635 -288.417022) (xy 26.495862 -288.463535) (xy 26.458645 -288.505072) (xy 26.415777 -288.540747)
			(xy 26.368171 -288.569801) (xy 26.316842 -288.591613) (xy 26.262885 -288.605719) (xy 26.207448 -288.611819)
			(xy 26.151714 -288.609782) (xy 26.096871 -288.599652) (xy 26.044087 -288.581645) (xy 25.994487 -288.556144)
			(xy 25.949129 -288.523693) (xy 25.90898 -288.484984) (xy 25.874894 -288.440841) (xy 25.847598 -288.392206)
			(xy 25.827675 -288.340115) (xy 25.815549 -288.285678) (xy 25.811478 -288.230056) (xy 21.415248 -288.230056)
			(xy 21.415248 -290.321238) (xy 31.234888 -290.321238) (xy 31.235327 -290.29466) (xy 31.242726 -290.24202)
			(xy 31.257359 -290.190917) (xy 31.278942 -290.142339) (xy 31.307058 -290.097226) (xy 31.341163 -290.056452)
			(xy 31.380596 -290.020805) (xy 31.424594 -289.990976) (xy 31.448248 -289.978846) (xy 31.460777 -289.972266)
			(xy 31.481831 -289.953371) (xy 31.49689 -289.929422) (xy 31.504794 -289.902259) (xy 31.504938 -289.873969)
			(xy 31.49731 -289.846727) (xy 31.482496 -289.822626) (xy 31.472378 -289.81273) (xy 31.45335 -289.794617)
			(xy 31.419969 -289.754051) (xy 31.392474 -289.709287) (xy 31.371382 -289.661172) (xy 31.357095 -289.610618)
			(xy 31.349882 -289.558581) (xy 31.349442 -289.532314) (xy 31.349928 -289.505063) (xy 31.357684 -289.451115)
			(xy 31.373039 -289.39882) (xy 31.395681 -289.349243) (xy 31.425147 -289.303393) (xy 31.460838 -289.262202)
			(xy 31.502029 -289.226511) (xy 31.547879 -289.197045) (xy 31.597456 -289.174403) (xy 31.649751 -289.159048)
			(xy 31.703699 -289.151292) (xy 31.758201 -289.151292) (xy 31.812149 -289.159048) (xy 31.864444 -289.174403)
			(xy 31.914021 -289.197045) (xy 31.959871 -289.226511) (xy 32.001062 -289.262202) (xy 32.036753 -289.303393)
			(xy 32.066219 -289.349243) (xy 32.088861 -289.39882) (xy 32.104216 -289.451115) (xy 32.111972 -289.505063)
			(xy 32.112458 -289.532314) (xy 32.111954 -289.55889) (xy 32.104562 -289.611525) (xy 32.089937 -289.662626)
			(xy 32.068363 -289.711202) (xy 32.040256 -289.756315) (xy 32.006161 -289.79709) (xy 31.966737 -289.83274)
			(xy 31.922747 -289.862573) (xy 31.899098 -289.874706) (xy 31.886606 -289.881344) (xy 31.865564 -289.900233)
			(xy 31.850513 -289.92417) (xy 31.842608 -289.951319) (xy 31.842456 -289.979595) (xy 31.850069 -290.006827)
			(xy 31.864862 -290.030925) (xy 31.874968 -290.040822) (xy 31.893963 -290.058969) (xy 31.927348 -290.099526)
			(xy 31.95485 -290.144283) (xy 31.975947 -290.192391) (xy 31.990241 -290.24294) (xy 31.997461 -290.294973)
			(xy 31.997904 -290.321238) (xy 31.997418 -290.348489) (xy 31.989662 -290.402437) (xy 31.974307 -290.454732)
			(xy 31.951665 -290.504309) (xy 31.922199 -290.550159) (xy 31.886508 -290.59135) (xy 31.845317 -290.627041)
			(xy 31.799467 -290.656507) (xy 31.74989 -290.679149) (xy 31.697595 -290.694504) (xy 31.643647 -290.70226)
			(xy 31.589145 -290.70226) (xy 31.535197 -290.694504) (xy 31.482902 -290.679149) (xy 31.433325 -290.656507)
			(xy 31.387475 -290.627041) (xy 31.346284 -290.59135) (xy 31.310593 -290.550159) (xy 31.281127 -290.504309)
			(xy 31.258485 -290.454732) (xy 31.24313 -290.402437) (xy 31.235374 -290.348489) (xy 31.234888 -290.321238)
			(xy 21.415248 -290.321238) (xy 21.415248 -290.820856) (xy 32.748218 -290.820856) (xy 32.752289 -290.765234)
			(xy 32.764415 -290.710797) (xy 32.784338 -290.658706) (xy 32.811634 -290.610071) (xy 32.84572 -290.565928)
			(xy 32.885869 -290.527219) (xy 32.931227 -290.494768) (xy 32.980827 -290.469267) (xy 33.033611 -290.45126)
			(xy 33.088454 -290.44113) (xy 33.144188 -290.439093) (xy 33.199625 -290.445193) (xy 33.253582 -290.459299)
			(xy 33.304911 -290.481111) (xy 33.352517 -290.510165) (xy 33.395385 -290.54584) (xy 33.432602 -290.587377)
			(xy 33.463375 -290.63389) (xy 33.487047 -290.684387) (xy 33.503115 -290.737794) (xy 33.511235 -290.79297)
			(xy 33.511744 -290.820856) (xy 33.511235 -290.848742) (xy 33.503115 -290.903918) (xy 33.487047 -290.957325)
			(xy 33.463375 -291.007822) (xy 33.432602 -291.054335) (xy 33.395385 -291.095872) (xy 33.352517 -291.131547)
			(xy 33.304911 -291.160601) (xy 33.253582 -291.182413) (xy 33.199625 -291.196519) (xy 33.144188 -291.202619)
			(xy 33.088454 -291.200582) (xy 33.033611 -291.190452) (xy 32.980827 -291.172445) (xy 32.931227 -291.146944)
			(xy 32.885869 -291.114493) (xy 32.84572 -291.075784) (xy 32.811634 -291.031641) (xy 32.784338 -290.983006)
			(xy 32.764415 -290.930915) (xy 32.752289 -290.876478) (xy 32.748218 -290.820856) (xy 21.415248 -290.820856)
			(xy 21.415248 -291.430456) (xy 25.811478 -291.430456) (xy 25.815549 -291.374834) (xy 25.827675 -291.320397)
			(xy 25.847598 -291.268306) (xy 25.874894 -291.219671) (xy 25.90898 -291.175528) (xy 25.949129 -291.136819)
			(xy 25.994487 -291.104368) (xy 26.044087 -291.078867) (xy 26.096871 -291.06086) (xy 26.151714 -291.05073)
			(xy 26.207448 -291.048693) (xy 26.262885 -291.054793) (xy 26.316842 -291.068899) (xy 26.368171 -291.090711)
			(xy 26.415777 -291.119765) (xy 26.458645 -291.15544) (xy 26.495862 -291.196977) (xy 26.526635 -291.24349)
			(xy 26.550307 -291.293987) (xy 26.566375 -291.347394) (xy 26.574495 -291.40257) (xy 26.575004 -291.430456)
			(xy 27.296616 -291.430456) (xy 27.300687 -291.374834) (xy 27.312813 -291.320397) (xy 27.332736 -291.268306)
			(xy 27.360032 -291.219671) (xy 27.394118 -291.175528) (xy 27.434267 -291.136819) (xy 27.479625 -291.104368)
			(xy 27.529225 -291.078867) (xy 27.582009 -291.06086) (xy 27.636852 -291.05073) (xy 27.692586 -291.048693)
			(xy 27.748023 -291.054793) (xy 27.80198 -291.068899) (xy 27.853309 -291.090711) (xy 27.900915 -291.119765)
			(xy 27.943783 -291.15544) (xy 27.981 -291.196977) (xy 28.011773 -291.24349) (xy 28.035445 -291.293987)
			(xy 28.051513 -291.347394) (xy 28.059633 -291.40257) (xy 28.060142 -291.430456) (xy 28.059633 -291.458342)
			(xy 28.051513 -291.513518) (xy 28.035445 -291.566925) (xy 28.011773 -291.617422) (xy 27.981 -291.663935)
			(xy 27.943783 -291.705472) (xy 27.900915 -291.741147) (xy 27.853309 -291.770201) (xy 27.80198 -291.792013)
			(xy 27.748023 -291.806119) (xy 27.692586 -291.812219) (xy 27.636852 -291.810182) (xy 27.582009 -291.800052)
			(xy 27.529225 -291.782045) (xy 27.479625 -291.756544) (xy 27.434267 -291.724093) (xy 27.394118 -291.685384)
			(xy 27.360032 -291.641241) (xy 27.332736 -291.592606) (xy 27.312813 -291.540515) (xy 27.300687 -291.486078)
			(xy 27.296616 -291.430456) (xy 26.575004 -291.430456) (xy 26.574495 -291.458342) (xy 26.566375 -291.513518)
			(xy 26.550307 -291.566925) (xy 26.526635 -291.617422) (xy 26.495862 -291.663935) (xy 26.458645 -291.705472)
			(xy 26.415777 -291.741147) (xy 26.368171 -291.770201) (xy 26.316842 -291.792013) (xy 26.262885 -291.806119)
			(xy 26.207448 -291.812219) (xy 26.151714 -291.810182) (xy 26.096871 -291.800052) (xy 26.044087 -291.782045)
			(xy 25.994487 -291.756544) (xy 25.949129 -291.724093) (xy 25.90898 -291.685384) (xy 25.874894 -291.641241)
			(xy 25.847598 -291.592606) (xy 25.827675 -291.540515) (xy 25.815549 -291.486078) (xy 25.811478 -291.430456)
			(xy 21.415248 -291.430456) (xy 21.415248 -293.494714) (xy 31.338012 -293.494714) (xy 31.338555 -293.465332)
			(xy 31.347584 -293.407265) (xy 31.365415 -293.35127) (xy 31.391626 -293.298675) (xy 31.425597 -293.250724)
			(xy 31.466521 -293.208552) (xy 31.48965 -293.190422) (xy 31.499048 -293.183056) (xy 31.509462 -293.162482)
			(xy 31.510986 -293.058596) (xy 31.50108 -293.037514) (xy 31.491936 -293.030148) (xy 31.470088 -293.011942)
			(xy 31.431546 -292.970124) (xy 31.399638 -292.923049) (xy 31.375071 -292.871759) (xy 31.358388 -292.817391)
			(xy 31.34996 -292.761149) (xy 31.349442 -292.732714) (xy 31.349928 -292.705463) (xy 31.357684 -292.651515)
			(xy 31.373039 -292.59922) (xy 31.395681 -292.549643) (xy 31.425147 -292.503793) (xy 31.460838 -292.462602)
			(xy 31.502029 -292.426911) (xy 31.547879 -292.397445) (xy 31.597456 -292.374803) (xy 31.649751 -292.359448)
			(xy 31.703699 -292.351692) (xy 31.758201 -292.351692) (xy 31.812149 -292.359448) (xy 31.864444 -292.374803)
			(xy 31.914021 -292.397445) (xy 31.959871 -292.426911) (xy 32.001062 -292.462602) (xy 32.036753 -292.503793)
			(xy 32.066219 -292.549643) (xy 32.088861 -292.59922) (xy 32.104216 -292.651515) (xy 32.111972 -292.705463)
			(xy 32.112458 -292.732714) (xy 32.111907 -292.762096) (xy 32.102876 -292.820161) (xy 32.085044 -292.876154)
			(xy 32.058835 -292.928749) (xy 32.024867 -292.9767) (xy 31.983946 -293.018874) (xy 31.96082 -293.037006)
			(xy 31.951422 -293.044372) (xy 31.941008 -293.064946) (xy 31.939484 -293.168832) (xy 31.94939 -293.189914)
			(xy 31.958534 -293.19728) (xy 31.980362 -293.215509) (xy 32.018902 -293.257324) (xy 32.05081 -293.304395)
			(xy 32.07538 -293.35568) (xy 32.092068 -293.410043) (xy 32.100505 -293.466281) (xy 32.101028 -293.494714)
			(xy 32.734502 -293.494714) (xy 32.738573 -293.439092) (xy 32.750699 -293.384655) (xy 32.770622 -293.332564)
			(xy 32.797918 -293.283929) (xy 32.832004 -293.239786) (xy 32.872153 -293.201077) (xy 32.917511 -293.168626)
			(xy 32.967111 -293.143125) (xy 33.019895 -293.125118) (xy 33.074738 -293.114988) (xy 33.130472 -293.112951)
			(xy 33.185909 -293.119051) (xy 33.239866 -293.133157) (xy 33.291195 -293.154969) (xy 33.338801 -293.184023)
			(xy 33.381669 -293.219698) (xy 33.418886 -293.261235) (xy 33.449659 -293.307748) (xy 33.473331 -293.358245)
			(xy 33.489399 -293.411652) (xy 33.497519 -293.466828) (xy 33.498028 -293.494714) (xy 33.497519 -293.5226)
			(xy 33.489399 -293.577776) (xy 33.473331 -293.631183) (xy 33.449659 -293.68168) (xy 33.418886 -293.728193)
			(xy 33.381669 -293.76973) (xy 33.338801 -293.805405) (xy 33.291195 -293.834459) (xy 33.239866 -293.856271)
			(xy 33.185909 -293.870377) (xy 33.130472 -293.876477) (xy 33.074738 -293.87444) (xy 33.019895 -293.86431)
			(xy 32.967111 -293.846303) (xy 32.917511 -293.820802) (xy 32.872153 -293.788351) (xy 32.832004 -293.749642)
			(xy 32.797918 -293.705499) (xy 32.770622 -293.656864) (xy 32.750699 -293.604773) (xy 32.738573 -293.550336)
			(xy 32.734502 -293.494714) (xy 32.101028 -293.494714) (xy 32.100542 -293.521965) (xy 32.092786 -293.575913)
			(xy 32.077431 -293.628208) (xy 32.054789 -293.677785) (xy 32.025323 -293.723635) (xy 31.989632 -293.764826)
			(xy 31.948441 -293.800517) (xy 31.902591 -293.829983) (xy 31.853014 -293.852625) (xy 31.800719 -293.86798)
			(xy 31.746771 -293.875736) (xy 31.692269 -293.875736) (xy 31.638321 -293.86798) (xy 31.586026 -293.852625)
			(xy 31.536449 -293.829983) (xy 31.490599 -293.800517) (xy 31.449408 -293.764826) (xy 31.413717 -293.723635)
			(xy 31.384251 -293.677785) (xy 31.361609 -293.628208) (xy 31.346254 -293.575913) (xy 31.338498 -293.521965)
			(xy 31.338012 -293.494714) (xy 21.415248 -293.494714) (xy 21.415248 -294.630856) (xy 25.811478 -294.630856)
			(xy 25.815549 -294.575234) (xy 25.827675 -294.520797) (xy 25.847598 -294.468706) (xy 25.874894 -294.420071)
			(xy 25.90898 -294.375928) (xy 25.949129 -294.337219) (xy 25.994487 -294.304768) (xy 26.044087 -294.279267)
			(xy 26.096871 -294.26126) (xy 26.151714 -294.25113) (xy 26.207448 -294.249093) (xy 26.262885 -294.255193)
			(xy 26.316842 -294.269299) (xy 26.368171 -294.291111) (xy 26.415777 -294.320165) (xy 26.458645 -294.35584)
			(xy 26.495862 -294.397377) (xy 26.526635 -294.44389) (xy 26.550307 -294.494387) (xy 26.566375 -294.547794)
			(xy 26.574495 -294.60297) (xy 26.575004 -294.630856) (xy 27.296616 -294.630856) (xy 27.300687 -294.575234)
			(xy 27.312813 -294.520797) (xy 27.332736 -294.468706) (xy 27.360032 -294.420071) (xy 27.394118 -294.375928)
			(xy 27.434267 -294.337219) (xy 27.479625 -294.304768) (xy 27.529225 -294.279267) (xy 27.582009 -294.26126)
			(xy 27.636852 -294.25113) (xy 27.692586 -294.249093) (xy 27.748023 -294.255193) (xy 27.80198 -294.269299)
			(xy 27.853309 -294.291111) (xy 27.900915 -294.320165) (xy 27.943783 -294.35584) (xy 27.981 -294.397377)
			(xy 28.011773 -294.44389) (xy 28.035445 -294.494387) (xy 28.051513 -294.547794) (xy 28.059633 -294.60297)
			(xy 28.060142 -294.630856) (xy 28.059633 -294.658742) (xy 28.051513 -294.713918) (xy 28.035445 -294.767325)
			(xy 28.011773 -294.817822) (xy 27.981 -294.864335) (xy 27.943783 -294.905872) (xy 27.900915 -294.941547)
			(xy 27.853309 -294.970601) (xy 27.80198 -294.992413) (xy 27.748023 -295.006519) (xy 27.692586 -295.012619)
			(xy 27.636852 -295.010582) (xy 27.582009 -295.000452) (xy 27.529225 -294.982445) (xy 27.479625 -294.956944)
			(xy 27.434267 -294.924493) (xy 27.394118 -294.885784) (xy 27.360032 -294.841641) (xy 27.332736 -294.793006)
			(xy 27.312813 -294.740915) (xy 27.300687 -294.686478) (xy 27.296616 -294.630856) (xy 26.575004 -294.630856)
			(xy 26.574495 -294.658742) (xy 26.566375 -294.713918) (xy 26.550307 -294.767325) (xy 26.526635 -294.817822)
			(xy 26.495862 -294.864335) (xy 26.458645 -294.905872) (xy 26.415777 -294.941547) (xy 26.368171 -294.970601)
			(xy 26.316842 -294.992413) (xy 26.262885 -295.006519) (xy 26.207448 -295.012619) (xy 26.151714 -295.010582)
			(xy 26.096871 -295.000452) (xy 26.044087 -294.982445) (xy 25.994487 -294.956944) (xy 25.949129 -294.924493)
			(xy 25.90898 -294.885784) (xy 25.874894 -294.841641) (xy 25.847598 -294.793006) (xy 25.827675 -294.740915)
			(xy 25.815549 -294.686478) (xy 25.811478 -294.630856) (xy 21.415248 -294.630856) (xy 21.415248 -295.347898)
			(xy 21.415786 -295.357885) (xy 21.423505 -295.376313) (xy 21.430234 -295.383712) (xy 22.768656 -296.722038)
			(xy 31.234888 -296.722038) (xy 31.235327 -296.69546) (xy 31.242726 -296.64282) (xy 31.257359 -296.591717)
			(xy 31.278942 -296.543139) (xy 31.307058 -296.498026) (xy 31.341163 -296.457252) (xy 31.380596 -296.421605)
			(xy 31.424594 -296.391776) (xy 31.448248 -296.379646) (xy 31.460777 -296.373066) (xy 31.481831 -296.354171)
			(xy 31.49689 -296.330222) (xy 31.504794 -296.303059) (xy 31.504938 -296.274769) (xy 31.49731 -296.247527)
			(xy 31.482496 -296.223426) (xy 31.472378 -296.21353) (xy 31.45335 -296.195417) (xy 31.419969 -296.154851)
			(xy 31.392474 -296.110087) (xy 31.371382 -296.061972) (xy 31.357095 -296.011418) (xy 31.349882 -295.959381)
			(xy 31.349442 -295.933114) (xy 31.349928 -295.905863) (xy 31.357684 -295.851915) (xy 31.373039 -295.79962)
			(xy 31.395681 -295.750043) (xy 31.425147 -295.704193) (xy 31.460838 -295.663002) (xy 31.502029 -295.627311)
			(xy 31.547879 -295.597845) (xy 31.597456 -295.575203) (xy 31.649751 -295.559848) (xy 31.703699 -295.552092)
			(xy 31.758201 -295.552092) (xy 31.812149 -295.559848) (xy 31.864444 -295.575203) (xy 31.914021 -295.597845)
			(xy 31.959871 -295.627311) (xy 32.001062 -295.663002) (xy 32.036753 -295.704193) (xy 32.066219 -295.750043)
			(xy 32.088861 -295.79962) (xy 32.104216 -295.851915) (xy 32.111972 -295.905863) (xy 32.112458 -295.933114)
			(xy 32.111954 -295.95969) (xy 32.104562 -296.012325) (xy 32.089937 -296.063426) (xy 32.068363 -296.112002)
			(xy 32.040256 -296.157115) (xy 32.006161 -296.19789) (xy 31.966737 -296.23354) (xy 31.922747 -296.263373)
			(xy 31.899098 -296.275506) (xy 31.886606 -296.282144) (xy 31.865564 -296.301033) (xy 31.850513 -296.32497)
			(xy 31.842608 -296.352119) (xy 31.842456 -296.380395) (xy 31.850069 -296.407627) (xy 31.864862 -296.431725)
			(xy 31.874968 -296.441622) (xy 31.893963 -296.459769) (xy 31.927348 -296.500326) (xy 31.95485 -296.545083)
			(xy 31.975947 -296.593191) (xy 31.990241 -296.64374) (xy 31.997461 -296.695773) (xy 31.997904 -296.722038)
			(xy 31.997418 -296.749289) (xy 31.989662 -296.803237) (xy 31.974307 -296.855532) (xy 31.951665 -296.905109)
			(xy 31.922199 -296.950959) (xy 31.886508 -296.99215) (xy 31.845317 -297.027841) (xy 31.799467 -297.057307)
			(xy 31.74989 -297.079949) (xy 31.697595 -297.095304) (xy 31.643647 -297.10306) (xy 31.589145 -297.10306)
			(xy 31.535197 -297.095304) (xy 31.482902 -297.079949) (xy 31.433325 -297.057307) (xy 31.387475 -297.027841)
			(xy 31.346284 -296.99215) (xy 31.310593 -296.950959) (xy 31.281127 -296.905109) (xy 31.258485 -296.855532)
			(xy 31.24313 -296.803237) (xy 31.235374 -296.749289) (xy 31.234888 -296.722038) (xy 22.768656 -296.722038)
			(xy 23.26831 -297.221656) (xy 32.748218 -297.221656) (xy 32.752289 -297.166034) (xy 32.764415 -297.111597)
			(xy 32.784338 -297.059506) (xy 32.811634 -297.010871) (xy 32.84572 -296.966728) (xy 32.885869 -296.928019)
			(xy 32.931227 -296.895568) (xy 32.980827 -296.870067) (xy 33.033611 -296.85206) (xy 33.088454 -296.84193)
			(xy 33.144188 -296.839893) (xy 33.199625 -296.845993) (xy 33.253582 -296.860099) (xy 33.304911 -296.881911)
			(xy 33.352517 -296.910965) (xy 33.395385 -296.94664) (xy 33.432602 -296.988177) (xy 33.463375 -297.03469)
			(xy 33.487047 -297.085187) (xy 33.503115 -297.138594) (xy 33.511235 -297.19377) (xy 33.511744 -297.221656)
			(xy 33.511235 -297.249542) (xy 33.503115 -297.304718) (xy 33.487047 -297.358125) (xy 33.463375 -297.408622)
			(xy 33.432602 -297.455135) (xy 33.395385 -297.496672) (xy 33.352517 -297.532347) (xy 33.304911 -297.561401)
			(xy 33.253582 -297.583213) (xy 33.199625 -297.597319) (xy 33.144188 -297.603419) (xy 33.088454 -297.601382)
			(xy 33.033611 -297.591252) (xy 32.980827 -297.573245) (xy 32.931227 -297.547744) (xy 32.885869 -297.515293)
			(xy 32.84572 -297.476584) (xy 32.811634 -297.432441) (xy 32.784338 -297.383806) (xy 32.764415 -297.331715)
			(xy 32.752289 -297.277278) (xy 32.748218 -297.221656) (xy 23.26831 -297.221656) (xy 23.877953 -297.831256)
			(xy 25.811478 -297.831256) (xy 25.815549 -297.775634) (xy 25.827675 -297.721197) (xy 25.847598 -297.669106)
			(xy 25.874894 -297.620471) (xy 25.90898 -297.576328) (xy 25.949129 -297.537619) (xy 25.994487 -297.505168)
			(xy 26.044087 -297.479667) (xy 26.096871 -297.46166) (xy 26.151714 -297.45153) (xy 26.207448 -297.449493)
			(xy 26.262885 -297.455593) (xy 26.316842 -297.469699) (xy 26.368171 -297.491511) (xy 26.415777 -297.520565)
			(xy 26.458645 -297.55624) (xy 26.495862 -297.597777) (xy 26.526635 -297.64429) (xy 26.550307 -297.694787)
			(xy 26.566375 -297.748194) (xy 26.574495 -297.80337) (xy 26.575004 -297.831256) (xy 27.296616 -297.831256)
			(xy 27.300687 -297.775634) (xy 27.312813 -297.721197) (xy 27.332736 -297.669106) (xy 27.360032 -297.620471)
			(xy 27.394118 -297.576328) (xy 27.434267 -297.537619) (xy 27.479625 -297.505168) (xy 27.529225 -297.479667)
			(xy 27.582009 -297.46166) (xy 27.636852 -297.45153) (xy 27.692586 -297.449493) (xy 27.748023 -297.455593)
			(xy 27.80198 -297.469699) (xy 27.853309 -297.491511) (xy 27.900915 -297.520565) (xy 27.943783 -297.55624)
			(xy 27.981 -297.597777) (xy 28.011773 -297.64429) (xy 28.035445 -297.694787) (xy 28.051513 -297.748194)
			(xy 28.059633 -297.80337) (xy 28.060142 -297.831256) (xy 28.059633 -297.859142) (xy 28.051513 -297.914318)
			(xy 28.035445 -297.967725) (xy 28.011773 -298.018222) (xy 27.981 -298.064735) (xy 27.943783 -298.106272)
			(xy 27.900915 -298.141947) (xy 27.853309 -298.171001) (xy 27.80198 -298.192813) (xy 27.748023 -298.206919)
			(xy 27.692586 -298.213019) (xy 27.636852 -298.210982) (xy 27.582009 -298.200852) (xy 27.529225 -298.182845)
			(xy 27.479625 -298.157344) (xy 27.434267 -298.124893) (xy 27.394118 -298.086184) (xy 27.360032 -298.042041)
			(xy 27.332736 -297.993406) (xy 27.312813 -297.941315) (xy 27.300687 -297.886878) (xy 27.296616 -297.831256)
			(xy 26.575004 -297.831256) (xy 26.574495 -297.859142) (xy 26.566375 -297.914318) (xy 26.550307 -297.967725)
			(xy 26.526635 -298.018222) (xy 26.495862 -298.064735) (xy 26.458645 -298.106272) (xy 26.415777 -298.141947)
			(xy 26.368171 -298.171001) (xy 26.316842 -298.192813) (xy 26.262885 -298.206919) (xy 26.207448 -298.213019)
			(xy 26.151714 -298.210982) (xy 26.096871 -298.200852) (xy 26.044087 -298.182845) (xy 25.994487 -298.157344)
			(xy 25.949129 -298.124893) (xy 25.90898 -298.086184) (xy 25.874894 -298.042041) (xy 25.847598 -297.993406)
			(xy 25.827675 -297.941315) (xy 25.815549 -297.886878) (xy 25.811478 -297.831256) (xy 23.877953 -297.831256)
			(xy 24.974296 -298.92752) (xy 24.996295 -298.950246) (xy 25.034768 -299.000451) (xy 25.066358 -299.055248)
			(xy 25.090524 -299.113701) (xy 25.106853 -299.174808) (xy 25.115065 -299.237524) (xy 25.11552 -299.26915)
			(xy 25.11552 -300.209966) (xy 25.116052 -300.219956) (xy 25.123759 -300.238395) (xy 25.130506 -300.24578)
			(xy 25.291288 -300.406562) (xy 25.998676 -300.406562) (xy 26.002747 -300.35094) (xy 26.014873 -300.296503)
			(xy 26.034796 -300.244412) (xy 26.062092 -300.195777) (xy 26.096178 -300.151634) (xy 26.136327 -300.112925)
			(xy 26.181685 -300.080474) (xy 26.231285 -300.054973) (xy 26.284069 -300.036966) (xy 26.338912 -300.026836)
			(xy 26.394646 -300.024799) (xy 26.450083 -300.030899) (xy 26.50404 -300.045005) (xy 26.555369 -300.066817)
			(xy 26.602975 -300.095871) (xy 26.645843 -300.131546) (xy 26.68306 -300.173083) (xy 26.713833 -300.219596)
			(xy 26.737505 -300.270093) (xy 26.753573 -300.3235) (xy 26.761693 -300.378676) (xy 26.762202 -300.406562)
			(xy 26.761693 -300.434448) (xy 26.753573 -300.489624) (xy 26.737505 -300.543031) (xy 26.713833 -300.593528)
			(xy 26.68306 -300.640041) (xy 26.645843 -300.681578) (xy 26.602975 -300.717253) (xy 26.555369 -300.746307)
			(xy 26.50404 -300.768119) (xy 26.450083 -300.782225) (xy 26.394646 -300.788325) (xy 26.338912 -300.786288)
			(xy 26.284069 -300.776158) (xy 26.231285 -300.758151) (xy 26.181685 -300.73265) (xy 26.136327 -300.700199)
			(xy 26.096178 -300.66149) (xy 26.062092 -300.617347) (xy 26.034796 -300.568712) (xy 26.014873 -300.516621)
			(xy 26.002747 -300.462184) (xy 25.998676 -300.406562) (xy 25.291288 -300.406562) (xy 26.29789 -301.413164)
			(xy 26.305286 -301.420016) (xy 26.323885 -301.42776) (xy 26.333958 -301.42815)
		)
		(stroke
			(width 0)
			(type solid)
		)
		(fill yes)
		(layer "In5.Cu")
		(net "GND")
	)
	(gr_poly
		(pts
			(xy 173.78553 -269.286736) (xy 173.795596 -269.286306) (xy 173.814187 -269.278576) (xy 173.821598 -269.27175)
			(xy 173.834806 -269.258542) (xy 173.840906 -269.251945) (xy 173.848435 -269.235645) (xy 173.849861 -269.217747)
			(xy 173.84776 -269.209012) (xy 159.582104 -218.189556) (xy 159.578609 -218.179043) (xy 159.56426 -218.162196)
			(xy 159.544149 -218.15296) (xy 159.533082 -218.152472) (xy 153.255218 -218.152472) (xy 153.245168 -218.152978)
			(xy 153.226607 -218.1607) (xy 153.21915 -218.167458) (xy 153.156158 -218.23045) (xy 153.149349 -218.237795)
			(xy 153.141626 -218.256258) (xy 153.141172 -218.266264) (xy 153.141172 -230.324406) (xy 153.14171 -230.334394)
			(xy 153.149422 -230.352827) (xy 153.156158 -230.36022) (xy 154.361896 -231.565958) (xy 154.379982 -231.58475)
			(xy 154.410613 -231.626962) (xy 154.434261 -231.673446) (xy 154.450344 -231.723059) (xy 154.458465 -231.774577)
			(xy 154.458924 -231.800654) (xy 154.458924 -233.171746) (xy 154.458459 -233.197823) (xy 154.450337 -233.24934)
			(xy 154.434255 -233.298951) (xy 154.410607 -233.345435) (xy 154.379977 -233.387645) (xy 154.361896 -233.406442)
			(xy 152.88006 -234.888278) (xy 152.873255 -234.895625) (xy 152.865542 -234.914088) (xy 152.865074 -234.924092)
			(xy 152.855882 -239.07907) (xy 153.398934 -239.07907) (xy 153.398934 -239.01913) (xy 153.406758 -238.959703)
			(xy 153.422271 -238.901805) (xy 153.445208 -238.846427) (xy 153.475178 -238.794517) (xy 153.511666 -238.746963)
			(xy 153.554049 -238.704578) (xy 153.601602 -238.668088) (xy 153.653511 -238.638116) (xy 153.708888 -238.615177)
			(xy 153.766785 -238.599661) (xy 153.826212 -238.591835) (xy 153.856182 -238.591344) (xy 154.719782 -238.591344)
			(xy 154.749749 -238.591908) (xy 154.809169 -238.599729) (xy 154.867061 -238.615239) (xy 154.922433 -238.638172)
			(xy 154.974337 -238.668138) (xy 155.021886 -238.704622) (xy 155.064267 -238.747) (xy 155.100752 -238.794548)
			(xy 155.13072 -238.846451) (xy 155.153656 -238.901822) (xy 155.169168 -238.959713) (xy 155.176991 -239.019133)
			(xy 155.176991 -239.079067) (xy 155.169168 -239.138487) (xy 155.153656 -239.196378) (xy 155.13072 -239.251749)
			(xy 155.100752 -239.303652) (xy 155.064267 -239.3512) (xy 155.021886 -239.393578) (xy 154.974337 -239.430062)
			(xy 154.922433 -239.460028) (xy 154.867061 -239.482961) (xy 154.809169 -239.498471) (xy 154.749749 -239.506292)
			(xy 154.719782 -239.50676) (xy 153.856182 -239.50676) (xy 153.826212 -239.506365) (xy 153.766785 -239.498539)
			(xy 153.708888 -239.483023) (xy 153.653511 -239.460084) (xy 153.601602 -239.430112) (xy 153.554049 -239.393622)
			(xy 153.511666 -239.351237) (xy 153.475178 -239.303683) (xy 153.445208 -239.251773) (xy 153.422271 -239.196395)
			(xy 153.406758 -239.138497) (xy 153.398934 -239.07907) (xy 152.855882 -239.07907) (xy 152.855676 -239.171988)
			(xy 152.856096 -239.18206) (xy 152.863805 -239.20067) (xy 152.870662 -239.208056) (xy 155.440126 -241.77752)
			(xy 155.458239 -241.796301) (xy 155.488924 -241.838498) (xy 155.512625 -241.884979) (xy 155.528758 -241.934597)
			(xy 155.536923 -241.986129) (xy 155.537408 -242.012216) (xy 155.537408 -251.158502) (xy 156.316424 -251.158502)
			(xy 156.320495 -251.10288) (xy 156.332621 -251.048443) (xy 156.352544 -250.996352) (xy 156.37984 -250.947717)
			(xy 156.413926 -250.903574) (xy 156.454075 -250.864865) (xy 156.499433 -250.832414) (xy 156.549033 -250.806913)
			(xy 156.601817 -250.788906) (xy 156.65666 -250.778776) (xy 156.712394 -250.776739) (xy 156.767831 -250.782839)
			(xy 156.821788 -250.796945) (xy 156.873117 -250.818757) (xy 156.920723 -250.847811) (xy 156.963591 -250.883486)
			(xy 157.000808 -250.925023) (xy 157.031581 -250.971536) (xy 157.055253 -251.022033) (xy 157.071321 -251.07544)
			(xy 157.079441 -251.130616) (xy 157.07995 -251.158502) (xy 157.079441 -251.186388) (xy 157.071321 -251.241564)
			(xy 157.055253 -251.294971) (xy 157.031581 -251.345468) (xy 157.000808 -251.391981) (xy 156.963591 -251.433518)
			(xy 156.920723 -251.469193) (xy 156.873117 -251.498247) (xy 156.821788 -251.520059) (xy 156.767831 -251.534165)
			(xy 156.712394 -251.540265) (xy 156.65666 -251.538228) (xy 156.601817 -251.528098) (xy 156.549033 -251.510091)
			(xy 156.499433 -251.48459) (xy 156.454075 -251.452139) (xy 156.413926 -251.41343) (xy 156.37984 -251.369287)
			(xy 156.352544 -251.320652) (xy 156.332621 -251.268561) (xy 156.320495 -251.214124) (xy 156.316424 -251.158502)
			(xy 155.537408 -251.158502) (xy 155.537408 -252.820932) (xy 155.537888 -252.830897) (xy 155.545468 -252.849329)
			(xy 155.55214 -252.856746) (xy 155.779216 -253.083822) (xy 155.789884 -253.090172) (xy 155.795726 -253.092204)
			(xy 155.821283 -253.100642) (xy 155.869913 -253.123698) (xy 155.914822 -253.153358) (xy 155.955118 -253.189032)
			(xy 155.990003 -253.230014) (xy 156.018784 -253.275491) (xy 156.040891 -253.32456) (xy 156.055885 -253.376249)
			(xy 156.063469 -253.429531) (xy 156.06395 -253.45644) (xy 156.063462 -253.48369) (xy 156.055701 -253.537636)
			(xy 156.040342 -253.589928) (xy 156.0177 -253.639503) (xy 155.988233 -253.685352) (xy 155.952542 -253.726541)
			(xy 155.911353 -253.762232) (xy 155.865505 -253.791699) (xy 155.81593 -253.814342) (xy 155.763638 -253.8297)
			(xy 155.709692 -253.837461) (xy 155.682442 -253.837948) (xy 155.655529 -253.837488) (xy 155.602238 -253.829926)
			(xy 155.550539 -253.814944) (xy 155.501461 -253.792842) (xy 155.455978 -253.764059) (xy 155.414994 -253.729166)
			(xy 155.379324 -253.688857) (xy 155.349677 -253.643932) (xy 155.326641 -253.595285) (xy 155.318206 -253.569724)
			(xy 155.316174 -253.563882) (xy 155.309824 -253.553214) (xy 154.970734 -253.214124) (xy 154.952621 -253.195344)
			(xy 154.921938 -253.153147) (xy 154.89824 -253.106665) (xy 154.882113 -253.057047) (xy 154.873955 -253.005515)
			(xy 154.873452 -252.979428) (xy 154.873452 -251.629926) (xy 154.872992 -251.618509) (xy 154.863205 -251.597885)
			(xy 154.854656 -251.590302) (xy 154.783536 -251.533406) (xy 154.761184 -251.528326) (xy 154.749754 -251.530866)
			(xy 154.729194 -251.535156) (xy 154.687443 -251.539736) (xy 154.666442 -251.54001) (xy 154.639187 -251.53955)
			(xy 154.585231 -251.531797) (xy 154.532928 -251.516445) (xy 154.483342 -251.493805) (xy 154.437484 -251.464338)
			(xy 154.396286 -251.428644) (xy 154.360588 -251.38745) (xy 154.331115 -251.341594) (xy 154.30847 -251.292011)
			(xy 154.293112 -251.23971) (xy 154.285353 -251.185755) (xy 154.285353 -251.131245) (xy 154.293112 -251.07729)
			(xy 154.30847 -251.024989) (xy 154.331115 -250.975406) (xy 154.360588 -250.92955) (xy 154.396286 -250.888356)
			(xy 154.437484 -250.852662) (xy 154.483342 -250.823195) (xy 154.532928 -250.800555) (xy 154.585231 -250.785203)
			(xy 154.639187 -250.77745) (xy 154.666442 -250.776994) (xy 154.687443 -250.777266) (xy 154.729195 -250.781845)
			(xy 154.749754 -250.786138) (xy 154.761184 -250.788678) (xy 154.783536 -250.783598) (xy 154.854656 -250.726702)
			(xy 154.863099 -250.719037) (xy 154.872869 -250.698465) (xy 154.873452 -250.687078) (xy 154.873452 -245.876064)
			(xy 154.873026 -245.866051) (xy 154.865347 -245.847555) (xy 154.851175 -245.833405) (xy 154.832666 -245.825758)
			(xy 154.822652 -245.825264) (xy 154.814016 -245.825264) (xy 154.805634 -245.828312) (xy 154.790394 -245.833392)
			(xy 154.784552 -245.835424) (xy 154.773884 -245.841774) (xy 152.97023 -247.645428) (xy 152.951439 -247.663516)
			(xy 152.909229 -247.694152) (xy 152.862745 -247.717803) (xy 152.813131 -247.733888) (xy 152.761612 -247.742009)
			(xy 152.735534 -247.742456) (xy 152.531572 -247.742456) (xy 152.521588 -247.743) (xy 152.503169 -247.750727)
			(xy 152.495758 -247.757442) (xy 152.487376 -247.765824) (xy 152.47998 -247.772675) (xy 152.461381 -247.780413)
			(xy 152.451308 -247.78081) (xy 144.34693 -247.78081) (xy 144.336866 -247.781246) (xy 144.318281 -247.78898)
			(xy 144.310862 -247.795796) (xy 143.855694 -248.250964) (xy 143.848894 -248.258313) (xy 143.841186 -248.276776)
			(xy 143.840708 -248.286778) (xy 143.840708 -248.845578) (xy 143.84024 -248.871655) (xy 143.832116 -248.92317)
			(xy 143.816033 -248.972781) (xy 143.792387 -249.019265) (xy 143.76176 -249.061477) (xy 143.74368 -249.080274)
			(xy 142.821152 -250.002802) (xy 142.814473 -250.010214) (xy 142.806899 -250.028649) (xy 142.80642 -250.038616)
			(xy 142.80642 -250.96343) (xy 142.809214 -250.975368) (xy 142.812008 -250.980956) (xy 142.825841 -251.008484)
			(xy 142.845415 -251.066898) (xy 142.855339 -251.127699) (xy 142.85595 -251.158502) (xy 143.108424 -251.158502)
			(xy 143.112495 -251.10288) (xy 143.124621 -251.048443) (xy 143.144544 -250.996352) (xy 143.17184 -250.947717)
			(xy 143.205926 -250.903574) (xy 143.246075 -250.864865) (xy 143.291433 -250.832414) (xy 143.341033 -250.806913)
			(xy 143.393817 -250.788906) (xy 143.44866 -250.778776) (xy 143.504394 -250.776739) (xy 143.559831 -250.782839)
			(xy 143.613788 -250.796945) (xy 143.665117 -250.818757) (xy 143.712723 -250.847811) (xy 143.755591 -250.883486)
			(xy 143.792808 -250.925023) (xy 143.823581 -250.971536) (xy 143.847253 -251.022033) (xy 143.863321 -251.07544)
			(xy 143.871441 -251.130616) (xy 143.87195 -251.158502) (xy 144.124424 -251.158502) (xy 144.128495 -251.10288)
			(xy 144.140621 -251.048443) (xy 144.160544 -250.996352) (xy 144.18784 -250.947717) (xy 144.221926 -250.903574)
			(xy 144.262075 -250.864865) (xy 144.307433 -250.832414) (xy 144.357033 -250.806913) (xy 144.409817 -250.788906)
			(xy 144.46466 -250.778776) (xy 144.520394 -250.776739) (xy 144.575831 -250.782839) (xy 144.629788 -250.796945)
			(xy 144.681117 -250.818757) (xy 144.728723 -250.847811) (xy 144.771591 -250.883486) (xy 144.808808 -250.925023)
			(xy 144.839581 -250.971536) (xy 144.863253 -251.022033) (xy 144.879321 -251.07544) (xy 144.887441 -251.130616)
			(xy 144.88795 -251.158502) (xy 145.140424 -251.158502) (xy 145.144495 -251.10288) (xy 145.156621 -251.048443)
			(xy 145.176544 -250.996352) (xy 145.20384 -250.947717) (xy 145.237926 -250.903574) (xy 145.278075 -250.864865)
			(xy 145.323433 -250.832414) (xy 145.373033 -250.806913) (xy 145.425817 -250.788906) (xy 145.48066 -250.778776)
			(xy 145.536394 -250.776739) (xy 145.591831 -250.782839) (xy 145.645788 -250.796945) (xy 145.697117 -250.818757)
			(xy 145.744723 -250.847811) (xy 145.787591 -250.883486) (xy 145.824808 -250.925023) (xy 145.855581 -250.971536)
			(xy 145.879253 -251.022033) (xy 145.895321 -251.07544) (xy 145.903441 -251.130616) (xy 145.90395 -251.158502)
			(xy 146.156424 -251.158502) (xy 146.160495 -251.10288) (xy 146.172621 -251.048443) (xy 146.192544 -250.996352)
			(xy 146.21984 -250.947717) (xy 146.253926 -250.903574) (xy 146.294075 -250.864865) (xy 146.339433 -250.832414)
			(xy 146.389033 -250.806913) (xy 146.441817 -250.788906) (xy 146.49666 -250.778776) (xy 146.552394 -250.776739)
			(xy 146.607831 -250.782839) (xy 146.661788 -250.796945) (xy 146.713117 -250.818757) (xy 146.760723 -250.847811)
			(xy 146.803591 -250.883486) (xy 146.840808 -250.925023) (xy 146.871581 -250.971536) (xy 146.895253 -251.022033)
			(xy 146.911321 -251.07544) (xy 146.919441 -251.130616) (xy 146.91995 -251.158502) (xy 147.172424 -251.158502)
			(xy 147.176495 -251.10288) (xy 147.188621 -251.048443) (xy 147.208544 -250.996352) (xy 147.23584 -250.947717)
			(xy 147.269926 -250.903574) (xy 147.310075 -250.864865) (xy 147.355433 -250.832414) (xy 147.405033 -250.806913)
			(xy 147.457817 -250.788906) (xy 147.51266 -250.778776) (xy 147.568394 -250.776739) (xy 147.623831 -250.782839)
			(xy 147.677788 -250.796945) (xy 147.729117 -250.818757) (xy 147.776723 -250.847811) (xy 147.819591 -250.883486)
			(xy 147.856808 -250.925023) (xy 147.887581 -250.971536) (xy 147.911253 -251.022033) (xy 147.927321 -251.07544)
			(xy 147.935441 -251.130616) (xy 147.93595 -251.158502) (xy 148.188424 -251.158502) (xy 148.192495 -251.10288)
			(xy 148.204621 -251.048443) (xy 148.224544 -250.996352) (xy 148.25184 -250.947717) (xy 148.285926 -250.903574)
			(xy 148.326075 -250.864865) (xy 148.371433 -250.832414) (xy 148.421033 -250.806913) (xy 148.473817 -250.788906)
			(xy 148.52866 -250.778776) (xy 148.584394 -250.776739) (xy 148.639831 -250.782839) (xy 148.693788 -250.796945)
			(xy 148.745117 -250.818757) (xy 148.792723 -250.847811) (xy 148.835591 -250.883486) (xy 148.872808 -250.925023)
			(xy 148.903581 -250.971536) (xy 148.927253 -251.022033) (xy 148.943321 -251.07544) (xy 148.951441 -251.130616)
			(xy 148.95195 -251.158502) (xy 149.204424 -251.158502) (xy 149.208495 -251.10288) (xy 149.220621 -251.048443)
			(xy 149.240544 -250.996352) (xy 149.26784 -250.947717) (xy 149.301926 -250.903574) (xy 149.342075 -250.864865)
			(xy 149.387433 -250.832414) (xy 149.437033 -250.806913) (xy 149.489817 -250.788906) (xy 149.54466 -250.778776)
			(xy 149.600394 -250.776739) (xy 149.655831 -250.782839) (xy 149.709788 -250.796945) (xy 149.761117 -250.818757)
			(xy 149.808723 -250.847811) (xy 149.851591 -250.883486) (xy 149.888808 -250.925023) (xy 149.919581 -250.971536)
			(xy 149.943253 -251.022033) (xy 149.959321 -251.07544) (xy 149.967441 -251.130616) (xy 149.96795 -251.158502)
			(xy 150.220424 -251.158502) (xy 150.224495 -251.10288) (xy 150.236621 -251.048443) (xy 150.256544 -250.996352)
			(xy 150.28384 -250.947717) (xy 150.317926 -250.903574) (xy 150.358075 -250.864865) (xy 150.403433 -250.832414)
			(xy 150.453033 -250.806913) (xy 150.505817 -250.788906) (xy 150.56066 -250.778776) (xy 150.616394 -250.776739)
			(xy 150.671831 -250.782839) (xy 150.725788 -250.796945) (xy 150.777117 -250.818757) (xy 150.824723 -250.847811)
			(xy 150.867591 -250.883486) (xy 150.904808 -250.925023) (xy 150.935581 -250.971536) (xy 150.959253 -251.022033)
			(xy 150.975321 -251.07544) (xy 150.983441 -251.130616) (xy 150.98395 -251.158502) (xy 151.236424 -251.158502)
			(xy 151.240495 -251.10288) (xy 151.252621 -251.048443) (xy 151.272544 -250.996352) (xy 151.29984 -250.947717)
			(xy 151.333926 -250.903574) (xy 151.374075 -250.864865) (xy 151.419433 -250.832414) (xy 151.469033 -250.806913)
			(xy 151.521817 -250.788906) (xy 151.57666 -250.778776) (xy 151.632394 -250.776739) (xy 151.687831 -250.782839)
			(xy 151.741788 -250.796945) (xy 151.793117 -250.818757) (xy 151.840723 -250.847811) (xy 151.883591 -250.883486)
			(xy 151.920808 -250.925023) (xy 151.951581 -250.971536) (xy 151.975253 -251.022033) (xy 151.991321 -251.07544)
			(xy 151.999441 -251.130616) (xy 151.99995 -251.158502) (xy 152.252424 -251.158502) (xy 152.256495 -251.10288)
			(xy 152.268621 -251.048443) (xy 152.288544 -250.996352) (xy 152.31584 -250.947717) (xy 152.349926 -250.903574)
			(xy 152.390075 -250.864865) (xy 152.435433 -250.832414) (xy 152.485033 -250.806913) (xy 152.537817 -250.788906)
			(xy 152.59266 -250.778776) (xy 152.648394 -250.776739) (xy 152.703831 -250.782839) (xy 152.757788 -250.796945)
			(xy 152.809117 -250.818757) (xy 152.856723 -250.847811) (xy 152.899591 -250.883486) (xy 152.936808 -250.925023)
			(xy 152.967581 -250.971536) (xy 152.991253 -251.022033) (xy 153.007321 -251.07544) (xy 153.015441 -251.130616)
			(xy 153.01595 -251.158502) (xy 153.268424 -251.158502) (xy 153.272495 -251.10288) (xy 153.284621 -251.048443)
			(xy 153.304544 -250.996352) (xy 153.33184 -250.947717) (xy 153.365926 -250.903574) (xy 153.406075 -250.864865)
			(xy 153.451433 -250.832414) (xy 153.501033 -250.806913) (xy 153.553817 -250.788906) (xy 153.60866 -250.778776)
			(xy 153.664394 -250.776739) (xy 153.719831 -250.782839) (xy 153.773788 -250.796945) (xy 153.825117 -250.818757)
			(xy 153.872723 -250.847811) (xy 153.915591 -250.883486) (xy 153.952808 -250.925023) (xy 153.983581 -250.971536)
			(xy 154.007253 -251.022033) (xy 154.023321 -251.07544) (xy 154.031441 -251.130616) (xy 154.03195 -251.158502)
			(xy 154.031441 -251.186388) (xy 154.023321 -251.241564) (xy 154.007253 -251.294971) (xy 153.983581 -251.345468)
			(xy 153.952808 -251.391981) (xy 153.915591 -251.433518) (xy 153.872723 -251.469193) (xy 153.825117 -251.498247)
			(xy 153.773788 -251.520059) (xy 153.719831 -251.534165) (xy 153.664394 -251.540265) (xy 153.60866 -251.538228)
			(xy 153.553817 -251.528098) (xy 153.501033 -251.510091) (xy 153.451433 -251.48459) (xy 153.406075 -251.452139)
			(xy 153.365926 -251.41343) (xy 153.33184 -251.369287) (xy 153.304544 -251.320652) (xy 153.284621 -251.268561)
			(xy 153.272495 -251.214124) (xy 153.268424 -251.158502) (xy 153.01595 -251.158502) (xy 153.015441 -251.186388)
			(xy 153.007321 -251.241564) (xy 152.991253 -251.294971) (xy 152.967581 -251.345468) (xy 152.936808 -251.391981)
			(xy 152.899591 -251.433518) (xy 152.856723 -251.469193) (xy 152.809117 -251.498247) (xy 152.757788 -251.520059)
			(xy 152.703831 -251.534165) (xy 152.648394 -251.540265) (xy 152.59266 -251.538228) (xy 152.537817 -251.528098)
			(xy 152.485033 -251.510091) (xy 152.435433 -251.48459) (xy 152.390075 -251.452139) (xy 152.349926 -251.41343)
			(xy 152.31584 -251.369287) (xy 152.288544 -251.320652) (xy 152.268621 -251.268561) (xy 152.256495 -251.214124)
			(xy 152.252424 -251.158502) (xy 151.99995 -251.158502) (xy 151.999441 -251.186388) (xy 151.991321 -251.241564)
			(xy 151.975253 -251.294971) (xy 151.951581 -251.345468) (xy 151.920808 -251.391981) (xy 151.883591 -251.433518)
			(xy 151.840723 -251.469193) (xy 151.793117 -251.498247) (xy 151.741788 -251.520059) (xy 151.687831 -251.534165)
			(xy 151.632394 -251.540265) (xy 151.57666 -251.538228) (xy 151.521817 -251.528098) (xy 151.469033 -251.510091)
			(xy 151.419433 -251.48459) (xy 151.374075 -251.452139) (xy 151.333926 -251.41343) (xy 151.29984 -251.369287)
			(xy 151.272544 -251.320652) (xy 151.252621 -251.268561) (xy 151.240495 -251.214124) (xy 151.236424 -251.158502)
			(xy 150.98395 -251.158502) (xy 150.983441 -251.186388) (xy 150.975321 -251.241564) (xy 150.959253 -251.294971)
			(xy 150.935581 -251.345468) (xy 150.904808 -251.391981) (xy 150.867591 -251.433518) (xy 150.824723 -251.469193)
			(xy 150.777117 -251.498247) (xy 150.725788 -251.520059) (xy 150.671831 -251.534165) (xy 150.616394 -251.540265)
			(xy 150.56066 -251.538228) (xy 150.505817 -251.528098) (xy 150.453033 -251.510091) (xy 150.403433 -251.48459)
			(xy 150.358075 -251.452139) (xy 150.317926 -251.41343) (xy 150.28384 -251.369287) (xy 150.256544 -251.320652)
			(xy 150.236621 -251.268561) (xy 150.224495 -251.214124) (xy 150.220424 -251.158502) (xy 149.96795 -251.158502)
			(xy 149.967441 -251.186388) (xy 149.959321 -251.241564) (xy 149.943253 -251.294971) (xy 149.919581 -251.345468)
			(xy 149.888808 -251.391981) (xy 149.851591 -251.433518) (xy 149.808723 -251.469193) (xy 149.761117 -251.498247)
			(xy 149.709788 -251.520059) (xy 149.655831 -251.534165) (xy 149.600394 -251.540265) (xy 149.54466 -251.538228)
			(xy 149.489817 -251.528098) (xy 149.437033 -251.510091) (xy 149.387433 -251.48459) (xy 149.342075 -251.452139)
			(xy 149.301926 -251.41343) (xy 149.26784 -251.369287) (xy 149.240544 -251.320652) (xy 149.220621 -251.268561)
			(xy 149.208495 -251.214124) (xy 149.204424 -251.158502) (xy 148.95195 -251.158502) (xy 148.951441 -251.186388)
			(xy 148.943321 -251.241564) (xy 148.927253 -251.294971) (xy 148.903581 -251.345468) (xy 148.872808 -251.391981)
			(xy 148.835591 -251.433518) (xy 148.792723 -251.469193) (xy 148.745117 -251.498247) (xy 148.693788 -251.520059)
			(xy 148.639831 -251.534165) (xy 148.584394 -251.540265) (xy 148.52866 -251.538228) (xy 148.473817 -251.528098)
			(xy 148.421033 -251.510091) (xy 148.371433 -251.48459) (xy 148.326075 -251.452139) (xy 148.285926 -251.41343)
			(xy 148.25184 -251.369287) (xy 148.224544 -251.320652) (xy 148.204621 -251.268561) (xy 148.192495 -251.214124)
			(xy 148.188424 -251.158502) (xy 147.93595 -251.158502) (xy 147.935441 -251.186388) (xy 147.927321 -251.241564)
			(xy 147.911253 -251.294971) (xy 147.887581 -251.345468) (xy 147.856808 -251.391981) (xy 147.819591 -251.433518)
			(xy 147.776723 -251.469193) (xy 147.729117 -251.498247) (xy 147.677788 -251.520059) (xy 147.623831 -251.534165)
			(xy 147.568394 -251.540265) (xy 147.51266 -251.538228) (xy 147.457817 -251.528098) (xy 147.405033 -251.510091)
			(xy 147.355433 -251.48459) (xy 147.310075 -251.452139) (xy 147.269926 -251.41343) (xy 147.23584 -251.369287)
			(xy 147.208544 -251.320652) (xy 147.188621 -251.268561) (xy 147.176495 -251.214124) (xy 147.172424 -251.158502)
			(xy 146.91995 -251.158502) (xy 146.919441 -251.186388) (xy 146.911321 -251.241564) (xy 146.895253 -251.294971)
			(xy 146.871581 -251.345468) (xy 146.840808 -251.391981) (xy 146.803591 -251.433518) (xy 146.760723 -251.469193)
			(xy 146.713117 -251.498247) (xy 146.661788 -251.520059) (xy 146.607831 -251.534165) (xy 146.552394 -251.540265)
			(xy 146.49666 -251.538228) (xy 146.441817 -251.528098) (xy 146.389033 -251.510091) (xy 146.339433 -251.48459)
			(xy 146.294075 -251.452139) (xy 146.253926 -251.41343) (xy 146.21984 -251.369287) (xy 146.192544 -251.320652)
			(xy 146.172621 -251.268561) (xy 146.160495 -251.214124) (xy 146.156424 -251.158502) (xy 145.90395 -251.158502)
			(xy 145.903441 -251.186388) (xy 145.895321 -251.241564) (xy 145.879253 -251.294971) (xy 145.855581 -251.345468)
			(xy 145.824808 -251.391981) (xy 145.787591 -251.433518) (xy 145.744723 -251.469193) (xy 145.697117 -251.498247)
			(xy 145.645788 -251.520059) (xy 145.591831 -251.534165) (xy 145.536394 -251.540265) (xy 145.48066 -251.538228)
			(xy 145.425817 -251.528098) (xy 145.373033 -251.510091) (xy 145.323433 -251.48459) (xy 145.278075 -251.452139)
			(xy 145.237926 -251.41343) (xy 145.20384 -251.369287) (xy 145.176544 -251.320652) (xy 145.156621 -251.268561)
			(xy 145.144495 -251.214124) (xy 145.140424 -251.158502) (xy 144.88795 -251.158502) (xy 144.887441 -251.186388)
			(xy 144.879321 -251.241564) (xy 144.863253 -251.294971) (xy 144.839581 -251.345468) (xy 144.808808 -251.391981)
			(xy 144.771591 -251.433518) (xy 144.728723 -251.469193) (xy 144.681117 -251.498247) (xy 144.629788 -251.520059)
			(xy 144.575831 -251.534165) (xy 144.520394 -251.540265) (xy 144.46466 -251.538228) (xy 144.409817 -251.528098)
			(xy 144.357033 -251.510091) (xy 144.307433 -251.48459) (xy 144.262075 -251.452139) (xy 144.221926 -251.41343)
			(xy 144.18784 -251.369287) (xy 144.160544 -251.320652) (xy 144.140621 -251.268561) (xy 144.128495 -251.214124)
			(xy 144.124424 -251.158502) (xy 143.87195 -251.158502) (xy 143.871441 -251.186388) (xy 143.863321 -251.241564)
			(xy 143.847253 -251.294971) (xy 143.823581 -251.345468) (xy 143.792808 -251.391981) (xy 143.755591 -251.433518)
			(xy 143.712723 -251.469193) (xy 143.665117 -251.498247) (xy 143.613788 -251.520059) (xy 143.559831 -251.534165)
			(xy 143.504394 -251.540265) (xy 143.44866 -251.538228) (xy 143.393817 -251.528098) (xy 143.341033 -251.510091)
			(xy 143.291433 -251.48459) (xy 143.246075 -251.452139) (xy 143.205926 -251.41343) (xy 143.17184 -251.369287)
			(xy 143.144544 -251.320652) (xy 143.124621 -251.268561) (xy 143.112495 -251.214124) (xy 143.108424 -251.158502)
			(xy 142.85595 -251.158502) (xy 142.855464 -251.185753) (xy 142.847708 -251.239701) (xy 142.832353 -251.291996)
			(xy 142.809711 -251.341573) (xy 142.780245 -251.387423) (xy 142.744554 -251.428614) (xy 142.703363 -251.464305)
			(xy 142.657513 -251.493771) (xy 142.607936 -251.516413) (xy 142.555641 -251.531768) (xy 142.501693 -251.539524)
			(xy 142.447191 -251.539524) (xy 142.393243 -251.531768) (xy 142.340948 -251.516413) (xy 142.291371 -251.493771)
			(xy 142.245521 -251.464305) (xy 142.20433 -251.428614) (xy 142.168639 -251.387423) (xy 142.139173 -251.341573)
			(xy 142.116531 -251.291996) (xy 142.101176 -251.239701) (xy 142.09342 -251.185753) (xy 142.092934 -251.158502)
			(xy 142.093546 -251.1277) (xy 142.103482 -251.066902) (xy 142.12305 -251.008487) (xy 142.136876 -250.980956)
			(xy 142.13967 -250.975368) (xy 142.142464 -250.96343) (xy 142.142464 -249.88012) (xy 142.142949 -249.854032)
			(xy 142.151113 -249.8025) (xy 142.167244 -249.75288) (xy 142.190943 -249.706398) (xy 142.221626 -249.664198)
			(xy 142.239746 -249.645424) (xy 142.34287 -249.542554) (xy 142.351013 -249.533314) (xy 142.358296 -249.509828)
			(xy 142.35684 -249.497596) (xy 142.340076 -249.403362) (xy 142.32509 -249.383804) (xy 142.31366 -249.37847)
			(xy 142.289295 -249.36662) (xy 142.24389 -249.337058) (xy 142.203123 -249.301371) (xy 142.167815 -249.260275)
			(xy 142.138677 -249.214598) (xy 142.116293 -249.165258) (xy 142.101114 -249.113247) (xy 142.093446 -249.059612)
			(xy 142.092934 -249.032522) (xy 142.093396 -249.005269) (xy 142.101151 -248.951318) (xy 142.116505 -248.89902)
			(xy 142.139147 -248.84944) (xy 142.168615 -248.803587) (xy 142.204309 -248.762395) (xy 142.245503 -248.726703)
			(xy 142.291357 -248.697237) (xy 142.340939 -248.674598) (xy 142.393238 -248.659246) (xy 142.447189 -248.651494)
			(xy 142.474442 -248.651014) (xy 142.501535 -248.651485) (xy 142.555177 -248.659146) (xy 142.607194 -248.674323)
			(xy 142.656539 -248.696709) (xy 142.70222 -248.725854) (xy 142.743315 -248.761171) (xy 142.778998 -248.801949)
			(xy 142.80855 -248.847366) (xy 142.82039 -248.87174) (xy 142.825724 -248.88317) (xy 142.845282 -248.898156)
			(xy 142.939516 -248.91492) (xy 142.95175 -248.916427) (xy 142.975254 -248.90913) (xy 142.984474 -248.90095)
			(xy 143.162274 -248.722896) (xy 143.169087 -248.715552) (xy 143.176822 -248.697089) (xy 143.17726 -248.687082)
			(xy 143.17726 -248.128282) (xy 143.177723 -248.102204) (xy 143.18584 -248.050685) (xy 143.201919 -248.00107)
			(xy 143.225564 -247.954583) (xy 143.256191 -247.912368) (xy 143.274288 -247.893586) (xy 143.30045 -247.867424)
			(xy 143.307234 -247.860036) (xy 143.31488 -247.841509) (xy 143.314835 -247.821466) (xy 143.311372 -247.812052)
			(xy 143.30553 -247.797828) (xy 143.28013 -247.78081) (xy 141.47292 -247.78081) (xy 141.462857 -247.781248)
			(xy 141.444274 -247.788984) (xy 141.436852 -247.795796) (xy 140.184632 -249.048016) (xy 140.180165 -249.052842)
			(xy 141.076424 -249.052842) (xy 141.080495 -248.99722) (xy 141.092621 -248.942783) (xy 141.112544 -248.890692)
			(xy 141.13984 -248.842057) (xy 141.173926 -248.797914) (xy 141.214075 -248.759205) (xy 141.259433 -248.726754)
			(xy 141.309033 -248.701253) (xy 141.361817 -248.683246) (xy 141.41666 -248.673116) (xy 141.472394 -248.671079)
			(xy 141.527831 -248.677179) (xy 141.581788 -248.691285) (xy 141.633117 -248.713097) (xy 141.680723 -248.742151)
			(xy 141.723591 -248.777826) (xy 141.760808 -248.819363) (xy 141.791581 -248.865876) (xy 141.815253 -248.916373)
			(xy 141.831321 -248.96978) (xy 141.839441 -249.024956) (xy 141.83995 -249.052842) (xy 141.839441 -249.080728)
			(xy 141.831321 -249.135904) (xy 141.815253 -249.189311) (xy 141.791581 -249.239808) (xy 141.760808 -249.286321)
			(xy 141.723591 -249.327858) (xy 141.680723 -249.363533) (xy 141.633117 -249.392587) (xy 141.581788 -249.414399)
			(xy 141.527831 -249.428505) (xy 141.472394 -249.434605) (xy 141.41666 -249.432568) (xy 141.361817 -249.422438)
			(xy 141.309033 -249.404431) (xy 141.259433 -249.37893) (xy 141.214075 -249.346479) (xy 141.173926 -249.30777)
			(xy 141.13984 -249.263627) (xy 141.112544 -249.214992) (xy 141.092621 -249.162901) (xy 141.080495 -249.108464)
			(xy 141.076424 -249.052842) (xy 140.180165 -249.052842) (xy 140.177785 -249.055414) (xy 140.170051 -249.074012)
			(xy 140.169646 -249.084084) (xy 140.169646 -250.706636) (xy 140.170184 -250.719031) (xy 140.181634 -250.74101)
			(xy 140.19149 -250.748546) (xy 140.270738 -250.803156) (xy 140.295376 -250.806204) (xy 140.307314 -250.801632)
			(xy 140.339901 -250.790114) (xy 140.407888 -250.777717) (xy 140.442442 -250.776994) (xy 140.469691 -250.777483)
			(xy 140.523634 -250.785244) (xy 140.575923 -250.800603) (xy 140.625495 -250.823246) (xy 140.67134 -250.852713)
			(xy 140.712525 -250.888405) (xy 140.748212 -250.929594) (xy 140.777674 -250.975442) (xy 140.800312 -251.025016)
			(xy 140.815665 -251.077307) (xy 140.82342 -251.131251) (xy 140.82342 -251.158502) (xy 141.076424 -251.158502)
			(xy 141.080495 -251.10288) (xy 141.092621 -251.048443) (xy 141.112544 -250.996352) (xy 141.13984 -250.947717)
			(xy 141.173926 -250.903574) (xy 141.214075 -250.864865) (xy 141.259433 -250.832414) (xy 141.309033 -250.806913)
			(xy 141.361817 -250.788906) (xy 141.41666 -250.778776) (xy 141.472394 -250.776739) (xy 141.527831 -250.782839)
			(xy 141.581788 -250.796945) (xy 141.633117 -250.818757) (xy 141.680723 -250.847811) (xy 141.723591 -250.883486)
			(xy 141.760808 -250.925023) (xy 141.791581 -250.971536) (xy 141.815253 -251.022033) (xy 141.831321 -251.07544)
			(xy 141.839441 -251.130616) (xy 141.83995 -251.158502) (xy 141.839441 -251.186388) (xy 141.831321 -251.241564)
			(xy 141.815253 -251.294971) (xy 141.791581 -251.345468) (xy 141.760808 -251.391981) (xy 141.723591 -251.433518)
			(xy 141.680723 -251.469193) (xy 141.633117 -251.498247) (xy 141.581788 -251.520059) (xy 141.527831 -251.534165)
			(xy 141.472394 -251.540265) (xy 141.41666 -251.538228) (xy 141.361817 -251.528098) (xy 141.309033 -251.510091)
			(xy 141.259433 -251.48459) (xy 141.214075 -251.452139) (xy 141.173926 -251.41343) (xy 141.13984 -251.369287)
			(xy 141.112544 -251.320652) (xy 141.092621 -251.268561) (xy 141.080495 -251.214124) (xy 141.076424 -251.158502)
			(xy 140.82342 -251.158502) (xy 140.82342 -251.185749) (xy 140.815665 -251.239693) (xy 140.800312 -251.291984)
			(xy 140.777674 -251.341558) (xy 140.748212 -251.387406) (xy 140.712525 -251.428595) (xy 140.67134 -251.464287)
			(xy 140.625495 -251.493754) (xy 140.575923 -251.516397) (xy 140.523634 -251.531756) (xy 140.469691 -251.539517)
			(xy 140.442442 -251.54001) (xy 140.407888 -251.539284) (xy 140.339901 -251.526887) (xy 140.307314 -251.515372)
			(xy 140.295376 -251.5108) (xy 140.270738 -251.513848) (xy 140.19149 -251.568458) (xy 140.181785 -251.576122)
			(xy 140.170384 -251.598022) (xy 140.169646 -251.610368) (xy 140.169646 -253.438152) (xy 140.17008 -253.448217)
			(xy 140.177813 -253.466803) (xy 140.184632 -253.47422) (xy 140.902436 -254.192024) (xy 140.911326 -254.192024)
			(xy 141.388846 -254.669544) (xy 141.396244 -254.676389) (xy 141.414843 -254.684116) (xy 141.424914 -254.68453)
			(xy 142.172436 -254.68453) (xy 142.182503 -254.68496) (xy 142.201095 -254.692687) (xy 142.208504 -254.699516)
			(xy 143.36903 -255.860042) (xy 143.375877 -255.867439) (xy 143.383608 -255.886038) (xy 143.384016 -255.89611)
			(xy 143.384016 -256.218944) (xy 143.387064 -256.230882) (xy 143.390112 -256.236724) (xy 143.402582 -256.261081)
			(xy 143.420249 -256.312865) (xy 143.429179 -256.366846) (xy 143.429736 -256.394204) (xy 143.429736 -257.137916)
			(xy 150.396194 -257.137916) (xy 150.396746 -257.108534) (xy 150.405774 -257.050468) (xy 150.423604 -256.994474)
			(xy 150.449813 -256.941879) (xy 150.483782 -256.893927) (xy 150.524705 -256.851754) (xy 150.547832 -256.833624)
			(xy 150.55723 -256.826258) (xy 150.567644 -256.805684) (xy 150.569168 -256.701798) (xy 150.559262 -256.680716)
			(xy 150.550118 -256.67335) (xy 150.528267 -256.655147) (xy 150.489727 -256.613328) (xy 150.45782 -256.566252)
			(xy 150.433253 -256.514962) (xy 150.41657 -256.460593) (xy 150.408142 -256.404351) (xy 150.407624 -256.375916)
			(xy 150.40811 -256.348665) (xy 150.415866 -256.294717) (xy 150.431221 -256.242422) (xy 150.453863 -256.192845)
			(xy 150.483329 -256.146995) (xy 150.51902 -256.105804) (xy 150.560211 -256.070113) (xy 150.606061 -256.040647)
			(xy 150.655638 -256.018005) (xy 150.707933 -256.00265) (xy 150.761881 -255.994894) (xy 150.816383 -255.994894)
			(xy 150.870331 -256.00265) (xy 150.922626 -256.018005) (xy 150.972203 -256.040647) (xy 151.018053 -256.070113)
			(xy 151.059244 -256.105804) (xy 151.094935 -256.146995) (xy 151.124401 -256.192845) (xy 151.147043 -256.242422)
			(xy 151.162398 -256.294717) (xy 151.170154 -256.348665) (xy 151.17064 -256.375916) (xy 151.170098 -256.405298)
			(xy 151.161066 -256.463364) (xy 151.143233 -256.519357) (xy 151.117022 -256.571952) (xy 151.083052 -256.619904)
			(xy 151.042129 -256.662077) (xy 151.019002 -256.680208) (xy 151.009604 -256.687574) (xy 150.99919 -256.708148)
			(xy 150.997666 -256.812034) (xy 151.007572 -256.833116) (xy 151.016716 -256.840482) (xy 151.038541 -256.858714)
			(xy 151.077082 -256.900528) (xy 151.108991 -256.947598) (xy 151.133562 -256.998883) (xy 151.15025 -257.053245)
			(xy 151.158687 -257.109483) (xy 151.15921 -257.137916) (xy 151.792684 -257.137916) (xy 151.796755 -257.082294)
			(xy 151.808881 -257.027857) (xy 151.828804 -256.975766) (xy 151.8561 -256.927131) (xy 151.890186 -256.882988)
			(xy 151.930335 -256.844279) (xy 151.975693 -256.811828) (xy 152.025293 -256.786327) (xy 152.078077 -256.76832)
			(xy 152.13292 -256.75819) (xy 152.188654 -256.756153) (xy 152.244091 -256.762253) (xy 152.298048 -256.776359)
			(xy 152.349377 -256.798171) (xy 152.396983 -256.827225) (xy 152.439851 -256.8629) (xy 152.477068 -256.904437)
			(xy 152.507841 -256.95095) (xy 152.531513 -257.001447) (xy 152.538947 -257.026156) (xy 156.812994 -257.026156)
			(xy 156.817065 -256.970534) (xy 156.829191 -256.916097) (xy 156.849114 -256.864006) (xy 156.87641 -256.815371)
			(xy 156.910496 -256.771228) (xy 156.950645 -256.732519) (xy 156.996003 -256.700068) (xy 157.045603 -256.674567)
			(xy 157.098387 -256.65656) (xy 157.15323 -256.64643) (xy 157.208964 -256.644393) (xy 157.264401 -256.650493)
			(xy 157.318358 -256.664599) (xy 157.369687 -256.686411) (xy 157.417293 -256.715465) (xy 157.460161 -256.75114)
			(xy 157.497378 -256.792677) (xy 157.528151 -256.83919) (xy 157.551823 -256.889687) (xy 157.567891 -256.943094)
			(xy 157.576011 -256.99827) (xy 157.57652 -257.026156) (xy 157.576011 -257.054042) (xy 157.567891 -257.109218)
			(xy 157.551823 -257.162625) (xy 157.528151 -257.213122) (xy 157.497378 -257.259635) (xy 157.460161 -257.301172)
			(xy 157.417293 -257.336847) (xy 157.369687 -257.365901) (xy 157.318358 -257.387713) (xy 157.264401 -257.401819)
			(xy 157.208964 -257.407919) (xy 157.15323 -257.405882) (xy 157.098387 -257.395752) (xy 157.045603 -257.377745)
			(xy 156.996003 -257.352244) (xy 156.950645 -257.319793) (xy 156.910496 -257.281084) (xy 156.87641 -257.236941)
			(xy 156.849114 -257.188306) (xy 156.829191 -257.136215) (xy 156.817065 -257.081778) (xy 156.812994 -257.026156)
			(xy 152.538947 -257.026156) (xy 152.547581 -257.054854) (xy 152.555701 -257.11003) (xy 152.55621 -257.137916)
			(xy 152.555701 -257.165802) (xy 152.547581 -257.220978) (xy 152.531513 -257.274385) (xy 152.507841 -257.324882)
			(xy 152.477068 -257.371395) (xy 152.439851 -257.412932) (xy 152.396983 -257.448607) (xy 152.349377 -257.477661)
			(xy 152.298048 -257.499473) (xy 152.244091 -257.513579) (xy 152.188654 -257.519679) (xy 152.13292 -257.517642)
			(xy 152.078077 -257.507512) (xy 152.025293 -257.489505) (xy 151.975693 -257.464004) (xy 151.930335 -257.431553)
			(xy 151.890186 -257.392844) (xy 151.8561 -257.348701) (xy 151.828804 -257.300066) (xy 151.808881 -257.247975)
			(xy 151.796755 -257.193538) (xy 151.792684 -257.137916) (xy 151.15921 -257.137916) (xy 151.158724 -257.165167)
			(xy 151.150968 -257.219115) (xy 151.135613 -257.27141) (xy 151.112971 -257.320987) (xy 151.083505 -257.366837)
			(xy 151.047814 -257.408028) (xy 151.006623 -257.443719) (xy 150.960773 -257.473185) (xy 150.911196 -257.495827)
			(xy 150.858901 -257.511182) (xy 150.804953 -257.518938) (xy 150.750451 -257.518938) (xy 150.696503 -257.511182)
			(xy 150.644208 -257.495827) (xy 150.594631 -257.473185) (xy 150.548781 -257.443719) (xy 150.50759 -257.408028)
			(xy 150.471899 -257.366837) (xy 150.442433 -257.320987) (xy 150.419791 -257.27141) (xy 150.404436 -257.219115)
			(xy 150.39668 -257.165167) (xy 150.396194 -257.137916) (xy 143.429736 -257.137916) (xy 143.429736 -258.075176)
			(xy 143.43027 -258.085165) (xy 143.437982 -258.103599) (xy 143.444722 -258.11099) (xy 143.804132 -258.4704)
			(xy 143.811532 -258.477241) (xy 143.83013 -258.484964) (xy 143.8402 -258.485386) (xy 144.78127 -258.485386)
			(xy 144.792714 -258.484692) (xy 144.813297 -258.474668) (xy 144.820894 -258.466082) (xy 144.87779 -258.394454)
			(xy 144.88287 -258.372356) (xy 144.880076 -258.360672) (xy 144.875426 -258.339322) (xy 144.870464 -258.295907)
			(xy 144.87017 -258.274058) (xy 144.870656 -258.246807) (xy 144.878412 -258.192859) (xy 144.893767 -258.140564)
			(xy 144.916409 -258.090987) (xy 144.945875 -258.045137) (xy 144.981566 -258.003946) (xy 145.022757 -257.968255)
			(xy 145.068607 -257.938789) (xy 145.118184 -257.916147) (xy 145.170479 -257.900792) (xy 145.224427 -257.893036)
			(xy 145.278929 -257.893036) (xy 145.332877 -257.900792) (xy 145.385172 -257.916147) (xy 145.434749 -257.938789)
			(xy 145.480599 -257.968255) (xy 145.52179 -258.003946) (xy 145.557481 -258.045137) (xy 145.586947 -258.090987)
			(xy 145.609589 -258.140564) (xy 145.624944 -258.192859) (xy 145.6327 -258.246807) (xy 145.633186 -258.274058)
			(xy 145.632897 -258.295907) (xy 145.627927 -258.339321) (xy 145.62328 -258.360672) (xy 145.620486 -258.372356)
			(xy 145.625566 -258.394454) (xy 145.682462 -258.466082) (xy 145.689992 -258.474751) (xy 145.710618 -258.484794)
			(xy 145.722086 -258.485386) (xy 146.266408 -258.485386) (xy 146.277848 -258.484685) (xy 146.298418 -258.47465)
			(xy 146.306032 -258.466082) (xy 146.362928 -258.394454) (xy 146.368008 -258.372356) (xy 146.365214 -258.360672)
			(xy 146.360564 -258.339322) (xy 146.355601 -258.295907) (xy 146.355308 -258.274058) (xy 146.355794 -258.246807)
			(xy 146.36355 -258.192859) (xy 146.378905 -258.140564) (xy 146.401547 -258.090987) (xy 146.431013 -258.045137)
			(xy 146.466704 -258.003946) (xy 146.507895 -257.968255) (xy 146.553745 -257.938789) (xy 146.603322 -257.916147)
			(xy 146.655617 -257.900792) (xy 146.709565 -257.893036) (xy 146.764067 -257.893036) (xy 146.818015 -257.900792)
			(xy 146.87031 -257.916147) (xy 146.919887 -257.938789) (xy 146.965737 -257.968255) (xy 147.006928 -258.003946)
			(xy 147.042619 -258.045137) (xy 147.072085 -258.090987) (xy 147.094727 -258.140564) (xy 147.110082 -258.192859)
			(xy 147.117838 -258.246807) (xy 147.118324 -258.274058) (xy 147.118035 -258.295907) (xy 147.113066 -258.339321)
			(xy 147.108418 -258.360672) (xy 147.105624 -258.372356) (xy 147.110704 -258.394454) (xy 147.1676 -258.466082)
			(xy 147.175132 -258.474745) (xy 147.195759 -258.484773) (xy 147.207224 -258.485386) (xy 147.828 -258.485386)
			(xy 147.838071 -258.485809) (xy 147.856676 -258.493521) (xy 147.864068 -258.500372) (xy 149.702012 -260.338316)
			(xy 150.396194 -260.338316) (xy 150.396746 -260.308934) (xy 150.405774 -260.250868) (xy 150.423604 -260.194874)
			(xy 150.449813 -260.142279) (xy 150.483782 -260.094327) (xy 150.524705 -260.052154) (xy 150.547832 -260.034024)
			(xy 150.55723 -260.026658) (xy 150.567644 -260.006084) (xy 150.569168 -259.902198) (xy 150.559262 -259.881116)
			(xy 150.550118 -259.87375) (xy 150.528267 -259.855547) (xy 150.489727 -259.813728) (xy 150.45782 -259.766652)
			(xy 150.433253 -259.715362) (xy 150.41657 -259.660993) (xy 150.408142 -259.604751) (xy 150.407624 -259.576316)
			(xy 150.40811 -259.549065) (xy 150.415866 -259.495117) (xy 150.431221 -259.442822) (xy 150.453863 -259.393245)
			(xy 150.483329 -259.347395) (xy 150.51902 -259.306204) (xy 150.560211 -259.270513) (xy 150.606061 -259.241047)
			(xy 150.655638 -259.218405) (xy 150.707933 -259.20305) (xy 150.761881 -259.195294) (xy 150.816383 -259.195294)
			(xy 150.870331 -259.20305) (xy 150.922626 -259.218405) (xy 150.972203 -259.241047) (xy 151.018053 -259.270513)
			(xy 151.059244 -259.306204) (xy 151.094935 -259.347395) (xy 151.124401 -259.393245) (xy 151.147043 -259.442822)
			(xy 151.162398 -259.495117) (xy 151.170154 -259.549065) (xy 151.17064 -259.576316) (xy 151.170098 -259.605698)
			(xy 151.161066 -259.663764) (xy 151.143233 -259.719757) (xy 151.117022 -259.772352) (xy 151.083052 -259.820304)
			(xy 151.042129 -259.862477) (xy 151.019002 -259.880608) (xy 151.009604 -259.887974) (xy 150.99919 -259.908548)
			(xy 150.997666 -260.012434) (xy 151.007572 -260.033516) (xy 151.016716 -260.040882) (xy 151.038541 -260.059114)
			(xy 151.077082 -260.100928) (xy 151.108991 -260.147998) (xy 151.133562 -260.199283) (xy 151.15025 -260.253645)
			(xy 151.158687 -260.309883) (xy 151.15921 -260.338316) (xy 151.792684 -260.338316) (xy 151.796755 -260.282694)
			(xy 151.808881 -260.228257) (xy 151.828804 -260.176166) (xy 151.8561 -260.127531) (xy 151.890186 -260.083388)
			(xy 151.930335 -260.044679) (xy 151.975693 -260.012228) (xy 152.025293 -259.986727) (xy 152.078077 -259.96872)
			(xy 152.13292 -259.95859) (xy 152.188654 -259.956553) (xy 152.244091 -259.962653) (xy 152.298048 -259.976759)
			(xy 152.349377 -259.998571) (xy 152.396983 -260.027625) (xy 152.439851 -260.0633) (xy 152.477068 -260.104837)
			(xy 152.507841 -260.15135) (xy 152.531513 -260.201847) (xy 152.547581 -260.255254) (xy 152.555701 -260.31043)
			(xy 152.55621 -260.338316) (xy 152.555701 -260.366202) (xy 152.547581 -260.421378) (xy 152.531513 -260.474785)
			(xy 152.507841 -260.525282) (xy 152.477068 -260.571795) (xy 152.439851 -260.613332) (xy 152.396983 -260.649007)
			(xy 152.349377 -260.678061) (xy 152.298048 -260.699873) (xy 152.244091 -260.713979) (xy 152.188654 -260.720079)
			(xy 152.13292 -260.718042) (xy 152.078077 -260.707912) (xy 152.025293 -260.689905) (xy 151.975693 -260.664404)
			(xy 151.930335 -260.631953) (xy 151.890186 -260.593244) (xy 151.8561 -260.549101) (xy 151.828804 -260.500466)
			(xy 151.808881 -260.448375) (xy 151.796755 -260.393938) (xy 151.792684 -260.338316) (xy 151.15921 -260.338316)
			(xy 151.158724 -260.365567) (xy 151.150968 -260.419515) (xy 151.135613 -260.47181) (xy 151.112971 -260.521387)
			(xy 151.083505 -260.567237) (xy 151.047814 -260.608428) (xy 151.006623 -260.644119) (xy 150.960773 -260.673585)
			(xy 150.911196 -260.696227) (xy 150.858901 -260.711582) (xy 150.804953 -260.719338) (xy 150.750451 -260.719338)
			(xy 150.696503 -260.711582) (xy 150.644208 -260.696227) (xy 150.594631 -260.673585) (xy 150.548781 -260.644119)
			(xy 150.50759 -260.608428) (xy 150.471899 -260.567237) (xy 150.442433 -260.521387) (xy 150.419791 -260.47181)
			(xy 150.404436 -260.419515) (xy 150.39668 -260.365567) (xy 150.396194 -260.338316) (xy 149.702012 -260.338316)
			(xy 150.357586 -260.99389) (xy 150.36493 -261.000704) (xy 150.383392 -261.008443) (xy 150.3934 -261.008876)
			(xy 154.15895 -261.008876) (xy 154.185027 -261.009342) (xy 154.236543 -261.017464) (xy 154.286154 -261.033547)
			(xy 154.332637 -261.057195) (xy 154.374848 -261.087825) (xy 154.393646 -261.105904) (xy 155.03017 -261.742428)
			(xy 157.474158 -261.742428) (xy 157.474644 -261.715177) (xy 157.4824 -261.661229) (xy 157.497755 -261.608934)
			(xy 157.520397 -261.559357) (xy 157.549863 -261.513507) (xy 157.585554 -261.472316) (xy 157.626745 -261.436625)
			(xy 157.672595 -261.407159) (xy 157.722172 -261.384517) (xy 157.774467 -261.369162) (xy 157.828415 -261.361406)
			(xy 157.882917 -261.361406) (xy 157.936865 -261.369162) (xy 157.98916 -261.384517) (xy 158.038737 -261.407159)
			(xy 158.084587 -261.436625) (xy 158.125778 -261.472316) (xy 158.161469 -261.513507) (xy 158.190935 -261.559357)
			(xy 158.213577 -261.608934) (xy 158.228932 -261.661229) (xy 158.236688 -261.715177) (xy 158.237174 -261.742428)
			(xy 158.236651 -261.771382) (xy 158.22789 -261.828623) (xy 158.210586 -261.883885) (xy 158.185138 -261.935901)
			(xy 158.152129 -261.983479) (xy 158.112314 -262.025528) (xy 158.066608 -262.061084) (xy 158.041594 -262.075676)
			(xy 158.029689 -262.08289) (xy 158.009983 -262.102534) (xy 157.996317 -262.126771) (xy 157.989707 -262.153798)
			(xy 157.990643 -262.181606) (xy 157.999057 -262.208128) (xy 158.014323 -262.23139) (xy 158.035305 -262.249664)
			(xy 158.04769 -262.256016) (xy 158.071847 -262.267919) (xy 158.11678 -262.297609) (xy 158.157094 -262.333319)
			(xy 158.191989 -262.374339) (xy 158.220773 -262.419857) (xy 158.242875 -262.468968) (xy 158.257855 -262.520698)
			(xy 158.265417 -262.57402) (xy 158.265876 -262.600948) (xy 158.26539 -262.628199) (xy 158.257634 -262.682147)
			(xy 158.242279 -262.734442) (xy 158.219637 -262.784019) (xy 158.190171 -262.829869) (xy 158.15448 -262.87106)
			(xy 158.113289 -262.906751) (xy 158.067439 -262.936217) (xy 158.017862 -262.958859) (xy 157.965567 -262.974214)
			(xy 157.911619 -262.98197) (xy 157.857117 -262.98197) (xy 157.803169 -262.974214) (xy 157.750874 -262.958859)
			(xy 157.701297 -262.936217) (xy 157.655447 -262.906751) (xy 157.614256 -262.87106) (xy 157.578565 -262.829869)
			(xy 157.549099 -262.784019) (xy 157.526457 -262.734442) (xy 157.511102 -262.682147) (xy 157.503346 -262.628199)
			(xy 157.50286 -262.600948) (xy 157.503426 -262.571996) (xy 157.512177 -262.514756) (xy 157.529472 -262.459494)
			(xy 157.554912 -262.407477) (xy 157.587916 -262.359898) (xy 157.627725 -262.317848) (xy 157.673428 -262.282291)
			(xy 157.69844 -262.2677) (xy 157.710363 -262.260516) (xy 157.730064 -262.240864) (xy 157.743725 -262.216622)
			(xy 157.750331 -262.189591) (xy 157.749391 -262.161781) (xy 157.740976 -262.135258) (xy 157.72571 -262.111993)
			(xy 157.704729 -262.093715) (xy 157.692344 -262.08736) (xy 157.668225 -262.075383) (xy 157.623293 -262.045704)
			(xy 157.582978 -262.010006) (xy 157.548079 -261.968996) (xy 157.51929 -261.923489) (xy 157.497182 -261.874387)
			(xy 157.482193 -261.822667) (xy 157.474622 -261.769352) (xy 157.474158 -261.742428) (xy 155.03017 -261.742428)
			(xy 156.951172 -263.66343) (xy 156.97095 -263.684081) (xy 157.003821 -263.730864) (xy 157.028184 -263.782589)
			(xy 157.043321 -263.837725) (xy 157.046676 -263.866122) (xy 157.047692 -263.875012) (xy 157.055058 -263.89076)
			(xy 159.504126 -266.339828) (xy 159.510976 -266.347224) (xy 159.518712 -266.365823) (xy 159.519112 -266.375896)
			(xy 159.519112 -269.235936) (xy 159.519606 -269.245938) (xy 159.527273 -269.264415) (xy 159.541425 -269.278554)
			(xy 159.55991 -269.286203) (xy 159.569912 -269.286736)
		)
		(stroke
			(width 0)
			(type solid)
		)
		(fill yes)
		(layer "In5.Cu")
		(net "GND")
	)
	(gr_poly
		(pts
			(xy 229.86365 -217.3605) (xy 229.876074 -217.359893) (xy 229.898061 -217.348323) (xy 229.90556 -217.338402)
			(xy 229.96017 -217.259154) (xy 229.963218 -217.234516) (xy 229.958646 -217.222578) (xy 229.948481 -217.194113)
			(xy 229.937487 -217.134685) (xy 229.936802 -217.104468) (xy 229.937312 -217.078481) (xy 229.945442 -217.027146)
			(xy 229.961503 -216.977716) (xy 229.985099 -216.931406) (xy 230.015649 -216.889358) (xy 230.0524 -216.852607)
			(xy 230.094448 -216.822057) (xy 230.140758 -216.798461) (xy 230.190188 -216.7824) (xy 230.241523 -216.77427)
			(xy 230.293497 -216.77427) (xy 230.344832 -216.7824) (xy 230.394262 -216.798461) (xy 230.440572 -216.822057)
			(xy 230.48262 -216.852607) (xy 230.519371 -216.889358) (xy 230.549921 -216.931406) (xy 230.573517 -216.977716)
			(xy 230.589578 -217.027146) (xy 230.597708 -217.078481) (xy 230.598218 -217.104468) (xy 230.597552 -217.134688)
			(xy 230.586567 -217.194121) (xy 230.576374 -217.222578) (xy 230.571802 -217.234516) (xy 230.57485 -217.259154)
			(xy 230.62946 -217.338402) (xy 230.636983 -217.348303) (xy 230.658951 -217.359897) (xy 230.67137 -217.3605)
			(xy 230.71582 -217.3605) (xy 230.724918 -217.360086) (xy 230.741941 -217.353651) (xy 230.755642 -217.341672)
			(xy 230.76027 -217.33383) (xy 230.773732 -217.309192) (xy 230.777881 -217.300679) (xy 230.780342 -217.281918)
			(xy 230.778558 -217.272616) (xy 230.775256 -217.259916) (xy 230.772716 -217.254582) (xy 230.761341 -217.231212)
			(xy 230.745265 -217.181787) (xy 230.737121 -217.130455) (xy 230.736648 -217.104468) (xy 230.737158 -217.078481)
			(xy 230.745288 -217.027146) (xy 230.761349 -216.977716) (xy 230.784945 -216.931406) (xy 230.815495 -216.889358)
			(xy 230.852246 -216.852607) (xy 230.894294 -216.822057) (xy 230.940604 -216.798461) (xy 230.990034 -216.7824)
			(xy 231.041369 -216.77427) (xy 231.093343 -216.77427) (xy 231.144678 -216.7824) (xy 231.194108 -216.798461)
			(xy 231.240418 -216.822057) (xy 231.282466 -216.852607) (xy 231.319217 -216.889358) (xy 231.349767 -216.931406)
			(xy 231.373363 -216.977716) (xy 231.389424 -217.027146) (xy 231.397554 -217.078481) (xy 231.398064 -217.104468)
			(xy 231.397398 -217.134688) (xy 231.386414 -217.194122) (xy 231.37622 -217.222578) (xy 231.371648 -217.234516)
			(xy 231.374696 -217.259154) (xy 231.429306 -217.338402) (xy 231.436833 -217.348295) (xy 231.458801 -217.359869)
			(xy 231.471216 -217.3605) (xy 231.51592 -217.3605) (xy 231.525018 -217.360086) (xy 231.542041 -217.353651)
			(xy 231.555742 -217.341672) (xy 231.56037 -217.33383) (xy 231.573832 -217.309192) (xy 231.577981 -217.300679)
			(xy 231.580442 -217.281918) (xy 231.578658 -217.272616) (xy 231.575356 -217.259916) (xy 231.572816 -217.254582)
			(xy 231.561441 -217.231212) (xy 231.545365 -217.181787) (xy 231.537221 -217.130455) (xy 231.536748 -217.104468)
			(xy 231.537258 -217.078481) (xy 231.545388 -217.027146) (xy 231.561449 -216.977716) (xy 231.585045 -216.931406)
			(xy 231.615595 -216.889358) (xy 231.652346 -216.852607) (xy 231.694394 -216.822057) (xy 231.740704 -216.798461)
			(xy 231.790134 -216.7824) (xy 231.841469 -216.77427) (xy 231.893443 -216.77427) (xy 231.944778 -216.7824)
			(xy 231.994208 -216.798461) (xy 232.040518 -216.822057) (xy 232.082566 -216.852607) (xy 232.119317 -216.889358)
			(xy 232.149867 -216.931406) (xy 232.173463 -216.977716) (xy 232.189524 -217.027146) (xy 232.197654 -217.078481)
			(xy 232.198164 -217.104468) (xy 232.197498 -217.134688) (xy 232.186514 -217.194122) (xy 232.17632 -217.222578)
			(xy 232.171748 -217.234516) (xy 232.174796 -217.259154) (xy 232.229406 -217.338402) (xy 232.236933 -217.348295)
			(xy 232.258901 -217.359869) (xy 232.271316 -217.3605) (xy 232.31602 -217.3605) (xy 232.325118 -217.360086)
			(xy 232.342141 -217.353651) (xy 232.355842 -217.341672) (xy 232.36047 -217.33383) (xy 232.373932 -217.309192)
			(xy 232.378081 -217.300679) (xy 232.380542 -217.281918) (xy 232.378758 -217.272616) (xy 232.375456 -217.259916)
			(xy 232.372916 -217.254582) (xy 232.361541 -217.231212) (xy 232.345465 -217.181787) (xy 232.337321 -217.130455)
			(xy 232.336848 -217.104468) (xy 232.337358 -217.078481) (xy 232.345488 -217.027146) (xy 232.361549 -216.977716)
			(xy 232.385145 -216.931406) (xy 232.415695 -216.889358) (xy 232.452446 -216.852607) (xy 232.494494 -216.822057)
			(xy 232.540804 -216.798461) (xy 232.590234 -216.7824) (xy 232.641569 -216.77427) (xy 232.693543 -216.77427)
			(xy 232.744878 -216.7824) (xy 232.794308 -216.798461) (xy 232.840618 -216.822057) (xy 232.882666 -216.852607)
			(xy 232.919417 -216.889358) (xy 232.949967 -216.931406) (xy 232.973563 -216.977716) (xy 232.989624 -217.027146)
			(xy 232.997754 -217.078481) (xy 232.998264 -217.104468) (xy 232.997938 -217.126152) (xy 232.992301 -217.169152)
			(xy 232.981092 -217.211047) (xy 232.973118 -217.231214) (xy 232.967022 -217.245692) (xy 232.973372 -217.276172)
			(xy 232.984548 -217.287094) (xy 232.992 -217.293663) (xy 233.01042 -217.30105) (xy 233.030265 -217.300915)
			(xy 233.048583 -217.293279) (xy 233.055922 -217.286586) (xy 233.137964 -217.204544) (xy 233.14533 -217.18016)
			(xy 233.14279 -217.167714) (xy 233.140018 -217.15256) (xy 233.136966 -217.121903) (xy 233.136694 -217.1065)
			(xy 233.136694 -217.102182) (xy 233.1375 -217.073544) (xy 233.147747 -217.017183) (xy 233.167534 -216.963423)
			(xy 233.181398 -216.938352) (xy 233.186478 -216.929716) (xy 233.189272 -216.910666) (xy 233.167936 -216.823036)
			(xy 233.15676 -216.807288) (xy 233.148378 -216.8017) (xy 233.120965 -216.783589) (xy 233.06993 -216.742206)
			(xy 233.0238 -216.695417) (xy 232.983144 -216.6438) (xy 232.948465 -216.587992) (xy 232.920189 -216.528682)
			(xy 232.898667 -216.466602) (xy 232.884163 -216.402518) (xy 232.876857 -216.33722) (xy 232.876344 -216.304368)
			(xy 232.876805 -216.271216) (xy 232.884256 -216.205332) (xy 232.899038 -216.140697) (xy 232.920966 -216.078123)
			(xy 232.949763 -216.018399) (xy 232.985067 -215.962276) (xy 233.005376 -215.936068) (xy 233.012158 -215.926752)
			(xy 233.017309 -215.904314) (xy 233.01217 -215.881874) (xy 233.005376 -215.872568) (xy 232.996002 -215.860651)
			(xy 232.978342 -215.835999) (xy 232.97007 -215.823292) (xy 232.964736 -215.81491) (xy 232.948988 -215.803734)
			(xy 232.861358 -215.782652) (xy 232.842054 -215.785192) (xy 232.833418 -215.790272) (xy 232.808054 -215.804314)
			(xy 232.75362 -215.824249) (xy 232.696541 -215.834377) (xy 232.667556 -215.834976) (xy 232.641574 -215.834463)
			(xy 232.590249 -215.826328) (xy 232.540829 -215.810265) (xy 232.494531 -215.786669) (xy 232.452492 -215.756121)
			(xy 232.41575 -215.719374) (xy 232.385208 -215.677332) (xy 232.361618 -215.63103) (xy 232.345562 -215.581608)
			(xy 232.337433 -215.530282) (xy 232.337433 -215.478318) (xy 232.345562 -215.426992) (xy 232.361618 -215.37757)
			(xy 232.385208 -215.331268) (xy 232.41575 -215.289226) (xy 232.452492 -215.252479) (xy 232.494531 -215.221931)
			(xy 232.54083 -215.198335) (xy 232.590249 -215.182272) (xy 232.641574 -215.174137) (xy 232.667556 -215.17356)
			(xy 232.696537 -215.174189) (xy 232.753606 -215.184335) (xy 232.80804 -215.204254) (xy 232.833418 -215.218264)
			(xy 232.842054 -215.223344) (xy 232.861358 -215.225884) (xy 232.948988 -215.204802) (xy 232.964736 -215.193626)
			(xy 232.97007 -215.185244) (xy 232.98758 -215.158728) (xy 233.027434 -215.109234) (xy 233.072369 -215.064303)
			(xy 233.121867 -215.024453) (xy 233.148378 -215.006936) (xy 233.15676 -215.001602) (xy 233.167936 -214.985854)
			(xy 233.189018 -214.898224) (xy 233.186478 -214.87892) (xy 233.181398 -214.870284) (xy 233.16736 -214.844919)
			(xy 233.147432 -214.790484) (xy 233.137311 -214.733406) (xy 233.136694 -214.704422) (xy 233.137175 -214.678432)
			(xy 233.145304 -214.627091) (xy 233.161364 -214.577653) (xy 233.184961 -214.531337) (xy 233.215513 -214.489283)
			(xy 233.252268 -214.452526) (xy 233.29432 -214.421971) (xy 233.340635 -214.398372) (xy 233.390071 -214.382309)
			(xy 233.441412 -214.374177) (xy 233.467402 -214.373714) (xy 233.491677 -214.374142) (xy 233.539704 -214.381243)
			(xy 233.586177 -214.395292) (xy 233.630094 -214.415987) (xy 233.650536 -214.429086) (xy 233.656866 -214.43295)
			(xy 233.671064 -214.437207) (xy 233.678476 -214.437468) (xy 234.056428 -214.437468) (xy 234.063838 -214.437208)
			(xy 234.07803 -214.432935) (xy 234.084368 -214.429086) (xy 234.104812 -214.41599) (xy 234.148727 -214.395287)
			(xy 234.195199 -214.381233) (xy 234.243227 -214.374129) (xy 234.291777 -214.374129) (xy 234.339805 -214.381233)
			(xy 234.386277 -214.395287) (xy 234.430192 -214.41599) (xy 234.450636 -214.429086) (xy 234.456966 -214.43295)
			(xy 234.471164 -214.437207) (xy 234.478576 -214.437468) (xy 234.809792 -214.437468) (xy 234.819862 -214.437046)
			(xy 234.838466 -214.42933) (xy 234.84586 -214.422482) (xy 234.940856 -214.327486) (xy 234.960997 -214.308057)
			(xy 235.006253 -214.275139) (xy 235.056103 -214.249712) (xy 235.10932 -214.232403) (xy 235.16459 -214.223638)
			(xy 235.19257 -214.223092) (xy 236.4486 -214.223092) (xy 236.469043 -214.223394) (xy 236.509656 -214.228109)
			(xy 236.529626 -214.23249) (xy 236.538262 -214.234522) (xy 236.555788 -214.23249) (xy 236.63021 -214.195152)
			(xy 236.642148 -214.182452) (xy 236.645958 -214.17407) (xy 236.657855 -214.148065) (xy 236.688227 -214.099613)
			(xy 236.725478 -214.056225) (xy 236.746796 -214.037164) (xy 236.755432 -214.029544) (xy 236.764576 -214.009478)
			(xy 236.76356 -213.908894) (xy 236.753908 -213.888828) (xy 236.745018 -213.881462) (xy 236.723651 -213.863248)
			(xy 236.685978 -213.821619) (xy 236.654811 -213.77492) (xy 236.630823 -213.724159) (xy 236.614531 -213.67043)
			(xy 236.606287 -213.614894) (xy 236.605826 -213.586822) (xy 236.606288 -213.559569) (xy 236.614042 -213.505618)
			(xy 236.629397 -213.453319) (xy 236.652039 -213.403738) (xy 236.681507 -213.357885) (xy 236.717201 -213.316692)
			(xy 236.758394 -213.280999) (xy 236.804249 -213.251533) (xy 236.85383 -213.228893) (xy 236.906129 -213.21354)
			(xy 236.960081 -213.205787) (xy 236.987334 -213.205314) (xy 237.014041 -213.205764) (xy 237.066931 -213.21322)
			(xy 237.118265 -213.22798) (xy 237.167038 -213.249757) (xy 237.212296 -213.278125) (xy 237.253154 -213.312528)
			(xy 237.288814 -213.352295) (xy 237.318578 -213.396647) (xy 237.341864 -213.444717) (xy 237.358217 -213.495566)
			(xy 237.363254 -213.521798) (xy 237.365794 -213.536022) (xy 237.384336 -213.557358) (xy 237.483904 -213.588854)
			(xy 237.492871 -213.591305) (xy 237.511417 -213.590289) (xy 237.528371 -213.582701) (xy 237.535212 -213.576408)
			(xy 238.057944 -213.053676) (xy 238.058452 -213.053168) (xy 238.065038 -213.045788) (xy 238.072496 -213.027489)
			(xy 238.07293 -213.017608) (xy 238.07293 -209.283808) (xy 238.072509 -209.273736) (xy 238.0648 -209.255127)
			(xy 238.057944 -209.24774) (xy 237.416594 -208.60639) (xy 237.409482 -208.599024) (xy 237.390686 -208.591404)
			(xy 230.653844 -208.591404) (xy 230.643778 -208.591838) (xy 230.625189 -208.599567) (xy 230.617776 -208.60639)
			(xy 228.759512 -210.464654) (xy 228.752146 -210.471766) (xy 228.744526 -210.490562) (xy 228.744526 -210.785964)
			(xy 230.220518 -210.785964) (xy 230.224589 -210.730342) (xy 230.236715 -210.675905) (xy 230.256638 -210.623814)
			(xy 230.283934 -210.575179) (xy 230.31802 -210.531036) (xy 230.358169 -210.492327) (xy 230.403527 -210.459876)
			(xy 230.453127 -210.434375) (xy 230.505911 -210.416368) (xy 230.560754 -210.406238) (xy 230.616488 -210.404201)
			(xy 230.671925 -210.410301) (xy 230.725882 -210.424407) (xy 230.777211 -210.446219) (xy 230.824817 -210.475273)
			(xy 230.845437 -210.492433) (xy 235.785717 -210.492433) (xy 235.785719 -210.437939) (xy 235.793476 -210.383999)
			(xy 235.80883 -210.331713) (xy 235.831469 -210.282143) (xy 235.860931 -210.2363) (xy 235.896618 -210.195116)
			(xy 235.937802 -210.15943) (xy 235.983645 -210.129968) (xy 236.033215 -210.107329) (xy 236.085501 -210.091976)
			(xy 236.139441 -210.084219) (xy 236.193935 -210.084217) (xy 236.247875 -210.091971) (xy 236.300163 -210.107321)
			(xy 236.349734 -210.129956) (xy 236.395579 -210.159416) (xy 236.436765 -210.195099) (xy 236.472454 -210.236281)
			(xy 236.50192 -210.282122) (xy 236.524561 -210.33169) (xy 236.539919 -210.383976) (xy 236.547679 -210.437915)
			(xy 236.548168 -210.465162) (xy 236.547721 -210.492332) (xy 236.540066 -210.54613) (xy 236.532928 -210.57235)
			(xy 236.529118 -210.585304) (xy 236.53496 -210.611212) (xy 236.61243 -210.695032) (xy 236.637576 -210.70316)
			(xy 236.650784 -210.700366) (xy 236.669876 -210.696687) (xy 236.708558 -210.692743) (xy 236.728 -210.692492)
			(xy 236.754141 -210.6929) (xy 236.805932 -210.700059) (xy 236.856262 -210.714215) (xy 236.904191 -210.735104)
			(xy 236.948823 -210.762335) (xy 236.989324 -210.795399) (xy 237.024935 -210.833679) (xy 237.054993 -210.876458)
			(xy 237.067344 -210.899502) (xy 237.073186 -210.910932) (xy 237.09376 -210.925156) (xy 237.202472 -210.938618)
			(xy 237.22584 -210.929474) (xy 237.234222 -210.920076) (xy 237.252411 -210.899951) (xy 237.293517 -210.864557)
			(xy 237.339224 -210.835344) (xy 237.388609 -210.812902) (xy 237.440676 -210.797684) (xy 237.494374 -210.789998)
			(xy 237.521496 -210.78952) (xy 237.548751 -210.789927) (xy 237.602706 -210.797684) (xy 237.655009 -210.813041)
			(xy 237.704593 -210.835685) (xy 237.75045 -210.865155) (xy 237.791646 -210.900851) (xy 237.827343 -210.942047)
			(xy 237.856814 -210.987903) (xy 237.879458 -211.037488) (xy 237.894815 -211.08979) (xy 237.902573 -211.143745)
			(xy 237.902573 -211.198255) (xy 237.894815 -211.25221) (xy 237.879458 -211.304512) (xy 237.856814 -211.354097)
			(xy 237.827343 -211.399953) (xy 237.791646 -211.441149) (xy 237.75045 -211.476845) (xy 237.704593 -211.506315)
			(xy 237.655009 -211.528959) (xy 237.602706 -211.544316) (xy 237.548751 -211.552073) (xy 237.521496 -211.552536)
			(xy 237.495355 -211.552116) (xy 237.443566 -211.544958) (xy 237.393236 -211.530802) (xy 237.345308 -211.509915)
			(xy 237.300676 -211.482685) (xy 237.260176 -211.449623) (xy 237.224563 -211.411345) (xy 237.194504 -211.368568)
			(xy 237.182152 -211.345526) (xy 237.17631 -211.334096) (xy 237.155736 -211.319872) (xy 237.047024 -211.30641)
			(xy 237.023656 -211.315554) (xy 237.015274 -211.324952) (xy 236.997093 -211.345084) (xy 236.955984 -211.380477)
			(xy 236.910275 -211.409688) (xy 236.860889 -211.432128) (xy 236.808821 -211.447345) (xy 236.755123 -211.455031)
			(xy 236.728 -211.455508) (xy 236.700749 -211.455022) (xy 236.646801 -211.447266) (xy 236.594506 -211.431911)
			(xy 236.544929 -211.409269) (xy 236.499079 -211.379803) (xy 236.457888 -211.344112) (xy 236.422197 -211.302921)
			(xy 236.392731 -211.257071) (xy 236.370089 -211.207494) (xy 236.354734 -211.155199) (xy 236.346978 -211.101251)
			(xy 236.346492 -211.074) (xy 236.346949 -211.04683) (xy 236.354597 -210.993032) (xy 236.361732 -210.966812)
			(xy 236.365542 -210.953858) (xy 236.3597 -210.92795) (xy 236.28223 -210.84413) (xy 236.257084 -210.836002)
			(xy 236.243876 -210.838796) (xy 236.224786 -210.842488) (xy 236.186102 -210.846429) (xy 236.16666 -210.84667)
			(xy 236.139413 -210.846179) (xy 236.085474 -210.838418) (xy 236.033188 -210.823061) (xy 235.983621 -210.800419)
			(xy 235.937779 -210.770953) (xy 235.896598 -210.735264) (xy 235.860914 -210.694077) (xy 235.831455 -210.648232)
			(xy 235.80882 -210.598661) (xy 235.79347 -210.546373) (xy 235.785717 -210.492433) (xy 230.845437 -210.492433)
			(xy 230.867685 -210.510948) (xy 230.904902 -210.552485) (xy 230.935675 -210.598998) (xy 230.959347 -210.649495)
			(xy 230.975415 -210.702902) (xy 230.983535 -210.758078) (xy 230.984044 -210.785964) (xy 230.983535 -210.81385)
			(xy 230.975415 -210.869026) (xy 230.959347 -210.922433) (xy 230.935675 -210.97293) (xy 230.904902 -211.019443)
			(xy 230.867685 -211.06098) (xy 230.824817 -211.096655) (xy 230.777211 -211.125709) (xy 230.725882 -211.147521)
			(xy 230.671925 -211.161627) (xy 230.616488 -211.167727) (xy 230.560754 -211.16569) (xy 230.505911 -211.15556)
			(xy 230.453127 -211.137553) (xy 230.403527 -211.112052) (xy 230.358169 -211.079601) (xy 230.31802 -211.040892)
			(xy 230.283934 -210.996749) (xy 230.256638 -210.948114) (xy 230.236715 -210.896023) (xy 230.224589 -210.841586)
			(xy 230.220518 -210.785964) (xy 228.744526 -210.785964) (xy 228.744526 -211.905088) (xy 228.745017 -211.915048)
			(xy 228.752613 -211.933464) (xy 228.759258 -211.940902) (xy 228.834696 -212.016594) (xy 228.839014 -212.020404)
			(xy 228.845364 -212.025484) (xy 228.847396 -212.026754) (xy 228.870144 -212.042157) (xy 228.910663 -212.079253)
			(xy 228.944502 -212.122529) (xy 228.970735 -212.170796) (xy 228.98864 -212.222731) (xy 228.997728 -212.276909)
			(xy 228.998272 -212.304376) (xy 228.997801 -212.329798) (xy 228.997713 -212.330363) (xy 233.137204 -212.330363)
			(xy 233.137204 -212.278389) (xy 233.145334 -212.227054) (xy 233.161395 -212.177624) (xy 233.184991 -212.131314)
			(xy 233.215541 -212.089266) (xy 233.252292 -212.052515) (xy 233.29434 -212.021965) (xy 233.34065 -211.998369)
			(xy 233.39008 -211.982308) (xy 233.441415 -211.974178) (xy 233.493389 -211.974178) (xy 233.544724 -211.982308)
			(xy 233.594154 -211.998369) (xy 233.640464 -212.021965) (xy 233.682512 -212.052515) (xy 233.719263 -212.089266)
			(xy 233.749813 -212.131314) (xy 233.773409 -212.177624) (xy 233.78947 -212.227054) (xy 233.7976 -212.278389)
			(xy 233.79811 -212.304376) (xy 233.7976 -212.330363) (xy 235.53725 -212.330363) (xy 235.53725 -212.278389)
			(xy 235.54538 -212.227054) (xy 235.561441 -212.177624) (xy 235.585037 -212.131314) (xy 235.615587 -212.089266)
			(xy 235.652338 -212.052515) (xy 235.694386 -212.021965) (xy 235.740696 -211.998369) (xy 235.790126 -211.982308)
			(xy 235.841461 -211.974178) (xy 235.893435 -211.974178) (xy 235.94477 -211.982308) (xy 235.9942 -211.998369)
			(xy 236.04051 -212.021965) (xy 236.082558 -212.052515) (xy 236.119309 -212.089266) (xy 236.149859 -212.131314)
			(xy 236.173455 -212.177624) (xy 236.189516 -212.227054) (xy 236.197646 -212.278389) (xy 236.198156 -212.304376)
			(xy 236.197646 -212.330363) (xy 236.189516 -212.381698) (xy 236.173455 -212.431128) (xy 236.149859 -212.477438)
			(xy 236.119309 -212.519486) (xy 236.082558 -212.556237) (xy 236.04051 -212.586787) (xy 235.9942 -212.610383)
			(xy 235.94477 -212.626444) (xy 235.893435 -212.634574) (xy 235.841461 -212.634574) (xy 235.790126 -212.626444)
			(xy 235.740696 -212.610383) (xy 235.694386 -212.586787) (xy 235.652338 -212.556237) (xy 235.615587 -212.519486)
			(xy 235.585037 -212.477438) (xy 235.561441 -212.431128) (xy 235.54538 -212.381698) (xy 235.53725 -212.330363)
			(xy 233.7976 -212.330363) (xy 233.78947 -212.381698) (xy 233.773409 -212.431128) (xy 233.749813 -212.477438)
			(xy 233.719263 -212.519486) (xy 233.682512 -212.556237) (xy 233.640464 -212.586787) (xy 233.594154 -212.610383)
			(xy 233.544724 -212.626444) (xy 233.493389 -212.634574) (xy 233.441415 -212.634574) (xy 233.39008 -212.626444)
			(xy 233.34065 -212.610383) (xy 233.29434 -212.586787) (xy 233.252292 -212.556237) (xy 233.215541 -212.519486)
			(xy 233.184991 -212.477438) (xy 233.161395 -212.431128) (xy 233.145334 -212.381698) (xy 233.137204 -212.330363)
			(xy 228.997713 -212.330363) (xy 228.990009 -212.380043) (xy 228.97462 -212.428503) (xy 228.951996 -212.474037)
			(xy 228.922671 -212.515574) (xy 228.887335 -212.552133) (xy 228.846821 -212.582855) (xy 228.802083 -212.607015)
			(xy 228.778308 -212.616034) (xy 228.763068 -212.621368) (xy 228.744526 -212.64753) (xy 228.744526 -212.760814)
			(xy 228.763068 -212.786722) (xy 228.778308 -212.79231) (xy 228.802125 -212.801254) (xy 228.846901 -212.825401)
			(xy 228.887452 -212.856119) (xy 228.922824 -212.892682) (xy 228.952181 -212.934229) (xy 228.974833 -212.97978)
			(xy 228.990244 -213.028262) (xy 228.998051 -213.078532) (xy 228.998526 -213.103968) (xy 228.998037 -213.130065)
			(xy 228.997974 -213.130463) (xy 229.937312 -213.130463) (xy 229.937312 -213.078489) (xy 229.945442 -213.027154)
			(xy 229.961503 -212.977724) (xy 229.985099 -212.931414) (xy 230.015649 -212.889366) (xy 230.0524 -212.852615)
			(xy 230.094448 -212.822065) (xy 230.140758 -212.798469) (xy 230.190188 -212.782408) (xy 230.241523 -212.774278)
			(xy 230.293497 -212.774278) (xy 230.344832 -212.782408) (xy 230.394262 -212.798469) (xy 230.440572 -212.822065)
			(xy 230.48262 -212.852615) (xy 230.519371 -212.889366) (xy 230.549921 -212.931414) (xy 230.573517 -212.977724)
			(xy 230.589578 -213.027154) (xy 230.597708 -213.078489) (xy 230.598218 -213.104476) (xy 230.597708 -213.130463)
			(xy 230.737158 -213.130463) (xy 230.737158 -213.078489) (xy 230.745288 -213.027154) (xy 230.761349 -212.977724)
			(xy 230.784945 -212.931414) (xy 230.815495 -212.889366) (xy 230.852246 -212.852615) (xy 230.894294 -212.822065)
			(xy 230.940604 -212.798469) (xy 230.990034 -212.782408) (xy 231.041369 -212.774278) (xy 231.093343 -212.774278)
			(xy 231.144678 -212.782408) (xy 231.194108 -212.798469) (xy 231.240418 -212.822065) (xy 231.282466 -212.852615)
			(xy 231.319217 -212.889366) (xy 231.349767 -212.931414) (xy 231.373363 -212.977724) (xy 231.389424 -213.027154)
			(xy 231.397554 -213.078489) (xy 231.398064 -213.104476) (xy 231.397554 -213.130463) (xy 233.137204 -213.130463)
			(xy 233.137204 -213.078489) (xy 233.145334 -213.027154) (xy 233.161395 -212.977724) (xy 233.184991 -212.931414)
			(xy 233.215541 -212.889366) (xy 233.252292 -212.852615) (xy 233.29434 -212.822065) (xy 233.34065 -212.798469)
			(xy 233.39008 -212.782408) (xy 233.441415 -212.774278) (xy 233.493389 -212.774278) (xy 233.544724 -212.782408)
			(xy 233.594154 -212.798469) (xy 233.640464 -212.822065) (xy 233.682512 -212.852615) (xy 233.719263 -212.889366)
			(xy 233.749813 -212.931414) (xy 233.773409 -212.977724) (xy 233.78947 -213.027154) (xy 233.7976 -213.078489)
			(xy 233.79811 -213.104476) (xy 233.7976 -213.130463) (xy 233.78947 -213.181798) (xy 233.773409 -213.231228)
			(xy 233.749813 -213.277538) (xy 233.719263 -213.319586) (xy 233.682512 -213.356337) (xy 233.640464 -213.386887)
			(xy 233.594154 -213.410483) (xy 233.544724 -213.426544) (xy 233.493389 -213.434674) (xy 233.441415 -213.434674)
			(xy 233.39008 -213.426544) (xy 233.34065 -213.410483) (xy 233.29434 -213.386887) (xy 233.252292 -213.356337)
			(xy 233.215541 -213.319586) (xy 233.184991 -213.277538) (xy 233.161395 -213.231228) (xy 233.145334 -213.181798)
			(xy 233.137204 -213.130463) (xy 231.397554 -213.130463) (xy 231.389424 -213.181798) (xy 231.373363 -213.231228)
			(xy 231.349767 -213.277538) (xy 231.319217 -213.319586) (xy 231.282466 -213.356337) (xy 231.240418 -213.386887)
			(xy 231.194108 -213.410483) (xy 231.144678 -213.426544) (xy 231.093343 -213.434674) (xy 231.041369 -213.434674)
			(xy 230.990034 -213.426544) (xy 230.940604 -213.410483) (xy 230.894294 -213.386887) (xy 230.852246 -213.356337)
			(xy 230.815495 -213.319586) (xy 230.784945 -213.277538) (xy 230.761349 -213.231228) (xy 230.745288 -213.181798)
			(xy 230.737158 -213.130463) (xy 230.597708 -213.130463) (xy 230.589578 -213.181798) (xy 230.573517 -213.231228)
			(xy 230.549921 -213.277538) (xy 230.519371 -213.319586) (xy 230.48262 -213.356337) (xy 230.440572 -213.386887)
			(xy 230.394262 -213.410483) (xy 230.344832 -213.426544) (xy 230.293497 -213.434674) (xy 230.241523 -213.434674)
			(xy 230.190188 -213.426544) (xy 230.140758 -213.410483) (xy 230.094448 -213.386887) (xy 230.0524 -213.356337)
			(xy 230.015649 -213.319586) (xy 229.985099 -213.277538) (xy 229.961503 -213.231228) (xy 229.945442 -213.181798)
			(xy 229.937312 -213.130463) (xy 228.997974 -213.130463) (xy 228.989844 -213.181612) (xy 228.973656 -213.231232)
			(xy 228.949875 -213.277693) (xy 228.919092 -213.319843) (xy 228.88207 -213.356634) (xy 228.839729 -213.387154)
			(xy 228.816662 -213.39937) (xy 228.809296 -213.402926) (xy 228.759512 -213.452964) (xy 228.75271 -213.460312)
			(xy 228.744999 -213.478775) (xy 228.744526 -213.488778) (xy 228.744526 -213.561168) (xy 228.763068 -213.587076)
			(xy 228.778308 -213.592664) (xy 228.802123 -213.601605) (xy 228.846897 -213.625747) (xy 228.887444 -213.656462)
			(xy 228.92281 -213.693025) (xy 228.952158 -213.734572) (xy 228.974798 -213.780124) (xy 228.990194 -213.828606)
			(xy 228.997983 -213.878873) (xy 228.997982 -213.929741) (xy 228.997894 -213.930309) (xy 229.937312 -213.930309)
			(xy 229.937312 -213.878335) (xy 229.945442 -213.827) (xy 229.961503 -213.77757) (xy 229.985099 -213.73126)
			(xy 230.015649 -213.689212) (xy 230.0524 -213.652461) (xy 230.094448 -213.621911) (xy 230.140758 -213.598315)
			(xy 230.190188 -213.582254) (xy 230.241523 -213.574124) (xy 230.293497 -213.574124) (xy 230.344832 -213.582254)
			(xy 230.394262 -213.598315) (xy 230.440572 -213.621911) (xy 230.48262 -213.652461) (xy 230.519371 -213.689212)
			(xy 230.549921 -213.73126) (xy 230.573517 -213.77757) (xy 230.589578 -213.827) (xy 230.597708 -213.878335)
			(xy 230.598218 -213.904322) (xy 230.597708 -213.930309) (xy 230.737158 -213.930309) (xy 230.737158 -213.878335)
			(xy 230.745288 -213.827) (xy 230.761349 -213.77757) (xy 230.784945 -213.73126) (xy 230.815495 -213.689212)
			(xy 230.852246 -213.652461) (xy 230.894294 -213.621911) (xy 230.940604 -213.598315) (xy 230.990034 -213.582254)
			(xy 231.041369 -213.574124) (xy 231.093343 -213.574124) (xy 231.144678 -213.582254) (xy 231.194108 -213.598315)
			(xy 231.240418 -213.621911) (xy 231.282466 -213.652461) (xy 231.319217 -213.689212) (xy 231.349767 -213.73126)
			(xy 231.373363 -213.77757) (xy 231.389424 -213.827) (xy 231.397554 -213.878335) (xy 231.398064 -213.904322)
			(xy 231.397554 -213.930309) (xy 231.537258 -213.930309) (xy 231.537258 -213.878335) (xy 231.545388 -213.827)
			(xy 231.561449 -213.77757) (xy 231.585045 -213.73126) (xy 231.615595 -213.689212) (xy 231.652346 -213.652461)
			(xy 231.694394 -213.621911) (xy 231.740704 -213.598315) (xy 231.790134 -213.582254) (xy 231.841469 -213.574124)
			(xy 231.893443 -213.574124) (xy 231.944778 -213.582254) (xy 231.994208 -213.598315) (xy 232.040518 -213.621911)
			(xy 232.082566 -213.652461) (xy 232.119317 -213.689212) (xy 232.149867 -213.73126) (xy 232.173463 -213.77757)
			(xy 232.189524 -213.827) (xy 232.197654 -213.878335) (xy 232.198164 -213.904322) (xy 232.197654 -213.930309)
			(xy 232.337358 -213.930309) (xy 232.337358 -213.878335) (xy 232.345488 -213.827) (xy 232.361549 -213.77757)
			(xy 232.385145 -213.73126) (xy 232.415695 -213.689212) (xy 232.452446 -213.652461) (xy 232.494494 -213.621911)
			(xy 232.540804 -213.598315) (xy 232.590234 -213.582254) (xy 232.641569 -213.574124) (xy 232.693543 -213.574124)
			(xy 232.744878 -213.582254) (xy 232.794308 -213.598315) (xy 232.840618 -213.621911) (xy 232.882666 -213.652461)
			(xy 232.919417 -213.689212) (xy 232.949967 -213.73126) (xy 232.973563 -213.77757) (xy 232.989624 -213.827)
			(xy 232.997754 -213.878335) (xy 232.998264 -213.904322) (xy 232.997754 -213.930309) (xy 233.137204 -213.930309)
			(xy 233.137204 -213.878335) (xy 233.145334 -213.827) (xy 233.161395 -213.77757) (xy 233.184991 -213.73126)
			(xy 233.215541 -213.689212) (xy 233.252292 -213.652461) (xy 233.29434 -213.621911) (xy 233.34065 -213.598315)
			(xy 233.39008 -213.582254) (xy 233.441415 -213.574124) (xy 233.493389 -213.574124) (xy 233.544724 -213.582254)
			(xy 233.594154 -213.598315) (xy 233.640464 -213.621911) (xy 233.682512 -213.652461) (xy 233.719263 -213.689212)
			(xy 233.749813 -213.73126) (xy 233.773409 -213.77757) (xy 233.78947 -213.827) (xy 233.7976 -213.878335)
			(xy 233.79811 -213.904322) (xy 233.7976 -213.930309) (xy 233.937304 -213.930309) (xy 233.937304 -213.878335)
			(xy 233.945434 -213.827) (xy 233.961495 -213.77757) (xy 233.985091 -213.73126) (xy 234.015641 -213.689212)
			(xy 234.052392 -213.652461) (xy 234.09444 -213.621911) (xy 234.14075 -213.598315) (xy 234.19018 -213.582254)
			(xy 234.241515 -213.574124) (xy 234.293489 -213.574124) (xy 234.344824 -213.582254) (xy 234.394254 -213.598315)
			(xy 234.440564 -213.621911) (xy 234.482612 -213.652461) (xy 234.519363 -213.689212) (xy 234.549913 -213.73126)
			(xy 234.573509 -213.77757) (xy 234.58957 -213.827) (xy 234.5977 -213.878335) (xy 234.59821 -213.904322)
			(xy 234.5977 -213.930309) (xy 234.58957 -213.981644) (xy 234.573509 -214.031074) (xy 234.549913 -214.077384)
			(xy 234.519363 -214.119432) (xy 234.482612 -214.156183) (xy 234.440564 -214.186733) (xy 234.394254 -214.210329)
			(xy 234.344824 -214.22639) (xy 234.293489 -214.23452) (xy 234.241515 -214.23452) (xy 234.19018 -214.22639)
			(xy 234.14075 -214.210329) (xy 234.09444 -214.186733) (xy 234.052392 -214.156183) (xy 234.015641 -214.119432)
			(xy 233.985091 -214.077384) (xy 233.961495 -214.031074) (xy 233.945434 -213.981644) (xy 233.937304 -213.930309)
			(xy 233.7976 -213.930309) (xy 233.78947 -213.981644) (xy 233.773409 -214.031074) (xy 233.749813 -214.077384)
			(xy 233.719263 -214.119432) (xy 233.682512 -214.156183) (xy 233.640464 -214.186733) (xy 233.594154 -214.210329)
			(xy 233.544724 -214.22639) (xy 233.493389 -214.23452) (xy 233.441415 -214.23452) (xy 233.39008 -214.22639)
			(xy 233.34065 -214.210329) (xy 233.29434 -214.186733) (xy 233.252292 -214.156183) (xy 233.215541 -214.119432)
			(xy 233.184991 -214.077384) (xy 233.161395 -214.031074) (xy 233.145334 -213.981644) (xy 233.137204 -213.930309)
			(xy 232.997754 -213.930309) (xy 232.989624 -213.981644) (xy 232.973563 -214.031074) (xy 232.949967 -214.077384)
			(xy 232.919417 -214.119432) (xy 232.882666 -214.156183) (xy 232.840618 -214.186733) (xy 232.794308 -214.210329)
			(xy 232.744878 -214.22639) (xy 232.693543 -214.23452) (xy 232.641569 -214.23452) (xy 232.590234 -214.22639)
			(xy 232.540804 -214.210329) (xy 232.494494 -214.186733) (xy 232.452446 -214.156183) (xy 232.415695 -214.119432)
			(xy 232.385145 -214.077384) (xy 232.361549 -214.031074) (xy 232.345488 -213.981644) (xy 232.337358 -213.930309)
			(xy 232.197654 -213.930309) (xy 232.189524 -213.981644) (xy 232.173463 -214.031074) (xy 232.149867 -214.077384)
			(xy 232.119317 -214.119432) (xy 232.082566 -214.156183) (xy 232.040518 -214.186733) (xy 231.994208 -214.210329)
			(xy 231.944778 -214.22639) (xy 231.893443 -214.23452) (xy 231.841469 -214.23452) (xy 231.790134 -214.22639)
			(xy 231.740704 -214.210329) (xy 231.694394 -214.186733) (xy 231.652346 -214.156183) (xy 231.615595 -214.119432)
			(xy 231.585045 -214.077384) (xy 231.561449 -214.031074) (xy 231.545388 -213.981644) (xy 231.537258 -213.930309)
			(xy 231.397554 -213.930309) (xy 231.389424 -213.981644) (xy 231.373363 -214.031074) (xy 231.349767 -214.077384)
			(xy 231.319217 -214.119432) (xy 231.282466 -214.156183) (xy 231.240418 -214.186733) (xy 231.194108 -214.210329)
			(xy 231.144678 -214.22639) (xy 231.093343 -214.23452) (xy 231.041369 -214.23452) (xy 230.990034 -214.22639)
			(xy 230.940604 -214.210329) (xy 230.894294 -214.186733) (xy 230.852246 -214.156183) (xy 230.815495 -214.119432)
			(xy 230.784945 -214.077384) (xy 230.761349 -214.031074) (xy 230.745288 -213.981644) (xy 230.737158 -213.930309)
			(xy 230.597708 -213.930309) (xy 230.589578 -213.981644) (xy 230.573517 -214.031074) (xy 230.549921 -214.077384)
			(xy 230.519371 -214.119432) (xy 230.48262 -214.156183) (xy 230.440572 -214.186733) (xy 230.394262 -214.210329)
			(xy 230.344832 -214.22639) (xy 230.293497 -214.23452) (xy 230.241523 -214.23452) (xy 230.190188 -214.22639)
			(xy 230.140758 -214.210329) (xy 230.094448 -214.186733) (xy 230.0524 -214.156183) (xy 230.015649 -214.119432)
			(xy 229.985099 -214.077384) (xy 229.961503 -214.031074) (xy 229.945442 -213.981644) (xy 229.937312 -213.930309)
			(xy 228.997894 -213.930309) (xy 228.99019 -213.980009) (xy 228.974792 -214.02849) (xy 228.952151 -214.074041)
			(xy 228.9228 -214.115587) (xy 228.887433 -214.152148) (xy 228.846884 -214.182861) (xy 228.80211 -214.207001)
			(xy 228.778308 -214.21598) (xy 228.763068 -214.221568) (xy 228.744526 -214.247476) (xy 228.744526 -214.361268)
			(xy 228.763068 -214.387176) (xy 228.778308 -214.392764) (xy 228.802123 -214.401705) (xy 228.846897 -214.425847)
			(xy 228.887444 -214.456562) (xy 228.92281 -214.493125) (xy 228.952158 -214.534672) (xy 228.974798 -214.580224)
			(xy 228.990194 -214.628706) (xy 228.997983 -214.678973) (xy 228.997982 -214.729841) (xy 228.997894 -214.730409)
			(xy 229.937312 -214.730409) (xy 229.937312 -214.678435) (xy 229.945442 -214.6271) (xy 229.961503 -214.57767)
			(xy 229.985099 -214.53136) (xy 230.015649 -214.489312) (xy 230.0524 -214.452561) (xy 230.094448 -214.422011)
			(xy 230.140758 -214.398415) (xy 230.190188 -214.382354) (xy 230.241523 -214.374224) (xy 230.293497 -214.374224)
			(xy 230.344832 -214.382354) (xy 230.394262 -214.398415) (xy 230.440572 -214.422011) (xy 230.48262 -214.452561)
			(xy 230.519371 -214.489312) (xy 230.549921 -214.53136) (xy 230.573517 -214.57767) (xy 230.589578 -214.6271)
			(xy 230.597708 -214.678435) (xy 230.598218 -214.704422) (xy 230.597708 -214.730409) (xy 230.737158 -214.730409)
			(xy 230.737158 -214.678435) (xy 230.745288 -214.6271) (xy 230.761349 -214.57767) (xy 230.784945 -214.53136)
			(xy 230.815495 -214.489312) (xy 230.852246 -214.452561) (xy 230.894294 -214.422011) (xy 230.940604 -214.398415)
			(xy 230.990034 -214.382354) (xy 231.041369 -214.374224) (xy 231.093343 -214.374224) (xy 231.144678 -214.382354)
			(xy 231.194108 -214.398415) (xy 231.240418 -214.422011) (xy 231.282466 -214.452561) (xy 231.319217 -214.489312)
			(xy 231.349767 -214.53136) (xy 231.373363 -214.57767) (xy 231.389424 -214.6271) (xy 231.397554 -214.678435)
			(xy 231.398064 -214.704422) (xy 231.397554 -214.730409) (xy 231.537258 -214.730409) (xy 231.537258 -214.678435)
			(xy 231.545388 -214.6271) (xy 231.561449 -214.57767) (xy 231.585045 -214.53136) (xy 231.615595 -214.489312)
			(xy 231.652346 -214.452561) (xy 231.694394 -214.422011) (xy 231.740704 -214.398415) (xy 231.790134 -214.382354)
			(xy 231.841469 -214.374224) (xy 231.893443 -214.374224) (xy 231.944778 -214.382354) (xy 231.994208 -214.398415)
			(xy 232.040518 -214.422011) (xy 232.082566 -214.452561) (xy 232.119317 -214.489312) (xy 232.149867 -214.53136)
			(xy 232.173463 -214.57767) (xy 232.189524 -214.6271) (xy 232.197654 -214.678435) (xy 232.198164 -214.704422)
			(xy 232.197654 -214.730409) (xy 232.337358 -214.730409) (xy 232.337358 -214.678435) (xy 232.345488 -214.6271)
			(xy 232.361549 -214.57767) (xy 232.385145 -214.53136) (xy 232.415695 -214.489312) (xy 232.452446 -214.452561)
			(xy 232.494494 -214.422011) (xy 232.540804 -214.398415) (xy 232.590234 -214.382354) (xy 232.641569 -214.374224)
			(xy 232.693543 -214.374224) (xy 232.744878 -214.382354) (xy 232.794308 -214.398415) (xy 232.840618 -214.422011)
			(xy 232.882666 -214.452561) (xy 232.919417 -214.489312) (xy 232.949967 -214.53136) (xy 232.973563 -214.57767)
			(xy 232.989624 -214.6271) (xy 232.997754 -214.678435) (xy 232.998264 -214.704422) (xy 232.997754 -214.730409)
			(xy 232.989624 -214.781744) (xy 232.973563 -214.831174) (xy 232.949967 -214.877484) (xy 232.919417 -214.919532)
			(xy 232.882666 -214.956283) (xy 232.840618 -214.986833) (xy 232.794308 -215.010429) (xy 232.744878 -215.02649)
			(xy 232.693543 -215.03462) (xy 232.641569 -215.03462) (xy 232.590234 -215.02649) (xy 232.540804 -215.010429)
			(xy 232.494494 -214.986833) (xy 232.452446 -214.956283) (xy 232.415695 -214.919532) (xy 232.385145 -214.877484)
			(xy 232.361549 -214.831174) (xy 232.345488 -214.781744) (xy 232.337358 -214.730409) (xy 232.197654 -214.730409)
			(xy 232.189524 -214.781744) (xy 232.173463 -214.831174) (xy 232.149867 -214.877484) (xy 232.119317 -214.919532)
			(xy 232.082566 -214.956283) (xy 232.040518 -214.986833) (xy 231.994208 -215.010429) (xy 231.944778 -215.02649)
			(xy 231.893443 -215.03462) (xy 231.841469 -215.03462) (xy 231.790134 -215.02649) (xy 231.740704 -215.010429)
			(xy 231.694394 -214.986833) (xy 231.652346 -214.956283) (xy 231.615595 -214.919532) (xy 231.585045 -214.877484)
			(xy 231.561449 -214.831174) (xy 231.545388 -214.781744) (xy 231.537258 -214.730409) (xy 231.397554 -214.730409)
			(xy 231.389424 -214.781744) (xy 231.373363 -214.831174) (xy 231.349767 -214.877484) (xy 231.319217 -214.919532)
			(xy 231.282466 -214.956283) (xy 231.240418 -214.986833) (xy 231.194108 -215.010429) (xy 231.144678 -215.02649)
			(xy 231.093343 -215.03462) (xy 231.041369 -215.03462) (xy 230.990034 -215.02649) (xy 230.940604 -215.010429)
			(xy 230.894294 -214.986833) (xy 230.852246 -214.956283) (xy 230.815495 -214.919532) (xy 230.784945 -214.877484)
			(xy 230.761349 -214.831174) (xy 230.745288 -214.781744) (xy 230.737158 -214.730409) (xy 230.597708 -214.730409)
			(xy 230.589578 -214.781744) (xy 230.573517 -214.831174) (xy 230.549921 -214.877484) (xy 230.519371 -214.919532)
			(xy 230.48262 -214.956283) (xy 230.440572 -214.986833) (xy 230.394262 -215.010429) (xy 230.344832 -215.02649)
			(xy 230.293497 -215.03462) (xy 230.241523 -215.03462) (xy 230.190188 -215.02649) (xy 230.140758 -215.010429)
			(xy 230.094448 -214.986833) (xy 230.0524 -214.956283) (xy 230.015649 -214.919532) (xy 229.985099 -214.877484)
			(xy 229.961503 -214.831174) (xy 229.945442 -214.781744) (xy 229.937312 -214.730409) (xy 228.997894 -214.730409)
			(xy 228.99019 -214.780109) (xy 228.974792 -214.82859) (xy 228.952151 -214.874141) (xy 228.9228 -214.915687)
			(xy 228.887433 -214.952248) (xy 228.846884 -214.982961) (xy 228.80211 -215.007101) (xy 228.778308 -215.01608)
			(xy 228.763068 -215.021668) (xy 228.744526 -215.047576) (xy 228.744526 -215.161114) (xy 228.763068 -215.187022)
			(xy 228.778308 -215.19261) (xy 228.802128 -215.20155) (xy 228.846909 -215.225694) (xy 228.887465 -215.256412)
			(xy 228.922838 -215.292978) (xy 228.952193 -215.33453) (xy 228.974838 -215.380088) (xy 228.990239 -215.428576)
			(xy 228.998033 -215.478852) (xy 228.998034 -215.529727) (xy 228.997952 -215.530255) (xy 229.937312 -215.530255)
			(xy 229.937312 -215.478281) (xy 229.945442 -215.426946) (xy 229.961503 -215.377516) (xy 229.985099 -215.331206)
			(xy 230.015649 -215.289158) (xy 230.0524 -215.252407) (xy 230.094448 -215.221857) (xy 230.140758 -215.198261)
			(xy 230.190188 -215.1822) (xy 230.241523 -215.17407) (xy 230.293497 -215.17407) (xy 230.344832 -215.1822)
			(xy 230.394262 -215.198261) (xy 230.440572 -215.221857) (xy 230.48262 -215.252407) (xy 230.519371 -215.289158)
			(xy 230.549921 -215.331206) (xy 230.573517 -215.377516) (xy 230.589578 -215.426946) (xy 230.597708 -215.478281)
			(xy 230.598218 -215.504268) (xy 230.597708 -215.530255) (xy 230.737158 -215.530255) (xy 230.737158 -215.478281)
			(xy 230.745288 -215.426946) (xy 230.761349 -215.377516) (xy 230.784945 -215.331206) (xy 230.815495 -215.289158)
			(xy 230.852246 -215.252407) (xy 230.894294 -215.221857) (xy 230.940604 -215.198261) (xy 230.990034 -215.1822)
			(xy 231.041369 -215.17407) (xy 231.093343 -215.17407) (xy 231.144678 -215.1822) (xy 231.194108 -215.198261)
			(xy 231.240418 -215.221857) (xy 231.282466 -215.252407) (xy 231.319217 -215.289158) (xy 231.349767 -215.331206)
			(xy 231.373363 -215.377516) (xy 231.389424 -215.426946) (xy 231.397554 -215.478281) (xy 231.398064 -215.504268)
			(xy 231.397554 -215.530255) (xy 231.537258 -215.530255) (xy 231.537258 -215.478281) (xy 231.545388 -215.426946)
			(xy 231.561449 -215.377516) (xy 231.585045 -215.331206) (xy 231.615595 -215.289158) (xy 231.652346 -215.252407)
			(xy 231.694394 -215.221857) (xy 231.740704 -215.198261) (xy 231.790134 -215.1822) (xy 231.841469 -215.17407)
			(xy 231.893443 -215.17407) (xy 231.944778 -215.1822) (xy 231.994208 -215.198261) (xy 232.040518 -215.221857)
			(xy 232.082566 -215.252407) (xy 232.119317 -215.289158) (xy 232.149867 -215.331206) (xy 232.173463 -215.377516)
			(xy 232.189524 -215.426946) (xy 232.197654 -215.478281) (xy 232.198164 -215.504268) (xy 232.197654 -215.530255)
			(xy 232.189524 -215.58159) (xy 232.173463 -215.63102) (xy 232.149867 -215.67733) (xy 232.119317 -215.719378)
			(xy 232.082566 -215.756129) (xy 232.040518 -215.786679) (xy 231.994208 -215.810275) (xy 231.944778 -215.826336)
			(xy 231.893443 -215.834466) (xy 231.841469 -215.834466) (xy 231.790134 -215.826336) (xy 231.740704 -215.810275)
			(xy 231.694394 -215.786679) (xy 231.652346 -215.756129) (xy 231.615595 -215.719378) (xy 231.585045 -215.67733)
			(xy 231.561449 -215.63102) (xy 231.545388 -215.58159) (xy 231.537258 -215.530255) (xy 231.397554 -215.530255)
			(xy 231.389424 -215.58159) (xy 231.373363 -215.63102) (xy 231.349767 -215.67733) (xy 231.319217 -215.719378)
			(xy 231.282466 -215.756129) (xy 231.240418 -215.786679) (xy 231.194108 -215.810275) (xy 231.144678 -215.826336)
			(xy 231.093343 -215.834466) (xy 231.041369 -215.834466) (xy 230.990034 -215.826336) (xy 230.940604 -215.810275)
			(xy 230.894294 -215.786679) (xy 230.852246 -215.756129) (xy 230.815495 -215.719378) (xy 230.784945 -215.67733)
			(xy 230.761349 -215.63102) (xy 230.745288 -215.58159) (xy 230.737158 -215.530255) (xy 230.597708 -215.530255)
			(xy 230.589578 -215.58159) (xy 230.573517 -215.63102) (xy 230.549921 -215.67733) (xy 230.519371 -215.719378)
			(xy 230.48262 -215.756129) (xy 230.440572 -215.786679) (xy 230.394262 -215.810275) (xy 230.344832 -215.826336)
			(xy 230.293497 -215.834466) (xy 230.241523 -215.834466) (xy 230.190188 -215.826336) (xy 230.140758 -215.810275)
			(xy 230.094448 -215.786679) (xy 230.0524 -215.756129) (xy 230.015649 -215.719378) (xy 229.985099 -215.67733)
			(xy 229.961503 -215.63102) (xy 229.945442 -215.58159) (xy 229.937312 -215.530255) (xy 228.997952 -215.530255)
			(xy 228.990244 -215.580003) (xy 228.974846 -215.628492) (xy 228.952204 -215.674052) (xy 228.922851 -215.715606)
			(xy 228.887481 -215.752174) (xy 228.846927 -215.782894) (xy 228.802147 -215.807041) (xy 228.778308 -215.815926)
			(xy 228.763068 -215.821514) (xy 228.744526 -215.847422) (xy 228.744526 -215.961214) (xy 228.763068 -215.987122)
			(xy 228.778308 -215.99271) (xy 228.802128 -216.00165) (xy 228.846909 -216.025794) (xy 228.887465 -216.056512)
			(xy 228.922838 -216.093078) (xy 228.952193 -216.13463) (xy 228.974838 -216.180188) (xy 228.990239 -216.228676)
			(xy 228.998033 -216.278952) (xy 228.998034 -216.329827) (xy 228.997952 -216.330355) (xy 229.937312 -216.330355)
			(xy 229.937312 -216.278381) (xy 229.945442 -216.227046) (xy 229.961503 -216.177616) (xy 229.985099 -216.131306)
			(xy 230.015649 -216.089258) (xy 230.0524 -216.052507) (xy 230.094448 -216.021957) (xy 230.140758 -215.998361)
			(xy 230.190188 -215.9823) (xy 230.241523 -215.97417) (xy 230.293497 -215.97417) (xy 230.344832 -215.9823)
			(xy 230.394262 -215.998361) (xy 230.440572 -216.021957) (xy 230.48262 -216.052507) (xy 230.519371 -216.089258)
			(xy 230.549921 -216.131306) (xy 230.573517 -216.177616) (xy 230.589578 -216.227046) (xy 230.597708 -216.278381)
			(xy 230.598218 -216.304368) (xy 230.597708 -216.330355) (xy 230.737158 -216.330355) (xy 230.737158 -216.278381)
			(xy 230.745288 -216.227046) (xy 230.761349 -216.177616) (xy 230.784945 -216.131306) (xy 230.815495 -216.089258)
			(xy 230.852246 -216.052507) (xy 230.894294 -216.021957) (xy 230.940604 -215.998361) (xy 230.990034 -215.9823)
			(xy 231.041369 -215.97417) (xy 231.093343 -215.97417) (xy 231.144678 -215.9823) (xy 231.194108 -215.998361)
			(xy 231.240418 -216.021957) (xy 231.282466 -216.052507) (xy 231.319217 -216.089258) (xy 231.349767 -216.131306)
			(xy 231.373363 -216.177616) (xy 231.389424 -216.227046) (xy 231.397554 -216.278381) (xy 231.398064 -216.304368)
			(xy 231.397554 -216.330355) (xy 231.537258 -216.330355) (xy 231.537258 -216.278381) (xy 231.545388 -216.227046)
			(xy 231.561449 -216.177616) (xy 231.585045 -216.131306) (xy 231.615595 -216.089258) (xy 231.652346 -216.052507)
			(xy 231.694394 -216.021957) (xy 231.740704 -215.998361) (xy 231.790134 -215.9823) (xy 231.841469 -215.97417)
			(xy 231.893443 -215.97417) (xy 231.944778 -215.9823) (xy 231.994208 -215.998361) (xy 232.040518 -216.021957)
			(xy 232.082566 -216.052507) (xy 232.119317 -216.089258) (xy 232.149867 -216.131306) (xy 232.173463 -216.177616)
			(xy 232.189524 -216.227046) (xy 232.197654 -216.278381) (xy 232.198164 -216.304368) (xy 232.197654 -216.330355)
			(xy 232.189524 -216.38169) (xy 232.173463 -216.43112) (xy 232.149867 -216.47743) (xy 232.119317 -216.519478)
			(xy 232.082566 -216.556229) (xy 232.040518 -216.586779) (xy 231.994208 -216.610375) (xy 231.944778 -216.626436)
			(xy 231.893443 -216.634566) (xy 231.841469 -216.634566) (xy 231.790134 -216.626436) (xy 231.740704 -216.610375)
			(xy 231.694394 -216.586779) (xy 231.652346 -216.556229) (xy 231.615595 -216.519478) (xy 231.585045 -216.47743)
			(xy 231.561449 -216.43112) (xy 231.545388 -216.38169) (xy 231.537258 -216.330355) (xy 231.397554 -216.330355)
			(xy 231.389424 -216.38169) (xy 231.373363 -216.43112) (xy 231.349767 -216.47743) (xy 231.319217 -216.519478)
			(xy 231.282466 -216.556229) (xy 231.240418 -216.586779) (xy 231.194108 -216.610375) (xy 231.144678 -216.626436)
			(xy 231.093343 -216.634566) (xy 231.041369 -216.634566) (xy 230.990034 -216.626436) (xy 230.940604 -216.610375)
			(xy 230.894294 -216.586779) (xy 230.852246 -216.556229) (xy 230.815495 -216.519478) (xy 230.784945 -216.47743)
			(xy 230.761349 -216.43112) (xy 230.745288 -216.38169) (xy 230.737158 -216.330355) (xy 230.597708 -216.330355)
			(xy 230.589578 -216.38169) (xy 230.573517 -216.43112) (xy 230.549921 -216.47743) (xy 230.519371 -216.519478)
			(xy 230.48262 -216.556229) (xy 230.440572 -216.586779) (xy 230.394262 -216.610375) (xy 230.344832 -216.626436)
			(xy 230.293497 -216.634566) (xy 230.241523 -216.634566) (xy 230.190188 -216.626436) (xy 230.140758 -216.610375)
			(xy 230.094448 -216.586779) (xy 230.0524 -216.556229) (xy 230.015649 -216.519478) (xy 229.985099 -216.47743)
			(xy 229.961503 -216.43112) (xy 229.945442 -216.38169) (xy 229.937312 -216.330355) (xy 228.997952 -216.330355)
			(xy 228.990244 -216.380103) (xy 228.974846 -216.428592) (xy 228.952204 -216.474152) (xy 228.922851 -216.515706)
			(xy 228.887481 -216.552274) (xy 228.846927 -216.582994) (xy 228.802147 -216.607141) (xy 228.778308 -216.616026)
			(xy 228.763068 -216.621614) (xy 228.744526 -216.647522) (xy 228.744526 -216.761314) (xy 228.763068 -216.787222)
			(xy 228.778308 -216.79281) (xy 228.802125 -216.801754) (xy 228.846901 -216.825901) (xy 228.887452 -216.856619)
			(xy 228.922824 -216.893182) (xy 228.952181 -216.934729) (xy 228.974833 -216.98028) (xy 228.990244 -217.028762)
			(xy 228.998051 -217.079032) (xy 228.998526 -217.104468) (xy 228.997782 -217.135712) (xy 228.986029 -217.197087)
			(xy 228.975158 -217.226388) (xy 228.96957 -217.240612) (xy 228.975666 -217.270076) (xy 229.051104 -217.345514)
			(xy 229.051612 -217.346022) (xy 229.05899 -217.352614) (xy 229.077289 -217.360084) (xy 229.087172 -217.3605)
		)
		(stroke
			(width 0)
			(type solid)
		)
		(fill yes)
		(layer "In5.Cu")
		(net "P3V3_BIC_USB2AV33")
	)
	(gr_poly
		(pts
			(xy 386.785866 -248.569226) (xy 386.79574 -248.568758) (xy 386.814029 -248.561305) (xy 386.821426 -248.554748)
			(xy 386.82168 -248.554494) (xy 387.02742 -248.348754) (xy 387.027928 -248.348246) (xy 387.034513 -248.340866)
			(xy 387.041967 -248.322567) (xy 387.042406 -248.312686) (xy 387.042406 -247.725438) (xy 387.042337 -247.721632)
			(xy 387.041184 -247.714107) (xy 387.04012 -247.710452) (xy 387.034024 -247.690386) (xy 387.030214 -247.684544)
			(xy 387.015831 -247.661346) (xy 386.993125 -247.611712) (xy 386.977722 -247.559349) (xy 386.969939 -247.505326)
			(xy 386.969934 -247.450745) (xy 386.977707 -247.39672) (xy 386.9931 -247.344354) (xy 387.015797 -247.294716)
			(xy 387.030214 -247.27154) (xy 387.034024 -247.265698) (xy 387.04012 -247.245632) (xy 387.041173 -247.241975)
			(xy 387.04232 -247.234451) (xy 387.042406 -247.230646) (xy 387.042406 -243.404898) (xy 387.042363 -243.401228)
			(xy 387.041347 -243.393959) (xy 387.040374 -243.39042) (xy 387.034278 -243.370354) (xy 387.030722 -243.364512)
			(xy 387.017289 -243.341844) (xy 386.996101 -243.293601) (xy 386.981749 -243.242902) (xy 386.974507 -243.190711)
			(xy 386.974512 -243.138021) (xy 386.981763 -243.085831) (xy 386.996124 -243.035135) (xy 387.01732 -242.986895)
			(xy 387.030722 -242.964208) (xy 387.034278 -242.958366) (xy 387.040374 -242.9383) (xy 387.041336 -242.934759)
			(xy 387.04235 -242.927491) (xy 387.042406 -242.923822) (xy 387.042406 -241.551206) (xy 387.042175 -241.544834)
			(xy 387.038962 -241.532498) (xy 387.036056 -241.526822) (xy 387.021832 -241.500914) (xy 387.013958 -241.492278)
			(xy 387.008878 -241.488722) (xy 386.985493 -241.472222) (xy 386.94348 -241.433359) (xy 386.907741 -241.388658)
			(xy 386.879077 -241.339122) (xy 386.858131 -241.285862) (xy 386.845373 -241.230071) (xy 386.841088 -241.173)
			(xy 386.845373 -241.115929) (xy 386.858131 -241.060138) (xy 386.879077 -241.006878) (xy 386.907741 -240.957342)
			(xy 386.94348 -240.912641) (xy 386.985493 -240.873778) (xy 387.008878 -240.857278) (xy 387.013958 -240.853722)
			(xy 387.021832 -240.845086) (xy 387.036056 -240.819178) (xy 387.038986 -240.813512) (xy 387.04219 -240.80117)
			(xy 387.042406 -240.794794) (xy 387.042406 -238.714788) (xy 387.04206 -238.705832) (xy 387.035915 -238.689006)
			(xy 387.024373 -238.675307) (xy 387.016752 -238.670592) (xy 386.927852 -238.620046) (xy 386.900674 -238.6203)
			(xy 386.888736 -238.627412) (xy 386.860557 -238.643666) (xy 386.800763 -238.66929) (xy 386.738069 -238.686653)
			(xy 386.673612 -238.69544) (xy 386.641086 -238.695992) (xy 386.60946 -238.695496) (xy 386.546748 -238.687236)
			(xy 386.485653 -238.670859) (xy 386.427218 -238.646645) (xy 386.372445 -238.61501) (xy 386.322271 -238.576493)
			(xy 386.277555 -238.531756) (xy 386.239063 -238.481564) (xy 386.207453 -238.426776) (xy 386.183267 -238.368329)
			(xy 386.166919 -238.307226) (xy 386.158689 -238.244511) (xy 386.158232 -238.212884) (xy 386.158596 -238.184485)
			(xy 386.165168 -238.128069) (xy 386.178313 -238.072813) (xy 386.187696 -238.046006) (xy 386.200312 -238.013504)
			(xy 386.233548 -237.952217) (xy 386.275245 -237.896341) (xy 386.299456 -237.871254) (xy 387.02742 -237.14329)
			(xy 387.034238 -237.135948) (xy 387.041979 -237.117485) (xy 387.042406 -237.107476) (xy 387.042406 -235.102908)
			(xy 387.041809 -235.091574) (xy 387.03206 -235.071112) (xy 387.02361 -235.063538) (xy 386.953506 -235.006388)
			(xy 386.931408 -235.001054) (xy 386.919978 -235.00334) (xy 386.900705 -235.007121) (xy 386.861639 -235.011197)
			(xy 386.842 -235.011468) (xy 386.814752 -235.010982) (xy 386.76081 -235.003226) (xy 386.70852 -234.987873)
			(xy 386.658948 -234.965234) (xy 386.613103 -234.935771) (xy 386.571917 -234.900083) (xy 386.536229 -234.858897)
			(xy 386.506766 -234.813052) (xy 386.484127 -234.76348) (xy 386.468774 -234.71119) (xy 386.461018 -234.657248)
			(xy 386.461018 -234.602752) (xy 386.468774 -234.54881) (xy 386.484127 -234.49652) (xy 386.506766 -234.446948)
			(xy 386.536229 -234.401103) (xy 386.571917 -234.359917) (xy 386.613103 -234.324229) (xy 386.658948 -234.294766)
			(xy 386.70852 -234.272127) (xy 386.76081 -234.256774) (xy 386.814752 -234.249018) (xy 386.842 -234.248452)
			(xy 386.86164 -234.248705) (xy 386.900709 -234.252772) (xy 386.919978 -234.25658) (xy 386.931408 -234.258866)
			(xy 386.953506 -234.253532) (xy 387.02361 -234.196382) (xy 387.032002 -234.188762) (xy 387.041751 -234.168329)
			(xy 387.042406 -234.157012) (xy 387.042406 -233.698288) (xy 387.041981 -233.688219) (xy 387.034264 -233.669617)
			(xy 387.02742 -233.66222) (xy 386.754878 -233.389678) (xy 386.747766 -233.382312) (xy 386.72897 -233.374692)
			(xy 380.56439 -233.374692) (xy 380.55432 -233.375116) (xy 380.535718 -233.382833) (xy 380.528322 -233.389678)
			(xy 380.500128 -233.417872) (xy 380.492508 -233.43489) (xy 380.492 -233.444542) (xy 380.490093 -233.472925)
			(xy 380.478924 -233.528702) (xy 380.459598 -233.582203) (xy 380.432543 -233.632241) (xy 380.398359 -233.677708)
			(xy 380.357803 -233.717597) (xy 380.311775 -233.751022) (xy 380.286768 -233.764582) (xy 380.2761 -233.77017)
			(xy 380.26213 -233.78922) (xy 380.244858 -233.89336) (xy 380.251716 -233.915966) (xy 380.260098 -233.924856)
			(xy 380.279759 -233.94626) (xy 380.313026 -233.993914) (xy 380.313541 -233.99496) (xy 381.97358 -233.99496)
			(xy 381.977651 -233.939338) (xy 381.989777 -233.884901) (xy 382.0097 -233.83281) (xy 382.036996 -233.784175)
			(xy 382.071082 -233.740032) (xy 382.111231 -233.701323) (xy 382.156589 -233.668872) (xy 382.206189 -233.643371)
			(xy 382.258973 -233.625364) (xy 382.313816 -233.615234) (xy 382.36955 -233.613197) (xy 382.424987 -233.619297)
			(xy 382.478944 -233.633403) (xy 382.530273 -233.655215) (xy 382.577879 -233.684269) (xy 382.620747 -233.719944)
			(xy 382.657964 -233.761481) (xy 382.688737 -233.807994) (xy 382.712409 -233.858491) (xy 382.728477 -233.911898)
			(xy 382.736597 -233.967074) (xy 382.737041 -233.991404) (xy 382.973578 -233.991404) (xy 382.977649 -233.935782)
			(xy 382.989775 -233.881345) (xy 383.009698 -233.829254) (xy 383.036994 -233.780619) (xy 383.07108 -233.736476)
			(xy 383.111229 -233.697767) (xy 383.156587 -233.665316) (xy 383.206187 -233.639815) (xy 383.258971 -233.621808)
			(xy 383.313814 -233.611678) (xy 383.369548 -233.609641) (xy 383.424985 -233.615741) (xy 383.478942 -233.629847)
			(xy 383.530271 -233.651659) (xy 383.577877 -233.680713) (xy 383.620745 -233.716388) (xy 383.657962 -233.757925)
			(xy 383.688735 -233.804438) (xy 383.712407 -233.854935) (xy 383.728475 -233.908342) (xy 383.735765 -233.957876)
			(xy 384.473448 -233.957876) (xy 384.477519 -233.902254) (xy 384.489645 -233.847817) (xy 384.509568 -233.795726)
			(xy 384.536864 -233.747091) (xy 384.57095 -233.702948) (xy 384.611099 -233.664239) (xy 384.656457 -233.631788)
			(xy 384.706057 -233.606287) (xy 384.758841 -233.58828) (xy 384.813684 -233.57815) (xy 384.869418 -233.576113)
			(xy 384.924855 -233.582213) (xy 384.978812 -233.596319) (xy 385.030141 -233.618131) (xy 385.077747 -233.647185)
			(xy 385.120615 -233.68286) (xy 385.157832 -233.724397) (xy 385.188605 -233.77091) (xy 385.212277 -233.821407)
			(xy 385.228345 -233.874814) (xy 385.236465 -233.92999) (xy 385.236974 -233.957876) (xy 385.236465 -233.985762)
			(xy 385.228345 -234.040938) (xy 385.212277 -234.094345) (xy 385.188605 -234.144842) (xy 385.157832 -234.191355)
			(xy 385.120615 -234.232892) (xy 385.077747 -234.268567) (xy 385.030141 -234.297621) (xy 384.978812 -234.319433)
			(xy 384.924855 -234.333539) (xy 384.869418 -234.339639) (xy 384.813684 -234.337602) (xy 384.758841 -234.327472)
			(xy 384.706057 -234.309465) (xy 384.656457 -234.283964) (xy 384.611099 -234.251513) (xy 384.57095 -234.212804)
			(xy 384.536864 -234.168661) (xy 384.509568 -234.120026) (xy 384.489645 -234.067935) (xy 384.477519 -234.013498)
			(xy 384.473448 -233.957876) (xy 383.735765 -233.957876) (xy 383.736595 -233.963518) (xy 383.737104 -233.991404)
			(xy 383.736595 -234.01929) (xy 383.728475 -234.074466) (xy 383.712407 -234.127873) (xy 383.688735 -234.17837)
			(xy 383.657962 -234.224883) (xy 383.620745 -234.26642) (xy 383.577877 -234.302095) (xy 383.530271 -234.331149)
			(xy 383.478942 -234.352961) (xy 383.424985 -234.367067) (xy 383.369548 -234.373167) (xy 383.313814 -234.37113)
			(xy 383.258971 -234.361) (xy 383.206187 -234.342993) (xy 383.156587 -234.317492) (xy 383.111229 -234.285041)
			(xy 383.07108 -234.246332) (xy 383.036994 -234.202189) (xy 383.009698 -234.153554) (xy 382.989775 -234.101463)
			(xy 382.977649 -234.047026) (xy 382.973578 -233.991404) (xy 382.737041 -233.991404) (xy 382.737106 -233.99496)
			(xy 382.736597 -234.022846) (xy 382.728477 -234.078022) (xy 382.712409 -234.131429) (xy 382.688737 -234.181926)
			(xy 382.657964 -234.228439) (xy 382.620747 -234.269976) (xy 382.577879 -234.305651) (xy 382.530273 -234.334705)
			(xy 382.478944 -234.356517) (xy 382.424987 -234.370623) (xy 382.36955 -234.376723) (xy 382.313816 -234.374686)
			(xy 382.258973 -234.364556) (xy 382.206189 -234.346549) (xy 382.156589 -234.321048) (xy 382.111231 -234.288597)
			(xy 382.071082 -234.249888) (xy 382.036996 -234.205745) (xy 382.0097 -234.15711) (xy 381.989777 -234.105019)
			(xy 381.977651 -234.050582) (xy 381.97358 -233.99496) (xy 380.313541 -233.99496) (xy 380.338679 -234.046063)
			(xy 380.356123 -234.1015) (xy 380.364955 -234.158942) (xy 380.365508 -234.188) (xy 380.365022 -234.215251)
			(xy 380.357266 -234.269199) (xy 380.341911 -234.321494) (xy 380.319269 -234.371071) (xy 380.289803 -234.416921)
			(xy 380.254112 -234.458112) (xy 380.212921 -234.493803) (xy 380.167071 -234.523269) (xy 380.117494 -234.545911)
			(xy 380.065199 -234.561266) (xy 380.011251 -234.569022) (xy 379.956749 -234.569022) (xy 379.902801 -234.561266)
			(xy 379.850506 -234.545911) (xy 379.800929 -234.523269) (xy 379.755079 -234.493803) (xy 379.713888 -234.458112)
			(xy 379.678197 -234.416921) (xy 379.648731 -234.371071) (xy 379.626089 -234.321494) (xy 379.610734 -234.269199)
			(xy 379.602978 -234.215251) (xy 379.602492 -234.188) (xy 379.602936 -234.161954) (xy 379.610026 -234.110347)
			(xy 379.624073 -234.060185) (xy 379.644817 -234.012402) (xy 379.671871 -233.967886) (xy 379.704732 -233.927467)
			(xy 379.742789 -233.891896) (xy 379.785332 -233.861836) (xy 379.808232 -233.849418) (xy 379.8189 -233.84383)
			(xy 379.83287 -233.82478) (xy 379.850142 -233.72064) (xy 379.843284 -233.698034) (xy 379.834902 -233.689144)
			(xy 379.815223 -233.667691) (xy 379.781932 -233.619935) (xy 379.756269 -233.567683) (xy 379.738829 -233.512142)
			(xy 379.730016 -233.454599) (xy 379.729492 -233.425492) (xy 379.729002 -233.415486) (xy 379.721341 -233.396998)
			(xy 379.707188 -233.38285) (xy 379.688698 -233.375194) (xy 379.678692 -233.374692) (xy 378.558806 -233.374692)
			(xy 378.548735 -233.375114) (xy 378.530128 -233.382826) (xy 378.522738 -233.389678) (xy 378.09805 -233.814366)
			(xy 378.090938 -233.83748) (xy 378.09297 -233.849926) (xy 378.095585 -233.866055) (xy 378.098387 -233.898612)
			(xy 378.098558 -233.91495) (xy 378.098098 -233.942204) (xy 378.090347 -233.996158) (xy 378.074994 -234.048459)
			(xy 378.052354 -234.098042) (xy 378.022887 -234.143898) (xy 377.987192 -234.185092) (xy 377.945998 -234.220787)
			(xy 377.900142 -234.250254) (xy 377.850559 -234.272894) (xy 377.798258 -234.288247) (xy 377.744304 -234.295998)
			(xy 377.71705 -234.296458) (xy 377.700711 -234.296286) (xy 377.668154 -234.293489) (xy 377.652026 -234.29087)
			(xy 377.63958 -234.288838) (xy 377.616466 -234.29595) (xy 377.073414 -234.839002) (xy 377.066048 -234.846114)
			(xy 377.058428 -234.86491) (xy 377.058428 -235.057442) (xy 377.058893 -235.067317) (xy 377.066345 -235.085607)
			(xy 377.072906 -235.093002) (xy 377.129294 -235.150914) (xy 377.14682 -235.158534) (xy 377.15698 -235.159042)
			(xy 377.184941 -235.160391) (xy 377.240042 -235.170264) (xy 377.293108 -235.188085) (xy 377.343 -235.213471)
			(xy 377.388645 -235.245876) (xy 377.429064 -235.284604) (xy 377.463389 -235.328824) (xy 377.490882 -235.377586)
			(xy 377.510952 -235.429843) (xy 377.52317 -235.484472) (xy 377.527272 -235.5403) (xy 377.52317 -235.596128)
			(xy 377.510953 -235.650757) (xy 377.490882 -235.703014) (xy 377.463389 -235.751776) (xy 377.429064 -235.795996)
			(xy 377.388645 -235.834724) (xy 377.343 -235.867129) (xy 377.293108 -235.892515) (xy 377.240042 -235.910336)
			(xy 377.184941 -235.920209) (xy 377.15698 -235.92155) (xy 377.14682 -235.922058) (xy 377.129294 -235.929678)
			(xy 377.072906 -235.98759) (xy 377.066334 -235.994975) (xy 377.058903 -236.013274) (xy 377.058428 -236.02315)
			(xy 377.058428 -236.398054) (xy 377.059131 -236.41021) (xy 377.070281 -236.431816) (xy 377.079764 -236.439456)
			(xy 377.15698 -236.494828) (xy 377.18111 -236.49813) (xy 377.193048 -236.49432) (xy 377.223124 -236.48466)
			(xy 377.285418 -236.474198) (xy 377.317 -236.473492) (xy 377.344251 -236.473978) (xy 377.398199 -236.481734)
			(xy 377.450494 -236.497089) (xy 377.500071 -236.519731) (xy 377.545921 -236.549197) (xy 377.587112 -236.584888)
			(xy 377.601073 -236.601) (xy 383.284982 -236.601) (xy 383.289053 -236.545378) (xy 383.301179 -236.490941)
			(xy 383.321102 -236.43885) (xy 383.348398 -236.390215) (xy 383.382484 -236.346072) (xy 383.422633 -236.307363)
			(xy 383.467991 -236.274912) (xy 383.517591 -236.249411) (xy 383.570375 -236.231404) (xy 383.625218 -236.221274)
			(xy 383.680952 -236.219237) (xy 383.736389 -236.225337) (xy 383.790346 -236.239443) (xy 383.841675 -236.261255)
			(xy 383.889281 -236.290309) (xy 383.932149 -236.325984) (xy 383.969366 -236.367521) (xy 384.000139 -236.414034)
			(xy 384.023811 -236.464531) (xy 384.039879 -236.517938) (xy 384.047999 -236.573114) (xy 384.048508 -236.601)
			(xy 384.047999 -236.628886) (xy 384.039879 -236.684062) (xy 384.023811 -236.737469) (xy 384.000139 -236.787966)
			(xy 383.969366 -236.834479) (xy 383.932149 -236.876016) (xy 383.889281 -236.911691) (xy 383.841675 -236.940745)
			(xy 383.790346 -236.962557) (xy 383.736389 -236.976663) (xy 383.680952 -236.982763) (xy 383.625218 -236.980726)
			(xy 383.570375 -236.970596) (xy 383.517591 -236.952589) (xy 383.467991 -236.927088) (xy 383.422633 -236.894637)
			(xy 383.382484 -236.855928) (xy 383.348398 -236.811785) (xy 383.321102 -236.76315) (xy 383.301179 -236.711059)
			(xy 383.289053 -236.656622) (xy 383.284982 -236.601) (xy 377.601073 -236.601) (xy 377.622803 -236.626079)
			(xy 377.652269 -236.671929) (xy 377.674911 -236.721506) (xy 377.690266 -236.773801) (xy 377.698022 -236.827749)
			(xy 377.698022 -236.882251) (xy 377.690266 -236.936199) (xy 377.674911 -236.988494) (xy 377.652269 -237.038071)
			(xy 377.622803 -237.083921) (xy 377.587112 -237.125112) (xy 377.545921 -237.160803) (xy 377.500071 -237.190269)
			(xy 377.450494 -237.212911) (xy 377.398199 -237.228266) (xy 377.344404 -237.236) (xy 379.871984 -237.236)
			(xy 379.876055 -237.180378) (xy 379.888181 -237.125941) (xy 379.908104 -237.07385) (xy 379.9354 -237.025215)
			(xy 379.969486 -236.981072) (xy 380.009635 -236.942363) (xy 380.054993 -236.909912) (xy 380.104593 -236.884411)
			(xy 380.157377 -236.866404) (xy 380.21222 -236.856274) (xy 380.267954 -236.854237) (xy 380.323391 -236.860337)
			(xy 380.377348 -236.874443) (xy 380.428677 -236.896255) (xy 380.476283 -236.925309) (xy 380.519151 -236.960984)
			(xy 380.556368 -237.002521) (xy 380.587141 -237.049034) (xy 380.610813 -237.099531) (xy 380.626881 -237.152938)
			(xy 380.635001 -237.208114) (xy 380.63551 -237.236) (xy 380.635001 -237.263886) (xy 380.626881 -237.319062)
			(xy 380.610813 -237.372469) (xy 380.587141 -237.422966) (xy 380.556368 -237.469479) (xy 380.519151 -237.511016)
			(xy 380.476283 -237.546691) (xy 380.428677 -237.575745) (xy 380.377348 -237.597557) (xy 380.323391 -237.611663)
			(xy 380.267954 -237.617763) (xy 380.21222 -237.615726) (xy 380.157377 -237.605596) (xy 380.104593 -237.587589)
			(xy 380.054993 -237.562088) (xy 380.009635 -237.529637) (xy 379.969486 -237.490928) (xy 379.9354 -237.446785)
			(xy 379.908104 -237.39815) (xy 379.888181 -237.346059) (xy 379.876055 -237.291622) (xy 379.871984 -237.236)
			(xy 377.344404 -237.236) (xy 377.344251 -237.236022) (xy 377.317 -237.236508) (xy 377.285412 -237.235874)
			(xy 377.223107 -237.225409) (xy 377.193048 -237.21568) (xy 377.18111 -237.21187) (xy 377.15698 -237.215172)
			(xy 377.079764 -237.270544) (xy 377.07026 -237.278163) (xy 377.059123 -237.299785) (xy 377.058428 -237.311946)
			(xy 377.058428 -237.998) (xy 383.030982 -237.998) (xy 383.035053 -237.942378) (xy 383.047179 -237.887941)
			(xy 383.067102 -237.83585) (xy 383.094398 -237.787215) (xy 383.128484 -237.743072) (xy 383.168633 -237.704363)
			(xy 383.213991 -237.671912) (xy 383.263591 -237.646411) (xy 383.316375 -237.628404) (xy 383.371218 -237.618274)
			(xy 383.426952 -237.616237) (xy 383.482389 -237.622337) (xy 383.536346 -237.636443) (xy 383.587675 -237.658255)
			(xy 383.635281 -237.687309) (xy 383.678149 -237.722984) (xy 383.715366 -237.764521) (xy 383.746139 -237.811034)
			(xy 383.769811 -237.861531) (xy 383.785879 -237.914938) (xy 383.793999 -237.970114) (xy 383.794508 -237.998)
			(xy 383.793999 -238.025886) (xy 383.785879 -238.081062) (xy 383.769811 -238.134469) (xy 383.746139 -238.184966)
			(xy 383.715366 -238.231479) (xy 383.678149 -238.273016) (xy 383.635281 -238.308691) (xy 383.587675 -238.337745)
			(xy 383.536346 -238.359557) (xy 383.482389 -238.373663) (xy 383.426952 -238.379763) (xy 383.371218 -238.377726)
			(xy 383.316375 -238.367596) (xy 383.263591 -238.349589) (xy 383.213991 -238.324088) (xy 383.168633 -238.291637)
			(xy 383.128484 -238.252928) (xy 383.094398 -238.208785) (xy 383.067102 -238.16015) (xy 383.047179 -238.108059)
			(xy 383.035053 -238.053622) (xy 383.030982 -237.998) (xy 377.058428 -237.998) (xy 377.058428 -238.327692)
			(xy 377.058714 -238.335947) (xy 377.06391 -238.351616) (xy 377.068588 -238.358426) (xy 377.086728 -238.383404)
			(xy 377.115544 -238.437995) (xy 377.135194 -238.496513) (xy 377.145166 -238.557432) (xy 377.145804 -238.588296)
			(xy 377.145185 -238.61916) (xy 377.1352 -238.680076) (xy 377.115537 -238.738589) (xy 377.08671 -238.793174)
			(xy 377.073745 -238.811054) (xy 379.62078 -238.811054) (xy 379.621266 -238.783803) (xy 379.629022 -238.729855)
			(xy 379.644377 -238.67756) (xy 379.667019 -238.627983) (xy 379.696485 -238.582133) (xy 379.732176 -238.540942)
			(xy 379.773367 -238.505251) (xy 379.819217 -238.475785) (xy 379.868794 -238.453143) (xy 379.921089 -238.437788)
			(xy 379.975037 -238.430032) (xy 380.029539 -238.430032) (xy 380.083487 -238.437788) (xy 380.135782 -238.453143)
			(xy 380.146404 -238.457994) (xy 384.263898 -238.457994) (xy 384.267969 -238.402372) (xy 384.280095 -238.347935)
			(xy 384.300018 -238.295844) (xy 384.327314 -238.247209) (xy 384.3614 -238.203066) (xy 384.401549 -238.164357)
			(xy 384.446907 -238.131906) (xy 384.496507 -238.106405) (xy 384.549291 -238.088398) (xy 384.604134 -238.078268)
			(xy 384.659868 -238.076231) (xy 384.715305 -238.082331) (xy 384.769262 -238.096437) (xy 384.820591 -238.118249)
			(xy 384.868197 -238.147303) (xy 384.911065 -238.182978) (xy 384.948282 -238.224515) (xy 384.979055 -238.271028)
			(xy 385.002727 -238.321525) (xy 385.018795 -238.374932) (xy 385.026915 -238.430108) (xy 385.027424 -238.457994)
			(xy 385.026915 -238.48588) (xy 385.018795 -238.541056) (xy 385.002727 -238.594463) (xy 384.979055 -238.64496)
			(xy 384.948282 -238.691473) (xy 384.911065 -238.73301) (xy 384.868197 -238.768685) (xy 384.820591 -238.797739)
			(xy 384.769262 -238.819551) (xy 384.715305 -238.833657) (xy 384.659868 -238.839757) (xy 384.604134 -238.83772)
			(xy 384.549291 -238.82759) (xy 384.496507 -238.809583) (xy 384.446907 -238.784082) (xy 384.401549 -238.751631)
			(xy 384.3614 -238.712922) (xy 384.327314 -238.668779) (xy 384.300018 -238.620144) (xy 384.280095 -238.568053)
			(xy 384.267969 -238.513616) (xy 384.263898 -238.457994) (xy 380.146404 -238.457994) (xy 380.185359 -238.475785)
			(xy 380.231209 -238.505251) (xy 380.2724 -238.540942) (xy 380.308091 -238.582133) (xy 380.337557 -238.627983)
			(xy 380.360199 -238.67756) (xy 380.375554 -238.729855) (xy 380.38331 -238.783803) (xy 380.383796 -238.811054)
			(xy 380.383313 -238.839415) (xy 380.374913 -238.895512) (xy 380.358292 -238.949744) (xy 380.333817 -239.000914)
			(xy 380.302029 -239.047892) (xy 380.283212 -239.069118) (xy 380.275592 -239.0775) (xy 380.268988 -239.098582)
			(xy 380.280926 -239.197642) (xy 380.29261 -239.216438) (xy 380.302008 -239.222534) (xy 380.324224 -239.237761)
			(xy 380.364562 -239.27345) (xy 380.399481 -239.314456) (xy 380.428289 -239.359963) (xy 380.450413 -239.409069)
			(xy 380.465413 -239.460797) (xy 380.472992 -239.51412) (xy 380.473458 -239.54105) (xy 380.472972 -239.568301)
			(xy 380.465216 -239.622249) (xy 380.449861 -239.674544) (xy 380.427219 -239.724121) (xy 380.397753 -239.769971)
			(xy 380.362157 -239.811052) (xy 383.030982 -239.811052) (xy 383.035053 -239.75543) (xy 383.047179 -239.700993)
			(xy 383.067102 -239.648902) (xy 383.094398 -239.600267) (xy 383.128484 -239.556124) (xy 383.168633 -239.517415)
			(xy 383.213991 -239.484964) (xy 383.263591 -239.459463) (xy 383.316375 -239.441456) (xy 383.371218 -239.431326)
			(xy 383.426952 -239.429289) (xy 383.482389 -239.435389) (xy 383.536346 -239.449495) (xy 383.587675 -239.471307)
			(xy 383.635281 -239.500361) (xy 383.678149 -239.536036) (xy 383.715366 -239.577573) (xy 383.746139 -239.624086)
			(xy 383.769811 -239.674583) (xy 383.785879 -239.72799) (xy 383.793999 -239.783166) (xy 383.794508 -239.811052)
			(xy 383.793999 -239.838938) (xy 383.785879 -239.894114) (xy 383.769811 -239.947521) (xy 383.746139 -239.998018)
			(xy 383.715366 -240.044531) (xy 383.678149 -240.086068) (xy 383.635281 -240.121743) (xy 383.587675 -240.150797)
			(xy 383.536346 -240.172609) (xy 383.482389 -240.186715) (xy 383.426952 -240.192815) (xy 383.371218 -240.190778)
			(xy 383.316375 -240.180648) (xy 383.263591 -240.162641) (xy 383.213991 -240.13714) (xy 383.168633 -240.104689)
			(xy 383.128484 -240.06598) (xy 383.094398 -240.021837) (xy 383.067102 -239.973202) (xy 383.047179 -239.921111)
			(xy 383.035053 -239.866674) (xy 383.030982 -239.811052) (xy 380.362157 -239.811052) (xy 380.362062 -239.811162)
			(xy 380.320871 -239.846853) (xy 380.275021 -239.876319) (xy 380.225444 -239.898961) (xy 380.173149 -239.914316)
			(xy 380.119201 -239.922072) (xy 380.064699 -239.922072) (xy 380.010751 -239.914316) (xy 379.958456 -239.898961)
			(xy 379.908879 -239.876319) (xy 379.863029 -239.846853) (xy 379.821838 -239.811162) (xy 379.786147 -239.769971)
			(xy 379.756681 -239.724121) (xy 379.734039 -239.674544) (xy 379.718684 -239.622249) (xy 379.710928 -239.568301)
			(xy 379.710442 -239.54105) (xy 379.710944 -239.51269) (xy 379.719341 -239.456595) (xy 379.735959 -239.402363)
			(xy 379.760429 -239.351193) (xy 379.792212 -239.304214) (xy 379.811026 -239.282986) (xy 379.818646 -239.274604)
			(xy 379.82525 -239.253522) (xy 379.813312 -239.154462) (xy 379.801628 -239.135666) (xy 379.79223 -239.12957)
			(xy 379.770024 -239.114328) (xy 379.729685 -239.078643) (xy 379.694763 -239.03764) (xy 379.665954 -238.992135)
			(xy 379.643828 -238.943032) (xy 379.628826 -238.891305) (xy 379.621246 -238.837983) (xy 379.62078 -238.811054)
			(xy 377.073745 -238.811054) (xy 377.068588 -238.818166) (xy 377.063894 -238.824964) (xy 377.058722 -238.840643)
			(xy 377.058428 -238.8489) (xy 377.058428 -239.270794) (xy 377.058868 -239.280953) (xy 377.066719 -239.299694)
			(xy 377.073668 -239.307116) (xy 377.074684 -239.307878) (xy 377.139962 -239.366298) (xy 377.16079 -239.372902)
			(xy 377.171458 -239.371632) (xy 377.182404 -239.37044) (xy 377.204389 -239.369168) (xy 377.2154 -239.369092)
			(xy 377.242651 -239.369578) (xy 377.296599 -239.377334) (xy 377.348894 -239.392689) (xy 377.398471 -239.415331)
			(xy 377.444321 -239.444797) (xy 377.485512 -239.480488) (xy 377.521203 -239.521679) (xy 377.550669 -239.567529)
			(xy 377.573311 -239.617106) (xy 377.588666 -239.669401) (xy 377.596422 -239.723349) (xy 377.596908 -239.7506)
			(xy 377.597162 -239.7506) (xy 377.596737 -239.776671) (xy 377.589635 -239.828326) (xy 377.575564 -239.878532)
			(xy 377.554786 -239.926354) (xy 377.527687 -239.970901) (xy 377.511564 -239.991392) (xy 377.50242 -240.002568)
			(xy 377.49861 -240.031016) (xy 377.547886 -240.140236) (xy 377.571508 -240.156238) (xy 377.58624 -240.156746)
			(xy 377.612759 -240.158266) (xy 377.665026 -240.167731) (xy 377.715475 -240.184356) (xy 377.763129 -240.20782)
			(xy 377.807066 -240.237669) (xy 377.846438 -240.273325) (xy 377.880481 -240.314098) (xy 377.908539 -240.359201)
			(xy 377.930067 -240.407759) (xy 377.944651 -240.458836) (xy 377.952006 -240.511441) (xy 377.952508 -240.538)
			(xy 377.952022 -240.565251) (xy 377.944266 -240.619199) (xy 377.930818 -240.665) (xy 384.808982 -240.665)
			(xy 384.813053 -240.609378) (xy 384.825179 -240.554941) (xy 384.845102 -240.50285) (xy 384.872398 -240.454215)
			(xy 384.906484 -240.410072) (xy 384.946633 -240.371363) (xy 384.991991 -240.338912) (xy 385.041591 -240.313411)
			(xy 385.094375 -240.295404) (xy 385.149218 -240.285274) (xy 385.204952 -240.283237) (xy 385.260389 -240.289337)
			(xy 385.314346 -240.303443) (xy 385.365675 -240.325255) (xy 385.413281 -240.354309) (xy 385.456149 -240.389984)
			(xy 385.493366 -240.431521) (xy 385.524139 -240.478034) (xy 385.547811 -240.528531) (xy 385.563879 -240.581938)
			(xy 385.571999 -240.637114) (xy 385.572508 -240.665) (xy 386.078982 -240.665) (xy 386.083053 -240.609378)
			(xy 386.095179 -240.554941) (xy 386.115102 -240.50285) (xy 386.142398 -240.454215) (xy 386.176484 -240.410072)
			(xy 386.216633 -240.371363) (xy 386.261991 -240.338912) (xy 386.311591 -240.313411) (xy 386.364375 -240.295404)
			(xy 386.419218 -240.285274) (xy 386.474952 -240.283237) (xy 386.530389 -240.289337) (xy 386.584346 -240.303443)
			(xy 386.635675 -240.325255) (xy 386.683281 -240.354309) (xy 386.726149 -240.389984) (xy 386.763366 -240.431521)
			(xy 386.794139 -240.478034) (xy 386.817811 -240.528531) (xy 386.833879 -240.581938) (xy 386.841999 -240.637114)
			(xy 386.842508 -240.665) (xy 386.841999 -240.692886) (xy 386.833879 -240.748062) (xy 386.817811 -240.801469)
			(xy 386.794139 -240.851966) (xy 386.763366 -240.898479) (xy 386.726149 -240.940016) (xy 386.683281 -240.975691)
			(xy 386.635675 -241.004745) (xy 386.584346 -241.026557) (xy 386.530389 -241.040663) (xy 386.474952 -241.046763)
			(xy 386.419218 -241.044726) (xy 386.364375 -241.034596) (xy 386.311591 -241.016589) (xy 386.261991 -240.991088)
			(xy 386.216633 -240.958637) (xy 386.176484 -240.919928) (xy 386.142398 -240.875785) (xy 386.115102 -240.82715)
			(xy 386.095179 -240.775059) (xy 386.083053 -240.720622) (xy 386.078982 -240.665) (xy 385.572508 -240.665)
			(xy 385.571999 -240.692886) (xy 385.563879 -240.748062) (xy 385.547811 -240.801469) (xy 385.524139 -240.851966)
			(xy 385.493366 -240.898479) (xy 385.456149 -240.940016) (xy 385.413281 -240.975691) (xy 385.365675 -241.004745)
			(xy 385.314346 -241.026557) (xy 385.260389 -241.040663) (xy 385.204952 -241.046763) (xy 385.149218 -241.044726)
			(xy 385.094375 -241.034596) (xy 385.041591 -241.016589) (xy 384.991991 -240.991088) (xy 384.946633 -240.958637)
			(xy 384.906484 -240.919928) (xy 384.872398 -240.875785) (xy 384.845102 -240.82715) (xy 384.825179 -240.775059)
			(xy 384.813053 -240.720622) (xy 384.808982 -240.665) (xy 377.930818 -240.665) (xy 377.928911 -240.671494)
			(xy 377.906269 -240.721071) (xy 377.876803 -240.766921) (xy 377.841112 -240.808112) (xy 377.799921 -240.843803)
			(xy 377.754071 -240.873269) (xy 377.704494 -240.895911) (xy 377.652199 -240.911266) (xy 377.598251 -240.919022)
			(xy 377.543749 -240.919022) (xy 377.489801 -240.911266) (xy 377.437506 -240.895911) (xy 377.387929 -240.873269)
			(xy 377.342079 -240.843803) (xy 377.300888 -240.808112) (xy 377.265197 -240.766921) (xy 377.235731 -240.721071)
			(xy 377.213089 -240.671494) (xy 377.197734 -240.619199) (xy 377.189978 -240.565251) (xy 377.189492 -240.538)
			(xy 377.189238 -240.538) (xy 377.189663 -240.511929) (xy 377.196765 -240.460274) (xy 377.210836 -240.410068)
			(xy 377.231614 -240.362246) (xy 377.258713 -240.317699) (xy 377.274836 -240.297208) (xy 377.28398 -240.286032)
			(xy 377.28779 -240.257584) (xy 377.24461 -240.161826) (xy 377.24043 -240.153383) (xy 377.227061 -240.140127)
			(xy 377.209805 -240.132597) (xy 377.200414 -240.131854) (xy 377.18238 -240.130584) (xy 377.171458 -240.129568)
			(xy 377.16079 -240.128298) (xy 377.139962 -240.134902) (xy 377.075446 -240.19256) (xy 377.067064 -240.199926)
			(xy 377.058428 -240.219484) (xy 377.058428 -241.311176) (xy 379.62027 -241.311176) (xy 379.624341 -241.255554)
			(xy 379.636467 -241.201117) (xy 379.65639 -241.149026) (xy 379.683686 -241.100391) (xy 379.717772 -241.056248)
			(xy 379.757921 -241.017539) (xy 379.803279 -240.985088) (xy 379.852879 -240.959587) (xy 379.905663 -240.94158)
			(xy 379.960506 -240.93145) (xy 380.01624 -240.929413) (xy 380.071677 -240.935513) (xy 380.125634 -240.949619)
			(xy 380.176963 -240.971431) (xy 380.224569 -241.000485) (xy 380.267437 -241.03616) (xy 380.304654 -241.077697)
			(xy 380.335427 -241.12421) (xy 380.359099 -241.174707) (xy 380.375167 -241.228114) (xy 380.383287 -241.28329)
			(xy 380.383796 -241.311176) (xy 380.383287 -241.339062) (xy 380.375167 -241.394238) (xy 380.36531 -241.427)
			(xy 383.030982 -241.427) (xy 383.035053 -241.371378) (xy 383.047179 -241.316941) (xy 383.067102 -241.26485)
			(xy 383.094398 -241.216215) (xy 383.128484 -241.172072) (xy 383.168633 -241.133363) (xy 383.213991 -241.100912)
			(xy 383.263591 -241.075411) (xy 383.316375 -241.057404) (xy 383.371218 -241.047274) (xy 383.426952 -241.045237)
			(xy 383.482389 -241.051337) (xy 383.536346 -241.065443) (xy 383.587675 -241.087255) (xy 383.635281 -241.116309)
			(xy 383.678149 -241.151984) (xy 383.715366 -241.193521) (xy 383.746139 -241.240034) (xy 383.769811 -241.290531)
			(xy 383.785879 -241.343938) (xy 383.793999 -241.399114) (xy 383.794026 -241.400584) (xy 384.162552 -241.400584)
			(xy 384.166623 -241.344962) (xy 384.178749 -241.290525) (xy 384.198672 -241.238434) (xy 384.225968 -241.189799)
			(xy 384.260054 -241.145656) (xy 384.300203 -241.106947) (xy 384.345561 -241.074496) (xy 384.395161 -241.048995)
			(xy 384.447945 -241.030988) (xy 384.502788 -241.020858) (xy 384.558522 -241.018821) (xy 384.613959 -241.024921)
			(xy 384.667916 -241.039027) (xy 384.719245 -241.060839) (xy 384.766851 -241.089893) (xy 384.809719 -241.125568)
			(xy 384.846936 -241.167105) (xy 384.877709 -241.213618) (xy 384.901381 -241.264115) (xy 384.917449 -241.317522)
			(xy 384.925569 -241.372698) (xy 384.926078 -241.400584) (xy 384.925569 -241.42847) (xy 384.917449 -241.483646)
			(xy 384.901381 -241.537053) (xy 384.877709 -241.58755) (xy 384.846936 -241.634063) (xy 384.809719 -241.6756)
			(xy 384.766851 -241.711275) (xy 384.719245 -241.740329) (xy 384.667916 -241.762141) (xy 384.613959 -241.776247)
			(xy 384.558522 -241.782347) (xy 384.502788 -241.78031) (xy 384.447945 -241.77018) (xy 384.395161 -241.752173)
			(xy 384.345561 -241.726672) (xy 384.300203 -241.694221) (xy 384.260054 -241.655512) (xy 384.225968 -241.611369)
			(xy 384.198672 -241.562734) (xy 384.178749 -241.510643) (xy 384.166623 -241.456206) (xy 384.162552 -241.400584)
			(xy 383.794026 -241.400584) (xy 383.794508 -241.427) (xy 383.793999 -241.454886) (xy 383.785879 -241.510062)
			(xy 383.769811 -241.563469) (xy 383.746139 -241.613966) (xy 383.715366 -241.660479) (xy 383.678149 -241.702016)
			(xy 383.635281 -241.737691) (xy 383.587675 -241.766745) (xy 383.536346 -241.788557) (xy 383.482389 -241.802663)
			(xy 383.426952 -241.808763) (xy 383.371218 -241.806726) (xy 383.316375 -241.796596) (xy 383.263591 -241.778589)
			(xy 383.213991 -241.753088) (xy 383.168633 -241.720637) (xy 383.128484 -241.681928) (xy 383.094398 -241.637785)
			(xy 383.067102 -241.58915) (xy 383.047179 -241.537059) (xy 383.035053 -241.482622) (xy 383.030982 -241.427)
			(xy 380.36531 -241.427) (xy 380.359099 -241.447645) (xy 380.335427 -241.498142) (xy 380.304654 -241.544655)
			(xy 380.267437 -241.586192) (xy 380.224569 -241.621867) (xy 380.176963 -241.650921) (xy 380.125634 -241.672733)
			(xy 380.071677 -241.686839) (xy 380.01624 -241.692939) (xy 379.960506 -241.690902) (xy 379.905663 -241.680772)
			(xy 379.852879 -241.662765) (xy 379.803279 -241.637264) (xy 379.757921 -241.604813) (xy 379.717772 -241.566104)
			(xy 379.683686 -241.521961) (xy 379.65639 -241.473326) (xy 379.636467 -241.421235) (xy 379.624341 -241.366798)
			(xy 379.62027 -241.311176) (xy 377.058428 -241.311176) (xy 377.058428 -241.811048) (xy 377.376942 -241.811048)
			(xy 377.381013 -241.755426) (xy 377.393139 -241.700989) (xy 377.413062 -241.648898) (xy 377.440358 -241.600263)
			(xy 377.474444 -241.55612) (xy 377.514593 -241.517411) (xy 377.559951 -241.48496) (xy 377.609551 -241.459459)
			(xy 377.662335 -241.441452) (xy 377.717178 -241.431322) (xy 377.772912 -241.429285) (xy 377.828349 -241.435385)
			(xy 377.882306 -241.449491) (xy 377.933635 -241.471303) (xy 377.981241 -241.500357) (xy 378.024109 -241.536032)
			(xy 378.061326 -241.577569) (xy 378.092099 -241.624082) (xy 378.115771 -241.674579) (xy 378.131839 -241.727986)
			(xy 378.139959 -241.783162) (xy 378.140468 -241.811048) (xy 378.139959 -241.838934) (xy 378.131839 -241.89411)
			(xy 378.115771 -241.947517) (xy 378.092099 -241.998014) (xy 378.061326 -242.044527) (xy 378.024109 -242.086064)
			(xy 377.981241 -242.121739) (xy 377.933635 -242.150793) (xy 377.882306 -242.172605) (xy 377.828349 -242.186711)
			(xy 377.772912 -242.192811) (xy 377.717178 -242.190774) (xy 377.662335 -242.180644) (xy 377.609551 -242.162637)
			(xy 377.559951 -242.137136) (xy 377.514593 -242.104685) (xy 377.474444 -242.065976) (xy 377.440358 -242.021833)
			(xy 377.413062 -241.973198) (xy 377.393139 -241.921107) (xy 377.381013 -241.86667) (xy 377.376942 -241.811048)
			(xy 377.058428 -241.811048) (xy 377.058428 -243.215414) (xy 383.706876 -243.215414) (xy 383.710947 -243.159792)
			(xy 383.723073 -243.105355) (xy 383.742996 -243.053264) (xy 383.770292 -243.004629) (xy 383.804378 -242.960486)
			(xy 383.844527 -242.921777) (xy 383.889885 -242.889326) (xy 383.939485 -242.863825) (xy 383.992269 -242.845818)
			(xy 384.047112 -242.835688) (xy 384.102846 -242.833651) (xy 384.158283 -242.839751) (xy 384.21224 -242.853857)
			(xy 384.263569 -242.875669) (xy 384.311175 -242.904723) (xy 384.354043 -242.940398) (xy 384.39126 -242.981935)
			(xy 384.422033 -243.028448) (xy 384.445705 -243.078945) (xy 384.461773 -243.132352) (xy 384.469893 -243.187528)
			(xy 384.470402 -243.215414) (xy 384.469893 -243.2433) (xy 384.461773 -243.298476) (xy 384.445705 -243.351883)
			(xy 384.422033 -243.40238) (xy 384.39126 -243.448893) (xy 384.354043 -243.49043) (xy 384.311175 -243.526105)
			(xy 384.263569 -243.555159) (xy 384.21224 -243.576971) (xy 384.158283 -243.591077) (xy 384.102846 -243.597177)
			(xy 384.047112 -243.59514) (xy 383.992269 -243.58501) (xy 383.939485 -243.567003) (xy 383.889885 -243.541502)
			(xy 383.844527 -243.509051) (xy 383.804378 -243.470342) (xy 383.770292 -243.426199) (xy 383.742996 -243.377564)
			(xy 383.723073 -243.325473) (xy 383.710947 -243.271036) (xy 383.706876 -243.215414) (xy 377.058428 -243.215414)
			(xy 377.058428 -244.094) (xy 379.875032 -244.094) (xy 379.879103 -244.038378) (xy 379.891229 -243.983941)
			(xy 379.911152 -243.93185) (xy 379.938448 -243.883215) (xy 379.972534 -243.839072) (xy 380.012683 -243.800363)
			(xy 380.058041 -243.767912) (xy 380.107641 -243.742411) (xy 380.160425 -243.724404) (xy 380.215268 -243.714274)
			(xy 380.271002 -243.712237) (xy 380.326439 -243.718337) (xy 380.380396 -243.732443) (xy 380.431725 -243.754255)
			(xy 380.479331 -243.783309) (xy 380.522199 -243.818984) (xy 380.559416 -243.860521) (xy 380.590189 -243.907034)
			(xy 380.613861 -243.957531) (xy 380.629929 -244.010938) (xy 380.638049 -244.066114) (xy 380.638558 -244.094)
			(xy 380.638049 -244.121886) (xy 380.629929 -244.177062) (xy 380.613861 -244.230469) (xy 380.590189 -244.280966)
			(xy 380.559416 -244.327479) (xy 380.522199 -244.369016) (xy 380.479331 -244.404691) (xy 380.431725 -244.433745)
			(xy 380.380396 -244.455557) (xy 380.326439 -244.469663) (xy 380.271002 -244.475763) (xy 380.215268 -244.473726)
			(xy 380.160425 -244.463596) (xy 380.107641 -244.445589) (xy 380.058041 -244.420088) (xy 380.012683 -244.387637)
			(xy 379.972534 -244.348928) (xy 379.938448 -244.304785) (xy 379.911152 -244.25615) (xy 379.891229 -244.204059)
			(xy 379.879103 -244.149622) (xy 379.875032 -244.094) (xy 377.058428 -244.094) (xy 377.058428 -245.354602)
			(xy 377.058864 -245.364) (xy 380.973582 -245.364) (xy 380.977653 -245.308378) (xy 380.989779 -245.253941)
			(xy 381.009702 -245.20185) (xy 381.036998 -245.153215) (xy 381.071084 -245.109072) (xy 381.111233 -245.070363)
			(xy 381.156591 -245.037912) (xy 381.206191 -245.012411) (xy 381.258975 -244.994404) (xy 381.313818 -244.984274)
			(xy 381.369552 -244.982237) (xy 381.424989 -244.988337) (xy 381.478946 -245.002443) (xy 381.530275 -245.024255)
			(xy 381.577881 -245.053309) (xy 381.620749 -245.088984) (xy 381.657966 -245.130521) (xy 381.688739 -245.177034)
			(xy 381.712411 -245.227531) (xy 381.728479 -245.280938) (xy 381.736599 -245.336114) (xy 381.736941 -245.354856)
			(xy 382.113534 -245.354856) (xy 382.117605 -245.299234) (xy 382.129731 -245.244797) (xy 382.149654 -245.192706)
			(xy 382.17695 -245.144071) (xy 382.211036 -245.099928) (xy 382.251185 -245.061219) (xy 382.296543 -245.028768)
			(xy 382.346143 -245.003267) (xy 382.398927 -244.98526) (xy 382.45377 -244.97513) (xy 382.509504 -244.973093)
			(xy 382.564941 -244.979193) (xy 382.618898 -244.993299) (xy 382.670227 -245.015111) (xy 382.717833 -245.044165)
			(xy 382.760701 -245.07984) (xy 382.797918 -245.121377) (xy 382.828691 -245.16789) (xy 382.852363 -245.218387)
			(xy 382.868431 -245.271794) (xy 382.876551 -245.32697) (xy 382.87706 -245.354856) (xy 382.876551 -245.382742)
			(xy 382.868431 -245.437918) (xy 382.852363 -245.491325) (xy 382.828691 -245.541822) (xy 382.797918 -245.588335)
			(xy 382.760701 -245.629872) (xy 382.717833 -245.665547) (xy 382.670227 -245.694601) (xy 382.618898 -245.716413)
			(xy 382.564941 -245.730519) (xy 382.509504 -245.736619) (xy 382.45377 -245.734582) (xy 382.398927 -245.724452)
			(xy 382.346143 -245.706445) (xy 382.296543 -245.680944) (xy 382.251185 -245.648493) (xy 382.211036 -245.609784)
			(xy 382.17695 -245.565641) (xy 382.149654 -245.517006) (xy 382.129731 -245.464915) (xy 382.117605 -245.410478)
			(xy 382.113534 -245.354856) (xy 381.736941 -245.354856) (xy 381.737108 -245.364) (xy 381.736599 -245.391886)
			(xy 381.728479 -245.447062) (xy 381.712411 -245.500469) (xy 381.688739 -245.550966) (xy 381.657966 -245.597479)
			(xy 381.620749 -245.639016) (xy 381.577881 -245.674691) (xy 381.530275 -245.703745) (xy 381.478946 -245.725557)
			(xy 381.424989 -245.739663) (xy 381.369552 -245.745763) (xy 381.313818 -245.743726) (xy 381.258975 -245.733596)
			(xy 381.206191 -245.715589) (xy 381.156591 -245.690088) (xy 381.111233 -245.657637) (xy 381.071084 -245.618928)
			(xy 381.036998 -245.574785) (xy 381.009702 -245.52615) (xy 380.989779 -245.474059) (xy 380.977653 -245.419622)
			(xy 380.973582 -245.364) (xy 377.058864 -245.364) (xy 377.058886 -245.36448) (xy 377.066328 -245.38278)
			(xy 377.072906 -245.390162) (xy 377.07316 -245.390416) (xy 377.74245 -246.059706) (xy 384.173982 -246.059706)
			(xy 384.178053 -246.004084) (xy 384.190179 -245.949647) (xy 384.210102 -245.897556) (xy 384.237398 -245.848921)
			(xy 384.271484 -245.804778) (xy 384.311633 -245.766069) (xy 384.356991 -245.733618) (xy 384.406591 -245.708117)
			(xy 384.459375 -245.69011) (xy 384.514218 -245.67998) (xy 384.569952 -245.677943) (xy 384.625389 -245.684043)
			(xy 384.679346 -245.698149) (xy 384.730675 -245.719961) (xy 384.778281 -245.749015) (xy 384.821149 -245.78469)
			(xy 384.858366 -245.826227) (xy 384.889139 -245.87274) (xy 384.912811 -245.923237) (xy 384.928879 -245.976644)
			(xy 384.936999 -246.03182) (xy 384.937508 -246.059706) (xy 384.936999 -246.087592) (xy 384.928879 -246.142768)
			(xy 384.912811 -246.196175) (xy 384.889139 -246.246672) (xy 384.858366 -246.293185) (xy 384.821149 -246.334722)
			(xy 384.778281 -246.370397) (xy 384.730675 -246.399451) (xy 384.679346 -246.421263) (xy 384.625389 -246.435369)
			(xy 384.569952 -246.441469) (xy 384.514218 -246.439432) (xy 384.459375 -246.429302) (xy 384.406591 -246.411295)
			(xy 384.356991 -246.385794) (xy 384.311633 -246.353343) (xy 384.271484 -246.314634) (xy 384.237398 -246.270491)
			(xy 384.210102 -246.221856) (xy 384.190179 -246.169765) (xy 384.178053 -246.115328) (xy 384.173982 -246.059706)
			(xy 377.74245 -246.059706) (xy 378.308362 -246.625618) (xy 378.32665 -246.633492) (xy 378.33681 -246.633492)
			(xy 378.363711 -246.634222) (xy 378.416912 -246.642315) (xy 378.468448 -246.657804) (xy 378.517296 -246.680381)
			(xy 378.562488 -246.709598) (xy 378.603125 -246.744875) (xy 378.638402 -246.785512) (xy 378.667619 -246.830704)
			(xy 378.690196 -246.879552) (xy 378.705685 -246.931088) (xy 378.713778 -246.984289) (xy 378.714508 -247.01119)
			(xy 378.714508 -247.015) (xy 379.474982 -247.015) (xy 379.479053 -246.959378) (xy 379.491179 -246.904941)
			(xy 379.511102 -246.85285) (xy 379.538398 -246.804215) (xy 379.572484 -246.760072) (xy 379.612633 -246.721363)
			(xy 379.657991 -246.688912) (xy 379.707591 -246.663411) (xy 379.760375 -246.645404) (xy 379.815218 -246.635274)
			(xy 379.870952 -246.633237) (xy 379.926389 -246.639337) (xy 379.980346 -246.653443) (xy 380.031675 -246.675255)
			(xy 380.079281 -246.704309) (xy 380.122149 -246.739984) (xy 380.159366 -246.781521) (xy 380.190139 -246.828034)
			(xy 380.213811 -246.878531) (xy 380.229879 -246.931938) (xy 380.237999 -246.987114) (xy 380.238508 -247.015)
			(xy 380.237999 -247.042886) (xy 380.229879 -247.098062) (xy 380.213811 -247.151469) (xy 380.190139 -247.201966)
			(xy 380.159366 -247.248479) (xy 380.122149 -247.290016) (xy 380.079281 -247.325691) (xy 380.072286 -247.32996)
			(xy 383.346452 -247.32996) (xy 383.346892 -247.303603) (xy 383.35413 -247.25139) (xy 383.368491 -247.20067)
			(xy 383.389701 -247.152413) (xy 383.417355 -247.107536) (xy 383.450927 -247.066896) (xy 383.489776 -247.031267)
			(xy 383.533162 -247.001329) (xy 383.55651 -246.989092) (xy 383.569619 -246.982) (xy 383.591244 -246.961502)
			(xy 383.606034 -246.935635) (xy 383.612732 -246.906602) (xy 383.610767 -246.876871) (xy 383.600308 -246.848971)
			(xy 383.582243 -246.825276) (xy 383.57048 -246.816118) (xy 383.549876 -246.800661) (xy 383.512565 -246.765153)
			(xy 383.480374 -246.724945) (xy 383.453888 -246.68077) (xy 383.43359 -246.633431) (xy 383.41985 -246.583791)
			(xy 383.412916 -246.532753) (xy 383.412492 -246.507) (xy 383.412978 -246.479749) (xy 383.420734 -246.425801)
			(xy 383.436089 -246.373506) (xy 383.458731 -246.323929) (xy 383.488197 -246.278079) (xy 383.523888 -246.236888)
			(xy 383.565079 -246.201197) (xy 383.610929 -246.171731) (xy 383.660506 -246.149089) (xy 383.712801 -246.133734)
			(xy 383.766749 -246.125978) (xy 383.821251 -246.125978) (xy 383.875199 -246.133734) (xy 383.927494 -246.149089)
			(xy 383.977071 -246.171731) (xy 384.022921 -246.201197) (xy 384.064112 -246.236888) (xy 384.099803 -246.278079)
			(xy 384.129269 -246.323929) (xy 384.151911 -246.373506) (xy 384.167266 -246.425801) (xy 384.175022 -246.479749)
			(xy 384.175508 -246.507) (xy 384.175085 -246.533357) (xy 384.16784 -246.58557) (xy 384.153474 -246.636288)
			(xy 384.13226 -246.684544) (xy 384.104604 -246.72942) (xy 384.071031 -246.77006) (xy 384.032183 -246.805689)
			(xy 383.988797 -246.83563) (xy 383.96545 -246.847868) (xy 383.952373 -246.855018) (xy 383.930741 -246.8755)
			(xy 383.915943 -246.901354) (xy 383.909238 -246.93038) (xy 383.911197 -246.960106) (xy 383.921654 -246.988)
			(xy 383.939718 -247.011689) (xy 383.95148 -247.020842) (xy 383.972104 -247.036274) (xy 384.009415 -247.071786)
			(xy 384.041606 -247.111997) (xy 384.06809 -247.156177) (xy 384.088385 -247.203519) (xy 384.102121 -247.253164)
			(xy 384.109048 -247.304205) (xy 384.109468 -247.32996) (xy 384.108982 -247.357211) (xy 384.101226 -247.411159)
			(xy 384.085871 -247.463454) (xy 384.063229 -247.513031) (xy 384.033763 -247.558881) (xy 383.998072 -247.600072)
			(xy 383.956881 -247.635763) (xy 383.911031 -247.665229) (xy 383.861454 -247.687871) (xy 383.809159 -247.703226)
			(xy 383.755211 -247.710982) (xy 383.700709 -247.710982) (xy 383.646761 -247.703226) (xy 383.594466 -247.687871)
			(xy 383.544889 -247.665229) (xy 383.499039 -247.635763) (xy 383.457848 -247.600072) (xy 383.422157 -247.558881)
			(xy 383.392691 -247.513031) (xy 383.370049 -247.463454) (xy 383.354694 -247.411159) (xy 383.346938 -247.357211)
			(xy 383.346452 -247.32996) (xy 380.072286 -247.32996) (xy 380.031675 -247.354745) (xy 379.980346 -247.376557)
			(xy 379.926389 -247.390663) (xy 379.870952 -247.396763) (xy 379.815218 -247.394726) (xy 379.760375 -247.384596)
			(xy 379.707591 -247.366589) (xy 379.657991 -247.341088) (xy 379.612633 -247.308637) (xy 379.572484 -247.269928)
			(xy 379.538398 -247.225785) (xy 379.511102 -247.17715) (xy 379.491179 -247.125059) (xy 379.479053 -247.070622)
			(xy 379.474982 -247.015) (xy 378.714508 -247.015) (xy 378.714508 -247.02135) (xy 378.722382 -247.039638)
			(xy 378.901198 -247.218454) (xy 378.932694 -247.224042) (xy 378.947426 -247.217184) (xy 378.972999 -247.205642)
			(xy 379.026689 -247.189354) (xy 379.082187 -247.181117) (xy 379.11024 -247.180608) (xy 379.137489 -247.181097)
			(xy 379.191431 -247.188858) (xy 379.24372 -247.204217) (xy 379.293291 -247.226861) (xy 379.339136 -247.256328)
			(xy 379.38032 -247.29202) (xy 379.416005 -247.333209) (xy 379.445466 -247.379058) (xy 379.468103 -247.428632)
			(xy 379.483454 -247.480923) (xy 379.491207 -247.534867) (xy 379.491748 -247.562116) (xy 379.49123 -247.590168)
			(xy 379.482979 -247.645661) (xy 379.466701 -247.699352) (xy 379.455172 -247.72493) (xy 379.448314 -247.739662)
			(xy 379.45237 -247.762522) (xy 380.357124 -247.762522) (xy 380.361195 -247.7069) (xy 380.373321 -247.652463)
			(xy 380.393244 -247.600372) (xy 380.42054 -247.551737) (xy 380.454626 -247.507594) (xy 380.494775 -247.468885)
			(xy 380.540133 -247.436434) (xy 380.589733 -247.410933) (xy 380.642517 -247.392926) (xy 380.69736 -247.382796)
			(xy 380.753094 -247.380759) (xy 380.808531 -247.386859) (xy 380.862488 -247.400965) (xy 380.913817 -247.422777)
			(xy 380.961423 -247.451831) (xy 381.004291 -247.487506) (xy 381.041508 -247.529043) (xy 381.072281 -247.575556)
			(xy 381.095953 -247.626053) (xy 381.112021 -247.67946) (xy 381.120141 -247.734636) (xy 381.12065 -247.762522)
			(xy 381.120141 -247.790408) (xy 381.112021 -247.845584) (xy 381.095953 -247.898991) (xy 381.072281 -247.949488)
			(xy 381.041508 -247.996001) (xy 381.004291 -248.037538) (xy 380.961423 -248.073213) (xy 380.913817 -248.102267)
			(xy 380.862488 -248.124079) (xy 380.808531 -248.138185) (xy 380.753094 -248.144285) (xy 380.69736 -248.142248)
			(xy 380.642517 -248.132118) (xy 380.589733 -248.114111) (xy 380.540133 -248.08861) (xy 380.494775 -248.056159)
			(xy 380.454626 -248.01745) (xy 380.42054 -247.973307) (xy 380.393244 -247.924672) (xy 380.373321 -247.872581)
			(xy 380.361195 -247.818144) (xy 380.357124 -247.762522) (xy 379.45237 -247.762522) (xy 379.453902 -247.771158)
			(xy 380.236984 -248.55424) (xy 380.237492 -248.554748) (xy 380.244875 -248.561325) (xy 380.263174 -248.568762)
			(xy 380.273052 -248.569226)
		)
		(stroke
			(width 0)
			(type solid)
		)
		(fill yes)
		(layer "In5.Cu")
		(net "P1V8_SDB_VCORE")
	)
	(gr_poly
		(pts
			(xy 462.447132 -289.97021) (xy 462.4572 -289.969782) (xy 462.475797 -289.96206) (xy 462.4832 -289.955224)
			(xy 462.864962 -289.573462) (xy 462.871806 -289.566063) (xy 462.879533 -289.547465) (xy 462.879948 -289.537394)
			(xy 462.879948 -285.941516) (xy 462.879581 -285.932725) (xy 462.873631 -285.91618) (xy 462.86243 -285.902628)
			(xy 462.855056 -285.897828) (xy 462.834267 -285.885098) (xy 462.795791 -285.855167) (xy 462.778348 -285.838138)
			(xy 462.771236 -285.830772) (xy 462.75244 -285.823152) (xy 462.659984 -285.823152) (xy 462.641188 -285.830772)
			(xy 462.634076 -285.838138) (xy 462.612452 -285.859119) (xy 462.563819 -285.894683) (xy 462.510203 -285.922163)
			(xy 462.452934 -285.940878) (xy 462.393436 -285.950361) (xy 462.363312 -285.950914) (xy 462.334572 -285.950394)
			(xy 462.277744 -285.941773) (xy 462.222851 -285.924725) (xy 462.171137 -285.899635) (xy 462.123772 -285.867071)
			(xy 462.102454 -285.84779) (xy 462.095342 -285.841186) (xy 462.077816 -285.834074) (xy 461.988408 -285.834074)
			(xy 461.970882 -285.841186) (xy 461.96377 -285.84779) (xy 461.942443 -285.86706) (xy 461.89508 -285.899625)
			(xy 461.843369 -285.924716) (xy 461.788478 -285.941766) (xy 461.731651 -285.950388) (xy 461.674173 -285.950388)
			(xy 461.617346 -285.941766) (xy 461.562455 -285.924716) (xy 461.510744 -285.899625) (xy 461.463381 -285.86706)
			(xy 461.442054 -285.84779) (xy 461.434942 -285.841186) (xy 461.417416 -285.834074) (xy 461.328008 -285.834074)
			(xy 461.310482 -285.841186) (xy 461.30337 -285.84779) (xy 461.282043 -285.867061) (xy 461.234681 -285.899626)
			(xy 461.182969 -285.924719) (xy 461.128078 -285.94177) (xy 461.071251 -285.950394) (xy 461.042512 -285.950914)
			(xy 461.015258 -285.950451) (xy 460.961305 -285.942696) (xy 460.909005 -285.927341) (xy 460.859423 -285.904698)
			(xy 460.813567 -285.87523) (xy 460.772372 -285.839536) (xy 460.736677 -285.798342) (xy 460.707207 -285.752488)
			(xy 460.684564 -285.702906) (xy 460.669207 -285.650607) (xy 460.661449 -285.596654) (xy 460.661449 -285.542146)
			(xy 460.669207 -285.488193) (xy 460.684564 -285.435894) (xy 460.707207 -285.386312) (xy 460.736677 -285.340458)
			(xy 460.772372 -285.299264) (xy 460.813567 -285.26357) (xy 460.859423 -285.234102) (xy 460.909005 -285.211459)
			(xy 460.961305 -285.196104) (xy 461.015258 -285.188349) (xy 461.042512 -285.187898) (xy 461.071251 -285.18842)
			(xy 461.128078 -285.197044) (xy 461.182968 -285.214095) (xy 461.234679 -285.239188) (xy 461.28204 -285.271754)
			(xy 461.30337 -285.291022) (xy 461.310482 -285.297626) (xy 461.328008 -285.304738) (xy 461.417416 -285.304738)
			(xy 461.434942 -285.297626) (xy 461.442054 -285.291022) (xy 461.463381 -285.271752) (xy 461.510744 -285.239187)
			(xy 461.562455 -285.214096) (xy 461.617346 -285.197046) (xy 461.674173 -285.188424) (xy 461.731651 -285.188424)
			(xy 461.788478 -285.197046) (xy 461.843369 -285.214096) (xy 461.89508 -285.239187) (xy 461.942443 -285.271752)
			(xy 461.96377 -285.291022) (xy 461.970882 -285.297626) (xy 461.988408 -285.304738) (xy 462.077816 -285.304738)
			(xy 462.095342 -285.297626) (xy 462.102454 -285.291022) (xy 462.123781 -285.271752) (xy 462.171144 -285.239188)
			(xy 462.222856 -285.214099) (xy 462.277746 -285.19705) (xy 462.334573 -285.18843) (xy 462.363312 -285.187898)
			(xy 462.393435 -285.188469) (xy 462.452931 -285.197944) (xy 462.510197 -285.216658) (xy 462.563807 -285.244144)
			(xy 462.612428 -285.279718) (xy 462.634076 -285.300674) (xy 462.641188 -285.30804) (xy 462.659984 -285.31566)
			(xy 462.75244 -285.31566) (xy 462.771236 -285.30804) (xy 462.778348 -285.300674) (xy 462.795791 -285.283645)
			(xy 462.834263 -285.253707) (xy 462.855056 -285.240984) (xy 462.862422 -285.236179) (xy 462.873606 -285.222623)
			(xy 462.879547 -285.206083) (xy 462.879948 -285.197296) (xy 462.879948 -283.477208) (xy 462.864962 -283.452824)
			(xy 462.852008 -283.44622) (xy 462.824832 -283.431826) (xy 462.77506 -283.395711) (xy 462.752948 -283.374338)
			(xy 462.745836 -283.366972) (xy 462.72704 -283.359352) (xy 462.634584 -283.359352) (xy 462.615788 -283.366972)
			(xy 462.608676 -283.374338) (xy 462.587052 -283.395319) (xy 462.538419 -283.430883) (xy 462.484803 -283.458363)
			(xy 462.427534 -283.477078) (xy 462.368036 -283.486561) (xy 462.337912 -283.487114) (xy 462.309172 -283.486594)
			(xy 462.252344 -283.477973) (xy 462.197451 -283.460925) (xy 462.145737 -283.435835) (xy 462.098372 -283.403271)
			(xy 462.077054 -283.38399) (xy 462.069942 -283.377386) (xy 462.052416 -283.370274) (xy 461.963008 -283.370274)
			(xy 461.945482 -283.377386) (xy 461.93837 -283.38399) (xy 461.917043 -283.40326) (xy 461.86968 -283.435825)
			(xy 461.817969 -283.460916) (xy 461.763078 -283.477966) (xy 461.706251 -283.486588) (xy 461.648773 -283.486588)
			(xy 461.591946 -283.477966) (xy 461.537055 -283.460916) (xy 461.485344 -283.435825) (xy 461.437981 -283.40326)
			(xy 461.416654 -283.38399) (xy 461.409542 -283.377386) (xy 461.392016 -283.370274) (xy 461.302608 -283.370274)
			(xy 461.285082 -283.377386) (xy 461.27797 -283.38399) (xy 461.256643 -283.403261) (xy 461.209281 -283.435826)
			(xy 461.157569 -283.460919) (xy 461.102678 -283.47797) (xy 461.045851 -283.486594) (xy 461.017112 -283.487114)
			(xy 460.989858 -283.486651) (xy 460.935905 -283.478896) (xy 460.883605 -283.463541) (xy 460.834023 -283.440898)
			(xy 460.788167 -283.41143) (xy 460.746972 -283.375736) (xy 460.711277 -283.334542) (xy 460.681807 -283.288688)
			(xy 460.659164 -283.239106) (xy 460.643807 -283.186807) (xy 460.636049 -283.132854) (xy 460.636049 -283.078346)
			(xy 460.643807 -283.024393) (xy 460.659164 -282.972094) (xy 460.681807 -282.922512) (xy 460.711277 -282.876658)
			(xy 460.746972 -282.835464) (xy 460.788167 -282.79977) (xy 460.834023 -282.770302) (xy 460.883605 -282.747659)
			(xy 460.935905 -282.732304) (xy 460.989858 -282.724549) (xy 461.017112 -282.724098) (xy 461.045851 -282.72462)
			(xy 461.102678 -282.733244) (xy 461.157568 -282.750295) (xy 461.209279 -282.775388) (xy 461.25664 -282.807954)
			(xy 461.27797 -282.827222) (xy 461.285082 -282.833826) (xy 461.302608 -282.840938) (xy 461.392016 -282.840938)
			(xy 461.409542 -282.833826) (xy 461.416654 -282.827222) (xy 461.437981 -282.807952) (xy 461.485344 -282.775387)
			(xy 461.537055 -282.750296) (xy 461.591946 -282.733246) (xy 461.648773 -282.724624) (xy 461.706251 -282.724624)
			(xy 461.763078 -282.733246) (xy 461.817969 -282.750296) (xy 461.86968 -282.775387) (xy 461.917043 -282.807952)
			(xy 461.93837 -282.827222) (xy 461.945482 -282.833826) (xy 461.963008 -282.840938) (xy 462.052416 -282.840938)
			(xy 462.069942 -282.833826) (xy 462.077054 -282.827222) (xy 462.098381 -282.807952) (xy 462.145744 -282.775388)
			(xy 462.197456 -282.750299) (xy 462.252346 -282.73325) (xy 462.309173 -282.72463) (xy 462.337912 -282.724098)
			(xy 462.368035 -282.724669) (xy 462.427531 -282.734144) (xy 462.484797 -282.752858) (xy 462.538407 -282.780344)
			(xy 462.587028 -282.815918) (xy 462.608676 -282.836874) (xy 462.615788 -282.84424) (xy 462.634584 -282.85186)
			(xy 462.72704 -282.85186) (xy 462.745836 -282.84424) (xy 462.752948 -282.836874) (xy 462.775023 -282.815458)
			(xy 462.8248 -282.779335) (xy 462.852008 -282.764992) (xy 462.864962 -282.758388) (xy 462.879948 -282.734004)
			(xy 462.879948 -279.701244) (xy 462.879513 -279.691179) (xy 462.871779 -279.672595) (xy 462.864962 -279.665176)
			(xy 462.8007 -279.600914) (xy 462.777756 -279.577359) (xy 462.736739 -279.525958) (xy 462.70174 -279.470287)
			(xy 462.673197 -279.411044) (xy 462.651472 -279.348977) (xy 462.636837 -279.284866) (xy 462.629476 -279.21952)
			(xy 462.628996 -279.18664) (xy 462.628996 -278.642318) (xy 462.629477 -278.609441) (xy 462.636874 -278.544105)
			(xy 462.651532 -278.480006) (xy 462.673268 -278.417948) (xy 462.701808 -278.358711) (xy 462.736794 -278.303038)
			(xy 462.777788 -278.251627) (xy 462.8007 -278.228044) (xy 462.864962 -278.163782) (xy 462.87181 -278.156384)
			(xy 462.879544 -278.137786) (xy 462.879948 -278.127714) (xy 462.879948 -274.434808) (xy 462.879525 -274.424738)
			(xy 462.871807 -274.406137) (xy 462.864962 -274.39874) (xy 462.667604 -274.201382) (xy 462.66021 -274.194526)
			(xy 462.641611 -274.186777) (xy 462.631536 -274.186396) (xy 451.192138 -274.186396) (xy 451.182073 -274.186831)
			(xy 451.163484 -274.19456) (xy 451.15607 -274.201382) (xy 449.728844 -275.628608) (xy 454.42378 -275.628608)
			(xy 454.424296 -275.599308) (xy 454.433244 -275.541395) (xy 454.450947 -275.485532) (xy 454.476987 -275.433036)
			(xy 454.510752 -275.385141) (xy 454.530714 -275.363686) (xy 454.537318 -275.356828) (xy 454.544684 -275.339556)
			(xy 454.54697 -275.251672) (xy 454.54062 -275.233892) (xy 454.53427 -275.22678) (xy 454.516712 -275.205871)
			(xy 454.487157 -275.159963) (xy 454.464446 -275.110312) (xy 454.449043 -275.057931) (xy 454.441263 -275.003889)
			(xy 454.440798 -274.97659) (xy 454.441284 -274.949339) (xy 454.44904 -274.895391) (xy 454.464395 -274.843096)
			(xy 454.487037 -274.793519) (xy 454.516503 -274.747669) (xy 454.552194 -274.706478) (xy 454.593385 -274.670787)
			(xy 454.639235 -274.641321) (xy 454.688812 -274.618679) (xy 454.741107 -274.603324) (xy 454.795055 -274.595568)
			(xy 454.849557 -274.595568) (xy 454.903505 -274.603324) (xy 454.9558 -274.618679) (xy 455.005377 -274.641321)
			(xy 455.051227 -274.670787) (xy 455.092418 -274.706478) (xy 455.128109 -274.747669) (xy 455.133539 -274.756118)
			(xy 457.316076 -274.756118) (xy 457.320147 -274.700496) (xy 457.332273 -274.646059) (xy 457.352196 -274.593968)
			(xy 457.379492 -274.545333) (xy 457.413578 -274.50119) (xy 457.453727 -274.462481) (xy 457.499085 -274.43003)
			(xy 457.548685 -274.404529) (xy 457.601469 -274.386522) (xy 457.656312 -274.376392) (xy 457.712046 -274.374355)
			(xy 457.767483 -274.380455) (xy 457.82144 -274.394561) (xy 457.872769 -274.416373) (xy 457.920375 -274.445427)
			(xy 457.963243 -274.481102) (xy 458.00046 -274.522639) (xy 458.031233 -274.569152) (xy 458.054905 -274.619649)
			(xy 458.070973 -274.673056) (xy 458.079093 -274.728232) (xy 458.079602 -274.756118) (xy 458.079093 -274.784004)
			(xy 458.070973 -274.83918) (xy 458.054905 -274.892587) (xy 458.031233 -274.943084) (xy 458.00046 -274.989597)
			(xy 457.963243 -275.031134) (xy 457.920375 -275.066809) (xy 457.872769 -275.095863) (xy 457.82144 -275.117675)
			(xy 457.767483 -275.131781) (xy 457.712046 -275.137881) (xy 457.656312 -275.135844) (xy 457.601469 -275.125714)
			(xy 457.548685 -275.107707) (xy 457.499085 -275.082206) (xy 457.453727 -275.049755) (xy 457.413578 -275.011046)
			(xy 457.379492 -274.966903) (xy 457.352196 -274.918268) (xy 457.332273 -274.866177) (xy 457.320147 -274.81174)
			(xy 457.316076 -274.756118) (xy 455.133539 -274.756118) (xy 455.157575 -274.793519) (xy 455.180217 -274.843096)
			(xy 455.195572 -274.895391) (xy 455.203328 -274.949339) (xy 455.203814 -274.97659) (xy 455.203299 -275.00589)
			(xy 455.19435 -275.063803) (xy 455.176648 -275.119666) (xy 455.150607 -275.172162) (xy 455.116842 -275.220057)
			(xy 455.09688 -275.241512) (xy 455.090276 -275.24837) (xy 455.08291 -275.265642) (xy 455.081278 -275.32838)
			(xy 460.941672 -275.32838) (xy 460.945743 -275.272758) (xy 460.957869 -275.218321) (xy 460.977792 -275.16623)
			(xy 461.005088 -275.117595) (xy 461.039174 -275.073452) (xy 461.079323 -275.034743) (xy 461.124681 -275.002292)
			(xy 461.174281 -274.976791) (xy 461.227065 -274.958784) (xy 461.281908 -274.948654) (xy 461.337642 -274.946617)
			(xy 461.393079 -274.952717) (xy 461.447036 -274.966823) (xy 461.498365 -274.988635) (xy 461.545971 -275.017689)
			(xy 461.588839 -275.053364) (xy 461.626056 -275.094901) (xy 461.656829 -275.141414) (xy 461.680501 -275.191911)
			(xy 461.696569 -275.245318) (xy 461.704689 -275.300494) (xy 461.705198 -275.32838) (xy 461.704689 -275.356266)
			(xy 461.696569 -275.411442) (xy 461.680501 -275.464849) (xy 461.656829 -275.515346) (xy 461.626056 -275.561859)
			(xy 461.588839 -275.603396) (xy 461.545971 -275.639071) (xy 461.498365 -275.668125) (xy 461.447036 -275.689937)
			(xy 461.393079 -275.704043) (xy 461.337642 -275.710143) (xy 461.281908 -275.708106) (xy 461.227065 -275.697976)
			(xy 461.174281 -275.679969) (xy 461.124681 -275.654468) (xy 461.079323 -275.622017) (xy 461.039174 -275.583308)
			(xy 461.005088 -275.539165) (xy 460.977792 -275.49053) (xy 460.957869 -275.438439) (xy 460.945743 -275.384002)
			(xy 460.941672 -275.32838) (xy 455.081278 -275.32838) (xy 455.080624 -275.353526) (xy 455.086974 -275.371306)
			(xy 455.093324 -275.378418) (xy 455.11088 -275.399329) (xy 455.140436 -275.445236) (xy 455.163147 -275.494886)
			(xy 455.17855 -275.547267) (xy 455.186331 -275.601309) (xy 455.186796 -275.628608) (xy 455.18631 -275.655859)
			(xy 455.178554 -275.709807) (xy 455.163199 -275.762102) (xy 455.140557 -275.811679) (xy 455.111091 -275.857529)
			(xy 455.0754 -275.89872) (xy 455.034209 -275.934411) (xy 454.988359 -275.963877) (xy 454.938782 -275.986519)
			(xy 454.886487 -276.001874) (xy 454.832539 -276.00963) (xy 454.778037 -276.00963) (xy 454.724089 -276.001874)
			(xy 454.671794 -275.986519) (xy 454.622217 -275.963877) (xy 454.576367 -275.934411) (xy 454.535176 -275.89872)
			(xy 454.499485 -275.857529) (xy 454.470019 -275.811679) (xy 454.447377 -275.762102) (xy 454.432022 -275.709807)
			(xy 454.424266 -275.655859) (xy 454.42378 -275.628608) (xy 449.728844 -275.628608) (xy 449.257674 -276.099778)
			(xy 449.250832 -276.107177) (xy 449.243114 -276.125776) (xy 449.242688 -276.135846) (xy 449.242688 -277.457154)
			(xy 450.500496 -277.457154) (xy 450.500995 -277.429785) (xy 450.508805 -277.375607) (xy 450.524286 -277.323105)
			(xy 450.547121 -277.273357) (xy 450.576838 -277.227389) (xy 450.594476 -277.206456) (xy 450.600572 -277.199344)
			(xy 450.606922 -277.182326) (xy 450.606922 -277.096982) (xy 450.600572 -277.079964) (xy 450.594476 -277.072852)
			(xy 450.576844 -277.051914) (xy 450.547132 -277.005943) (xy 450.524295 -276.956197) (xy 450.508802 -276.903697)
			(xy 450.500972 -276.849523) (xy 450.500496 -276.822154) (xy 450.500935 -276.794901) (xy 450.508698 -276.740952)
			(xy 450.524059 -276.688656) (xy 450.546706 -276.639078) (xy 450.576177 -276.593228) (xy 450.611874 -276.552038)
			(xy 450.653068 -276.516347) (xy 450.698922 -276.486882) (xy 450.748503 -276.464242) (xy 450.800801 -276.448887)
			(xy 450.854751 -276.441131) (xy 450.882004 -276.440646) (xy 450.910742 -276.441182) (xy 450.967568 -276.449804)
			(xy 451.022458 -276.466852) (xy 451.07417 -276.49194) (xy 451.121534 -276.524501) (xy 451.142862 -276.54377)
			(xy 451.149974 -276.550374) (xy 451.1675 -276.557486) (xy 451.256908 -276.557486) (xy 451.274434 -276.550374)
			(xy 451.281546 -276.54377) (xy 451.302873 -276.5245) (xy 451.350236 -276.491935) (xy 451.401947 -276.466844)
			(xy 451.456838 -276.449794) (xy 451.513665 -276.441172) (xy 451.571143 -276.441172) (xy 451.62797 -276.449794)
			(xy 451.682861 -276.466844) (xy 451.734572 -276.491935) (xy 451.781935 -276.5245) (xy 451.803262 -276.54377)
			(xy 451.810374 -276.550374) (xy 451.8279 -276.557486) (xy 451.917308 -276.557486) (xy 451.934834 -276.550374)
			(xy 451.941946 -276.54377) (xy 451.963273 -276.5245) (xy 452.010636 -276.491935) (xy 452.062347 -276.466844)
			(xy 452.117238 -276.449794) (xy 452.174065 -276.441172) (xy 452.231543 -276.441172) (xy 452.28837 -276.449794)
			(xy 452.343261 -276.466844) (xy 452.394972 -276.491935) (xy 452.442335 -276.5245) (xy 452.463662 -276.54377)
			(xy 452.470774 -276.550374) (xy 452.4883 -276.557486) (xy 452.577708 -276.557486) (xy 452.595234 -276.550374)
			(xy 452.602346 -276.54377) (xy 452.623676 -276.524503) (xy 452.671037 -276.491935) (xy 452.722747 -276.466841)
			(xy 452.777638 -276.44979) (xy 452.834465 -276.441167) (xy 452.863204 -276.440646) (xy 452.890453 -276.441174)
			(xy 452.944397 -276.44893) (xy 452.996688 -276.464283) (xy 453.046262 -276.486921) (xy 453.054885 -276.492462)
			(xy 455.756008 -276.492462) (xy 455.760079 -276.43684) (xy 455.772205 -276.382403) (xy 455.792128 -276.330312)
			(xy 455.819424 -276.281677) (xy 455.85351 -276.237534) (xy 455.893659 -276.198825) (xy 455.939017 -276.166374)
			(xy 455.988617 -276.140873) (xy 456.041401 -276.122866) (xy 456.096244 -276.112736) (xy 456.151978 -276.110699)
			(xy 456.207415 -276.116799) (xy 456.261372 -276.130905) (xy 456.312701 -276.152717) (xy 456.360307 -276.181771)
			(xy 456.403175 -276.217446) (xy 456.440392 -276.258983) (xy 456.471165 -276.305496) (xy 456.494837 -276.355993)
			(xy 456.510905 -276.4094) (xy 456.519025 -276.464576) (xy 456.519534 -276.492462) (xy 456.519025 -276.520348)
			(xy 456.510905 -276.575524) (xy 456.494837 -276.628931) (xy 456.488321 -276.64283) (xy 461.074006 -276.64283)
			(xy 461.078077 -276.587208) (xy 461.090203 -276.532771) (xy 461.110126 -276.48068) (xy 461.137422 -276.432045)
			(xy 461.171508 -276.387902) (xy 461.211657 -276.349193) (xy 461.257015 -276.316742) (xy 461.306615 -276.291241)
			(xy 461.359399 -276.273234) (xy 461.414242 -276.263104) (xy 461.469976 -276.261067) (xy 461.525413 -276.267167)
			(xy 461.57937 -276.281273) (xy 461.630699 -276.303085) (xy 461.678305 -276.332139) (xy 461.721173 -276.367814)
			(xy 461.75839 -276.409351) (xy 461.789163 -276.455864) (xy 461.812835 -276.506361) (xy 461.828903 -276.559768)
			(xy 461.837023 -276.614944) (xy 461.837532 -276.64283) (xy 461.837023 -276.670716) (xy 461.828903 -276.725892)
			(xy 461.812835 -276.779299) (xy 461.789163 -276.829796) (xy 461.75839 -276.876309) (xy 461.721173 -276.917846)
			(xy 461.678305 -276.953521) (xy 461.630699 -276.982575) (xy 461.57937 -277.004387) (xy 461.525413 -277.018493)
			(xy 461.469976 -277.024593) (xy 461.414242 -277.022556) (xy 461.359399 -277.012426) (xy 461.306615 -276.994419)
			(xy 461.257015 -276.968918) (xy 461.211657 -276.936467) (xy 461.171508 -276.897758) (xy 461.137422 -276.853615)
			(xy 461.110126 -276.80498) (xy 461.090203 -276.752889) (xy 461.078077 -276.698452) (xy 461.074006 -276.64283)
			(xy 456.488321 -276.64283) (xy 456.471165 -276.679428) (xy 456.440392 -276.725941) (xy 456.403175 -276.767478)
			(xy 456.360307 -276.803153) (xy 456.312701 -276.832207) (xy 456.261372 -276.854019) (xy 456.207415 -276.868125)
			(xy 456.151978 -276.874225) (xy 456.096244 -276.872188) (xy 456.041401 -276.862058) (xy 455.988617 -276.844051)
			(xy 455.939017 -276.81855) (xy 455.893659 -276.786099) (xy 455.85351 -276.74739) (xy 455.819424 -276.703247)
			(xy 455.792128 -276.654612) (xy 455.772205 -276.602521) (xy 455.760079 -276.548084) (xy 455.756008 -276.492462)
			(xy 453.054885 -276.492462) (xy 453.092111 -276.516384) (xy 453.1333 -276.552071) (xy 453.168991 -276.593256)
			(xy 453.198458 -276.639101) (xy 453.221102 -276.688672) (xy 453.236461 -276.740962) (xy 453.244223 -276.794905)
			(xy 453.244712 -276.822154) (xy 453.244216 -276.849523) (xy 453.236405 -276.903701) (xy 453.220923 -276.956203)
			(xy 453.198088 -277.005951) (xy 453.16837 -277.051919) (xy 453.150732 -277.072852) (xy 453.144636 -277.079964)
			(xy 453.138286 -277.096982) (xy 453.138286 -277.182326) (xy 453.144636 -277.199344) (xy 453.150732 -277.206456)
			(xy 453.168369 -277.22739) (xy 453.19808 -277.273363) (xy 453.220916 -277.32311) (xy 453.224943 -277.336758)
			(xy 458.091284 -277.336758) (xy 458.095355 -277.281136) (xy 458.107481 -277.226699) (xy 458.127404 -277.174608)
			(xy 458.1547 -277.125973) (xy 458.188786 -277.08183) (xy 458.228935 -277.043121) (xy 458.274293 -277.01067)
			(xy 458.323893 -276.985169) (xy 458.376677 -276.967162) (xy 458.43152 -276.957032) (xy 458.487254 -276.954995)
			(xy 458.542691 -276.961095) (xy 458.596648 -276.975201) (xy 458.647977 -276.997013) (xy 458.695583 -277.026067)
			(xy 458.738451 -277.061742) (xy 458.775668 -277.103279) (xy 458.806441 -277.149792) (xy 458.830113 -277.200289)
			(xy 458.846181 -277.253696) (xy 458.854301 -277.308872) (xy 458.854601 -277.325328) (xy 459.280766 -277.325328)
			(xy 459.284837 -277.269706) (xy 459.296963 -277.215269) (xy 459.316886 -277.163178) (xy 459.344182 -277.114543)
			(xy 459.378268 -277.0704) (xy 459.418417 -277.031691) (xy 459.463775 -276.99924) (xy 459.513375 -276.973739)
			(xy 459.566159 -276.955732) (xy 459.621002 -276.945602) (xy 459.676736 -276.943565) (xy 459.732173 -276.949665)
			(xy 459.78613 -276.963771) (xy 459.837459 -276.985583) (xy 459.885065 -277.014637) (xy 459.927933 -277.050312)
			(xy 459.96515 -277.091849) (xy 459.995923 -277.138362) (xy 460.019595 -277.188859) (xy 460.035663 -277.242266)
			(xy 460.043783 -277.297442) (xy 460.044292 -277.325328) (xy 460.043783 -277.353214) (xy 460.035663 -277.40839)
			(xy 460.019595 -277.461797) (xy 459.995923 -277.512294) (xy 459.96515 -277.558807) (xy 459.927933 -277.600344)
			(xy 459.885065 -277.636019) (xy 459.837459 -277.665073) (xy 459.78613 -277.686885) (xy 459.732173 -277.700991)
			(xy 459.676736 -277.707091) (xy 459.621002 -277.705054) (xy 459.566159 -277.694924) (xy 459.513375 -277.676917)
			(xy 459.463775 -277.651416) (xy 459.418417 -277.618965) (xy 459.378268 -277.580256) (xy 459.344182 -277.536113)
			(xy 459.316886 -277.487478) (xy 459.296963 -277.435387) (xy 459.284837 -277.38095) (xy 459.280766 -277.325328)
			(xy 458.854601 -277.325328) (xy 458.85481 -277.336758) (xy 458.854301 -277.364644) (xy 458.846181 -277.41982)
			(xy 458.830113 -277.473227) (xy 458.806441 -277.523724) (xy 458.775668 -277.570237) (xy 458.738451 -277.611774)
			(xy 458.695583 -277.647449) (xy 458.647977 -277.676503) (xy 458.596648 -277.698315) (xy 458.542691 -277.712421)
			(xy 458.487254 -277.718521) (xy 458.43152 -277.716484) (xy 458.376677 -277.706354) (xy 458.323893 -277.688347)
			(xy 458.274293 -277.662846) (xy 458.228935 -277.630395) (xy 458.188786 -277.591686) (xy 458.1547 -277.547543)
			(xy 458.127404 -277.498908) (xy 458.107481 -277.446817) (xy 458.095355 -277.39238) (xy 458.091284 -277.336758)
			(xy 453.224943 -277.336758) (xy 453.236408 -277.37561) (xy 453.244237 -277.429785) (xy 453.244712 -277.457154)
			(xy 453.244202 -277.484406) (xy 453.236451 -277.538355) (xy 453.221101 -277.590651) (xy 453.198464 -277.640231)
			(xy 453.169002 -277.686084) (xy 453.133313 -277.727277) (xy 453.092124 -277.762972) (xy 453.046275 -277.79244)
			(xy 452.996698 -277.815084) (xy 452.944404 -277.830441) (xy 452.890455 -277.838198) (xy 452.863204 -277.838662)
			(xy 452.834466 -277.838119) (xy 452.77764 -277.829499) (xy 452.72275 -277.812452) (xy 452.671038 -277.787365)
			(xy 452.623674 -277.754806) (xy 452.602346 -277.735538) (xy 452.595234 -277.728934) (xy 452.577708 -277.721822)
			(xy 452.4883 -277.721822) (xy 452.470774 -277.728934) (xy 452.463662 -277.735538) (xy 452.442335 -277.754808)
			(xy 452.394972 -277.787373) (xy 452.343261 -277.812464) (xy 452.28837 -277.829514) (xy 452.231543 -277.838136)
			(xy 452.174065 -277.838136) (xy 452.117238 -277.829514) (xy 452.062347 -277.812464) (xy 452.010636 -277.787373)
			(xy 451.963273 -277.754808) (xy 451.941946 -277.735538) (xy 451.934834 -277.728934) (xy 451.917308 -277.721822)
			(xy 451.8279 -277.721822) (xy 451.810374 -277.728934) (xy 451.803262 -277.735538) (xy 451.781935 -277.754808)
			(xy 451.734572 -277.787373) (xy 451.682861 -277.812464) (xy 451.62797 -277.829514) (xy 451.571143 -277.838136)
			(xy 451.513665 -277.838136) (xy 451.456838 -277.829514) (xy 451.401947 -277.812464) (xy 451.350236 -277.787373)
			(xy 451.302873 -277.754808) (xy 451.281546 -277.735538) (xy 451.274434 -277.728934) (xy 451.256908 -277.721822)
			(xy 451.1675 -277.721822) (xy 451.149974 -277.728934) (xy 451.142862 -277.735538) (xy 451.12153 -277.754803)
			(xy 451.07417 -277.787371) (xy 451.022459 -277.812465) (xy 450.96757 -277.829517) (xy 450.910743 -277.838141)
			(xy 450.882004 -277.838662) (xy 450.854749 -277.838241) (xy 450.800794 -277.830483) (xy 450.748493 -277.815125)
			(xy 450.69891 -277.79248) (xy 450.653054 -277.763008) (xy 450.61186 -277.72731) (xy 450.576167 -277.686112)
			(xy 450.5467 -277.640253) (xy 450.52406 -277.590668) (xy 450.508708 -277.538365) (xy 450.500956 -277.484409)
			(xy 450.500496 -277.457154) (xy 449.242688 -277.457154) (xy 449.242688 -278.356822) (xy 456.56703 -278.356822)
			(xy 456.571101 -278.3012) (xy 456.583227 -278.246763) (xy 456.60315 -278.194672) (xy 456.630446 -278.146037)
			(xy 456.664532 -278.101894) (xy 456.704681 -278.063185) (xy 456.750039 -278.030734) (xy 456.799639 -278.005233)
			(xy 456.852423 -277.987226) (xy 456.907266 -277.977096) (xy 456.963 -277.975059) (xy 457.018437 -277.981159)
			(xy 457.072394 -277.995265) (xy 457.123723 -278.017077) (xy 457.171329 -278.046131) (xy 457.214197 -278.081806)
			(xy 457.251414 -278.123343) (xy 457.282187 -278.169856) (xy 457.305859 -278.220353) (xy 457.321927 -278.27376)
			(xy 457.330047 -278.328936) (xy 457.330556 -278.356822) (xy 457.330047 -278.384708) (xy 457.321927 -278.439884)
			(xy 457.305859 -278.493291) (xy 457.301129 -278.50338) (xy 458.091284 -278.50338) (xy 458.095355 -278.447758)
			(xy 458.107481 -278.393321) (xy 458.127404 -278.34123) (xy 458.1547 -278.292595) (xy 458.188786 -278.248452)
			(xy 458.228935 -278.209743) (xy 458.274293 -278.177292) (xy 458.323893 -278.151791) (xy 458.376677 -278.133784)
			(xy 458.43152 -278.123654) (xy 458.487254 -278.121617) (xy 458.542691 -278.127717) (xy 458.596648 -278.141823)
			(xy 458.647977 -278.163635) (xy 458.695583 -278.192689) (xy 458.738451 -278.228364) (xy 458.775668 -278.269901)
			(xy 458.806441 -278.316414) (xy 458.830113 -278.366911) (xy 458.846181 -278.420318) (xy 458.854301 -278.475494)
			(xy 458.854606 -278.492204) (xy 459.269336 -278.492204) (xy 459.273407 -278.436582) (xy 459.285533 -278.382145)
			(xy 459.305456 -278.330054) (xy 459.332752 -278.281419) (xy 459.366838 -278.237276) (xy 459.406987 -278.198567)
			(xy 459.452345 -278.166116) (xy 459.501945 -278.140615) (xy 459.554729 -278.122608) (xy 459.609572 -278.112478)
			(xy 459.665306 -278.110441) (xy 459.720743 -278.116541) (xy 459.7747 -278.130647) (xy 459.826029 -278.152459)
			(xy 459.873635 -278.181513) (xy 459.916503 -278.217188) (xy 459.95372 -278.258725) (xy 459.984493 -278.305238)
			(xy 460.008165 -278.355735) (xy 460.024233 -278.409142) (xy 460.032353 -278.464318) (xy 460.032862 -278.492204)
			(xy 460.032353 -278.52009) (xy 460.024233 -278.575266) (xy 460.008165 -278.628673) (xy 459.986528 -278.67483)
			(xy 461.074516 -278.67483) (xy 461.07505 -278.645914) (xy 461.083775 -278.588743) (xy 461.101029 -278.533544)
			(xy 461.126418 -278.481582) (xy 461.159359 -278.434048) (xy 461.199098 -278.39203) (xy 461.221582 -278.37384)
			(xy 461.230335 -278.366271) (xy 461.24052 -278.345517) (xy 461.24114 -278.333962) (xy 461.24114 -278.253698)
			(xy 461.240592 -278.242127) (xy 461.230384 -278.221355) (xy 461.221582 -278.21382) (xy 461.199104 -278.195622)
			(xy 461.15937 -278.153603) (xy 461.12643 -278.10607) (xy 461.101041 -278.05411) (xy 461.083783 -277.998914)
			(xy 461.075052 -277.941746) (xy 461.074516 -277.91283) (xy 461.075002 -277.885579) (xy 461.082758 -277.831631)
			(xy 461.098113 -277.779336) (xy 461.120755 -277.729759) (xy 461.150221 -277.683909) (xy 461.185912 -277.642718)
			(xy 461.227103 -277.607027) (xy 461.272953 -277.577561) (xy 461.32253 -277.554919) (xy 461.374825 -277.539564)
			(xy 461.428773 -277.531808) (xy 461.483275 -277.531808) (xy 461.537223 -277.539564) (xy 461.589518 -277.554919)
			(xy 461.639095 -277.577561) (xy 461.684945 -277.607027) (xy 461.726136 -277.642718) (xy 461.761827 -277.683909)
			(xy 461.791293 -277.729759) (xy 461.813935 -277.779336) (xy 461.82929 -277.831631) (xy 461.837046 -277.885579)
			(xy 461.837532 -277.91283) (xy 461.836989 -277.941746) (xy 461.828269 -277.998917) (xy 461.811017 -278.054117)
			(xy 461.78563 -278.106079) (xy 461.75269 -278.153614) (xy 461.712951 -278.19563) (xy 461.690466 -278.21382)
			(xy 461.681694 -278.221372) (xy 461.671517 -278.242138) (xy 461.670908 -278.253698) (xy 461.670908 -278.333962)
			(xy 461.671497 -278.345527) (xy 461.681678 -278.366299) (xy 461.690466 -278.37384) (xy 461.712962 -278.392017)
			(xy 461.752698 -278.434039) (xy 461.785636 -278.481576) (xy 461.811023 -278.53354) (xy 461.828276 -278.588741)
			(xy 461.837 -278.645913) (xy 461.837532 -278.67483) (xy 461.837046 -278.702081) (xy 461.82929 -278.756029)
			(xy 461.813935 -278.808324) (xy 461.791293 -278.857901) (xy 461.761827 -278.903751) (xy 461.726136 -278.944942)
			(xy 461.684945 -278.980633) (xy 461.639095 -279.010099) (xy 461.589518 -279.032741) (xy 461.537223 -279.048096)
			(xy 461.483275 -279.055852) (xy 461.428773 -279.055852) (xy 461.374825 -279.048096) (xy 461.32253 -279.032741)
			(xy 461.272953 -279.010099) (xy 461.227103 -278.980633) (xy 461.185912 -278.944942) (xy 461.150221 -278.903751)
			(xy 461.120755 -278.857901) (xy 461.098113 -278.808324) (xy 461.082758 -278.756029) (xy 461.075002 -278.702081)
			(xy 461.074516 -278.67483) (xy 459.986528 -278.67483) (xy 459.984493 -278.67917) (xy 459.95372 -278.725683)
			(xy 459.916503 -278.76722) (xy 459.873635 -278.802895) (xy 459.826029 -278.831949) (xy 459.7747 -278.853761)
			(xy 459.720743 -278.867867) (xy 459.665306 -278.873967) (xy 459.609572 -278.87193) (xy 459.554729 -278.8618)
			(xy 459.501945 -278.843793) (xy 459.452345 -278.818292) (xy 459.406987 -278.785841) (xy 459.366838 -278.747132)
			(xy 459.332752 -278.702989) (xy 459.305456 -278.654354) (xy 459.285533 -278.602263) (xy 459.273407 -278.547826)
			(xy 459.269336 -278.492204) (xy 458.854606 -278.492204) (xy 458.85481 -278.50338) (xy 458.854301 -278.531266)
			(xy 458.846181 -278.586442) (xy 458.830113 -278.639849) (xy 458.806441 -278.690346) (xy 458.775668 -278.736859)
			(xy 458.738451 -278.778396) (xy 458.695583 -278.814071) (xy 458.647977 -278.843125) (xy 458.596648 -278.864937)
			(xy 458.542691 -278.879043) (xy 458.487254 -278.885143) (xy 458.43152 -278.883106) (xy 458.376677 -278.872976)
			(xy 458.323893 -278.854969) (xy 458.274293 -278.829468) (xy 458.228935 -278.797017) (xy 458.188786 -278.758308)
			(xy 458.1547 -278.714165) (xy 458.127404 -278.66553) (xy 458.107481 -278.613439) (xy 458.095355 -278.559002)
			(xy 458.091284 -278.50338) (xy 457.301129 -278.50338) (xy 457.282187 -278.543788) (xy 457.251414 -278.590301)
			(xy 457.214197 -278.631838) (xy 457.171329 -278.667513) (xy 457.123723 -278.696567) (xy 457.072394 -278.718379)
			(xy 457.018437 -278.732485) (xy 456.963 -278.738585) (xy 456.907266 -278.736548) (xy 456.852423 -278.726418)
			(xy 456.799639 -278.708411) (xy 456.750039 -278.68291) (xy 456.704681 -278.650459) (xy 456.664532 -278.61175)
			(xy 456.630446 -278.567607) (xy 456.60315 -278.518972) (xy 456.583227 -278.466881) (xy 456.571101 -278.412444)
			(xy 456.56703 -278.356822) (xy 449.242688 -278.356822) (xy 449.242688 -279.19934) (xy 455.00112 -279.19934)
			(xy 455.005191 -279.143718) (xy 455.017317 -279.089281) (xy 455.03724 -279.03719) (xy 455.064536 -278.988555)
			(xy 455.098622 -278.944412) (xy 455.138771 -278.905703) (xy 455.184129 -278.873252) (xy 455.233729 -278.847751)
			(xy 455.286513 -278.829744) (xy 455.341356 -278.819614) (xy 455.39709 -278.817577) (xy 455.452527 -278.823677)
			(xy 455.506484 -278.837783) (xy 455.557813 -278.859595) (xy 455.605419 -278.888649) (xy 455.648287 -278.924324)
			(xy 455.685504 -278.965861) (xy 455.716277 -279.012374) (xy 455.739949 -279.062871) (xy 455.756017 -279.116278)
			(xy 455.764137 -279.171454) (xy 455.764646 -279.19934) (xy 455.764137 -279.227226) (xy 455.756017 -279.282402)
			(xy 455.739949 -279.335809) (xy 455.716277 -279.386306) (xy 455.685504 -279.432819) (xy 455.648287 -279.474356)
			(xy 455.605419 -279.510031) (xy 455.557813 -279.539085) (xy 455.506484 -279.560897) (xy 455.452527 -279.575003)
			(xy 455.39709 -279.581103) (xy 455.341356 -279.579066) (xy 455.286513 -279.568936) (xy 455.233729 -279.550929)
			(xy 455.184129 -279.525428) (xy 455.138771 -279.492977) (xy 455.098622 -279.454268) (xy 455.064536 -279.410125)
			(xy 455.03724 -279.36149) (xy 455.017317 -279.309399) (xy 455.005191 -279.254962) (xy 455.00112 -279.19934)
			(xy 449.242688 -279.19934) (xy 449.242688 -279.69083) (xy 461.074006 -279.69083) (xy 461.078077 -279.635208)
			(xy 461.090203 -279.580771) (xy 461.110126 -279.52868) (xy 461.137422 -279.480045) (xy 461.171508 -279.435902)
			(xy 461.211657 -279.397193) (xy 461.257015 -279.364742) (xy 461.306615 -279.339241) (xy 461.359399 -279.321234)
			(xy 461.414242 -279.311104) (xy 461.469976 -279.309067) (xy 461.525413 -279.315167) (xy 461.57937 -279.329273)
			(xy 461.630699 -279.351085) (xy 461.678305 -279.380139) (xy 461.721173 -279.415814) (xy 461.75839 -279.457351)
			(xy 461.789163 -279.503864) (xy 461.812835 -279.554361) (xy 461.828903 -279.607768) (xy 461.837023 -279.662944)
			(xy 461.837532 -279.69083) (xy 461.837023 -279.718716) (xy 461.828903 -279.773892) (xy 461.812835 -279.827299)
			(xy 461.789163 -279.877796) (xy 461.75839 -279.924309) (xy 461.721173 -279.965846) (xy 461.678305 -280.001521)
			(xy 461.630699 -280.030575) (xy 461.57937 -280.052387) (xy 461.525413 -280.066493) (xy 461.469976 -280.072593)
			(xy 461.414242 -280.070556) (xy 461.359399 -280.060426) (xy 461.306615 -280.042419) (xy 461.257015 -280.016918)
			(xy 461.211657 -279.984467) (xy 461.171508 -279.945758) (xy 461.137422 -279.901615) (xy 461.110126 -279.85298)
			(xy 461.090203 -279.800889) (xy 461.078077 -279.746452) (xy 461.074006 -279.69083) (xy 449.242688 -279.69083)
			(xy 449.242688 -280.224484) (xy 455.005184 -280.224484) (xy 455.009255 -280.168862) (xy 455.021381 -280.114425)
			(xy 455.041304 -280.062334) (xy 455.0686 -280.013699) (xy 455.102686 -279.969556) (xy 455.142835 -279.930847)
			(xy 455.188193 -279.898396) (xy 455.237793 -279.872895) (xy 455.290577 -279.854888) (xy 455.34542 -279.844758)
			(xy 455.401154 -279.842721) (xy 455.456591 -279.848821) (xy 455.510548 -279.862927) (xy 455.561877 -279.884739)
			(xy 455.609483 -279.913793) (xy 455.652351 -279.949468) (xy 455.689568 -279.991005) (xy 455.720341 -280.037518)
			(xy 455.744013 -280.088015) (xy 455.760081 -280.141422) (xy 455.768201 -280.196598) (xy 455.76871 -280.224484)
			(xy 457.024484 -280.224484) (xy 457.028555 -280.168862) (xy 457.040681 -280.114425) (xy 457.060604 -280.062334)
			(xy 457.0879 -280.013699) (xy 457.121986 -279.969556) (xy 457.162135 -279.930847) (xy 457.207493 -279.898396)
			(xy 457.257093 -279.872895) (xy 457.309877 -279.854888) (xy 457.36472 -279.844758) (xy 457.420454 -279.842721)
			(xy 457.475891 -279.848821) (xy 457.529848 -279.862927) (xy 457.581177 -279.884739) (xy 457.628783 -279.913793)
			(xy 457.671651 -279.949468) (xy 457.708868 -279.991005) (xy 457.739641 -280.037518) (xy 457.763313 -280.088015)
			(xy 457.779381 -280.141422) (xy 457.787501 -280.196598) (xy 457.78801 -280.224484) (xy 457.787501 -280.25237)
			(xy 457.779381 -280.307546) (xy 457.763313 -280.360953) (xy 457.739641 -280.41145) (xy 457.708868 -280.457963)
			(xy 457.671651 -280.4995) (xy 457.628783 -280.535175) (xy 457.581177 -280.564229) (xy 457.529848 -280.586041)
			(xy 457.475891 -280.600147) (xy 457.420454 -280.606247) (xy 457.36472 -280.60421) (xy 457.309877 -280.59408)
			(xy 457.257093 -280.576073) (xy 457.207493 -280.550572) (xy 457.162135 -280.518121) (xy 457.121986 -280.479412)
			(xy 457.0879 -280.435269) (xy 457.060604 -280.386634) (xy 457.040681 -280.334543) (xy 457.028555 -280.280106)
			(xy 457.024484 -280.224484) (xy 455.76871 -280.224484) (xy 455.768201 -280.25237) (xy 455.760081 -280.307546)
			(xy 455.744013 -280.360953) (xy 455.720341 -280.41145) (xy 455.689568 -280.457963) (xy 455.652351 -280.4995)
			(xy 455.609483 -280.535175) (xy 455.561877 -280.564229) (xy 455.510548 -280.586041) (xy 455.456591 -280.600147)
			(xy 455.401154 -280.606247) (xy 455.34542 -280.60421) (xy 455.290577 -280.59408) (xy 455.237793 -280.576073)
			(xy 455.188193 -280.550572) (xy 455.142835 -280.518121) (xy 455.102686 -280.479412) (xy 455.0686 -280.435269)
			(xy 455.041304 -280.386634) (xy 455.021381 -280.334543) (xy 455.009255 -280.280106) (xy 455.005184 -280.224484)
			(xy 449.242688 -280.224484) (xy 449.242688 -280.624026) (xy 459.436722 -280.624026) (xy 459.440793 -280.568404)
			(xy 459.452919 -280.513967) (xy 459.472842 -280.461876) (xy 459.500138 -280.413241) (xy 459.534224 -280.369098)
			(xy 459.574373 -280.330389) (xy 459.619731 -280.297938) (xy 459.669331 -280.272437) (xy 459.722115 -280.25443)
			(xy 459.776958 -280.2443) (xy 459.832692 -280.242263) (xy 459.888129 -280.248363) (xy 459.942086 -280.262469)
			(xy 459.993415 -280.284281) (xy 460.041021 -280.313335) (xy 460.083889 -280.34901) (xy 460.121106 -280.390547)
			(xy 460.151879 -280.43706) (xy 460.175551 -280.487557) (xy 460.191619 -280.540964) (xy 460.199739 -280.59614)
			(xy 460.200248 -280.624026) (xy 460.199739 -280.651912) (xy 460.191619 -280.707088) (xy 460.175551 -280.760495)
			(xy 460.151879 -280.810992) (xy 460.121106 -280.857505) (xy 460.083889 -280.899042) (xy 460.041021 -280.934717)
			(xy 459.993415 -280.963771) (xy 459.942086 -280.985583) (xy 459.888129 -280.999689) (xy 459.832692 -281.005789)
			(xy 459.776958 -281.003752) (xy 459.722115 -280.993622) (xy 459.669331 -280.975615) (xy 459.619731 -280.950114)
			(xy 459.574373 -280.917663) (xy 459.534224 -280.878954) (xy 459.500138 -280.834811) (xy 459.472842 -280.786176)
			(xy 459.452919 -280.734085) (xy 459.440793 -280.679648) (xy 459.436722 -280.624026) (xy 449.242688 -280.624026)
			(xy 449.242688 -284.294326) (xy 449.243306 -284.305751) (xy 449.253185 -284.326354) (xy 449.261738 -284.33395)
			(xy 449.333366 -284.390846) (xy 449.355718 -284.395926) (xy 449.367148 -284.393132) (xy 449.388255 -284.388593)
			(xy 449.431158 -284.383754) (xy 449.452746 -284.38348) (xy 449.481486 -284.383998) (xy 449.538316 -284.392615)
			(xy 449.59321 -284.409661) (xy 449.644925 -284.434752) (xy 449.692289 -284.467319) (xy 449.713604 -284.486604)
			(xy 449.720716 -284.493208) (xy 449.738242 -284.50032) (xy 449.82765 -284.50032) (xy 449.845176 -284.493208)
			(xy 449.852288 -284.486604) (xy 449.873614 -284.467331) (xy 449.920976 -284.434761) (xy 449.972687 -284.409663)
			(xy 450.027578 -284.392606) (xy 450.084406 -284.383976) (xy 450.113146 -284.38348) (xy 450.143271 -284.384045)
			(xy 450.202773 -284.393511) (xy 450.260046 -284.412217) (xy 450.313664 -284.439696) (xy 450.362295 -284.475265)
			(xy 450.38391 -284.496256) (xy 450.391022 -284.503622) (xy 450.409818 -284.511242) (xy 450.502274 -284.511242)
			(xy 450.52107 -284.503622) (xy 450.528182 -284.496256) (xy 450.549807 -284.475279) (xy 450.598442 -284.439723)
			(xy 450.65206 -284.412252) (xy 450.709328 -284.393546) (xy 450.768823 -284.384071) (xy 450.798946 -284.38348)
			(xy 450.826196 -284.383969) (xy 450.88014 -284.391731) (xy 450.932431 -284.407091) (xy 450.982004 -284.429735)
			(xy 451.02785 -284.459204) (xy 451.069036 -284.494896) (xy 451.104724 -284.536087) (xy 451.134187 -284.581936)
			(xy 451.156825 -284.631512) (xy 451.172179 -284.683805) (xy 451.179934 -284.73775) (xy 451.179934 -284.79225)
			(xy 451.172179 -284.846195) (xy 451.156825 -284.898488) (xy 451.134187 -284.948064) (xy 451.104724 -284.993913)
			(xy 451.069036 -285.035104) (xy 451.02785 -285.070796) (xy 450.982004 -285.100265) (xy 450.932431 -285.122909)
			(xy 450.88014 -285.138269) (xy 450.826196 -285.146031) (xy 450.798946 -285.146496) (xy 450.768821 -285.14593)
			(xy 450.709318 -285.136465) (xy 450.652044 -285.117761) (xy 450.598423 -285.090285) (xy 450.549788 -285.05472)
			(xy 450.528182 -285.03372) (xy 450.52107 -285.026354) (xy 450.502274 -285.018734) (xy 450.409818 -285.018734)
			(xy 450.391022 -285.026354) (xy 450.38391 -285.03372) (xy 450.362285 -285.054698) (xy 450.313651 -285.090254)
			(xy 450.260033 -285.117727) (xy 450.202765 -285.136432) (xy 450.143269 -285.145907) (xy 450.113146 -285.146496)
			(xy 450.084406 -285.145978) (xy 450.027574 -285.137362) (xy 449.972679 -285.120317) (xy 449.920962 -285.095229)
			(xy 449.873595 -285.062666) (xy 449.852288 -285.043372) (xy 449.845176 -285.036768) (xy 449.82765 -285.029656)
			(xy 449.738242 -285.029656) (xy 449.720716 -285.036768) (xy 449.713604 -285.043372) (xy 449.692278 -285.062646)
			(xy 449.644917 -285.095217) (xy 449.593206 -285.120315) (xy 449.538315 -285.137372) (xy 449.481486 -285.146001)
			(xy 449.452746 -285.146496) (xy 449.431159 -285.146208) (xy 449.388258 -285.141365) (xy 449.367148 -285.136844)
			(xy 449.355718 -285.13405) (xy 449.333366 -285.13913) (xy 449.261738 -285.196026) (xy 449.253231 -285.20366)
			(xy 449.243352 -285.224238) (xy 449.242688 -285.23565) (xy 449.242688 -286.76473) (xy 449.243346 -286.776513)
			(xy 449.25393 -286.797576) (xy 449.263008 -286.805116) (xy 449.33743 -286.86125) (xy 449.360798 -286.865568)
			(xy 449.372482 -286.862266) (xy 449.398335 -286.855264) (xy 449.451365 -286.847739) (xy 449.478146 -286.84728)
			(xy 449.506886 -286.847798) (xy 449.563716 -286.856415) (xy 449.61861 -286.873461) (xy 449.670325 -286.898552)
			(xy 449.717689 -286.931119) (xy 449.739004 -286.950404) (xy 449.746116 -286.957008) (xy 449.763642 -286.96412)
			(xy 449.85305 -286.96412) (xy 449.870576 -286.957008) (xy 449.877688 -286.950404) (xy 449.899014 -286.931131)
			(xy 449.946376 -286.898561) (xy 449.998087 -286.873463) (xy 450.052978 -286.856406) (xy 450.109806 -286.847776)
			(xy 450.138546 -286.84728) (xy 450.168671 -286.847845) (xy 450.228173 -286.857311) (xy 450.285446 -286.876017)
			(xy 450.339064 -286.903496) (xy 450.387695 -286.939065) (xy 450.40931 -286.960056) (xy 450.416422 -286.967422)
			(xy 450.435218 -286.975042) (xy 450.527674 -286.975042) (xy 450.54647 -286.967422) (xy 450.553582 -286.960056)
			(xy 450.575207 -286.939079) (xy 450.623842 -286.903523) (xy 450.67746 -286.876052) (xy 450.734728 -286.857346)
			(xy 450.794223 -286.847871) (xy 450.824346 -286.84728) (xy 450.851596 -286.847769) (xy 450.90554 -286.855531)
			(xy 450.957831 -286.870891) (xy 451.007404 -286.893535) (xy 451.05325 -286.923004) (xy 451.094436 -286.958696)
			(xy 451.130124 -286.999887) (xy 451.159587 -287.045736) (xy 451.182225 -287.095312) (xy 451.197579 -287.147605)
			(xy 451.205334 -287.20155) (xy 451.205334 -287.25605) (xy 451.197579 -287.309995) (xy 451.182225 -287.362288)
			(xy 451.159587 -287.411864) (xy 451.130124 -287.457713) (xy 451.094436 -287.498904) (xy 451.05325 -287.534596)
			(xy 451.007404 -287.564065) (xy 450.957831 -287.586709) (xy 450.90554 -287.602069) (xy 450.851596 -287.609831)
			(xy 450.824346 -287.610296) (xy 450.794221 -287.60973) (xy 450.734718 -287.600265) (xy 450.677444 -287.581561)
			(xy 450.623823 -287.554085) (xy 450.575188 -287.51852) (xy 450.553582 -287.49752) (xy 450.54647 -287.490154)
			(xy 450.527674 -287.482534) (xy 450.435218 -287.482534) (xy 450.416422 -287.490154) (xy 450.40931 -287.49752)
			(xy 450.387685 -287.518498) (xy 450.339051 -287.554054) (xy 450.285433 -287.581527) (xy 450.228165 -287.600232)
			(xy 450.168669 -287.609707) (xy 450.138546 -287.610296) (xy 450.109806 -287.609778) (xy 450.052974 -287.601162)
			(xy 449.998079 -287.584117) (xy 449.946362 -287.559029) (xy 449.898995 -287.526466) (xy 449.877688 -287.507172)
			(xy 449.870576 -287.500568) (xy 449.85305 -287.493456) (xy 449.763642 -287.493456) (xy 449.746116 -287.500568)
			(xy 449.739004 -287.507172) (xy 449.717678 -287.526446) (xy 449.670317 -287.559017) (xy 449.618606 -287.584115)
			(xy 449.563715 -287.601172) (xy 449.506886 -287.609801) (xy 449.478146 -287.610296) (xy 449.451366 -287.609828)
			(xy 449.398335 -287.602312) (xy 449.372482 -287.59531) (xy 449.360798 -287.592008) (xy 449.33743 -287.596326)
			(xy 449.263008 -287.65246) (xy 449.253945 -287.660014) (xy 449.243356 -287.681066) (xy 449.242688 -287.692846)
			(xy 449.242688 -287.872424) (xy 460.847692 -287.872424) (xy 460.851763 -287.816802) (xy 460.863889 -287.762365)
			(xy 460.883812 -287.710274) (xy 460.911108 -287.661639) (xy 460.945194 -287.617496) (xy 460.985343 -287.578787)
			(xy 461.030701 -287.546336) (xy 461.080301 -287.520835) (xy 461.133085 -287.502828) (xy 461.187928 -287.492698)
			(xy 461.243662 -287.490661) (xy 461.299099 -287.496761) (xy 461.353056 -287.510867) (xy 461.404385 -287.532679)
			(xy 461.451991 -287.561733) (xy 461.494859 -287.597408) (xy 461.532076 -287.638945) (xy 461.562849 -287.685458)
			(xy 461.586521 -287.735955) (xy 461.602589 -287.789362) (xy 461.610709 -287.844538) (xy 461.611218 -287.872424)
			(xy 461.610709 -287.90031) (xy 461.602589 -287.955486) (xy 461.586521 -288.008893) (xy 461.562849 -288.05939)
			(xy 461.532076 -288.105903) (xy 461.494859 -288.14744) (xy 461.451991 -288.183115) (xy 461.404385 -288.212169)
			(xy 461.353056 -288.233981) (xy 461.299099 -288.248087) (xy 461.243662 -288.254187) (xy 461.187928 -288.25215)
			(xy 461.133085 -288.24202) (xy 461.080301 -288.224013) (xy 461.030701 -288.198512) (xy 460.985343 -288.166061)
			(xy 460.945194 -288.127352) (xy 460.911108 -288.083209) (xy 460.883812 -288.034574) (xy 460.863889 -287.982483)
			(xy 460.851763 -287.928046) (xy 460.847692 -287.872424) (xy 449.242688 -287.872424) (xy 449.242688 -288.250884)
			(xy 449.243126 -288.260948) (xy 449.25086 -288.279531) (xy 449.257674 -288.286952) (xy 449.773569 -288.802847)
			(xy 460.345826 -288.802847) (xy 460.345826 -288.748353) (xy 460.353581 -288.694413) (xy 460.368934 -288.642125)
			(xy 460.391572 -288.592555) (xy 460.421033 -288.546711) (xy 460.456719 -288.505526) (xy 460.497903 -288.469839)
			(xy 460.543746 -288.440376) (xy 460.593316 -288.417738) (xy 460.645603 -288.402384) (xy 460.699543 -288.394627)
			(xy 460.72679 -288.39414) (xy 460.75416 -288.394602) (xy 460.80834 -288.402419) (xy 460.860844 -288.417909)
			(xy 460.91059 -288.440752) (xy 460.956557 -288.470478) (xy 460.977488 -288.48812) (xy 460.9846 -288.494216)
			(xy 461.001618 -288.500566) (xy 461.086962 -288.500566) (xy 461.10398 -288.494216) (xy 461.111092 -288.48812)
			(xy 461.132019 -288.470474) (xy 461.177993 -288.440763) (xy 461.227742 -288.417928) (xy 461.280244 -288.402438)
			(xy 461.33442 -288.394613) (xy 461.36179 -288.39414) (xy 461.389047 -288.394506) (xy 461.443006 -288.402263)
			(xy 461.495311 -288.41762) (xy 461.544899 -288.440265) (xy 461.590759 -288.469736) (xy 461.631958 -288.505435)
			(xy 461.667658 -288.546633) (xy 461.69713 -288.592492) (xy 461.719776 -288.642079) (xy 461.735135 -288.694385)
			(xy 461.742893 -288.748343) (xy 461.742893 -288.802857) (xy 461.735135 -288.856815) (xy 461.719776 -288.909121)
			(xy 461.69713 -288.958708) (xy 461.667658 -289.004567) (xy 461.631958 -289.045765) (xy 461.590759 -289.081464)
			(xy 461.544899 -289.110935) (xy 461.495311 -289.13358) (xy 461.443006 -289.148937) (xy 461.389047 -289.156694)
			(xy 461.36179 -289.157156) (xy 461.334419 -289.156707) (xy 461.280239 -289.148886) (xy 461.227735 -289.133394)
			(xy 461.177988 -289.110548) (xy 461.132023 -289.080819) (xy 461.111092 -289.063176) (xy 461.10398 -289.05708)
			(xy 461.086962 -289.05073) (xy 461.001618 -289.05073) (xy 460.9846 -289.05708) (xy 460.977488 -289.063176)
			(xy 460.95653 -289.080784) (xy 460.910565 -289.110501) (xy 460.860824 -289.133343) (xy 460.808329 -289.148842)
			(xy 460.754157 -289.156678) (xy 460.72679 -289.157156) (xy 460.699543 -289.156573) (xy 460.645603 -289.148816)
			(xy 460.593316 -289.133462) (xy 460.543746 -289.110824) (xy 460.497903 -289.081361) (xy 460.456719 -289.045674)
			(xy 460.421033 -289.004489) (xy 460.391572 -288.958645) (xy 460.368934 -288.909075) (xy 460.353581 -288.856787)
			(xy 460.345826 -288.802847) (xy 449.773569 -288.802847) (xy 449.980558 -289.009836) (xy 449.987956 -289.01668)
			(xy 450.006555 -289.024404) (xy 450.016626 -289.024822) (xy 451.841616 -289.024822) (xy 451.851684 -289.025249)
			(xy 451.870283 -289.03297) (xy 451.877684 -289.039808) (xy 452.7931 -289.955224) (xy 452.800495 -289.962078)
			(xy 452.819094 -289.969825) (xy 452.829168 -289.97021)
		)
		(stroke
			(width 0)
			(type solid)
		)
		(fill yes)
		(layer "In5.Cu")
		(net "P1V25_PEX3_R")
	)
	(gr_poly
		(pts
			(xy 18.213832 -291.278564) (xy 18.223899 -291.278134) (xy 18.242492 -291.270408) (xy 18.2499 -291.263578)
			(xy 18.693892 -290.819586) (xy 18.700737 -290.812187) (xy 18.708468 -290.793589) (xy 18.708878 -290.783518)
			(xy 18.708878 -277.616412) (xy 18.708457 -277.606341) (xy 18.700743 -277.587736) (xy 18.693892 -277.580344)
			(xy 16.749776 -275.636228) (xy 16.742933 -275.628829) (xy 16.735213 -275.61023) (xy 16.73479 -275.60016)
			(xy 16.73479 -272.322798) (xy 16.734366 -272.312728) (xy 16.72665 -272.294125) (xy 16.719804 -272.28673)
			(xy 16.043656 -271.610582) (xy 16.036544 -271.603216) (xy 16.017748 -271.595596) (xy 11.580622 -271.595596)
			(xy 11.570558 -271.596033) (xy 11.551974 -271.603767) (xy 11.544554 -271.610582) (xy 10.809224 -272.345912)
			(xy 11.635738 -272.345912) (xy 11.639809 -272.29029) (xy 11.651935 -272.235853) (xy 11.671858 -272.183762)
			(xy 11.699154 -272.135127) (xy 11.73324 -272.090984) (xy 11.773389 -272.052275) (xy 11.818747 -272.019824)
			(xy 11.868347 -271.994323) (xy 11.921131 -271.976316) (xy 11.975974 -271.966186) (xy 12.031708 -271.964149)
			(xy 12.087145 -271.970249) (xy 12.141102 -271.984355) (xy 12.192431 -272.006167) (xy 12.240037 -272.035221)
			(xy 12.282905 -272.070896) (xy 12.320122 -272.112433) (xy 12.350895 -272.158946) (xy 12.374567 -272.209443)
			(xy 12.390635 -272.26285) (xy 12.398755 -272.318026) (xy 12.399264 -272.345912) (xy 12.398755 -272.373798)
			(xy 12.390635 -272.428974) (xy 12.374567 -272.482381) (xy 12.350895 -272.532878) (xy 12.320122 -272.579391)
			(xy 12.282905 -272.620928) (xy 12.240037 -272.656603) (xy 12.192431 -272.685657) (xy 12.141102 -272.707469)
			(xy 12.087145 -272.721575) (xy 12.031708 -272.727675) (xy 11.975974 -272.725638) (xy 11.921131 -272.715508)
			(xy 11.868347 -272.697501) (xy 11.818747 -272.672) (xy 11.773389 -272.639549) (xy 11.73324 -272.60084)
			(xy 11.699154 -272.556697) (xy 11.671858 -272.508062) (xy 11.651935 -272.455971) (xy 11.639809 -272.401534)
			(xy 11.635738 -272.345912) (xy 10.809224 -272.345912) (xy 10.236962 -272.918174) (xy 15.261334 -272.918174)
			(xy 15.265405 -272.862552) (xy 15.277531 -272.808115) (xy 15.297454 -272.756024) (xy 15.32475 -272.707389)
			(xy 15.358836 -272.663246) (xy 15.398985 -272.624537) (xy 15.444343 -272.592086) (xy 15.493943 -272.566585)
			(xy 15.546727 -272.548578) (xy 15.60157 -272.538448) (xy 15.657304 -272.536411) (xy 15.712741 -272.542511)
			(xy 15.766698 -272.556617) (xy 15.818027 -272.578429) (xy 15.865633 -272.607483) (xy 15.908501 -272.643158)
			(xy 15.945718 -272.684695) (xy 15.976491 -272.731208) (xy 16.000163 -272.781705) (xy 16.016231 -272.835112)
			(xy 16.024351 -272.890288) (xy 16.02486 -272.918174) (xy 16.024351 -272.94606) (xy 16.016231 -273.001236)
			(xy 16.000163 -273.054643) (xy 15.976491 -273.10514) (xy 15.945718 -273.151653) (xy 15.908501 -273.19319)
			(xy 15.865633 -273.228865) (xy 15.818027 -273.257919) (xy 15.766698 -273.279731) (xy 15.712741 -273.293837)
			(xy 15.657304 -273.299937) (xy 15.60157 -273.2979) (xy 15.546727 -273.28777) (xy 15.493943 -273.269763)
			(xy 15.444343 -273.244262) (xy 15.398985 -273.211811) (xy 15.358836 -273.173102) (xy 15.32475 -273.128959)
			(xy 15.297454 -273.080324) (xy 15.277531 -273.028233) (xy 15.265405 -272.973796) (xy 15.261334 -272.918174)
			(xy 10.236962 -272.918174) (xy 9.549638 -273.605498) (xy 9.542272 -273.61261) (xy 9.534652 -273.631406)
			(xy 9.534652 -274.082256) (xy 10.07567 -274.082256) (xy 10.079741 -274.026634) (xy 10.091867 -273.972197)
			(xy 10.11179 -273.920106) (xy 10.139086 -273.871471) (xy 10.173172 -273.827328) (xy 10.213321 -273.788619)
			(xy 10.258679 -273.756168) (xy 10.308279 -273.730667) (xy 10.361063 -273.71266) (xy 10.415906 -273.70253)
			(xy 10.47164 -273.700493) (xy 10.527077 -273.706593) (xy 10.581034 -273.720699) (xy 10.632363 -273.742511)
			(xy 10.679969 -273.771565) (xy 10.722837 -273.80724) (xy 10.760054 -273.848777) (xy 10.790827 -273.89529)
			(xy 10.814499 -273.945787) (xy 10.830567 -273.999194) (xy 10.838687 -274.05437) (xy 10.839196 -274.082256)
			(xy 10.838687 -274.110142) (xy 10.830567 -274.165318) (xy 10.814499 -274.218725) (xy 10.807983 -274.232624)
			(xy 15.393668 -274.232624) (xy 15.397739 -274.177002) (xy 15.409865 -274.122565) (xy 15.429788 -274.070474)
			(xy 15.457084 -274.021839) (xy 15.49117 -273.977696) (xy 15.531319 -273.938987) (xy 15.576677 -273.906536)
			(xy 15.626277 -273.881035) (xy 15.679061 -273.863028) (xy 15.733904 -273.852898) (xy 15.789638 -273.850861)
			(xy 15.845075 -273.856961) (xy 15.899032 -273.871067) (xy 15.950361 -273.892879) (xy 15.997967 -273.921933)
			(xy 16.040835 -273.957608) (xy 16.078052 -273.999145) (xy 16.108825 -274.045658) (xy 16.132497 -274.096155)
			(xy 16.148565 -274.149562) (xy 16.156685 -274.204738) (xy 16.157194 -274.232624) (xy 16.156685 -274.26051)
			(xy 16.148565 -274.315686) (xy 16.132497 -274.369093) (xy 16.108825 -274.41959) (xy 16.078052 -274.466103)
			(xy 16.040835 -274.50764) (xy 15.997967 -274.543315) (xy 15.950361 -274.572369) (xy 15.899032 -274.594181)
			(xy 15.845075 -274.608287) (xy 15.789638 -274.614387) (xy 15.733904 -274.61235) (xy 15.679061 -274.60222)
			(xy 15.626277 -274.584213) (xy 15.576677 -274.558712) (xy 15.531319 -274.526261) (xy 15.49117 -274.487552)
			(xy 15.457084 -274.443409) (xy 15.429788 -274.394774) (xy 15.409865 -274.342683) (xy 15.397739 -274.288246)
			(xy 15.393668 -274.232624) (xy 10.807983 -274.232624) (xy 10.790827 -274.269222) (xy 10.760054 -274.315735)
			(xy 10.722837 -274.357272) (xy 10.679969 -274.392947) (xy 10.632363 -274.422001) (xy 10.581034 -274.443813)
			(xy 10.527077 -274.457919) (xy 10.47164 -274.464019) (xy 10.415906 -274.461982) (xy 10.361063 -274.451852)
			(xy 10.308279 -274.433845) (xy 10.258679 -274.408344) (xy 10.213321 -274.375893) (xy 10.173172 -274.337184)
			(xy 10.139086 -274.293041) (xy 10.11179 -274.244406) (xy 10.091867 -274.192315) (xy 10.079741 -274.137878)
			(xy 10.07567 -274.082256) (xy 9.534652 -274.082256) (xy 9.534652 -274.382992) (xy 9.542272 -274.401534)
			(xy 9.54278 -274.402042) (xy 9.54278 -274.926552) (xy 12.410946 -274.926552) (xy 12.415017 -274.87093)
			(xy 12.427143 -274.816493) (xy 12.447066 -274.764402) (xy 12.474362 -274.715767) (xy 12.508448 -274.671624)
			(xy 12.548597 -274.632915) (xy 12.593955 -274.600464) (xy 12.643555 -274.574963) (xy 12.696339 -274.556956)
			(xy 12.751182 -274.546826) (xy 12.806916 -274.544789) (xy 12.862353 -274.550889) (xy 12.91631 -274.564995)
			(xy 12.967639 -274.586807) (xy 13.015245 -274.615861) (xy 13.058113 -274.651536) (xy 13.09533 -274.693073)
			(xy 13.126103 -274.739586) (xy 13.149775 -274.790083) (xy 13.165843 -274.84349) (xy 13.173963 -274.898666)
			(xy 13.174263 -274.915122) (xy 13.600428 -274.915122) (xy 13.604499 -274.8595) (xy 13.616625 -274.805063)
			(xy 13.636548 -274.752972) (xy 13.663844 -274.704337) (xy 13.69793 -274.660194) (xy 13.738079 -274.621485)
			(xy 13.783437 -274.589034) (xy 13.833037 -274.563533) (xy 13.885821 -274.545526) (xy 13.940664 -274.535396)
			(xy 13.996398 -274.533359) (xy 14.051835 -274.539459) (xy 14.105792 -274.553565) (xy 14.157121 -274.575377)
			(xy 14.204727 -274.604431) (xy 14.247595 -274.640106) (xy 14.284812 -274.681643) (xy 14.315585 -274.728156)
			(xy 14.339257 -274.778653) (xy 14.355325 -274.83206) (xy 14.363445 -274.887236) (xy 14.363954 -274.915122)
			(xy 14.363445 -274.943008) (xy 14.355325 -274.998184) (xy 14.339257 -275.051591) (xy 14.315585 -275.102088)
			(xy 14.284812 -275.148601) (xy 14.247595 -275.190138) (xy 14.204727 -275.225813) (xy 14.157121 -275.254867)
			(xy 14.105792 -275.276679) (xy 14.051835 -275.290785) (xy 13.996398 -275.296885) (xy 13.940664 -275.294848)
			(xy 13.885821 -275.284718) (xy 13.833037 -275.266711) (xy 13.783437 -275.24121) (xy 13.738079 -275.208759)
			(xy 13.69793 -275.17005) (xy 13.663844 -275.125907) (xy 13.636548 -275.077272) (xy 13.616625 -275.025181)
			(xy 13.604499 -274.970744) (xy 13.600428 -274.915122) (xy 13.174263 -274.915122) (xy 13.174472 -274.926552)
			(xy 13.173963 -274.954438) (xy 13.165843 -275.009614) (xy 13.149775 -275.063021) (xy 13.126103 -275.113518)
			(xy 13.09533 -275.160031) (xy 13.058113 -275.201568) (xy 13.015245 -275.237243) (xy 12.967639 -275.266297)
			(xy 12.91631 -275.288109) (xy 12.862353 -275.302215) (xy 12.806916 -275.308315) (xy 12.751182 -275.306278)
			(xy 12.696339 -275.296148) (xy 12.643555 -275.278141) (xy 12.593955 -275.25264) (xy 12.548597 -275.220189)
			(xy 12.508448 -275.18148) (xy 12.474362 -275.137337) (xy 12.447066 -275.088702) (xy 12.427143 -275.036611)
			(xy 12.415017 -274.982174) (xy 12.410946 -274.926552) (xy 9.54278 -274.926552) (xy 9.54278 -275.481796)
			(xy 9.542357 -275.491866) (xy 9.534642 -275.51047) (xy 9.527794 -275.517864) (xy 9.251696 -275.793962)
			(xy 9.244299 -275.800812) (xy 9.225701 -275.808551) (xy 9.215628 -275.808948) (xy 2.015744 -275.808948)
			(xy 2.00472 -275.809478) (xy 1.984685 -275.818679) (xy 1.977136 -275.826728) (xy 1.919732 -275.89353)
			(xy 1.913636 -275.914612) (xy 1.91516 -275.925788) (xy 1.917167 -275.939927) (xy 1.917675 -275.946616)
			(xy 10.886692 -275.946616) (xy 10.890763 -275.890994) (xy 10.902889 -275.836557) (xy 10.922812 -275.784466)
			(xy 10.950108 -275.735831) (xy 10.984194 -275.691688) (xy 11.024343 -275.652979) (xy 11.069701 -275.620528)
			(xy 11.119301 -275.595027) (xy 11.172085 -275.57702) (xy 11.226928 -275.56689) (xy 11.282662 -275.564853)
			(xy 11.338099 -275.570953) (xy 11.392056 -275.585059) (xy 11.443385 -275.606871) (xy 11.490991 -275.635925)
			(xy 11.533859 -275.6716) (xy 11.571076 -275.713137) (xy 11.601849 -275.75965) (xy 11.625521 -275.810147)
			(xy 11.641589 -275.863554) (xy 11.649709 -275.91873) (xy 11.650218 -275.946616) (xy 11.649709 -275.974502)
			(xy 11.641589 -276.029678) (xy 11.625521 -276.083085) (xy 11.620791 -276.093174) (xy 12.410946 -276.093174)
			(xy 12.415017 -276.037552) (xy 12.427143 -275.983115) (xy 12.447066 -275.931024) (xy 12.474362 -275.882389)
			(xy 12.508448 -275.838246) (xy 12.548597 -275.799537) (xy 12.593955 -275.767086) (xy 12.643555 -275.741585)
			(xy 12.696339 -275.723578) (xy 12.751182 -275.713448) (xy 12.806916 -275.711411) (xy 12.862353 -275.717511)
			(xy 12.91631 -275.731617) (xy 12.967639 -275.753429) (xy 13.015245 -275.782483) (xy 13.058113 -275.818158)
			(xy 13.09533 -275.859695) (xy 13.126103 -275.906208) (xy 13.149775 -275.956705) (xy 13.165843 -276.010112)
			(xy 13.173963 -276.065288) (xy 13.174268 -276.081998) (xy 13.588998 -276.081998) (xy 13.593069 -276.026376)
			(xy 13.605195 -275.971939) (xy 13.625118 -275.919848) (xy 13.652414 -275.871213) (xy 13.6865 -275.82707)
			(xy 13.726649 -275.788361) (xy 13.772007 -275.75591) (xy 13.821607 -275.730409) (xy 13.874391 -275.712402)
			(xy 13.929234 -275.702272) (xy 13.984968 -275.700235) (xy 14.040405 -275.706335) (xy 14.094362 -275.720441)
			(xy 14.145691 -275.742253) (xy 14.193297 -275.771307) (xy 14.236165 -275.806982) (xy 14.273382 -275.848519)
			(xy 14.304155 -275.895032) (xy 14.327827 -275.945529) (xy 14.343895 -275.998936) (xy 14.352015 -276.054112)
			(xy 14.352524 -276.081998) (xy 14.352015 -276.109884) (xy 14.343895 -276.16506) (xy 14.327827 -276.218467)
			(xy 14.30619 -276.264624) (xy 15.394178 -276.264624) (xy 15.394684 -276.235706) (xy 15.403411 -276.178533)
			(xy 15.42067 -276.123333) (xy 15.446064 -276.07137) (xy 15.479011 -276.023837) (xy 15.518756 -275.981822)
			(xy 15.541244 -275.963634) (xy 15.549993 -275.95606) (xy 15.560182 -275.93531) (xy 15.560802 -275.923756)
			(xy 15.560802 -275.843492) (xy 15.560235 -275.831924) (xy 15.550038 -275.811153) (xy 15.541244 -275.803614)
			(xy 15.518776 -275.785404) (xy 15.479038 -275.743389) (xy 15.446096 -275.695859) (xy 15.420705 -275.643901)
			(xy 15.403445 -275.588706) (xy 15.394714 -275.531539) (xy 15.394178 -275.502624) (xy 15.394664 -275.475373)
			(xy 15.40242 -275.421425) (xy 15.417775 -275.36913) (xy 15.440417 -275.319553) (xy 15.469883 -275.273703)
			(xy 15.505574 -275.232512) (xy 15.546765 -275.196821) (xy 15.592615 -275.167355) (xy 15.642192 -275.144713)
			(xy 15.694487 -275.129358) (xy 15.748435 -275.121602) (xy 15.802937 -275.121602) (xy 15.856885 -275.129358)
			(xy 15.90918 -275.144713) (xy 15.958757 -275.167355) (xy 16.004607 -275.196821) (xy 16.045798 -275.232512)
			(xy 16.081489 -275.273703) (xy 16.110955 -275.319553) (xy 16.133597 -275.36913) (xy 16.148952 -275.421425)
			(xy 16.156708 -275.475373) (xy 16.157194 -275.502624) (xy 16.156624 -275.531539) (xy 16.147906 -275.588708)
			(xy 16.130658 -275.643906) (xy 16.105276 -275.695868) (xy 16.072342 -275.743403) (xy 16.03261 -275.785422)
			(xy 16.010128 -275.803614) (xy 16.001352 -275.811162) (xy 15.991179 -275.831932) (xy 15.99057 -275.843492)
			(xy 15.99057 -275.923756) (xy 15.991142 -275.935324) (xy 16.001333 -275.956097) (xy 16.010128 -275.963634)
			(xy 16.032634 -275.981799) (xy 16.072366 -276.023825) (xy 16.105302 -276.071365) (xy 16.130686 -276.123332)
			(xy 16.147938 -276.178534) (xy 16.156662 -276.235707) (xy 16.157194 -276.264624) (xy 16.156708 -276.291875)
			(xy 16.148952 -276.345823) (xy 16.133597 -276.398118) (xy 16.110955 -276.447695) (xy 16.081489 -276.493545)
			(xy 16.045798 -276.534736) (xy 16.004607 -276.570427) (xy 15.958757 -276.599893) (xy 15.90918 -276.622535)
			(xy 15.856885 -276.63789) (xy 15.802937 -276.645646) (xy 15.748435 -276.645646) (xy 15.694487 -276.63789)
			(xy 15.642192 -276.622535) (xy 15.592615 -276.599893) (xy 15.546765 -276.570427) (xy 15.505574 -276.534736)
			(xy 15.469883 -276.493545) (xy 15.440417 -276.447695) (xy 15.417775 -276.398118) (xy 15.40242 -276.345823)
			(xy 15.394664 -276.291875) (xy 15.394178 -276.264624) (xy 14.30619 -276.264624) (xy 14.304155 -276.268964)
			(xy 14.273382 -276.315477) (xy 14.236165 -276.357014) (xy 14.193297 -276.392689) (xy 14.145691 -276.421743)
			(xy 14.094362 -276.443555) (xy 14.040405 -276.457661) (xy 13.984968 -276.463761) (xy 13.929234 -276.461724)
			(xy 13.874391 -276.451594) (xy 13.821607 -276.433587) (xy 13.772007 -276.408086) (xy 13.726649 -276.375635)
			(xy 13.6865 -276.336926) (xy 13.652414 -276.292783) (xy 13.625118 -276.244148) (xy 13.605195 -276.192057)
			(xy 13.593069 -276.13762) (xy 13.588998 -276.081998) (xy 13.174268 -276.081998) (xy 13.174472 -276.093174)
			(xy 13.173963 -276.12106) (xy 13.165843 -276.176236) (xy 13.149775 -276.229643) (xy 13.126103 -276.28014)
			(xy 13.09533 -276.326653) (xy 13.058113 -276.36819) (xy 13.015245 -276.403865) (xy 12.967639 -276.432919)
			(xy 12.91631 -276.454731) (xy 12.862353 -276.468837) (xy 12.806916 -276.474937) (xy 12.751182 -276.4729)
			(xy 12.696339 -276.46277) (xy 12.643555 -276.444763) (xy 12.593955 -276.419262) (xy 12.548597 -276.386811)
			(xy 12.508448 -276.348102) (xy 12.474362 -276.303959) (xy 12.447066 -276.255324) (xy 12.427143 -276.203233)
			(xy 12.415017 -276.148796) (xy 12.410946 -276.093174) (xy 11.620791 -276.093174) (xy 11.601849 -276.133582)
			(xy 11.571076 -276.180095) (xy 11.533859 -276.221632) (xy 11.490991 -276.257307) (xy 11.443385 -276.286361)
			(xy 11.392056 -276.308173) (xy 11.338099 -276.322279) (xy 11.282662 -276.328379) (xy 11.226928 -276.326342)
			(xy 11.172085 -276.316212) (xy 11.119301 -276.298205) (xy 11.069701 -276.272704) (xy 11.024343 -276.240253)
			(xy 10.984194 -276.201544) (xy 10.950108 -276.157401) (xy 10.922812 -276.108766) (xy 10.902889 -276.056675)
			(xy 10.890763 -276.002238) (xy 10.886692 -275.946616) (xy 1.917675 -275.946616) (xy 1.919328 -275.968404)
			(xy 1.919478 -275.982684) (xy 1.918992 -276.009935) (xy 1.911235 -276.063882) (xy 1.895879 -276.116177)
			(xy 1.873238 -276.165753) (xy 1.843772 -276.211603) (xy 1.80808 -276.252793) (xy 1.76689 -276.288484)
			(xy 1.72104 -276.31795) (xy 1.671463 -276.340591) (xy 1.619168 -276.355946) (xy 1.565221 -276.363702)
			(xy 1.53797 -276.364192) (xy 1.524784 -276.364093) (xy 1.498472 -276.362311) (xy 1.485392 -276.360636)
			(xy 1.474216 -276.359112) (xy 1.453388 -276.365208) (xy 1.387348 -276.422866) (xy 1.379434 -276.430418)
			(xy 1.370347 -276.450294) (xy 1.369822 -276.46122) (xy 1.369822 -276.789134) (xy 9.320782 -276.789134)
			(xy 9.324853 -276.733512) (xy 9.336979 -276.679075) (xy 9.356902 -276.626984) (xy 9.384198 -276.578349)
			(xy 9.418284 -276.534206) (xy 9.458433 -276.495497) (xy 9.503791 -276.463046) (xy 9.553391 -276.437545)
			(xy 9.606175 -276.419538) (xy 9.661018 -276.409408) (xy 9.716752 -276.407371) (xy 9.772189 -276.413471)
			(xy 9.826146 -276.427577) (xy 9.877475 -276.449389) (xy 9.925081 -276.478443) (xy 9.967949 -276.514118)
			(xy 10.005166 -276.555655) (xy 10.035939 -276.602168) (xy 10.059611 -276.652665) (xy 10.075679 -276.706072)
			(xy 10.083799 -276.761248) (xy 10.084308 -276.789134) (xy 10.083799 -276.81702) (xy 10.075679 -276.872196)
			(xy 10.059611 -276.925603) (xy 10.035939 -276.9761) (xy 10.005166 -277.022613) (xy 9.967949 -277.06415)
			(xy 9.925081 -277.099825) (xy 9.877475 -277.128879) (xy 9.826146 -277.150691) (xy 9.772189 -277.164797)
			(xy 9.716752 -277.170897) (xy 9.661018 -277.16886) (xy 9.606175 -277.15873) (xy 9.553391 -277.140723)
			(xy 9.503791 -277.115222) (xy 9.458433 -277.082771) (xy 9.418284 -277.044062) (xy 9.384198 -276.999919)
			(xy 9.356902 -276.951284) (xy 9.336979 -276.899193) (xy 9.324853 -276.844756) (xy 9.320782 -276.789134)
			(xy 1.369822 -276.789134) (xy 1.369822 -276.880574) (xy 1.370342 -276.891503) (xy 1.379425 -276.911383)
			(xy 1.387348 -276.918928) (xy 1.453642 -276.976586) (xy 1.47447 -276.982682) (xy 1.485646 -276.981158)
			(xy 1.49891 -276.979383) (xy 1.525605 -276.977477) (xy 1.538986 -276.977348) (xy 1.566237 -276.977834)
			(xy 1.620185 -276.98559) (xy 1.67248 -277.000945) (xy 1.722057 -277.023587) (xy 1.767907 -277.053053)
			(xy 1.809098 -277.088744) (xy 1.844789 -277.129935) (xy 1.874255 -277.175785) (xy 1.896897 -277.225362)
			(xy 1.912252 -277.277657) (xy 1.912679 -277.280624) (xy 15.393668 -277.280624) (xy 15.397739 -277.225002)
			(xy 15.409865 -277.170565) (xy 15.429788 -277.118474) (xy 15.457084 -277.069839) (xy 15.49117 -277.025696)
			(xy 15.531319 -276.986987) (xy 15.576677 -276.954536) (xy 15.626277 -276.929035) (xy 15.679061 -276.911028)
			(xy 15.733904 -276.900898) (xy 15.789638 -276.898861) (xy 15.845075 -276.904961) (xy 15.899032 -276.919067)
			(xy 15.950361 -276.940879) (xy 15.997967 -276.969933) (xy 16.040835 -277.005608) (xy 16.078052 -277.047145)
			(xy 16.108825 -277.093658) (xy 16.132497 -277.144155) (xy 16.148565 -277.197562) (xy 16.156685 -277.252738)
			(xy 16.157194 -277.280624) (xy 16.156685 -277.30851) (xy 16.148565 -277.363686) (xy 16.132497 -277.417093)
			(xy 16.108825 -277.46759) (xy 16.078052 -277.514103) (xy 16.040835 -277.55564) (xy 15.997967 -277.591315)
			(xy 15.950361 -277.620369) (xy 15.899032 -277.642181) (xy 15.845075 -277.656287) (xy 15.789638 -277.662387)
			(xy 15.733904 -277.66035) (xy 15.679061 -277.65022) (xy 15.626277 -277.632213) (xy 15.576677 -277.606712)
			(xy 15.531319 -277.574261) (xy 15.49117 -277.535552) (xy 15.457084 -277.491409) (xy 15.429788 -277.442774)
			(xy 15.409865 -277.390683) (xy 15.397739 -277.336246) (xy 15.393668 -277.280624) (xy 1.912679 -277.280624)
			(xy 1.920008 -277.331605) (xy 1.920008 -277.386107) (xy 1.912252 -277.440055) (xy 1.896897 -277.49235)
			(xy 1.874255 -277.541927) (xy 1.844789 -277.587777) (xy 1.809098 -277.628968) (xy 1.767907 -277.664659)
			(xy 1.722057 -277.694125) (xy 1.67248 -277.716767) (xy 1.620185 -277.732122) (xy 1.566237 -277.739878)
			(xy 1.538986 -277.740364) (xy 1.525605 -277.740226) (xy 1.498911 -277.738317) (xy 1.485646 -277.736554)
			(xy 1.47447 -277.73503) (xy 1.453642 -277.741126) (xy 1.387348 -277.798784) (xy 1.379437 -277.806338)
			(xy 1.37581 -277.814278) (xy 9.324846 -277.814278) (xy 9.328917 -277.758656) (xy 9.341043 -277.704219)
			(xy 9.360966 -277.652128) (xy 9.388262 -277.603493) (xy 9.422348 -277.55935) (xy 9.462497 -277.520641)
			(xy 9.507855 -277.48819) (xy 9.557455 -277.462689) (xy 9.610239 -277.444682) (xy 9.665082 -277.434552)
			(xy 9.720816 -277.432515) (xy 9.776253 -277.438615) (xy 9.83021 -277.452721) (xy 9.881539 -277.474533)
			(xy 9.929145 -277.503587) (xy 9.972013 -277.539262) (xy 10.00923 -277.580799) (xy 10.040003 -277.627312)
			(xy 10.063675 -277.677809) (xy 10.079743 -277.731216) (xy 10.087863 -277.786392) (xy 10.088372 -277.814278)
			(xy 11.344146 -277.814278) (xy 11.348217 -277.758656) (xy 11.360343 -277.704219) (xy 11.380266 -277.652128)
			(xy 11.407562 -277.603493) (xy 11.441648 -277.55935) (xy 11.481797 -277.520641) (xy 11.527155 -277.48819)
			(xy 11.576755 -277.462689) (xy 11.629539 -277.444682) (xy 11.684382 -277.434552) (xy 11.740116 -277.432515)
			(xy 11.795553 -277.438615) (xy 11.84951 -277.452721) (xy 11.900839 -277.474533) (xy 11.948445 -277.503587)
			(xy 11.991313 -277.539262) (xy 12.02853 -277.580799) (xy 12.059303 -277.627312) (xy 12.082975 -277.677809)
			(xy 12.099043 -277.731216) (xy 12.107163 -277.786392) (xy 12.107672 -277.814278) (xy 12.107163 -277.842164)
			(xy 12.099043 -277.89734) (xy 12.082975 -277.950747) (xy 12.059303 -278.001244) (xy 12.02853 -278.047757)
			(xy 11.991313 -278.089294) (xy 11.948445 -278.124969) (xy 11.900839 -278.154023) (xy 11.84951 -278.175835)
			(xy 11.795553 -278.189941) (xy 11.740116 -278.196041) (xy 11.684382 -278.194004) (xy 11.629539 -278.183874)
			(xy 11.576755 -278.165867) (xy 11.527155 -278.140366) (xy 11.481797 -278.107915) (xy 11.441648 -278.069206)
			(xy 11.407562 -278.025063) (xy 11.380266 -277.976428) (xy 11.360343 -277.924337) (xy 11.348217 -277.8699)
			(xy 11.344146 -277.814278) (xy 10.088372 -277.814278) (xy 10.087863 -277.842164) (xy 10.079743 -277.89734)
			(xy 10.063675 -277.950747) (xy 10.040003 -278.001244) (xy 10.00923 -278.047757) (xy 9.972013 -278.089294)
			(xy 9.929145 -278.124969) (xy 9.881539 -278.154023) (xy 9.83021 -278.175835) (xy 9.776253 -278.189941)
			(xy 9.720816 -278.196041) (xy 9.665082 -278.194004) (xy 9.610239 -278.183874) (xy 9.557455 -278.165867)
			(xy 9.507855 -278.140366) (xy 9.462497 -278.107915) (xy 9.422348 -278.069206) (xy 9.388262 -278.025063)
			(xy 9.360966 -277.976428) (xy 9.341043 -277.924337) (xy 9.328917 -277.8699) (xy 9.324846 -277.814278)
			(xy 1.37581 -277.814278) (xy 1.370357 -277.826213) (xy 1.369822 -277.837138) (xy 1.369822 -280.72265)
			(xy 13.939778 -280.72265) (xy 13.939778 -280.66815) (xy 13.947534 -280.614204) (xy 13.962887 -280.561912)
			(xy 13.985527 -280.512336) (xy 14.01499 -280.466487) (xy 14.050679 -280.425298) (xy 14.091866 -280.389606)
			(xy 14.137713 -280.360139) (xy 14.187287 -280.337496) (xy 14.239579 -280.322139) (xy 14.293524 -280.31438)
			(xy 14.320774 -280.313892) (xy 14.349512 -280.314434) (xy 14.406339 -280.323052) (xy 14.461229 -280.340098)
			(xy 14.512941 -280.365186) (xy 14.560305 -280.397747) (xy 14.581632 -280.417016) (xy 14.588744 -280.42362)
			(xy 14.60627 -280.430732) (xy 14.695678 -280.430732) (xy 14.713204 -280.42362) (xy 14.720316 -280.417016)
			(xy 14.741643 -280.397746) (xy 14.789006 -280.365181) (xy 14.840717 -280.34009) (xy 14.895608 -280.32304)
			(xy 14.952435 -280.314418) (xy 15.009913 -280.314418) (xy 15.06674 -280.32304) (xy 15.121631 -280.34009)
			(xy 15.173342 -280.365181) (xy 15.220705 -280.397746) (xy 15.242032 -280.417016) (xy 15.249144 -280.42362)
			(xy 15.26667 -280.430732) (xy 15.356078 -280.430732) (xy 15.373604 -280.42362) (xy 15.380716 -280.417016)
			(xy 15.40205 -280.397754) (xy 15.449411 -280.365187) (xy 15.501121 -280.340094) (xy 15.55601 -280.323041)
			(xy 15.612836 -280.314415) (xy 15.641574 -280.313892) (xy 15.671697 -280.314467) (xy 15.731194 -280.323945)
			(xy 15.788462 -280.342655) (xy 15.84208 -280.37013) (xy 15.890713 -280.405689) (xy 15.912338 -280.426668)
			(xy 15.91945 -280.434034) (xy 15.938246 -280.441654) (xy 16.030702 -280.441654) (xy 16.049498 -280.434034)
			(xy 16.05661 -280.426668) (xy 16.078219 -280.40567) (xy 16.126851 -280.370101) (xy 16.180471 -280.342623)
			(xy 16.237745 -280.32392) (xy 16.297248 -280.314456) (xy 16.327374 -280.313892) (xy 16.354628 -280.314354)
			(xy 16.408582 -280.322108) (xy 16.460883 -280.337461) (xy 16.510466 -280.360102) (xy 16.556323 -280.38957)
			(xy 16.597518 -280.425263) (xy 16.633215 -280.466457) (xy 16.662685 -280.512311) (xy 16.68533 -280.561893)
			(xy 16.700687 -280.614193) (xy 16.708445 -280.668146) (xy 16.708445 -280.722654) (xy 16.700687 -280.776607)
			(xy 16.68533 -280.828907) (xy 16.662685 -280.878489) (xy 16.633215 -280.924343) (xy 16.597518 -280.965537)
			(xy 16.556323 -281.00123) (xy 16.510466 -281.030698) (xy 16.460883 -281.053339) (xy 16.408582 -281.068692)
			(xy 16.354628 -281.076446) (xy 16.327374 -281.076908) (xy 16.297249 -281.076366) (xy 16.237751 -281.06688)
			(xy 16.180482 -281.048163) (xy 16.126866 -281.02068) (xy 16.078233 -280.985115) (xy 16.05661 -280.964132)
			(xy 16.049498 -280.956766) (xy 16.030702 -280.949146) (xy 15.938246 -280.949146) (xy 15.91945 -280.956766)
			(xy 15.912338 -280.964132) (xy 15.890708 -280.985107) (xy 15.842082 -281.020678) (xy 15.788467 -281.048161)
			(xy 15.731197 -281.06687) (xy 15.671698 -281.07634) (xy 15.641574 -281.076908) (xy 15.612835 -281.076398)
			(xy 15.556007 -281.067772) (xy 15.501116 -281.050718) (xy 15.449404 -281.025624) (xy 15.402042 -280.993056)
			(xy 15.380716 -280.973784) (xy 15.373604 -280.96718) (xy 15.356078 -280.960068) (xy 15.26667 -280.960068)
			(xy 15.249144 -280.96718) (xy 15.242032 -280.973784) (xy 15.220705 -280.993054) (xy 15.173342 -281.025619)
			(xy 15.121631 -281.05071) (xy 15.06674 -281.06776) (xy 15.009913 -281.076382) (xy 14.952435 -281.076382)
			(xy 14.895608 -281.06776) (xy 14.840717 -281.05071) (xy 14.789006 -281.025619) (xy 14.741643 -280.993054)
			(xy 14.720316 -280.973784) (xy 14.713204 -280.96718) (xy 14.695678 -280.960068) (xy 14.60627 -280.960068)
			(xy 14.588744 -280.96718) (xy 14.581632 -280.973784) (xy 14.560319 -280.993071) (xy 14.512953 -281.025634)
			(xy 14.461237 -281.050723) (xy 14.406344 -281.06777) (xy 14.349514 -281.076389) (xy 14.320774 -281.076908)
			(xy 14.293524 -281.07642) (xy 14.239579 -281.068661) (xy 14.187287 -281.053304) (xy 14.137713 -281.030661)
			(xy 14.091866 -281.001194) (xy 14.050679 -280.965502) (xy 14.01499 -280.924313) (xy 13.985527 -280.878464)
			(xy 13.962887 -280.828888) (xy 13.947534 -280.776596) (xy 13.939778 -280.72265) (xy 1.369822 -280.72265)
			(xy 1.369822 -282.382031) (xy 1.86739 -282.382031) (xy 1.86739 -282.327529) (xy 1.875146 -282.273582)
			(xy 1.890501 -282.221287) (xy 1.913142 -282.171711) (xy 1.942608 -282.12586) (xy 1.978299 -282.084671)
			(xy 2.019489 -282.048979) (xy 2.065339 -282.019513) (xy 2.114916 -281.996872) (xy 2.16721 -281.981517)
			(xy 2.221157 -281.97376) (xy 2.248408 -281.973274) (xy 2.277147 -281.9738) (xy 2.333974 -281.982423)
			(xy 2.388864 -281.999473) (xy 2.440576 -282.024564) (xy 2.487939 -282.057128) (xy 2.509266 -282.076398)
			(xy 2.516378 -282.083002) (xy 2.533904 -282.090114) (xy 2.623312 -282.090114) (xy 2.640838 -282.083002)
			(xy 2.64795 -282.076398) (xy 2.669283 -282.057134) (xy 2.716642 -282.024564) (xy 2.768352 -281.99947)
			(xy 2.823242 -281.982418) (xy 2.880069 -281.973795) (xy 2.908808 -281.973274) (xy 2.938932 -281.973833)
			(xy 2.998429 -281.983316) (xy 3.055698 -282.002029) (xy 3.109314 -282.029508) (xy 3.157948 -282.065069)
			(xy 3.179572 -282.08605) (xy 3.186684 -282.093416) (xy 3.20548 -282.101036) (xy 3.297936 -282.101036)
			(xy 3.316732 -282.093416) (xy 3.323844 -282.08605) (xy 3.345479 -282.06508) (xy 3.394104 -282.029509)
			(xy 3.447718 -282.002026) (xy 3.504986 -281.983315) (xy 3.564484 -281.973843) (xy 3.594608 -281.973274)
			(xy 3.621979 -281.973717) (xy 3.67616 -281.981538) (xy 3.728664 -281.997031) (xy 3.778411 -282.019879)
			(xy 3.824376 -282.049609) (xy 3.845306 -282.067254) (xy 3.852418 -282.07335) (xy 3.869436 -282.0797)
			(xy 3.95478 -282.0797) (xy 3.971798 -282.07335) (xy 3.97891 -282.067254) (xy 3.999834 -282.049605)
			(xy 4.045808 -282.019893) (xy 4.095558 -281.997058) (xy 4.148061 -281.981569) (xy 4.202238 -281.973745)
			(xy 4.229608 -281.973274) (xy 4.256861 -281.973733) (xy 4.310813 -281.98149) (xy 4.363111 -281.996846)
			(xy 4.412691 -282.019488) (xy 4.458545 -282.048957) (xy 4.499738 -282.08465) (xy 4.535432 -282.125843)
			(xy 4.564901 -282.171697) (xy 4.587543 -282.221277) (xy 4.6029 -282.273576) (xy 4.610657 -282.327527)
			(xy 4.610657 -282.382033) (xy 4.6029 -282.435984) (xy 4.587543 -282.488283) (xy 4.564901 -282.537863)
			(xy 4.535432 -282.583717) (xy 4.499738 -282.62491) (xy 4.458545 -282.660603) (xy 4.412691 -282.690072)
			(xy 4.363111 -282.712714) (xy 4.310813 -282.72807) (xy 4.256861 -282.735827) (xy 4.229608 -282.73629)
			(xy 4.202238 -282.735822) (xy 4.148059 -282.728005) (xy 4.095556 -282.712516) (xy 4.045809 -282.689675)
			(xy 3.999842 -282.659951) (xy 3.97891 -282.64231) (xy 3.971798 -282.636214) (xy 3.95478 -282.629864)
			(xy 3.869436 -282.629864) (xy 3.852418 -282.636214) (xy 3.845306 -282.64231) (xy 3.824384 -282.659961)
			(xy 3.778408 -282.689671) (xy 3.728658 -282.712504) (xy 3.676155 -282.727993) (xy 3.621978 -282.735818)
			(xy 3.594608 -282.73629) (xy 3.564484 -282.735731) (xy 3.504986 -282.72625) (xy 3.447717 -282.707537)
			(xy 3.394101 -282.680058) (xy 3.345468 -282.644495) (xy 3.323844 -282.623514) (xy 3.316732 -282.616148)
			(xy 3.297936 -282.608528) (xy 3.20548 -282.608528) (xy 3.186684 -282.616148) (xy 3.179572 -282.623514)
			(xy 3.157941 -282.644487) (xy 3.109313 -282.680056) (xy 3.055699 -282.707537) (xy 2.99843 -282.726247)
			(xy 2.938932 -282.73572) (xy 2.908808 -282.73629) (xy 2.880069 -282.735764) (xy 2.823242 -282.727142)
			(xy 2.768351 -282.710093) (xy 2.716639 -282.685002) (xy 2.669277 -282.652437) (xy 2.64795 -282.633166)
			(xy 2.640838 -282.626562) (xy 2.623312 -282.61945) (xy 2.533904 -282.61945) (xy 2.516378 -282.626562)
			(xy 2.509266 -282.633166) (xy 2.487936 -282.652434) (xy 2.440575 -282.685) (xy 2.388864 -282.710093)
			(xy 2.333974 -282.727145) (xy 2.277147 -282.735768) (xy 2.248408 -282.73629) (xy 2.221157 -282.7358)
			(xy 2.16721 -282.728043) (xy 2.114916 -282.712688) (xy 2.065339 -282.690047) (xy 2.019489 -282.660581)
			(xy 1.978299 -282.624889) (xy 1.942608 -282.5837) (xy 1.913142 -282.537849) (xy 1.890501 -282.488273)
			(xy 1.875146 -282.435978) (xy 1.86739 -282.382031) (xy 1.369822 -282.382031) (xy 1.369822 -283.18645)
			(xy 13.965178 -283.18645) (xy 13.965178 -283.13195) (xy 13.972934 -283.078004) (xy 13.988287 -283.025712)
			(xy 14.010927 -282.976136) (xy 14.04039 -282.930287) (xy 14.076079 -282.889098) (xy 14.117266 -282.853406)
			(xy 14.163113 -282.823939) (xy 14.212687 -282.801296) (xy 14.264979 -282.785939) (xy 14.318924 -282.77818)
			(xy 14.346174 -282.777692) (xy 14.374912 -282.778234) (xy 14.431739 -282.786852) (xy 14.486629 -282.803898)
			(xy 14.538341 -282.828986) (xy 14.585705 -282.861547) (xy 14.607032 -282.880816) (xy 14.614144 -282.88742)
			(xy 14.63167 -282.894532) (xy 14.721078 -282.894532) (xy 14.738604 -282.88742) (xy 14.745716 -282.880816)
			(xy 14.767043 -282.861546) (xy 14.814406 -282.828981) (xy 14.866117 -282.80389) (xy 14.921008 -282.78684)
			(xy 14.977835 -282.778218) (xy 15.035313 -282.778218) (xy 15.09214 -282.78684) (xy 15.147031 -282.80389)
			(xy 15.198742 -282.828981) (xy 15.246105 -282.861546) (xy 15.267432 -282.880816) (xy 15.274544 -282.88742)
			(xy 15.29207 -282.894532) (xy 15.381478 -282.894532) (xy 15.399004 -282.88742) (xy 15.406116 -282.880816)
			(xy 15.42745 -282.861554) (xy 15.474811 -282.828987) (xy 15.526521 -282.803894) (xy 15.58141 -282.786841)
			(xy 15.638236 -282.778215) (xy 15.666974 -282.777692) (xy 15.697097 -282.778267) (xy 15.756594 -282.787745)
			(xy 15.813862 -282.806455) (xy 15.86748 -282.83393) (xy 15.916113 -282.869489) (xy 15.937738 -282.890468)
			(xy 15.94485 -282.897834) (xy 15.963646 -282.905454) (xy 16.056102 -282.905454) (xy 16.074898 -282.897834)
			(xy 16.08201 -282.890468) (xy 16.103619 -282.86947) (xy 16.152251 -282.833901) (xy 16.205871 -282.806423)
			(xy 16.263145 -282.78772) (xy 16.322648 -282.778256) (xy 16.352774 -282.777692) (xy 16.380028 -282.778154)
			(xy 16.433982 -282.785908) (xy 16.486283 -282.801261) (xy 16.535866 -282.823902) (xy 16.581723 -282.85337)
			(xy 16.622918 -282.889063) (xy 16.658615 -282.930257) (xy 16.688085 -282.976111) (xy 16.71073 -283.025693)
			(xy 16.726087 -283.077993) (xy 16.733845 -283.131946) (xy 16.733845 -283.186454) (xy 16.726087 -283.240407)
			(xy 16.71073 -283.292707) (xy 16.688085 -283.342289) (xy 16.658615 -283.388143) (xy 16.622918 -283.429337)
			(xy 16.581723 -283.46503) (xy 16.535866 -283.494498) (xy 16.486283 -283.517139) (xy 16.433982 -283.532492)
			(xy 16.380028 -283.540246) (xy 16.352774 -283.540708) (xy 16.322649 -283.540166) (xy 16.263151 -283.53068)
			(xy 16.205882 -283.511963) (xy 16.152266 -283.48448) (xy 16.103633 -283.448915) (xy 16.08201 -283.427932)
			(xy 16.074898 -283.420566) (xy 16.056102 -283.412946) (xy 15.963646 -283.412946) (xy 15.94485 -283.420566)
			(xy 15.937738 -283.427932) (xy 15.916108 -283.448907) (xy 15.867482 -283.484478) (xy 15.813867 -283.511961)
			(xy 15.756597 -283.53067) (xy 15.697098 -283.54014) (xy 15.666974 -283.540708) (xy 15.638235 -283.540198)
			(xy 15.581407 -283.531572) (xy 15.526516 -283.514518) (xy 15.474804 -283.489424) (xy 15.427442 -283.456856)
			(xy 15.406116 -283.437584) (xy 15.399004 -283.43098) (xy 15.381478 -283.423868) (xy 15.29207 -283.423868)
			(xy 15.274544 -283.43098) (xy 15.267432 -283.437584) (xy 15.246105 -283.456854) (xy 15.198742 -283.489419)
			(xy 15.147031 -283.51451) (xy 15.09214 -283.53156) (xy 15.035313 -283.540182) (xy 14.977835 -283.540182)
			(xy 14.921008 -283.53156) (xy 14.866117 -283.51451) (xy 14.814406 -283.489419) (xy 14.767043 -283.456854)
			(xy 14.745716 -283.437584) (xy 14.738604 -283.43098) (xy 14.721078 -283.423868) (xy 14.63167 -283.423868)
			(xy 14.614144 -283.43098) (xy 14.607032 -283.437584) (xy 14.585719 -283.456871) (xy 14.538353 -283.489434)
			(xy 14.486637 -283.514523) (xy 14.431744 -283.53157) (xy 14.374914 -283.540189) (xy 14.346174 -283.540708)
			(xy 14.318924 -283.54022) (xy 14.264979 -283.532461) (xy 14.212687 -283.517104) (xy 14.163113 -283.494461)
			(xy 14.117266 -283.464994) (xy 14.076079 -283.429302) (xy 14.04039 -283.388113) (xy 14.010927 -283.342264)
			(xy 13.988287 -283.292688) (xy 13.972934 -283.240396) (xy 13.965178 -283.18645) (xy 1.369822 -283.18645)
			(xy 1.369822 -284.845831) (xy 1.89279 -284.845831) (xy 1.89279 -284.791329) (xy 1.900546 -284.737382)
			(xy 1.915901 -284.685087) (xy 1.938542 -284.635511) (xy 1.968008 -284.58966) (xy 2.003699 -284.548471)
			(xy 2.044889 -284.512779) (xy 2.090739 -284.483313) (xy 2.140316 -284.460672) (xy 2.19261 -284.445317)
			(xy 2.246557 -284.43756) (xy 2.273808 -284.437074) (xy 2.302547 -284.4376) (xy 2.359374 -284.446223)
			(xy 2.414264 -284.463273) (xy 2.465976 -284.488364) (xy 2.513339 -284.520928) (xy 2.534666 -284.540198)
			(xy 2.541778 -284.546802) (xy 2.559304 -284.553914) (xy 2.648712 -284.553914) (xy 2.666238 -284.546802)
			(xy 2.67335 -284.540198) (xy 2.694683 -284.520934) (xy 2.742042 -284.488364) (xy 2.793752 -284.46327)
			(xy 2.848642 -284.446218) (xy 2.905469 -284.437595) (xy 2.934208 -284.437074) (xy 2.964332 -284.437633)
			(xy 3.023829 -284.447116) (xy 3.081098 -284.465829) (xy 3.134714 -284.493308) (xy 3.183348 -284.528869)
			(xy 3.204972 -284.54985) (xy 3.212084 -284.557216) (xy 3.23088 -284.564836) (xy 3.323336 -284.564836)
			(xy 3.342132 -284.557216) (xy 3.349244 -284.54985) (xy 3.370879 -284.52888) (xy 3.419504 -284.493309)
			(xy 3.473118 -284.465826) (xy 3.530386 -284.447115) (xy 3.589884 -284.437643) (xy 3.620008 -284.437074)
			(xy 3.647379 -284.437517) (xy 3.70156 -284.445338) (xy 3.754064 -284.460831) (xy 3.803811 -284.483679)
			(xy 3.849776 -284.513409) (xy 3.870706 -284.531054) (xy 3.877818 -284.53715) (xy 3.894836 -284.5435)
			(xy 3.98018 -284.5435) (xy 3.997198 -284.53715) (xy 4.00431 -284.531054) (xy 4.025234 -284.513405)
			(xy 4.071208 -284.483693) (xy 4.120958 -284.460858) (xy 4.173461 -284.445369) (xy 4.227638 -284.437545)
			(xy 4.255008 -284.437074) (xy 4.282261 -284.437533) (xy 4.336213 -284.44529) (xy 4.388511 -284.460646)
			(xy 4.438091 -284.483288) (xy 4.483945 -284.512757) (xy 4.525138 -284.54845) (xy 4.560832 -284.589643)
			(xy 4.590301 -284.635497) (xy 4.612943 -284.685077) (xy 4.6283 -284.737376) (xy 4.636057 -284.791327)
			(xy 4.636057 -284.845833) (xy 4.6283 -284.899784) (xy 4.612943 -284.952083) (xy 4.590301 -285.001663)
			(xy 4.560832 -285.047517) (xy 4.525138 -285.08871) (xy 4.483945 -285.124403) (xy 4.438091 -285.153872)
			(xy 4.388511 -285.176514) (xy 4.336213 -285.19187) (xy 4.282261 -285.199627) (xy 4.255008 -285.20009)
			(xy 4.227638 -285.199622) (xy 4.173459 -285.191805) (xy 4.120956 -285.176316) (xy 4.071209 -285.153475)
			(xy 4.025242 -285.123751) (xy 4.00431 -285.10611) (xy 3.997198 -285.100014) (xy 3.98018 -285.093664)
			(xy 3.894836 -285.093664) (xy 3.877818 -285.100014) (xy 3.870706 -285.10611) (xy 3.849784 -285.123761)
			(xy 3.803808 -285.153471) (xy 3.754058 -285.176304) (xy 3.701555 -285.191793) (xy 3.647378 -285.199618)
			(xy 3.620008 -285.20009) (xy 3.589884 -285.199531) (xy 3.530386 -285.19005) (xy 3.473117 -285.171337)
			(xy 3.419501 -285.143858) (xy 3.370868 -285.108295) (xy 3.349244 -285.087314) (xy 3.342132 -285.079948)
			(xy 3.323336 -285.072328) (xy 3.23088 -285.072328) (xy 3.212084 -285.079948) (xy 3.204972 -285.087314)
			(xy 3.183341 -285.108287) (xy 3.134713 -285.143856) (xy 3.081099 -285.171337) (xy 3.02383 -285.190047)
			(xy 2.964332 -285.19952) (xy 2.934208 -285.20009) (xy 2.905469 -285.199564) (xy 2.848642 -285.190942)
			(xy 2.793751 -285.173893) (xy 2.742039 -285.148802) (xy 2.694677 -285.116237) (xy 2.67335 -285.096966)
			(xy 2.666238 -285.090362) (xy 2.648712 -285.08325) (xy 2.559304 -285.08325) (xy 2.541778 -285.090362)
			(xy 2.534666 -285.096966) (xy 2.513336 -285.116234) (xy 2.465975 -285.1488) (xy 2.414264 -285.173893)
			(xy 2.359374 -285.190945) (xy 2.302547 -285.199568) (xy 2.273808 -285.20009) (xy 2.246557 -285.1996)
			(xy 2.19261 -285.191843) (xy 2.140316 -285.176488) (xy 2.090739 -285.153847) (xy 2.044889 -285.124381)
			(xy 2.003699 -285.088689) (xy 1.968008 -285.0475) (xy 1.938542 -285.001649) (xy 1.915901 -284.952073)
			(xy 1.900546 -284.899778) (xy 1.89279 -284.845831) (xy 1.369822 -284.845831) (xy 1.369822 -285.462218)
			(xy 14.151354 -285.462218) (xy 14.155425 -285.406596) (xy 14.167551 -285.352159) (xy 14.187474 -285.300068)
			(xy 14.21477 -285.251433) (xy 14.248856 -285.20729) (xy 14.289005 -285.168581) (xy 14.334363 -285.13613)
			(xy 14.383963 -285.110629) (xy 14.436747 -285.092622) (xy 14.49159 -285.082492) (xy 14.547324 -285.080455)
			(xy 14.602761 -285.086555) (xy 14.656718 -285.100661) (xy 14.708047 -285.122473) (xy 14.755653 -285.151527)
			(xy 14.798521 -285.187202) (xy 14.835738 -285.228739) (xy 14.866511 -285.275252) (xy 14.890183 -285.325749)
			(xy 14.906251 -285.379156) (xy 14.914371 -285.434332) (xy 14.91488 -285.462218) (xy 14.914371 -285.490104)
			(xy 14.906251 -285.54528) (xy 14.890183 -285.598687) (xy 14.866511 -285.649184) (xy 14.835738 -285.695697)
			(xy 14.798521 -285.737234) (xy 14.755653 -285.772909) (xy 14.708047 -285.801963) (xy 14.656718 -285.823775)
			(xy 14.602761 -285.837881) (xy 14.547324 -285.843981) (xy 14.49159 -285.841944) (xy 14.436747 -285.831814)
			(xy 14.383963 -285.813807) (xy 14.334363 -285.788306) (xy 14.289005 -285.755855) (xy 14.248856 -285.717146)
			(xy 14.21477 -285.673003) (xy 14.187474 -285.624368) (xy 14.167551 -285.572277) (xy 14.155425 -285.51784)
			(xy 14.151354 -285.462218) (xy 1.369822 -285.462218) (xy 1.369822 -287.131831) (xy 3.23899 -287.131831)
			(xy 3.23899 -287.077329) (xy 3.246746 -287.023382) (xy 3.262101 -286.971087) (xy 3.284742 -286.921511)
			(xy 3.314208 -286.87566) (xy 3.349899 -286.834471) (xy 3.391089 -286.798779) (xy 3.436939 -286.769313)
			(xy 3.486516 -286.746672) (xy 3.53881 -286.731317) (xy 3.592757 -286.72356) (xy 3.620008 -286.723074)
			(xy 3.647379 -286.723517) (xy 3.70156 -286.731338) (xy 3.754064 -286.746831) (xy 3.803811 -286.769679)
			(xy 3.849776 -286.799409) (xy 3.870706 -286.817054) (xy 3.877818 -286.82315) (xy 3.894836 -286.8295)
			(xy 3.98018 -286.8295) (xy 3.997198 -286.82315) (xy 4.00431 -286.817054) (xy 4.025234 -286.799405)
			(xy 4.071208 -286.769693) (xy 4.120958 -286.746858) (xy 4.173461 -286.731369) (xy 4.227638 -286.723545)
			(xy 4.255008 -286.723074) (xy 4.282261 -286.723533) (xy 4.336213 -286.73129) (xy 4.388511 -286.746646)
			(xy 4.438091 -286.769288) (xy 4.483945 -286.798757) (xy 4.525138 -286.83445) (xy 4.560832 -286.875643)
			(xy 4.590301 -286.921497) (xy 4.612943 -286.971077) (xy 4.6283 -287.023376) (xy 4.636057 -287.077327)
			(xy 4.636057 -287.131833) (xy 4.6283 -287.185784) (xy 4.612943 -287.238083) (xy 4.590301 -287.287663)
			(xy 4.560832 -287.333517) (xy 4.525138 -287.37471) (xy 4.483945 -287.410403) (xy 4.438091 -287.439872)
			(xy 4.388511 -287.462514) (xy 4.336213 -287.47787) (xy 4.282261 -287.485627) (xy 4.255008 -287.48609)
			(xy 4.227638 -287.485622) (xy 4.173459 -287.477805) (xy 4.120956 -287.462316) (xy 4.071209 -287.439475)
			(xy 4.025242 -287.409751) (xy 4.00431 -287.39211) (xy 3.997198 -287.386014) (xy 3.98018 -287.379664)
			(xy 3.894836 -287.379664) (xy 3.877818 -287.386014) (xy 3.870706 -287.39211) (xy 3.849784 -287.409761)
			(xy 3.803808 -287.439471) (xy 3.754058 -287.462304) (xy 3.701555 -287.477793) (xy 3.647378 -287.485618)
			(xy 3.620008 -287.48609) (xy 3.592757 -287.4856) (xy 3.53881 -287.477843) (xy 3.486516 -287.462488)
			(xy 3.436939 -287.439847) (xy 3.391089 -287.410381) (xy 3.349899 -287.374689) (xy 3.314208 -287.3335)
			(xy 3.284742 -287.287649) (xy 3.262101 -287.238073) (xy 3.246746 -287.185778) (xy 3.23899 -287.131831)
			(xy 1.369822 -287.131831) (xy 1.369822 -287.984001) (xy 13.68982 -287.984001) (xy 13.68982 -287.929499)
			(xy 13.697576 -287.875552) (xy 13.712931 -287.823257) (xy 13.735572 -287.773681) (xy 13.765038 -287.72783)
			(xy 13.800729 -287.686641) (xy 13.841919 -287.650949) (xy 13.887769 -287.621483) (xy 13.937346 -287.598842)
			(xy 13.98964 -287.583487) (xy 14.043587 -287.57573) (xy 14.070838 -287.575244) (xy 14.098207 -287.575736)
			(xy 14.152386 -287.583546) (xy 14.204889 -287.599028) (xy 14.254636 -287.621865) (xy 14.300604 -287.651585)
			(xy 14.321536 -287.669224) (xy 14.328648 -287.67532) (xy 14.345666 -287.68167) (xy 14.43101 -287.68167)
			(xy 14.448028 -287.67532) (xy 14.45514 -287.669224) (xy 14.476087 -287.651603) (xy 14.522055 -287.621888)
			(xy 14.571799 -287.599048) (xy 14.624296 -287.583553) (xy 14.67847 -287.57572) (xy 14.705838 -287.575244)
			(xy 14.733091 -287.575703) (xy 14.787043 -287.58346) (xy 14.839341 -287.598816) (xy 14.888921 -287.621458)
			(xy 14.934775 -287.650927) (xy 14.975968 -287.68662) (xy 15.011662 -287.727813) (xy 15.041131 -287.773667)
			(xy 15.063773 -287.823247) (xy 15.07913 -287.875546) (xy 15.086887 -287.929497) (xy 15.086887 -287.984003)
			(xy 15.07913 -288.037954) (xy 15.063773 -288.090253) (xy 15.041131 -288.139833) (xy 15.011662 -288.185687)
			(xy 14.975968 -288.22688) (xy 14.934775 -288.262573) (xy 14.888921 -288.292042) (xy 14.839341 -288.314684)
			(xy 14.787043 -288.33004) (xy 14.733091 -288.337797) (xy 14.705838 -288.33826) (xy 14.678468 -288.337781)
			(xy 14.624289 -288.329968) (xy 14.571786 -288.314482) (xy 14.522039 -288.291643) (xy 14.476072 -288.261921)
			(xy 14.45514 -288.24428) (xy 14.448028 -288.238184) (xy 14.43101 -288.231834) (xy 14.345666 -288.231834)
			(xy 14.328648 -288.238184) (xy 14.321536 -288.24428) (xy 14.300599 -288.261913) (xy 14.254628 -288.291626)
			(xy 14.204881 -288.314464) (xy 14.152382 -288.329956) (xy 14.098207 -288.337785) (xy 14.070838 -288.33826)
			(xy 14.043587 -288.33777) (xy 13.98964 -288.330013) (xy 13.937346 -288.314658) (xy 13.887769 -288.292017)
			(xy 13.841919 -288.262551) (xy 13.800729 -288.226859) (xy 13.765038 -288.18567) (xy 13.735572 -288.139819)
			(xy 13.712931 -288.090243) (xy 13.697576 -288.037948) (xy 13.68982 -287.984001) (xy 1.369822 -287.984001)
			(xy 1.369822 -289.258323) (xy 3.252675 -289.258323) (xy 3.252675 -289.203817) (xy 3.260432 -289.149866)
			(xy 3.275789 -289.097568) (xy 3.298431 -289.047987) (xy 3.3279 -289.002134) (xy 3.363594 -288.960941)
			(xy 3.404787 -288.925247) (xy 3.450641 -288.89578) (xy 3.500221 -288.873137) (xy 3.55252 -288.857782)
			(xy 3.606471 -288.850025) (xy 3.633724 -288.849562) (xy 3.661095 -288.849999) (xy 3.715276 -288.857821)
			(xy 3.76778 -288.873316) (xy 3.817527 -288.896165) (xy 3.863492 -288.925897) (xy 3.884422 -288.943542)
			(xy 3.891534 -288.949638) (xy 3.908552 -288.955988) (xy 3.993896 -288.955988) (xy 4.010914 -288.949638)
			(xy 4.018026 -288.943542) (xy 4.038981 -288.925931) (xy 4.084947 -288.896213) (xy 4.134688 -288.873371)
			(xy 4.187184 -288.857874) (xy 4.241356 -288.850039) (xy 4.268724 -288.849562) (xy 4.295975 -288.850048)
			(xy 4.349922 -288.857805) (xy 4.402217 -288.873161) (xy 4.451793 -288.895802) (xy 4.497643 -288.925268)
			(xy 4.538833 -288.96096) (xy 4.574524 -289.00215) (xy 4.60399 -289.048) (xy 4.626631 -289.097577)
			(xy 4.641986 -289.149872) (xy 4.649742 -289.203819) (xy 4.649742 -289.258321) (xy 4.641986 -289.312268)
			(xy 4.626631 -289.364563) (xy 4.60399 -289.41414) (xy 4.574524 -289.45999) (xy 4.538833 -289.50118)
			(xy 4.497643 -289.536872) (xy 4.451793 -289.566338) (xy 4.402217 -289.588979) (xy 4.349922 -289.604335)
			(xy 4.295975 -289.612092) (xy 4.268724 -289.612578) (xy 4.241354 -289.612103) (xy 4.187175 -289.604288)
			(xy 4.134672 -289.588802) (xy 4.084925 -289.565962) (xy 4.038958 -289.536239) (xy 4.018026 -289.518598)
			(xy 4.010914 -289.512502) (xy 3.993896 -289.506152) (xy 3.908552 -289.506152) (xy 3.891534 -289.512502)
			(xy 3.884422 -289.518598) (xy 3.863492 -289.53624) (xy 3.817519 -289.565951) (xy 3.767771 -289.588787)
			(xy 3.71527 -289.604277) (xy 3.661093 -289.612105) (xy 3.633724 -289.612578) (xy 3.606471 -289.612115)
			(xy 3.55252 -289.604358) (xy 3.500221 -289.589003) (xy 3.450641 -289.56636) (xy 3.404787 -289.536893)
			(xy 3.363594 -289.501199) (xy 3.3279 -289.460006) (xy 3.298431 -289.414153) (xy 3.275789 -289.364572)
			(xy 3.260432 -289.312274) (xy 3.252675 -289.258323) (xy 1.369822 -289.258323) (xy 1.369822 -290.994846)
			(xy 1.370254 -291.004912) (xy 1.377983 -291.023502) (xy 1.384808 -291.030914) (xy 1.617472 -291.263578)
			(xy 1.624873 -291.270415) (xy 1.643472 -291.278127) (xy 1.65354 -291.278564)
		)
		(stroke
			(width 0)
			(type solid)
		)
		(fill yes)
		(layer "In5.Cu")
		(net "P1V25_PEX0_R")
	)
	(gr_poly
		(pts
			(xy 118.469918 -202.1078) (xy 118.479987 -202.107373) (xy 118.498586 -202.099654) (xy 118.505986 -202.092814)
			(xy 122.870214 -197.728586) (xy 122.877068 -197.721191) (xy 122.88481 -197.702592) (xy 122.8852 -197.692518)
			(xy 122.8852 -186.49442) (xy 122.884762 -186.484356) (xy 122.877027 -186.465773) (xy 122.870214 -186.458352)
			(xy 119.586248 -183.174386) (xy 119.579398 -183.166989) (xy 119.571661 -183.148391) (xy 119.571262 -183.138318)
			(xy 119.571262 -154.827224) (xy 119.571357 -154.822205) (xy 119.57328 -154.812355) (xy 119.575072 -154.807666)
			(xy 119.582438 -154.790394) (xy 119.584235 -154.785707) (xy 119.58615 -154.775855) (xy 119.586248 -154.770836)
			(xy 119.586248 -133.763004) (xy 119.585824 -133.752935) (xy 119.578105 -133.734334) (xy 119.571262 -133.726936)
			(xy 119.259096 -133.41477) (xy 119.251984 -133.407404) (xy 119.233188 -133.399784) (xy 104.557068 -133.399784)
			(xy 104.547 -133.400212) (xy 104.528402 -133.407933) (xy 104.521 -133.41477) (xy 100.690934 -137.244836)
			(xy 100.690934 -137.25017) (xy 98.904044 -139.03706) (xy 106.080052 -139.03706) (xy 106.080564 -139.008321)
			(xy 106.089192 -138.951494) (xy 106.106245 -138.896603) (xy 106.131339 -138.844892) (xy 106.163905 -138.797529)
			(xy 106.183176 -138.776202) (xy 106.18978 -138.76909) (xy 106.196892 -138.751564) (xy 106.196892 -138.662156)
			(xy 106.18978 -138.64463) (xy 106.183176 -138.637518) (xy 106.163893 -138.616202) (xy 106.131327 -138.568838)
			(xy 106.106236 -138.517123) (xy 106.089188 -138.46223) (xy 106.08057 -138.4054) (xy 106.080052 -138.37666)
			(xy 106.080538 -138.349409) (xy 106.088294 -138.295461) (xy 106.103649 -138.243166) (xy 106.126291 -138.193589)
			(xy 106.155757 -138.147739) (xy 106.191448 -138.106548) (xy 106.232639 -138.070857) (xy 106.278489 -138.041391)
			(xy 106.328066 -138.018749) (xy 106.380361 -138.003394) (xy 106.434309 -137.995638) (xy 106.488811 -137.995638)
			(xy 106.542759 -138.003394) (xy 106.595054 -138.018749) (xy 106.644631 -138.041391) (xy 106.690481 -138.070857)
			(xy 106.731672 -138.106548) (xy 106.767363 -138.147739) (xy 106.796829 -138.193589) (xy 106.819471 -138.243166)
			(xy 106.834826 -138.295461) (xy 106.842582 -138.349409) (xy 106.843068 -138.37666) (xy 106.842563 -138.405399)
			(xy 106.833933 -138.462227) (xy 106.816877 -138.517117) (xy 106.791782 -138.568828) (xy 106.759215 -138.616191)
			(xy 106.739944 -138.637518) (xy 106.73334 -138.64463) (xy 106.726228 -138.662156) (xy 106.726228 -138.751564)
			(xy 106.73334 -138.76909) (xy 106.739944 -138.776202) (xy 106.759193 -138.797548) (xy 106.791763 -138.844905)
			(xy 106.81686 -138.896611) (xy 106.833916 -138.951498) (xy 106.842544 -139.008322) (xy 106.843068 -139.03706)
			(xy 106.842617 -139.062965) (xy 106.835599 -139.114299) (xy 106.821702 -139.164211) (xy 106.80118 -139.211785)
			(xy 106.774411 -139.256145) (xy 106.758486 -139.276582) (xy 106.75239 -139.284202) (xy 106.746802 -139.30249)
			(xy 106.75366 -139.39139) (xy 106.762042 -139.408916) (xy 106.769154 -139.41552) (xy 106.788401 -139.433678)
			(xy 106.822229 -139.474365) (xy 106.850113 -139.519334) (xy 106.87152 -139.567723) (xy 106.88604 -139.618605)
			(xy 106.893394 -139.671004) (xy 106.893868 -139.69746) (xy 106.893363 -139.726199) (xy 106.884733 -139.783027)
			(xy 106.867677 -139.837917) (xy 106.842582 -139.889628) (xy 106.810015 -139.936991) (xy 106.790744 -139.958318)
			(xy 106.78414 -139.96543) (xy 106.777028 -139.982956) (xy 106.777028 -140.072364) (xy 106.78414 -140.08989)
			(xy 106.790744 -140.097002) (xy 106.809977 -140.118362) (xy 106.842546 -140.165718) (xy 106.867642 -140.217424)
			(xy 106.884696 -140.27231) (xy 106.893323 -140.329134) (xy 106.893328 -140.386608) (xy 106.884709 -140.443433)
			(xy 106.867663 -140.498321) (xy 106.842575 -140.550031) (xy 106.810013 -140.597392) (xy 106.790744 -140.618718)
			(xy 106.78414 -140.62583) (xy 106.777028 -140.643356) (xy 106.777028 -140.732764) (xy 106.78414 -140.75029)
			(xy 106.790744 -140.757402) (xy 106.809993 -140.778748) (xy 106.842563 -140.826105) (xy 106.86766 -140.877811)
			(xy 106.884716 -140.932698) (xy 106.893344 -140.989522) (xy 106.893868 -141.01826) (xy 108.518452 -141.01826)
			(xy 108.518964 -140.989521) (xy 108.527592 -140.932694) (xy 108.544645 -140.877803) (xy 108.569739 -140.826092)
			(xy 108.602305 -140.778729) (xy 108.621576 -140.757402) (xy 108.62818 -140.75029) (xy 108.635292 -140.732764)
			(xy 108.635292 -140.643356) (xy 108.62818 -140.62583) (xy 108.621576 -140.618718) (xy 108.602268 -140.597425)
			(xy 108.569708 -140.550055) (xy 108.544622 -140.498337) (xy 108.527577 -140.443442) (xy 108.518959 -140.386611)
			(xy 108.518963 -140.329131) (xy 108.52759 -140.272301) (xy 108.544643 -140.217408) (xy 108.569737 -140.165694)
			(xy 108.602304 -140.11833) (xy 108.621576 -140.097002) (xy 108.62818 -140.08989) (xy 108.635292 -140.072364)
			(xy 108.635292 -139.982956) (xy 108.62818 -139.96543) (xy 108.621576 -139.958318) (xy 108.602293 -139.937002)
			(xy 108.569727 -139.889638) (xy 108.544636 -139.837923) (xy 108.527588 -139.78303) (xy 108.51897 -139.7262)
			(xy 108.518452 -139.69746) (xy 108.518993 -139.668544) (xy 108.527715 -139.611373) (xy 108.544967 -139.556173)
			(xy 108.570354 -139.504211) (xy 108.603295 -139.456677) (xy 108.643033 -139.41466) (xy 108.665518 -139.39647)
			(xy 108.674292 -139.38892) (xy 108.684468 -139.368152) (xy 108.685076 -139.356592) (xy 108.685076 -139.276328)
			(xy 108.684498 -139.264761) (xy 108.67431 -139.243989) (xy 108.665518 -139.23645) (xy 108.643062 -139.218226)
			(xy 108.603324 -139.176214) (xy 108.570382 -139.128686) (xy 108.544988 -139.076731) (xy 108.527726 -139.021539)
			(xy 108.518991 -138.964374) (xy 108.518452 -138.93546) (xy 108.518964 -138.906721) (xy 108.527592 -138.849894)
			(xy 108.544645 -138.795003) (xy 108.569739 -138.743292) (xy 108.602305 -138.695929) (xy 108.621576 -138.674602)
			(xy 108.62818 -138.66749) (xy 108.635292 -138.649964) (xy 108.635292 -138.560556) (xy 108.62818 -138.54303)
			(xy 108.621576 -138.535918) (xy 108.602293 -138.514602) (xy 108.569727 -138.467238) (xy 108.544636 -138.415523)
			(xy 108.527588 -138.36063) (xy 108.51897 -138.3038) (xy 108.518452 -138.27506) (xy 108.51894 -138.24781)
			(xy 108.526701 -138.193864) (xy 108.54206 -138.141572) (xy 108.564702 -138.091997) (xy 108.594169 -138.046149)
			(xy 108.62986 -138.00496) (xy 108.671049 -137.969269) (xy 108.716897 -137.939802) (xy 108.766472 -137.91716)
			(xy 108.818764 -137.901801) (xy 108.87271 -137.89404) (xy 108.89996 -137.893552) (xy 108.929295 -137.894104)
			(xy 108.987274 -137.903069) (xy 109.043197 -137.920808) (xy 109.095742 -137.946903) (xy 109.143671 -137.980739)
			(xy 109.165136 -138.00074) (xy 109.172502 -138.007852) (xy 109.190282 -138.014964) (xy 109.281214 -138.014964)
			(xy 109.298994 -138.007852) (xy 109.30636 -138.00074) (xy 109.327833 -137.980749) (xy 109.375767 -137.946923)
			(xy 109.42831 -137.920828) (xy 109.484228 -137.903079) (xy 109.542203 -137.894094) (xy 109.571536 -137.893552)
			(xy 109.598786 -137.894044) (xy 109.652732 -137.901805) (xy 109.705024 -137.917162) (xy 109.754599 -137.939805)
			(xy 109.800447 -137.969271) (xy 109.841636 -138.004962) (xy 109.877327 -138.04615) (xy 109.906793 -138.091998)
			(xy 109.929436 -138.141572) (xy 109.944795 -138.193864) (xy 109.952556 -138.24781) (xy 109.953044 -138.27506)
			(xy 109.952545 -138.3038) (xy 109.943915 -138.360628) (xy 109.926858 -138.415518) (xy 109.901761 -138.467229)
			(xy 109.869192 -138.514591) (xy 109.84992 -138.535918) (xy 109.843316 -138.54303) (xy 109.836204 -138.560556)
			(xy 109.836204 -138.649964) (xy 109.843316 -138.66749) (xy 109.84992 -138.674602) (xy 109.869165 -138.695952)
			(xy 109.901736 -138.743307) (xy 109.926834 -138.795013) (xy 109.943891 -138.849899) (xy 109.95252 -138.906722)
			(xy 109.953044 -138.93546) (xy 112.090708 -138.93546) (xy 112.091205 -138.90672) (xy 112.099834 -138.849891)
			(xy 112.11689 -138.795) (xy 112.141988 -138.743289) (xy 112.174559 -138.695928) (xy 112.193832 -138.674602)
			(xy 112.200436 -138.66749) (xy 112.207548 -138.649964) (xy 112.207548 -138.560556) (xy 112.200436 -138.54303)
			(xy 112.193832 -138.535918) (xy 112.174541 -138.514608) (xy 112.141978 -138.467241) (xy 112.116889 -138.415525)
			(xy 112.099844 -138.360631) (xy 112.091226 -138.3038) (xy 112.090708 -138.27506) (xy 112.091194 -138.247809)
			(xy 112.09895 -138.193861) (xy 112.114305 -138.141566) (xy 112.136947 -138.091989) (xy 112.166413 -138.046139)
			(xy 112.202104 -138.004948) (xy 112.243295 -137.969257) (xy 112.289145 -137.939791) (xy 112.338722 -137.917149)
			(xy 112.391017 -137.901794) (xy 112.444965 -137.894038) (xy 112.499467 -137.894038) (xy 112.553415 -137.901794)
			(xy 112.60571 -137.917149) (xy 112.655287 -137.939791) (xy 112.701137 -137.969257) (xy 112.742328 -138.004948)
			(xy 112.778019 -138.046139) (xy 112.807485 -138.091989) (xy 112.830127 -138.141566) (xy 112.845482 -138.193861)
			(xy 112.853238 -138.247809) (xy 112.853724 -138.27506) (xy 112.85323 -138.3038) (xy 112.844599 -138.360628)
			(xy 112.827542 -138.415519) (xy 112.802444 -138.46723) (xy 112.769873 -138.514592) (xy 112.7506 -138.535918)
			(xy 112.743996 -138.54303) (xy 112.736884 -138.560556) (xy 112.736884 -138.649964) (xy 112.743996 -138.66749)
			(xy 112.7506 -138.674602) (xy 112.769841 -138.695955) (xy 112.802414 -138.743309) (xy 112.827513 -138.795014)
			(xy 112.84457 -138.849899) (xy 112.853199 -138.906723) (xy 112.853724 -138.93546) (xy 112.85327 -138.960927)
			(xy 112.84647 -139.011406) (xy 112.833011 -139.060531) (xy 112.813134 -139.107427) (xy 112.787191 -139.15126)
			(xy 112.755645 -139.19125) (xy 112.737646 -139.209272) (xy 112.729518 -139.2174) (xy 112.721644 -139.237974)
			(xy 112.728502 -139.33805) (xy 112.73917 -139.357608) (xy 112.748568 -139.364212) (xy 112.772282 -139.382359)
			(xy 112.81434 -139.42474) (xy 112.849289 -139.473152) (xy 112.876276 -139.526413) (xy 112.894644 -139.583226)
			(xy 112.903944 -139.642206) (xy 112.904524 -139.67206) (xy 112.90403 -139.7008) (xy 112.895399 -139.757628)
			(xy 112.878342 -139.812519) (xy 112.853244 -139.86423) (xy 112.820673 -139.911592) (xy 112.8014 -139.932918)
			(xy 112.794796 -139.94003) (xy 112.787684 -139.957556) (xy 112.787684 -140.046964) (xy 112.794796 -140.06449)
			(xy 112.8014 -140.071602) (xy 112.82063 -140.092964) (xy 112.853195 -140.140321) (xy 112.878287 -140.192027)
			(xy 112.895339 -140.246912) (xy 112.903964 -140.303734) (xy 112.903969 -140.361207) (xy 112.895352 -140.418031)
			(xy 112.878308 -140.472919) (xy 112.853224 -140.524629) (xy 112.820667 -140.571991) (xy 112.8014 -140.593318)
			(xy 112.794796 -140.60043) (xy 112.787684 -140.617956) (xy 112.787684 -140.707364) (xy 112.794796 -140.72489)
			(xy 112.8014 -140.732002) (xy 112.820641 -140.753355) (xy 112.853214 -140.800709) (xy 112.878313 -140.852414)
			(xy 112.89537 -140.907299) (xy 112.903999 -140.964123) (xy 112.90406 -140.96746) (xy 114.529108 -140.96746)
			(xy 114.529605 -140.93872) (xy 114.538234 -140.881891) (xy 114.55529 -140.827) (xy 114.580388 -140.775289)
			(xy 114.612959 -140.727928) (xy 114.632232 -140.706602) (xy 114.638836 -140.69949) (xy 114.645948 -140.681964)
			(xy 114.645948 -140.592556) (xy 114.638836 -140.57503) (xy 114.632232 -140.567918) (xy 114.612921 -140.546626)
			(xy 114.580357 -140.499258) (xy 114.555267 -140.44754) (xy 114.538219 -140.392644) (xy 114.5296 -140.335812)
			(xy 114.529605 -140.27833) (xy 114.538232 -140.221499) (xy 114.555288 -140.166605) (xy 114.580386 -140.114892)
			(xy 114.612958 -140.067529) (xy 114.632232 -140.046202) (xy 114.638836 -140.03909) (xy 114.645948 -140.021564)
			(xy 114.645948 -139.932156) (xy 114.638836 -139.91463) (xy 114.632232 -139.907518) (xy 114.612941 -139.886208)
			(xy 114.580378 -139.838841) (xy 114.555289 -139.787125) (xy 114.538244 -139.732231) (xy 114.529626 -139.6754)
			(xy 114.529108 -139.64666) (xy 114.529552 -139.620344) (xy 114.536774 -139.568209) (xy 114.551088 -139.517561)
			(xy 114.572224 -139.469359) (xy 114.599781 -139.424517) (xy 114.633237 -139.383886) (xy 114.652298 -139.365736)
			(xy 114.659685 -139.358203) (xy 114.668218 -139.338931) (xy 114.668808 -139.328398) (xy 114.668808 -139.253722)
			(xy 114.668278 -139.243173) (xy 114.659743 -139.223877) (xy 114.652298 -139.216384) (xy 114.63321 -139.198258)
			(xy 114.599733 -139.157635) (xy 114.572164 -139.112793) (xy 114.551027 -139.064584) (xy 114.536724 -139.013925)
			(xy 114.529528 -138.96178) (xy 114.529108 -138.93546) (xy 114.529605 -138.90672) (xy 114.538234 -138.849891)
			(xy 114.55529 -138.795) (xy 114.580388 -138.743289) (xy 114.612959 -138.695928) (xy 114.632232 -138.674602)
			(xy 114.638836 -138.66749) (xy 114.645948 -138.649964) (xy 114.645948 -138.560556) (xy 114.638836 -138.54303)
			(xy 114.632232 -138.535918) (xy 114.612941 -138.514608) (xy 114.580378 -138.467241) (xy 114.555289 -138.415525)
			(xy 114.538244 -138.360631) (xy 114.529626 -138.3038) (xy 114.529108 -138.27506) (xy 114.529541 -138.247807)
			(xy 114.537303 -138.193857) (xy 114.552664 -138.14156) (xy 114.575311 -138.091981) (xy 114.604783 -138.04613)
			(xy 114.64048 -138.00494) (xy 114.681675 -137.969249) (xy 114.727531 -137.939784) (xy 114.777112 -137.917144)
			(xy 114.829411 -137.901791) (xy 114.883363 -137.894037) (xy 114.910616 -137.893552) (xy 114.93829 -137.894058)
			(xy 114.993059 -137.902052) (xy 115.046094 -137.917884) (xy 115.096283 -137.94122) (xy 115.142567 -137.971571)
			(xy 115.1636 -137.989564) (xy 115.170712 -137.995914) (xy 115.189 -138.002518) (xy 115.278154 -137.999724)
			(xy 115.295934 -137.992104) (xy 115.302792 -137.985246) (xy 115.32441 -137.964521) (xy 115.372875 -137.929347)
			(xy 115.426241 -137.90218) (xy 115.483198 -137.883689) (xy 115.542344 -137.874327) (xy 115.572286 -137.87374)
			(xy 115.599541 -137.874169) (xy 115.653495 -137.881925) (xy 115.705797 -137.897281) (xy 115.75538 -137.919926)
			(xy 115.801236 -137.949397) (xy 115.84243 -137.985094) (xy 115.878124 -138.026292) (xy 115.90759 -138.07215)
			(xy 115.93023 -138.121735) (xy 115.945582 -138.174038) (xy 115.953334 -138.227993) (xy 115.953794 -138.255248)
			(xy 115.953301 -138.283988) (xy 115.944671 -138.340817) (xy 115.927614 -138.395708) (xy 115.902516 -138.447419)
			(xy 115.869944 -138.49478) (xy 115.85067 -138.516106) (xy 115.844066 -138.523218) (xy 115.836954 -138.540744)
			(xy 115.836954 -138.578844) (xy 118.705882 -138.578844) (xy 118.709953 -138.523222) (xy 118.722079 -138.468785)
			(xy 118.742002 -138.416694) (xy 118.769298 -138.368059) (xy 118.803384 -138.323916) (xy 118.843533 -138.285207)
			(xy 118.888891 -138.252756) (xy 118.938491 -138.227255) (xy 118.991275 -138.209248) (xy 119.046118 -138.199118)
			(xy 119.101852 -138.197081) (xy 119.157289 -138.203181) (xy 119.211246 -138.217287) (xy 119.262575 -138.239099)
			(xy 119.310181 -138.268153) (xy 119.353049 -138.303828) (xy 119.390266 -138.345365) (xy 119.421039 -138.391878)
			(xy 119.444711 -138.442375) (xy 119.460779 -138.495782) (xy 119.468899 -138.550958) (xy 119.469408 -138.578844)
			(xy 119.468899 -138.60673) (xy 119.460779 -138.661906) (xy 119.444711 -138.715313) (xy 119.421039 -138.76581)
			(xy 119.390266 -138.812323) (xy 119.353049 -138.85386) (xy 119.310181 -138.889535) (xy 119.262575 -138.918589)
			(xy 119.211246 -138.940401) (xy 119.157289 -138.954507) (xy 119.101852 -138.960607) (xy 119.046118 -138.95857)
			(xy 118.991275 -138.94844) (xy 118.938491 -138.930433) (xy 118.888891 -138.904932) (xy 118.843533 -138.872481)
			(xy 118.803384 -138.833772) (xy 118.769298 -138.789629) (xy 118.742002 -138.740994) (xy 118.722079 -138.688903)
			(xy 118.709953 -138.634466) (xy 118.705882 -138.578844) (xy 115.836954 -138.578844) (xy 115.836954 -138.630152)
			(xy 115.844066 -138.647678) (xy 115.85067 -138.65479) (xy 115.869965 -138.676096) (xy 115.902527 -138.723464)
			(xy 115.927615 -138.775181) (xy 115.94466 -138.830076) (xy 115.953277 -138.886908) (xy 115.953794 -138.915648)
			(xy 115.953355 -138.941964) (xy 115.946132 -138.994099) (xy 115.931816 -139.044748) (xy 115.910679 -139.09295)
			(xy 115.883122 -139.137791) (xy 115.849665 -139.178422) (xy 115.830604 -139.196572) (xy 115.823213 -139.204103)
			(xy 115.814683 -139.223376) (xy 115.814094 -139.23391) (xy 115.814094 -139.308586) (xy 115.814619 -139.319136)
			(xy 115.823157 -139.338431) (xy 115.830604 -139.345924) (xy 115.849696 -139.364046) (xy 115.883173 -139.404669)
			(xy 115.910741 -139.449513) (xy 115.931878 -139.497722) (xy 115.94618 -139.548382) (xy 115.953375 -139.600528)
			(xy 115.953794 -139.626848) (xy 115.953301 -139.655588) (xy 115.944671 -139.712417) (xy 115.927614 -139.767308)
			(xy 115.902516 -139.819019) (xy 115.869944 -139.86638) (xy 115.85067 -139.887706) (xy 115.844066 -139.894818)
			(xy 115.836954 -139.912344) (xy 115.836954 -140.001752) (xy 115.844066 -140.019278) (xy 115.85067 -140.02639)
			(xy 115.869989 -140.047675) (xy 115.902553 -140.095045) (xy 115.927642 -140.146763) (xy 115.944689 -140.20166)
			(xy 115.953307 -140.258494) (xy 115.953302 -140.315976) (xy 115.944673 -140.372808) (xy 115.927616 -140.427702)
			(xy 115.902518 -140.479416) (xy 115.869945 -140.526779) (xy 115.85067 -140.548106) (xy 115.844066 -140.555218)
			(xy 115.836954 -140.572744) (xy 115.836954 -140.662152) (xy 115.844066 -140.679678) (xy 115.85067 -140.68679)
			(xy 115.869965 -140.708096) (xy 115.902527 -140.755464) (xy 115.927615 -140.807181) (xy 115.94466 -140.862076)
			(xy 115.953277 -140.918908) (xy 115.953794 -140.947648) (xy 115.953367 -140.974901) (xy 115.945603 -141.028852)
			(xy 115.930241 -141.081148) (xy 115.907594 -141.130727) (xy 115.878121 -141.176577) (xy 115.842424 -141.217767)
			(xy 115.801228 -141.253458) (xy 115.755372 -141.282923) (xy 115.70579 -141.305563) (xy 115.653491 -141.320917)
			(xy 115.599539 -141.328671) (xy 115.572286 -141.329156) (xy 115.544612 -141.328647) (xy 115.489844 -141.320653)
			(xy 115.436808 -141.304822) (xy 115.38662 -141.281486) (xy 115.340335 -141.251136) (xy 115.319302 -141.233144)
			(xy 115.31219 -141.226794) (xy 115.293902 -141.22019) (xy 115.204748 -141.222984) (xy 115.186968 -141.230604)
			(xy 115.18011 -141.237462) (xy 115.158536 -141.258235) (xy 115.11006 -141.293403) (xy 115.056682 -141.32056)
			(xy 114.999716 -141.33904) (xy 114.940561 -141.348388) (xy 114.910616 -141.348968) (xy 114.883362 -141.34853)
			(xy 114.829408 -141.340774) (xy 114.777107 -141.325418) (xy 114.727524 -141.302774) (xy 114.681669 -141.273304)
			(xy 114.640475 -141.237608) (xy 114.604781 -141.196412) (xy 114.575314 -141.150555) (xy 114.552674 -141.10097)
			(xy 114.537321 -141.048669) (xy 114.529569 -140.994714) (xy 114.529108 -140.96746) (xy 112.90406 -140.96746)
			(xy 112.904524 -140.99286) (xy 112.904038 -141.020111) (xy 112.896282 -141.074059) (xy 112.880927 -141.126354)
			(xy 112.858285 -141.175931) (xy 112.828819 -141.221781) (xy 112.793128 -141.262972) (xy 112.751937 -141.298663)
			(xy 112.706087 -141.328129) (xy 112.65651 -141.350771) (xy 112.604215 -141.366126) (xy 112.550267 -141.373882)
			(xy 112.495765 -141.373882) (xy 112.441817 -141.366126) (xy 112.389522 -141.350771) (xy 112.339945 -141.328129)
			(xy 112.294095 -141.298663) (xy 112.252904 -141.262972) (xy 112.217213 -141.221781) (xy 112.187747 -141.175931)
			(xy 112.165105 -141.126354) (xy 112.14975 -141.074059) (xy 112.141994 -141.020111) (xy 112.141508 -140.99286)
			(xy 112.142005 -140.96412) (xy 112.150634 -140.907291) (xy 112.16769 -140.8524) (xy 112.192788 -140.800689)
			(xy 112.225359 -140.753328) (xy 112.244632 -140.732002) (xy 112.251236 -140.72489) (xy 112.258348 -140.707364)
			(xy 112.258348 -140.617956) (xy 112.251236 -140.60043) (xy 112.244632 -140.593318) (xy 112.225321 -140.572026)
			(xy 112.192757 -140.524658) (xy 112.167667 -140.47294) (xy 112.150619 -140.418044) (xy 112.142 -140.361212)
			(xy 112.142005 -140.30373) (xy 112.150632 -140.246899) (xy 112.167688 -140.192005) (xy 112.192786 -140.140292)
			(xy 112.225358 -140.092929) (xy 112.244632 -140.071602) (xy 112.251236 -140.06449) (xy 112.258348 -140.046964)
			(xy 112.258348 -139.957556) (xy 112.251236 -139.94003) (xy 112.244632 -139.932918) (xy 112.225341 -139.911608)
			(xy 112.192778 -139.864241) (xy 112.167689 -139.812525) (xy 112.150644 -139.757631) (xy 112.142026 -139.7008)
			(xy 112.141508 -139.67206) (xy 112.141965 -139.646593) (xy 112.148764 -139.596114) (xy 112.162221 -139.546989)
			(xy 112.182098 -139.500093) (xy 112.20804 -139.456259) (xy 112.239586 -139.41627) (xy 112.257586 -139.398248)
			(xy 112.265714 -139.39012) (xy 112.273588 -139.369546) (xy 112.26673 -139.26947) (xy 112.256062 -139.249912)
			(xy 112.246664 -139.243308) (xy 112.222945 -139.225168) (xy 112.18089 -139.182783) (xy 112.145944 -139.134369)
			(xy 112.118958 -139.081107) (xy 112.100591 -139.024294) (xy 112.091289 -138.965314) (xy 112.090708 -138.93546)
			(xy 109.953044 -138.93546) (xy 109.952518 -138.964377) (xy 109.943794 -139.021549) (xy 109.926539 -139.076748)
			(xy 109.901149 -139.128711) (xy 109.868205 -139.176245) (xy 109.828464 -139.218261) (xy 109.805978 -139.23645)
			(xy 109.797239 -139.244034) (xy 109.787044 -139.264776) (xy 109.78642 -139.276328) (xy 109.78642 -139.356592)
			(xy 109.786988 -139.36816) (xy 109.797184 -139.388932) (xy 109.805978 -139.39647) (xy 109.828443 -139.414684)
			(xy 109.86818 -139.456698) (xy 109.901122 -139.504228) (xy 109.926514 -139.556185) (xy 109.943774 -139.611379)
			(xy 109.952507 -139.668545) (xy 109.953044 -139.69746) (xy 109.952545 -139.7262) (xy 109.943915 -139.783028)
			(xy 109.926858 -139.837918) (xy 109.901761 -139.889629) (xy 109.869192 -139.936991) (xy 109.84992 -139.958318)
			(xy 109.843316 -139.96543) (xy 109.836204 -139.982956) (xy 109.836204 -140.072364) (xy 109.843316 -140.08989)
			(xy 109.84992 -140.097002) (xy 109.869149 -140.118364) (xy 109.901712 -140.165722) (xy 109.926803 -140.217428)
			(xy 109.943854 -140.272313) (xy 109.952479 -140.329135) (xy 109.952483 -140.386607) (xy 109.943867 -140.44343)
			(xy 109.926824 -140.498318) (xy 109.901741 -140.550028) (xy 109.869186 -140.59739) (xy 109.84992 -140.618718)
			(xy 109.843316 -140.62583) (xy 109.836204 -140.643356) (xy 109.836204 -140.732764) (xy 109.843316 -140.75029)
			(xy 109.84992 -140.757402) (xy 109.869165 -140.778752) (xy 109.901736 -140.826107) (xy 109.926834 -140.877813)
			(xy 109.943891 -140.932699) (xy 109.95252 -140.989522) (xy 109.953044 -141.01826) (xy 109.952508 -141.04551)
			(xy 109.944757 -141.099457) (xy 109.929408 -141.151751) (xy 109.906773 -141.201329) (xy 109.877312 -141.24718)
			(xy 109.841626 -141.288372) (xy 109.800441 -141.324067) (xy 109.754595 -141.353536) (xy 109.705022 -141.376181)
			(xy 109.652731 -141.391541) (xy 109.598786 -141.399302) (xy 109.571536 -141.399768) (xy 109.542202 -141.399213)
			(xy 109.484222 -141.390248) (xy 109.4283 -141.372509) (xy 109.375755 -141.346415) (xy 109.327825 -141.312581)
			(xy 109.30636 -141.29258) (xy 109.298994 -141.285468) (xy 109.281214 -141.278356) (xy 109.190282 -141.278356)
			(xy 109.172502 -141.285468) (xy 109.165136 -141.29258) (xy 109.143652 -141.312559) (xy 109.095723 -141.34639)
			(xy 109.043182 -141.372489) (xy 108.987266 -141.39024) (xy 108.929293 -141.399226) (xy 108.89996 -141.399768)
			(xy 108.872706 -141.399359) (xy 108.818753 -141.391596) (xy 108.766455 -141.376234) (xy 108.716875 -141.353585)
			(xy 108.671023 -141.324111) (xy 108.629832 -141.288412) (xy 108.594141 -141.247213) (xy 108.564676 -141.201355)
			(xy 108.542038 -141.15177) (xy 108.526687 -141.099468) (xy 108.518935 -141.045514) (xy 108.518452 -141.01826)
			(xy 106.893868 -141.01826) (xy 106.893382 -141.045511) (xy 106.885626 -141.099459) (xy 106.870271 -141.151754)
			(xy 106.847629 -141.201331) (xy 106.818163 -141.247181) (xy 106.782472 -141.288372) (xy 106.741281 -141.324063)
			(xy 106.695431 -141.353529) (xy 106.645854 -141.376171) (xy 106.593559 -141.391526) (xy 106.539611 -141.399282)
			(xy 106.485109 -141.399282) (xy 106.431161 -141.391526) (xy 106.378866 -141.376171) (xy 106.329289 -141.353529)
			(xy 106.283439 -141.324063) (xy 106.242248 -141.288372) (xy 106.206557 -141.247181) (xy 106.177091 -141.201331)
			(xy 106.154449 -141.151754) (xy 106.139094 -141.099459) (xy 106.131338 -141.045511) (xy 106.130852 -141.01826)
			(xy 106.131364 -140.989521) (xy 106.139992 -140.932694) (xy 106.157045 -140.877803) (xy 106.182139 -140.826092)
			(xy 106.214705 -140.778729) (xy 106.233976 -140.757402) (xy 106.24058 -140.75029) (xy 106.247692 -140.732764)
			(xy 106.247692 -140.643356) (xy 106.24058 -140.62583) (xy 106.233976 -140.618718) (xy 106.214668 -140.597425)
			(xy 106.182108 -140.550055) (xy 106.157022 -140.498337) (xy 106.139977 -140.443442) (xy 106.131359 -140.386611)
			(xy 106.131363 -140.329131) (xy 106.13999 -140.272301) (xy 106.157043 -140.217408) (xy 106.182137 -140.165694)
			(xy 106.214704 -140.11833) (xy 106.233976 -140.097002) (xy 106.24058 -140.08989) (xy 106.247692 -140.072364)
			(xy 106.247692 -139.982956) (xy 106.24058 -139.96543) (xy 106.233976 -139.958318) (xy 106.214693 -139.937002)
			(xy 106.182127 -139.889638) (xy 106.157036 -139.837923) (xy 106.139988 -139.78303) (xy 106.13137 -139.7262)
			(xy 106.130852 -139.69746) (xy 106.13131 -139.671555) (xy 106.138325 -139.620221) (xy 106.152221 -139.570309)
			(xy 106.172741 -139.522735) (xy 106.199509 -139.478375) (xy 106.215434 -139.457938) (xy 106.22153 -139.450318)
			(xy 106.227118 -139.43203) (xy 106.22026 -139.34313) (xy 106.211878 -139.325604) (xy 106.204766 -139.319)
			(xy 106.185484 -139.300878) (xy 106.151659 -139.260183) (xy 106.123778 -139.215207) (xy 106.102377 -139.166811)
			(xy 106.087865 -139.115923) (xy 106.080521 -139.063518) (xy 106.080052 -139.03706) (xy 98.904044 -139.03706)
			(xy 96.397064 -141.54404) (xy 96.389698 -141.568424) (xy 96.392492 -141.581378) (xy 96.395842 -141.598388)
			(xy 96.399405 -141.632876) (xy 96.399604 -141.650212) (xy 96.399604 -158.947612) (xy 107.304584 -158.947612)
			(xy 107.308655 -158.89199) (xy 107.320781 -158.837553) (xy 107.340704 -158.785462) (xy 107.368 -158.736827)
			(xy 107.402086 -158.692684) (xy 107.442235 -158.653975) (xy 107.487593 -158.621524) (xy 107.537193 -158.596023)
			(xy 107.589977 -158.578016) (xy 107.64482 -158.567886) (xy 107.700554 -158.565849) (xy 107.755991 -158.571949)
			(xy 107.809948 -158.586055) (xy 107.861277 -158.607867) (xy 107.908883 -158.636921) (xy 107.951751 -158.672596)
			(xy 107.988968 -158.714133) (xy 108.019741 -158.760646) (xy 108.043413 -158.811143) (xy 108.059481 -158.86455)
			(xy 108.067601 -158.919726) (xy 108.06811 -158.947612) (xy 108.067601 -158.975498) (xy 108.059481 -159.030674)
			(xy 108.043413 -159.084081) (xy 108.019741 -159.134578) (xy 107.988968 -159.181091) (xy 107.951751 -159.222628)
			(xy 107.908883 -159.258303) (xy 107.861277 -159.287357) (xy 107.809948 -159.309169) (xy 107.755991 -159.323275)
			(xy 107.700554 -159.329375) (xy 107.64482 -159.327338) (xy 107.589977 -159.317208) (xy 107.537193 -159.299201)
			(xy 107.487593 -159.2737) (xy 107.442235 -159.241249) (xy 107.402086 -159.20254) (xy 107.368 -159.158397)
			(xy 107.340704 -159.109762) (xy 107.320781 -159.057671) (xy 107.308655 -159.003234) (xy 107.304584 -158.947612)
			(xy 96.399604 -158.947612) (xy 96.399604 -159.681418) (xy 112.176558 -159.681418) (xy 112.180629 -159.625796)
			(xy 112.192755 -159.571359) (xy 112.212678 -159.519268) (xy 112.239974 -159.470633) (xy 112.27406 -159.42649)
			(xy 112.314209 -159.387781) (xy 112.359567 -159.35533) (xy 112.409167 -159.329829) (xy 112.461951 -159.311822)
			(xy 112.516794 -159.301692) (xy 112.572528 -159.299655) (xy 112.627965 -159.305755) (xy 112.681922 -159.319861)
			(xy 112.733251 -159.341673) (xy 112.780857 -159.370727) (xy 112.823725 -159.406402) (xy 112.860942 -159.447939)
			(xy 112.891715 -159.494452) (xy 112.915387 -159.544949) (xy 112.931455 -159.598356) (xy 112.939575 -159.653532)
			(xy 112.940084 -159.681418) (xy 112.939575 -159.709304) (xy 112.931455 -159.76448) (xy 112.915387 -159.817887)
			(xy 112.891715 -159.868384) (xy 112.860942 -159.914897) (xy 112.823725 -159.956434) (xy 112.780857 -159.992109)
			(xy 112.733251 -160.021163) (xy 112.681922 -160.042975) (xy 112.627965 -160.057081) (xy 112.572528 -160.063181)
			(xy 112.516794 -160.061144) (xy 112.461951 -160.051014) (xy 112.409167 -160.033007) (xy 112.359567 -160.007506)
			(xy 112.314209 -159.975055) (xy 112.27406 -159.936346) (xy 112.239974 -159.892203) (xy 112.212678 -159.843568)
			(xy 112.192755 -159.791477) (xy 112.180629 -159.73704) (xy 112.176558 -159.681418) (xy 96.399604 -159.681418)
			(xy 96.399604 -160.220406) (xy 113.389916 -160.220406) (xy 113.393987 -160.164784) (xy 113.406113 -160.110347)
			(xy 113.426036 -160.058256) (xy 113.453332 -160.009621) (xy 113.487418 -159.965478) (xy 113.527567 -159.926769)
			(xy 113.572925 -159.894318) (xy 113.622525 -159.868817) (xy 113.675309 -159.85081) (xy 113.730152 -159.84068)
			(xy 113.785886 -159.838643) (xy 113.841323 -159.844743) (xy 113.89528 -159.858849) (xy 113.946609 -159.880661)
			(xy 113.994215 -159.909715) (xy 114.037083 -159.94539) (xy 114.0743 -159.986927) (xy 114.105073 -160.03344)
			(xy 114.128745 -160.083937) (xy 114.144813 -160.137344) (xy 114.152933 -160.19252) (xy 114.153442 -160.220406)
			(xy 114.152933 -160.248292) (xy 114.144813 -160.303468) (xy 114.128745 -160.356875) (xy 114.105073 -160.407372)
			(xy 114.0743 -160.453885) (xy 114.058189 -160.471866) (xy 114.82019 -160.471866) (xy 114.824261 -160.416244)
			(xy 114.836387 -160.361807) (xy 114.85631 -160.309716) (xy 114.883606 -160.261081) (xy 114.917692 -160.216938)
			(xy 114.957841 -160.178229) (xy 115.003199 -160.145778) (xy 115.052799 -160.120277) (xy 115.105583 -160.10227)
			(xy 115.160426 -160.09214) (xy 115.21616 -160.090103) (xy 115.271597 -160.096203) (xy 115.325554 -160.110309)
			(xy 115.376883 -160.132121) (xy 115.424489 -160.161175) (xy 115.467357 -160.19685) (xy 115.504574 -160.238387)
			(xy 115.535347 -160.2849) (xy 115.559019 -160.335397) (xy 115.575087 -160.388804) (xy 115.583207 -160.44398)
			(xy 115.583716 -160.471866) (xy 115.583207 -160.499752) (xy 115.575087 -160.554928) (xy 115.559019 -160.608335)
			(xy 115.535347 -160.658832) (xy 115.504574 -160.705345) (xy 115.467357 -160.746882) (xy 115.424489 -160.782557)
			(xy 115.376883 -160.811611) (xy 115.325554 -160.833423) (xy 115.271597 -160.847529) (xy 115.21616 -160.853629)
			(xy 115.160426 -160.851592) (xy 115.105583 -160.841462) (xy 115.052799 -160.823455) (xy 115.003199 -160.797954)
			(xy 114.957841 -160.765503) (xy 114.917692 -160.726794) (xy 114.883606 -160.682651) (xy 114.85631 -160.634016)
			(xy 114.836387 -160.581925) (xy 114.824261 -160.527488) (xy 114.82019 -160.471866) (xy 114.058189 -160.471866)
			(xy 114.037083 -160.495422) (xy 113.994215 -160.531097) (xy 113.946609 -160.560151) (xy 113.89528 -160.581963)
			(xy 113.841323 -160.596069) (xy 113.785886 -160.602169) (xy 113.730152 -160.600132) (xy 113.675309 -160.590002)
			(xy 113.622525 -160.571995) (xy 113.572925 -160.546494) (xy 113.527567 -160.514043) (xy 113.487418 -160.475334)
			(xy 113.453332 -160.431191) (xy 113.426036 -160.382556) (xy 113.406113 -160.330465) (xy 113.393987 -160.276028)
			(xy 113.389916 -160.220406) (xy 96.399604 -160.220406) (xy 96.399604 -162.131502) (xy 111.67313 -162.131502)
			(xy 111.677201 -162.07588) (xy 111.689327 -162.021443) (xy 111.70925 -161.969352) (xy 111.736546 -161.920717)
			(xy 111.770632 -161.876574) (xy 111.810781 -161.837865) (xy 111.856139 -161.805414) (xy 111.905739 -161.779913)
			(xy 111.958523 -161.761906) (xy 112.013366 -161.751776) (xy 112.0691 -161.749739) (xy 112.124537 -161.755839)
			(xy 112.178494 -161.769945) (xy 112.229823 -161.791757) (xy 112.252954 -161.805874) (xy 113.226848 -161.805874)
			(xy 113.230919 -161.750252) (xy 113.243045 -161.695815) (xy 113.262968 -161.643724) (xy 113.290264 -161.595089)
			(xy 113.32435 -161.550946) (xy 113.364499 -161.512237) (xy 113.409857 -161.479786) (xy 113.459457 -161.454285)
			(xy 113.512241 -161.436278) (xy 113.567084 -161.426148) (xy 113.622818 -161.424111) (xy 113.678255 -161.430211)
			(xy 113.732212 -161.444317) (xy 113.783541 -161.466129) (xy 113.831147 -161.495183) (xy 113.874015 -161.530858)
			(xy 113.911232 -161.572395) (xy 113.942005 -161.618908) (xy 113.965677 -161.669405) (xy 113.981745 -161.722812)
			(xy 113.989865 -161.777988) (xy 113.990374 -161.805874) (xy 113.989865 -161.83376) (xy 113.981745 -161.888936)
			(xy 113.965677 -161.942343) (xy 113.942005 -161.99284) (xy 113.911232 -162.039353) (xy 113.874015 -162.08089)
			(xy 113.831147 -162.116565) (xy 113.81125 -162.128708) (xy 115.561108 -162.128708) (xy 115.565179 -162.073086)
			(xy 115.577305 -162.018649) (xy 115.597228 -161.966558) (xy 115.624524 -161.917923) (xy 115.65861 -161.87378)
			(xy 115.698759 -161.835071) (xy 115.744117 -161.80262) (xy 115.793717 -161.777119) (xy 115.846501 -161.759112)
			(xy 115.901344 -161.748982) (xy 115.957078 -161.746945) (xy 116.012515 -161.753045) (xy 116.066472 -161.767151)
			(xy 116.117801 -161.788963) (xy 116.165407 -161.818017) (xy 116.208275 -161.853692) (xy 116.245492 -161.895229)
			(xy 116.276265 -161.941742) (xy 116.299937 -161.992239) (xy 116.316005 -162.045646) (xy 116.324125 -162.100822)
			(xy 116.324634 -162.128708) (xy 116.324125 -162.156594) (xy 116.316005 -162.21177) (xy 116.299937 -162.265177)
			(xy 116.276265 -162.315674) (xy 116.245492 -162.362187) (xy 116.208275 -162.403724) (xy 116.165407 -162.439399)
			(xy 116.117801 -162.468453) (xy 116.066472 -162.490265) (xy 116.012515 -162.504371) (xy 115.957078 -162.510471)
			(xy 115.901344 -162.508434) (xy 115.846501 -162.498304) (xy 115.793717 -162.480297) (xy 115.744117 -162.454796)
			(xy 115.698759 -162.422345) (xy 115.65861 -162.383636) (xy 115.624524 -162.339493) (xy 115.597228 -162.290858)
			(xy 115.577305 -162.238767) (xy 115.565179 -162.18433) (xy 115.561108 -162.128708) (xy 113.81125 -162.128708)
			(xy 113.783541 -162.145619) (xy 113.732212 -162.167431) (xy 113.678255 -162.181537) (xy 113.622818 -162.187637)
			(xy 113.567084 -162.1856) (xy 113.512241 -162.17547) (xy 113.459457 -162.157463) (xy 113.409857 -162.131962)
			(xy 113.364499 -162.099511) (xy 113.32435 -162.060802) (xy 113.290264 -162.016659) (xy 113.262968 -161.968024)
			(xy 113.243045 -161.915933) (xy 113.230919 -161.861496) (xy 113.226848 -161.805874) (xy 112.252954 -161.805874)
			(xy 112.277429 -161.820811) (xy 112.320297 -161.856486) (xy 112.357514 -161.898023) (xy 112.388287 -161.944536)
			(xy 112.411959 -161.995033) (xy 112.428027 -162.04844) (xy 112.436147 -162.103616) (xy 112.436656 -162.131502)
			(xy 112.436147 -162.159388) (xy 112.428027 -162.214564) (xy 112.411959 -162.267971) (xy 112.388287 -162.318468)
			(xy 112.357514 -162.364981) (xy 112.320297 -162.406518) (xy 112.277429 -162.442193) (xy 112.229823 -162.471247)
			(xy 112.178494 -162.493059) (xy 112.124537 -162.507165) (xy 112.0691 -162.513265) (xy 112.013366 -162.511228)
			(xy 111.958523 -162.501098) (xy 111.905739 -162.483091) (xy 111.856139 -162.45759) (xy 111.810781 -162.425139)
			(xy 111.770632 -162.38643) (xy 111.736546 -162.342287) (xy 111.70925 -162.293652) (xy 111.689327 -162.241561)
			(xy 111.677201 -162.187124) (xy 111.67313 -162.131502) (xy 96.399604 -162.131502) (xy 96.399604 -163.41344)
			(xy 113.15268 -163.41344) (xy 113.156751 -163.357818) (xy 113.168877 -163.303381) (xy 113.1888 -163.25129)
			(xy 113.216096 -163.202655) (xy 113.250182 -163.158512) (xy 113.290331 -163.119803) (xy 113.335689 -163.087352)
			(xy 113.385289 -163.061851) (xy 113.438073 -163.043844) (xy 113.492916 -163.033714) (xy 113.54865 -163.031677)
			(xy 113.604087 -163.037777) (xy 113.658044 -163.051883) (xy 113.709373 -163.073695) (xy 113.756979 -163.102749)
			(xy 113.799847 -163.138424) (xy 113.837064 -163.179961) (xy 113.867837 -163.226474) (xy 113.891509 -163.276971)
			(xy 113.907577 -163.330378) (xy 113.915697 -163.385554) (xy 113.916206 -163.41344) (xy 113.915697 -163.441326)
			(xy 113.907577 -163.496502) (xy 113.891509 -163.549909) (xy 113.867837 -163.600406) (xy 113.837064 -163.646919)
			(xy 113.799847 -163.688456) (xy 113.756979 -163.724131) (xy 113.709373 -163.753185) (xy 113.658044 -163.774997)
			(xy 113.604087 -163.789103) (xy 113.54865 -163.795203) (xy 113.492916 -163.793166) (xy 113.438073 -163.783036)
			(xy 113.385289 -163.765029) (xy 113.335689 -163.739528) (xy 113.290331 -163.707077) (xy 113.250182 -163.668368)
			(xy 113.216096 -163.624225) (xy 113.1888 -163.57559) (xy 113.168877 -163.523499) (xy 113.156751 -163.469062)
			(xy 113.15268 -163.41344) (xy 96.399604 -163.41344) (xy 96.399604 -176.808384) (xy 96.400139 -176.818373)
			(xy 96.407849 -176.836809) (xy 96.41459 -176.844198) (xy 97.796604 -178.226212) (xy 97.814686 -178.245006)
			(xy 97.845309 -178.287219) (xy 97.868949 -178.333704) (xy 97.885024 -178.383316) (xy 97.893137 -178.434832)
			(xy 97.893632 -178.460908) (xy 97.893632 -180.93944) (xy 107.97667 -180.93944) (xy 107.977165 -180.9107)
			(xy 107.985796 -180.853872) (xy 108.002853 -180.798981) (xy 108.027951 -180.74727) (xy 108.060521 -180.699908)
			(xy 108.079794 -180.678582) (xy 108.086398 -180.67147) (xy 108.09351 -180.653944) (xy 108.09351 -180.564536)
			(xy 108.086398 -180.54701) (xy 108.079794 -180.539898) (xy 108.060552 -180.518546) (xy 108.02798 -180.471192)
			(xy 108.002881 -180.419487) (xy 107.985824 -180.364601) (xy 107.977195 -180.307777) (xy 107.97667 -180.27904)
			(xy 107.977192 -180.251789) (xy 107.984943 -180.197841) (xy 108.000293 -180.145546) (xy 108.022929 -180.095968)
			(xy 108.052391 -180.050115) (xy 108.088079 -180.008923) (xy 108.129266 -179.973228) (xy 108.175113 -179.943759)
			(xy 108.224688 -179.921115) (xy 108.276981 -179.905757) (xy 108.330927 -179.897997) (xy 108.358178 -179.897532)
			(xy 108.383547 -179.897949) (xy 108.433837 -179.904672) (xy 108.482791 -179.918002) (xy 108.529547 -179.937705)
			(xy 108.573278 -179.963431) (xy 108.613213 -179.994728) (xy 108.631228 -180.012594) (xy 108.63834 -180.01996)
			(xy 108.656628 -180.027834) (xy 108.74883 -180.029104) (xy 108.767118 -180.021738) (xy 108.774484 -180.014626)
			(xy 108.795961 -179.994638) (xy 108.843891 -179.960808) (xy 108.896434 -179.934711) (xy 108.952352 -179.916962)
			(xy 109.010327 -179.907978) (xy 109.03966 -179.907438) (xy 109.06703 -179.907918) (xy 109.121209 -179.915731)
			(xy 109.173712 -179.931216) (xy 109.223459 -179.954055) (xy 109.269426 -179.983778) (xy 109.290358 -180.001418)
			(xy 109.29747 -180.007514) (xy 109.314488 -180.013864) (xy 109.399832 -180.013864) (xy 109.41685 -180.007514)
			(xy 109.423962 -180.001418) (xy 109.444895 -179.983777) (xy 109.490863 -179.954053) (xy 109.540609 -179.931207)
			(xy 109.593111 -179.915711) (xy 109.647289 -179.907882) (xy 109.702031 -179.907882) (xy 109.756209 -179.915711)
			(xy 109.808711 -179.931207) (xy 109.858457 -179.954053) (xy 109.904425 -179.983777) (xy 109.925358 -180.001418)
			(xy 109.93247 -180.007514) (xy 109.949488 -180.013864) (xy 110.034832 -180.013864) (xy 110.05185 -180.007514)
			(xy 110.058962 -180.001418) (xy 110.079895 -179.983777) (xy 110.125863 -179.954053) (xy 110.175609 -179.931207)
			(xy 110.228111 -179.915711) (xy 110.282289 -179.907882) (xy 110.337031 -179.907882) (xy 110.391209 -179.915711)
			(xy 110.443711 -179.931207) (xy 110.493457 -179.954053) (xy 110.539425 -179.983777) (xy 110.560358 -180.001418)
			(xy 110.56747 -180.007514) (xy 110.584488 -180.013864) (xy 110.669832 -180.013864) (xy 110.68685 -180.007514)
			(xy 110.693962 -180.001418) (xy 110.714895 -179.983777) (xy 110.760863 -179.954053) (xy 110.810609 -179.931207)
			(xy 110.863111 -179.915711) (xy 110.917289 -179.907882) (xy 110.972031 -179.907882) (xy 111.026209 -179.915711)
			(xy 111.078711 -179.931207) (xy 111.128457 -179.954053) (xy 111.174425 -179.983777) (xy 111.195358 -180.001418)
			(xy 111.20247 -180.007514) (xy 111.219488 -180.013864) (xy 111.304832 -180.013864) (xy 111.32185 -180.007514)
			(xy 111.328962 -180.001418) (xy 111.3499 -179.983786) (xy 111.395871 -179.954073) (xy 111.445617 -179.931235)
			(xy 111.498116 -179.915742) (xy 111.552291 -179.907913) (xy 111.57966 -179.907438) (xy 111.606914 -179.907893)
			(xy 111.660868 -179.915645) (xy 111.713168 -179.930999) (xy 111.762751 -179.95364) (xy 111.808607 -179.983108)
			(xy 111.849801 -180.018803) (xy 111.885496 -180.059998) (xy 111.914963 -180.105854) (xy 111.937603 -180.155437)
			(xy 111.952956 -180.207738) (xy 111.960708 -180.261692) (xy 111.961168 -180.288946) (xy 111.960654 -180.317685)
			(xy 111.952026 -180.374512) (xy 111.934973 -180.429402) (xy 111.90988 -180.481114) (xy 111.877314 -180.528477)
			(xy 111.858044 -180.549804) (xy 111.85144 -180.556916) (xy 111.844328 -180.574442) (xy 111.844328 -180.66385)
			(xy 111.85144 -180.681376) (xy 111.858044 -180.688488) (xy 111.877334 -180.709799) (xy 111.909898 -180.757165)
			(xy 111.934987 -180.808881) (xy 111.952033 -180.863775) (xy 111.96065 -180.920606) (xy 111.961168 -180.949346)
			(xy 111.960765 -180.9766) (xy 111.953001 -181.030553) (xy 111.937638 -181.082852) (xy 111.914989 -181.132432)
			(xy 111.885514 -181.178284) (xy 111.849814 -181.219475) (xy 111.808615 -181.255165) (xy 111.762756 -181.28463)
			(xy 111.713171 -181.307268) (xy 111.660869 -181.322619) (xy 111.606914 -181.330371) (xy 111.57966 -181.330854)
			(xy 111.552291 -181.330364) (xy 111.498112 -181.322554) (xy 111.445609 -181.307071) (xy 111.395861 -181.284234)
			(xy 111.349894 -181.254514) (xy 111.328962 -181.236874) (xy 111.32185 -181.230778) (xy 111.304832 -181.224428)
			(xy 111.219488 -181.224428) (xy 111.20247 -181.230778) (xy 111.195358 -181.236874) (xy 111.174425 -181.254515)
			(xy 111.128457 -181.284239) (xy 111.078711 -181.307085) (xy 111.026209 -181.322581) (xy 110.972031 -181.33041)
			(xy 110.917289 -181.33041) (xy 110.863111 -181.322581) (xy 110.810609 -181.307085) (xy 110.760863 -181.284239)
			(xy 110.714895 -181.254515) (xy 110.693962 -181.236874) (xy 110.68685 -181.230778) (xy 110.669832 -181.224428)
			(xy 110.584488 -181.224428) (xy 110.56747 -181.230778) (xy 110.560358 -181.236874) (xy 110.539425 -181.254515)
			(xy 110.493457 -181.284239) (xy 110.443711 -181.307085) (xy 110.391209 -181.322581) (xy 110.337031 -181.33041)
			(xy 110.282289 -181.33041) (xy 110.228111 -181.322581) (xy 110.175609 -181.307085) (xy 110.125863 -181.284239)
			(xy 110.079895 -181.254515) (xy 110.058962 -181.236874) (xy 110.05185 -181.230778) (xy 110.034832 -181.224428)
			(xy 109.949488 -181.224428) (xy 109.93247 -181.230778) (xy 109.925358 -181.236874) (xy 109.904425 -181.254515)
			(xy 109.858457 -181.284239) (xy 109.808711 -181.307085) (xy 109.756209 -181.322581) (xy 109.702031 -181.33041)
			(xy 109.647289 -181.33041) (xy 109.593111 -181.322581) (xy 109.540609 -181.307085) (xy 109.490863 -181.284239)
			(xy 109.444895 -181.254515) (xy 109.423962 -181.236874) (xy 109.41685 -181.230778) (xy 109.399832 -181.224428)
			(xy 109.314488 -181.224428) (xy 109.29747 -181.230778) (xy 109.290358 -181.236874) (xy 109.269412 -181.254495)
			(xy 109.223443 -181.284211) (xy 109.173699 -181.30705) (xy 109.121202 -181.322546) (xy 109.067028 -181.330378)
			(xy 109.03966 -181.330854) (xy 109.01429 -181.330482) (xy 108.963998 -181.32375) (xy 108.915042 -181.310411)
			(xy 108.868286 -181.290701) (xy 108.824556 -181.264966) (xy 108.784624 -181.233662) (xy 108.76661 -181.215792)
			(xy 108.759498 -181.208426) (xy 108.74121 -181.200552) (xy 108.649008 -181.199282) (xy 108.63072 -181.206648)
			(xy 108.623354 -181.21376) (xy 108.601875 -181.233744) (xy 108.553943 -181.267571) (xy 108.501401 -181.293668)
			(xy 108.445485 -181.311418) (xy 108.387511 -181.320405) (xy 108.358178 -181.320948) (xy 108.330928 -181.320443)
			(xy 108.276983 -181.312684) (xy 108.224691 -181.297328) (xy 108.175117 -181.274688) (xy 108.129268 -181.245223)
			(xy 108.088079 -181.209534) (xy 108.052388 -181.168346) (xy 108.022921 -181.122499) (xy 108.000278 -181.072926)
			(xy 107.98492 -181.020635) (xy 107.977158 -180.96669) (xy 107.97667 -180.93944) (xy 97.893632 -180.93944)
			(xy 97.893632 -181.934866) (xy 97.894164 -181.944856) (xy 97.901872 -181.963294) (xy 97.908618 -181.97068)
			(xy 100.923852 -184.985914) (xy 107.566204 -184.985914) (xy 107.570275 -184.930292) (xy 107.582401 -184.875855)
			(xy 107.602324 -184.823764) (xy 107.62962 -184.775129) (xy 107.663706 -184.730986) (xy 107.703855 -184.692277)
			(xy 107.749213 -184.659826) (xy 107.798813 -184.634325) (xy 107.851597 -184.616318) (xy 107.90644 -184.606188)
			(xy 107.962174 -184.604151) (xy 108.017611 -184.610251) (xy 108.071568 -184.624357) (xy 108.122897 -184.646169)
			(xy 108.170503 -184.675223) (xy 108.213371 -184.710898) (xy 108.250588 -184.752435) (xy 108.281361 -184.798948)
			(xy 108.305033 -184.849445) (xy 108.321101 -184.902852) (xy 108.329221 -184.958028) (xy 108.32973 -184.985914)
			(xy 108.329221 -185.0138) (xy 108.321101 -185.068976) (xy 108.305033 -185.122383) (xy 108.281361 -185.17288)
			(xy 108.250588 -185.219393) (xy 108.213371 -185.26093) (xy 108.170503 -185.296605) (xy 108.122897 -185.325659)
			(xy 108.071568 -185.347471) (xy 108.017611 -185.361577) (xy 107.962174 -185.367677) (xy 107.90644 -185.36564)
			(xy 107.851597 -185.35551) (xy 107.798813 -185.337503) (xy 107.749213 -185.312002) (xy 107.703855 -185.279551)
			(xy 107.663706 -185.240842) (xy 107.62962 -185.196699) (xy 107.602324 -185.148064) (xy 107.582401 -185.095973)
			(xy 107.570275 -185.041536) (xy 107.566204 -184.985914) (xy 100.923852 -184.985914) (xy 101.707696 -185.769758)
			(xy 101.725782 -185.78855) (xy 101.756413 -185.830762) (xy 101.780061 -185.877246) (xy 101.796144 -185.926859)
			(xy 101.804265 -185.978377) (xy 101.804724 -186.004454) (xy 101.804724 -188.2902) (xy 102.792782 -188.2902)
			(xy 102.796853 -188.234578) (xy 102.808979 -188.180141) (xy 102.828902 -188.12805) (xy 102.856198 -188.079415)
			(xy 102.890284 -188.035272) (xy 102.930433 -187.996563) (xy 102.975791 -187.964112) (xy 103.025391 -187.938611)
			(xy 103.078175 -187.920604) (xy 103.133018 -187.910474) (xy 103.188752 -187.908437) (xy 103.244189 -187.914537)
			(xy 103.298146 -187.928643) (xy 103.349475 -187.950455) (xy 103.397081 -187.979509) (xy 103.439949 -188.015184)
			(xy 103.477166 -188.056721) (xy 103.507939 -188.103234) (xy 103.531611 -188.153731) (xy 103.547679 -188.207138)
			(xy 103.555799 -188.262314) (xy 103.556308 -188.2902) (xy 103.555799 -188.318086) (xy 103.547679 -188.373262)
			(xy 103.531611 -188.426669) (xy 103.507939 -188.477166) (xy 103.477166 -188.523679) (xy 103.439949 -188.565216)
			(xy 103.397081 -188.600891) (xy 103.349475 -188.629945) (xy 103.298146 -188.651757) (xy 103.244189 -188.665863)
			(xy 103.188752 -188.671963) (xy 103.133018 -188.669926) (xy 103.078175 -188.659796) (xy 103.025391 -188.641789)
			(xy 102.975791 -188.616288) (xy 102.930433 -188.583837) (xy 102.890284 -188.545128) (xy 102.856198 -188.500985)
			(xy 102.828902 -188.45235) (xy 102.808979 -188.400259) (xy 102.796853 -188.345822) (xy 102.792782 -188.2902)
			(xy 101.804724 -188.2902) (xy 101.804724 -189.824868) (xy 101.805256 -189.834858) (xy 101.812964 -189.853296)
			(xy 101.81971 -189.860682) (xy 102.374192 -190.415164) (xy 102.3816 -190.421853) (xy 102.400036 -190.429444)
			(xy 102.410006 -190.429896) (xy 105.809034 -190.429896) (xy 105.835121 -190.430385) (xy 105.88665 -190.438555)
			(xy 105.936266 -190.454689) (xy 105.982746 -190.47839) (xy 106.024943 -190.509072) (xy 106.04373 -190.527178)
			(xy 108.486448 -192.969896) (xy 108.493135 -192.97611) (xy 108.5097 -192.983747) (xy 108.527892 -192.985089)
			(xy 108.53674 -192.98285) (xy 108.6358 -192.95364) (xy 108.654596 -192.933574) (xy 108.657644 -192.919858)
			(xy 108.664262 -192.891871) (xy 108.684779 -192.838146) (xy 108.713134 -192.788114) (xy 108.748683 -192.742909)
			(xy 108.790621 -192.703558) (xy 108.837994 -192.670954) (xy 108.889728 -192.645837) (xy 108.944648 -192.628777)
			(xy 109.001507 -192.620162) (xy 109.030262 -192.61963) (xy 109.057514 -192.620091) (xy 109.111464 -192.627842)
			(xy 109.163761 -192.643194) (xy 109.213341 -192.665832) (xy 109.259194 -192.695296) (xy 109.300387 -192.730986)
			(xy 109.336081 -192.772175) (xy 109.36555 -192.818026) (xy 109.388193 -192.867604) (xy 109.403549 -192.919899)
			(xy 109.411307 -192.973848) (xy 109.411307 -193.028352) (xy 109.403549 -193.082301) (xy 109.388193 -193.134596)
			(xy 109.36555 -193.184174) (xy 109.336081 -193.230025) (xy 109.300387 -193.271214) (xy 109.259194 -193.306904)
			(xy 109.213341 -193.336368) (xy 109.163761 -193.359006) (xy 109.111464 -193.374358) (xy 109.057514 -193.382109)
			(xy 109.030262 -193.382646) (xy 109.005641 -193.382261) (xy 108.956806 -193.375934) (xy 108.909189 -193.36339)
			(xy 108.886244 -193.354452) (xy 108.874472 -193.350363) (xy 108.849708 -193.352901) (xy 108.839 -193.359278)
			(xy 108.789216 -193.392298) (xy 108.789724 -193.41084) (xy 108.789724 -199.358504) (xy 108.790263 -199.368491)
			(xy 108.79798 -199.386919) (xy 108.80471 -199.394318) (xy 109.241082 -199.83069) (xy 109.248431 -199.837489)
			(xy 109.266894 -199.845193) (xy 109.276896 -199.845676) (xy 109.45876 -199.845676) (xy 109.46871 -199.845137)
			(xy 109.48708 -199.837469) (xy 109.501178 -199.823415) (xy 109.505496 -199.814434) (xy 109.547914 -199.714104)
			(xy 109.542326 -199.684132) (xy 109.531658 -199.67321) (xy 109.51148 -199.651712) (xy 109.477324 -199.603656)
			(xy 109.450969 -199.550918) (xy 109.433041 -199.494752) (xy 109.423968 -199.436497) (xy 109.423454 -199.407018)
			(xy 109.423939 -199.379765) (xy 109.431693 -199.325813) (xy 109.447046 -199.273514) (xy 109.469686 -199.223932)
			(xy 109.499151 -199.178077) (xy 109.534842 -199.136881) (xy 109.576032 -199.101184) (xy 109.621883 -199.071712)
			(xy 109.671462 -199.049066) (xy 109.723758 -199.033705) (xy 109.777709 -199.025943) (xy 109.804962 -199.02551)
			(xy 109.831875 -199.02597) (xy 109.885168 -199.033533) (xy 109.936868 -199.048513) (xy 109.985948 -199.070615)
			(xy 110.031433 -199.099397) (xy 110.072419 -199.134289) (xy 110.108093 -199.174596) (xy 110.137744 -199.21952)
			(xy 110.160785 -199.268166) (xy 110.169198 -199.293734) (xy 110.17123 -199.299576) (xy 110.17758 -199.310244)
			(xy 112.96015 -202.092814) (xy 112.967547 -202.099662) (xy 112.986146 -202.107392) (xy 112.996218 -202.1078)
		)
		(stroke
			(width 0)
			(type solid)
		)
		(fill yes)
		(layer "In5.Cu")
		(net "GND")
	)
	(gr_poly
		(pts
			(xy 164.178742 -291.975032) (xy 164.18881 -291.974602) (xy 164.207406 -291.966881) (xy 164.21481 -291.960046)
			(xy 164.303964 -291.870892) (xy 164.310813 -291.863495) (xy 164.31855 -291.844896) (xy 164.31895 -291.834824)
			(xy 164.31895 -289.86988) (xy 164.318522 -289.859813) (xy 164.310797 -289.841218) (xy 164.303964 -289.833812)
			(xy 164.2745 -289.804348) (xy 164.267066 -289.797632) (xy 164.248566 -289.789996) (xy 164.228552 -289.789996)
			(xy 164.210052 -289.797632) (xy 164.202618 -289.804348) (xy 164.1983 -289.808666) (xy 164.19195 -289.818826)
			(xy 164.190172 -289.824922) (xy 164.181797 -289.849678) (xy 164.15835 -289.896383) (xy 164.127849 -289.938818)
			(xy 164.091053 -289.975928) (xy 164.048878 -290.006787) (xy 164.002374 -290.030628) (xy 163.952698 -290.046858)
			(xy 163.901088 -290.055072) (xy 163.874958 -290.055554) (xy 163.848972 -290.055041) (xy 163.79764 -290.046906)
			(xy 163.748212 -290.030842) (xy 163.701905 -290.007244) (xy 163.659858 -289.976695) (xy 163.623108 -289.939945)
			(xy 163.592558 -289.897899) (xy 163.56896 -289.851592) (xy 163.552895 -289.802164) (xy 163.544759 -289.750832)
			(xy 163.54425 -289.724846) (xy 163.544717 -289.699368) (xy 163.552528 -289.649013) (xy 163.567971 -289.600453)
			(xy 163.590681 -289.554837) (xy 163.620121 -289.513245) (xy 163.655594 -289.476662) (xy 163.696258 -289.445955)
			(xy 163.718494 -289.433508) (xy 163.729162 -289.427666) (xy 163.742878 -289.408108) (xy 163.756594 -289.315398)
			(xy 163.757706 -289.303578) (xy 163.750299 -289.281052) (xy 163.74237 -289.272218) (xy 163.620196 -289.150044)
			(xy 163.612799 -289.143193) (xy 163.594201 -289.135453) (xy 163.584128 -289.135058) (xy 159.611568 -289.135058)
			(xy 159.601501 -289.134628) (xy 159.582909 -289.1269) (xy 159.5755 -289.120072) (xy 159.48279 -289.027362)
			(xy 159.475674 -289.02078) (xy 159.457914 -289.013053) (xy 159.448246 -289.012376) (xy 159.369252 -289.009836)
			(xy 159.350964 -289.01644) (xy 159.343598 -289.02279) (xy 159.325398 -289.038309) (xy 159.285367 -289.064482)
			(xy 159.24198 -289.08461) (xy 159.196144 -289.098272) (xy 159.148818 -289.105183) (xy 159.124904 -289.105594)
			(xy 159.098915 -289.105111) (xy 159.047577 -289.09698) (xy 158.998143 -289.080918) (xy 158.95183 -289.057321)
			(xy 158.909779 -289.026768) (xy 158.873025 -288.990013) (xy 158.842474 -288.947962) (xy 158.818878 -288.901648)
			(xy 158.802817 -288.852214) (xy 158.794688 -288.800875) (xy 158.794196 -288.774886) (xy 158.79464 -288.750975)
			(xy 158.801567 -288.703657) (xy 158.815231 -288.657828) (xy 158.835348 -288.614443) (xy 158.8615 -288.574404)
			(xy 158.877 -288.556192) (xy 158.88335 -288.548826) (xy 158.889954 -288.530538) (xy 158.887414 -288.451544)
			(xy 158.886696 -288.441884) (xy 158.878983 -288.424133) (xy 158.872428 -288.417) (xy 157.58287 -287.127442)
			(xy 157.575752 -287.120865) (xy 157.557992 -287.113148) (xy 157.548326 -287.112456) (xy 157.469332 -287.109916)
			(xy 157.451044 -287.11652) (xy 157.443678 -287.12287) (xy 157.425476 -287.138384) (xy 157.385442 -287.164549)
			(xy 157.342055 -287.184669) (xy 157.296221 -287.198325) (xy 157.248897 -287.205231) (xy 157.224984 -287.205674)
			(xy 157.198997 -287.20519) (xy 157.147662 -287.197056) (xy 157.098232 -287.180992) (xy 157.051923 -287.157393)
			(xy 157.009877 -287.12684) (xy 156.973128 -287.090085) (xy 156.942581 -287.048034) (xy 156.918989 -287.001722)
			(xy 156.902932 -286.952289) (xy 156.894806 -286.900954) (xy 156.894276 -286.874966) (xy 156.894721 -286.851056)
			(xy 156.90165 -286.803738) (xy 156.915316 -286.757911) (xy 156.935434 -286.714527) (xy 156.961586 -286.674489)
			(xy 156.97708 -286.656272) (xy 156.98343 -286.648906) (xy 156.990034 -286.630618) (xy 156.987494 -286.551624)
			(xy 156.986772 -286.541966) (xy 156.979052 -286.524222) (xy 156.972508 -286.51708) (xy 156.632656 -286.177228)
			(xy 156.625561 -286.170767) (xy 156.607937 -286.163214) (xy 156.598366 -286.162496) (xy 156.519118 -286.159956)
			(xy 156.50083 -286.16656) (xy 156.493718 -286.17291) (xy 156.4755 -286.18839) (xy 156.435449 -286.21449)
			(xy 156.392059 -286.234557) (xy 156.346234 -286.248173) (xy 156.298927 -286.255054) (xy 156.275024 -286.25546)
			(xy 156.249035 -286.254979) (xy 156.197696 -286.24685) (xy 156.148262 -286.230789) (xy 156.101948 -286.207192)
			(xy 156.059898 -286.176639) (xy 156.023145 -286.139884) (xy 155.992595 -286.097831) (xy 155.969001 -286.051516)
			(xy 155.952944 -286.00208) (xy 155.944819 -285.950741) (xy 155.944316 -285.924752) (xy 155.944733 -285.900848)
			(xy 155.951603 -285.853538) (xy 155.965209 -285.807708) (xy 155.985267 -285.764312) (xy 156.011359 -285.724253)
			(xy 156.026866 -285.706058) (xy 156.033216 -285.698946) (xy 156.03982 -285.680658) (xy 156.03728 -285.60141)
			(xy 156.036595 -285.591832) (xy 156.029038 -285.574195) (xy 156.022548 -285.56712) (xy 155.682696 -285.227268)
			(xy 155.675605 -285.220797) (xy 155.657981 -285.213224) (xy 155.648406 -285.212536) (xy 155.569158 -285.209996)
			(xy 155.55087 -285.2166) (xy 155.543758 -285.22295) (xy 155.525538 -285.238425) (xy 155.485485 -285.264515)
			(xy 155.442094 -285.284571) (xy 155.39627 -285.298177) (xy 155.348965 -285.305048) (xy 155.325064 -285.3055)
			(xy 155.299079 -285.304988) (xy 155.247749 -285.296853) (xy 155.198324 -285.280788) (xy 155.15202 -285.257191)
			(xy 155.109978 -285.22664) (xy 155.073231 -285.189889) (xy 155.042686 -285.147842) (xy 155.019095 -285.101535)
			(xy 155.003037 -285.052108) (xy 154.994909 -285.000777) (xy 154.994356 -284.974792) (xy 154.994777 -284.95089)
			(xy 155.001656 -284.903584) (xy 155.01527 -284.85776) (xy 155.035335 -284.814372) (xy 155.061434 -284.774321)
			(xy 155.076906 -284.756098) (xy 155.083256 -284.748986) (xy 155.08986 -284.730698) (xy 155.08732 -284.65145)
			(xy 155.086623 -284.641878) (xy 155.079045 -284.624261) (xy 155.072588 -284.61716) (xy 154.732736 -284.277308)
			(xy 154.725649 -284.270827) (xy 154.708025 -284.263234) (xy 154.698446 -284.262576) (xy 154.619198 -284.260036)
			(xy 154.60091 -284.26664) (xy 154.593798 -284.27299) (xy 154.57558 -284.28847) (xy 154.535529 -284.314569)
			(xy 154.492139 -284.334634) (xy 154.446314 -284.348248) (xy 154.399006 -284.355127) (xy 154.375104 -284.35554)
			(xy 154.349116 -284.355031) (xy 154.297779 -284.346901) (xy 154.248346 -284.330841) (xy 154.202033 -284.307246)
			(xy 154.159982 -284.276696) (xy 154.123227 -284.239945) (xy 154.092673 -284.197897) (xy 154.069073 -284.151588)
			(xy 154.053008 -284.102156) (xy 154.044872 -284.05082) (xy 154.044396 -284.024832) (xy 154.044814 -284.000929)
			(xy 154.051689 -283.953621) (xy 154.0653 -283.907795) (xy 154.085363 -283.864404) (xy 154.111461 -283.824351)
			(xy 154.126946 -283.806138) (xy 154.133296 -283.799026) (xy 154.1399 -283.780738) (xy 154.13736 -283.70149)
			(xy 154.136671 -283.691914) (xy 154.129107 -283.674284) (xy 154.122628 -283.6672) (xy 153.836116 -283.380688)
			(xy 153.828717 -283.373845) (xy 153.810118 -283.366127) (xy 153.800048 -283.365702) (xy 153.58872 -283.365702)
			(xy 153.577544 -283.368242) (xy 153.57221 -283.371036) (xy 153.549199 -283.381936) (xy 153.500665 -283.397328)
			(xy 153.450348 -283.405114) (xy 153.42489 -283.40558) (xy 153.399431 -283.40513) (xy 153.34911 -283.397353)
			(xy 153.300582 -283.381938) (xy 153.27757 -283.371036) (xy 153.272236 -283.368242) (xy 153.26106 -283.365702)
			(xy 152.63876 -283.365702) (xy 152.627584 -283.368242) (xy 152.62225 -283.371036) (xy 152.599239 -283.381939)
			(xy 152.550706 -283.397336) (xy 152.500389 -283.405129) (xy 152.47493 -283.40558) (xy 152.44947 -283.405133)
			(xy 152.399147 -283.397362) (xy 152.350616 -283.381952) (xy 152.32761 -283.371036) (xy 152.322276 -283.368242)
			(xy 152.3111 -283.365702) (xy 148.156168 -283.365702) (xy 148.145269 -283.366169) (xy 148.125406 -283.375136)
			(xy 148.117814 -283.382974) (xy 148.100191 -283.402433) (xy 148.06051 -283.436807) (xy 148.016485 -283.465406)
			(xy 147.96895 -283.48769) (xy 147.918805 -283.503235) (xy 147.867001 -283.511748) (xy 147.814519 -283.513067)
			(xy 147.762353 -283.507167) (xy 147.736814 -283.501084) (xy 147.526502 -283.711396) (xy 147.526502 -283.893514)
			(xy 149.72106 -283.893514) (xy 149.725131 -283.837892) (xy 149.737257 -283.783455) (xy 149.75718 -283.731364)
			(xy 149.784476 -283.682729) (xy 149.818562 -283.638586) (xy 149.858711 -283.599877) (xy 149.904069 -283.567426)
			(xy 149.953669 -283.541925) (xy 150.006453 -283.523918) (xy 150.061296 -283.513788) (xy 150.11703 -283.511751)
			(xy 150.172467 -283.517851) (xy 150.226424 -283.531957) (xy 150.277753 -283.553769) (xy 150.325359 -283.582823)
			(xy 150.368227 -283.618498) (xy 150.405444 -283.660035) (xy 150.436217 -283.706548) (xy 150.459889 -283.757045)
			(xy 150.475957 -283.810452) (xy 150.484077 -283.865628) (xy 150.484586 -283.893514) (xy 150.484077 -283.9214)
			(xy 150.475957 -283.976576) (xy 150.459889 -284.029983) (xy 150.450121 -284.050819) (xy 152.144732 -284.050819)
			(xy 152.144732 -283.998845) (xy 152.152862 -283.94751) (xy 152.168923 -283.89808) (xy 152.192519 -283.85177)
			(xy 152.223069 -283.809722) (xy 152.25982 -283.772971) (xy 152.301868 -283.742421) (xy 152.348178 -283.718825)
			(xy 152.397608 -283.702764) (xy 152.448943 -283.694634) (xy 152.500917 -283.694634) (xy 152.552252 -283.702764)
			(xy 152.601682 -283.718825) (xy 152.647992 -283.742421) (xy 152.69004 -283.772971) (xy 152.726791 -283.809722)
			(xy 152.757341 -283.85177) (xy 152.780937 -283.89808) (xy 152.796998 -283.94751) (xy 152.805128 -283.998845)
			(xy 152.805638 -284.024832) (xy 152.805128 -284.050819) (xy 153.094692 -284.050819) (xy 153.094692 -283.998845)
			(xy 153.102822 -283.94751) (xy 153.118883 -283.89808) (xy 153.142479 -283.85177) (xy 153.173029 -283.809722)
			(xy 153.20978 -283.772971) (xy 153.251828 -283.742421) (xy 153.298138 -283.718825) (xy 153.347568 -283.702764)
			(xy 153.398903 -283.694634) (xy 153.450877 -283.694634) (xy 153.502212 -283.702764) (xy 153.551642 -283.718825)
			(xy 153.597952 -283.742421) (xy 153.64 -283.772971) (xy 153.676751 -283.809722) (xy 153.707301 -283.85177)
			(xy 153.730897 -283.89808) (xy 153.746958 -283.94751) (xy 153.755088 -283.998845) (xy 153.755598 -284.024832)
			(xy 153.755088 -284.050819) (xy 153.746958 -284.102154) (xy 153.730897 -284.151584) (xy 153.707301 -284.197894)
			(xy 153.676751 -284.239942) (xy 153.64 -284.276693) (xy 153.597952 -284.307243) (xy 153.551642 -284.330839)
			(xy 153.502212 -284.3469) (xy 153.450877 -284.35503) (xy 153.398903 -284.35503) (xy 153.347568 -284.3469)
			(xy 153.298138 -284.330839) (xy 153.251828 -284.307243) (xy 153.20978 -284.276693) (xy 153.173029 -284.239942)
			(xy 153.142479 -284.197894) (xy 153.118883 -284.151584) (xy 153.102822 -284.102154) (xy 153.094692 -284.050819)
			(xy 152.805128 -284.050819) (xy 152.796998 -284.102154) (xy 152.780937 -284.151584) (xy 152.757341 -284.197894)
			(xy 152.726791 -284.239942) (xy 152.69004 -284.276693) (xy 152.647992 -284.307243) (xy 152.601682 -284.330839)
			(xy 152.552252 -284.3469) (xy 152.500917 -284.35503) (xy 152.448943 -284.35503) (xy 152.397608 -284.3469)
			(xy 152.348178 -284.330839) (xy 152.301868 -284.307243) (xy 152.25982 -284.276693) (xy 152.223069 -284.239942)
			(xy 152.192519 -284.197894) (xy 152.168923 -284.151584) (xy 152.152862 -284.102154) (xy 152.144732 -284.050819)
			(xy 150.450121 -284.050819) (xy 150.436217 -284.08048) (xy 150.405444 -284.126993) (xy 150.368227 -284.16853)
			(xy 150.325359 -284.204205) (xy 150.277753 -284.233259) (xy 150.226424 -284.255071) (xy 150.172467 -284.269177)
			(xy 150.11703 -284.275277) (xy 150.061296 -284.27324) (xy 150.006453 -284.26311) (xy 149.953669 -284.245103)
			(xy 149.904069 -284.219602) (xy 149.858711 -284.187151) (xy 149.818562 -284.148442) (xy 149.784476 -284.104299)
			(xy 149.75718 -284.055664) (xy 149.737257 -284.003573) (xy 149.725131 -283.949136) (xy 149.72106 -283.893514)
			(xy 147.526502 -283.893514) (xy 147.526502 -285.000779) (xy 152.144732 -285.000779) (xy 152.144732 -284.948805)
			(xy 152.152862 -284.89747) (xy 152.168923 -284.84804) (xy 152.192519 -284.80173) (xy 152.223069 -284.759682)
			(xy 152.25982 -284.722931) (xy 152.301868 -284.692381) (xy 152.348178 -284.668785) (xy 152.397608 -284.652724)
			(xy 152.448943 -284.644594) (xy 152.500917 -284.644594) (xy 152.552252 -284.652724) (xy 152.601682 -284.668785)
			(xy 152.647992 -284.692381) (xy 152.69004 -284.722931) (xy 152.726791 -284.759682) (xy 152.757341 -284.80173)
			(xy 152.780937 -284.84804) (xy 152.796998 -284.89747) (xy 152.805128 -284.948805) (xy 152.805638 -284.974792)
			(xy 152.805128 -285.000779) (xy 153.094692 -285.000779) (xy 153.094692 -284.948805) (xy 153.102822 -284.89747)
			(xy 153.118883 -284.84804) (xy 153.142479 -284.80173) (xy 153.173029 -284.759682) (xy 153.20978 -284.722931)
			(xy 153.251828 -284.692381) (xy 153.298138 -284.668785) (xy 153.347568 -284.652724) (xy 153.398903 -284.644594)
			(xy 153.450877 -284.644594) (xy 153.502212 -284.652724) (xy 153.551642 -284.668785) (xy 153.597952 -284.692381)
			(xy 153.64 -284.722931) (xy 153.676751 -284.759682) (xy 153.707301 -284.80173) (xy 153.730897 -284.84804)
			(xy 153.746958 -284.89747) (xy 153.755088 -284.948805) (xy 153.755598 -284.974792) (xy 153.755088 -285.000779)
			(xy 154.044906 -285.000779) (xy 154.044906 -284.948805) (xy 154.053036 -284.89747) (xy 154.069097 -284.84804)
			(xy 154.092693 -284.80173) (xy 154.123243 -284.759682) (xy 154.159994 -284.722931) (xy 154.202042 -284.692381)
			(xy 154.248352 -284.668785) (xy 154.297782 -284.652724) (xy 154.349117 -284.644594) (xy 154.401091 -284.644594)
			(xy 154.452426 -284.652724) (xy 154.501856 -284.668785) (xy 154.548166 -284.692381) (xy 154.590214 -284.722931)
			(xy 154.626965 -284.759682) (xy 154.657515 -284.80173) (xy 154.681111 -284.84804) (xy 154.697172 -284.89747)
			(xy 154.705302 -284.948805) (xy 154.705812 -284.974792) (xy 154.705302 -285.000779) (xy 154.697172 -285.052114)
			(xy 154.681111 -285.101544) (xy 154.657515 -285.147854) (xy 154.626965 -285.189902) (xy 154.590214 -285.226653)
			(xy 154.548166 -285.257203) (xy 154.501856 -285.280799) (xy 154.452426 -285.29686) (xy 154.401091 -285.30499)
			(xy 154.349117 -285.30499) (xy 154.297782 -285.29686) (xy 154.248352 -285.280799) (xy 154.202042 -285.257203)
			(xy 154.159994 -285.226653) (xy 154.123243 -285.189902) (xy 154.092693 -285.147854) (xy 154.069097 -285.101544)
			(xy 154.053036 -285.052114) (xy 154.044906 -285.000779) (xy 153.755088 -285.000779) (xy 153.746958 -285.052114)
			(xy 153.730897 -285.101544) (xy 153.707301 -285.147854) (xy 153.676751 -285.189902) (xy 153.64 -285.226653)
			(xy 153.597952 -285.257203) (xy 153.551642 -285.280799) (xy 153.502212 -285.29686) (xy 153.450877 -285.30499)
			(xy 153.398903 -285.30499) (xy 153.347568 -285.29686) (xy 153.298138 -285.280799) (xy 153.251828 -285.257203)
			(xy 153.20978 -285.226653) (xy 153.173029 -285.189902) (xy 153.142479 -285.147854) (xy 153.118883 -285.101544)
			(xy 153.102822 -285.052114) (xy 153.094692 -285.000779) (xy 152.805128 -285.000779) (xy 152.796998 -285.052114)
			(xy 152.780937 -285.101544) (xy 152.757341 -285.147854) (xy 152.726791 -285.189902) (xy 152.69004 -285.226653)
			(xy 152.647992 -285.257203) (xy 152.601682 -285.280799) (xy 152.552252 -285.29686) (xy 152.500917 -285.30499)
			(xy 152.448943 -285.30499) (xy 152.397608 -285.29686) (xy 152.348178 -285.280799) (xy 152.301868 -285.257203)
			(xy 152.25982 -285.226653) (xy 152.223069 -285.189902) (xy 152.192519 -285.147854) (xy 152.168923 -285.101544)
			(xy 152.152862 -285.052114) (xy 152.144732 -285.000779) (xy 147.526502 -285.000779) (xy 147.526502 -285.67507)
			(xy 147.802854 -285.951422) (xy 147.831092 -285.949847) (xy 147.887491 -285.954047) (xy 147.942652 -285.966526)
			(xy 147.995367 -285.987012) (xy 148.04448 -286.015055) (xy 148.088914 -286.050041) (xy 148.127698 -286.091204)
			(xy 148.159979 -286.13764) (xy 148.185052 -286.188334) (xy 148.194268 -286.215074) (xy 148.199348 -286.231076)
			(xy 148.226018 -286.25038) (xy 152.105106 -286.25038) (xy 152.11413 -286.250064) (xy 152.131078 -286.243869)
			(xy 152.144801 -286.232151) (xy 152.149556 -286.224472) (xy 152.199848 -286.135318) (xy 152.19934 -286.10814)
			(xy 152.191974 -286.096202) (xy 152.180634 -286.076726) (xy 152.162755 -286.035356) (xy 152.15066 -285.991941)
			(xy 152.144572 -285.947286) (xy 152.144222 -285.924752) (xy 152.144732 -285.898765) (xy 152.152862 -285.84743)
			(xy 152.168923 -285.798) (xy 152.192519 -285.75169) (xy 152.223069 -285.709642) (xy 152.25982 -285.672891)
			(xy 152.301868 -285.642341) (xy 152.348178 -285.618745) (xy 152.397608 -285.602684) (xy 152.448943 -285.594554)
			(xy 152.500917 -285.594554) (xy 152.552252 -285.602684) (xy 152.601682 -285.618745) (xy 152.647992 -285.642341)
			(xy 152.69004 -285.672891) (xy 152.726791 -285.709642) (xy 152.757341 -285.75169) (xy 152.780937 -285.798)
			(xy 152.796998 -285.84743) (xy 152.805128 -285.898765) (xy 152.805638 -285.924752) (xy 152.805172 -285.950121)
			(xy 152.805076 -285.950739) (xy 153.094692 -285.950739) (xy 153.094692 -285.898765) (xy 153.102822 -285.84743)
			(xy 153.118883 -285.798) (xy 153.142479 -285.75169) (xy 153.173029 -285.709642) (xy 153.20978 -285.672891)
			(xy 153.251828 -285.642341) (xy 153.298138 -285.618745) (xy 153.347568 -285.602684) (xy 153.398903 -285.594554)
			(xy 153.450877 -285.594554) (xy 153.502212 -285.602684) (xy 153.551642 -285.618745) (xy 153.597952 -285.642341)
			(xy 153.64 -285.672891) (xy 153.676751 -285.709642) (xy 153.707301 -285.75169) (xy 153.730897 -285.798)
			(xy 153.746958 -285.84743) (xy 153.755088 -285.898765) (xy 153.755598 -285.924752) (xy 153.755088 -285.950739)
			(xy 154.044906 -285.950739) (xy 154.044906 -285.898765) (xy 154.053036 -285.84743) (xy 154.069097 -285.798)
			(xy 154.092693 -285.75169) (xy 154.123243 -285.709642) (xy 154.159994 -285.672891) (xy 154.202042 -285.642341)
			(xy 154.248352 -285.618745) (xy 154.297782 -285.602684) (xy 154.349117 -285.594554) (xy 154.401091 -285.594554)
			(xy 154.452426 -285.602684) (xy 154.501856 -285.618745) (xy 154.548166 -285.642341) (xy 154.590214 -285.672891)
			(xy 154.626965 -285.709642) (xy 154.657515 -285.75169) (xy 154.681111 -285.798) (xy 154.697172 -285.84743)
			(xy 154.705302 -285.898765) (xy 154.705812 -285.924752) (xy 154.705302 -285.950739) (xy 154.994866 -285.950739)
			(xy 154.994866 -285.898765) (xy 155.002996 -285.84743) (xy 155.019057 -285.798) (xy 155.042653 -285.75169)
			(xy 155.073203 -285.709642) (xy 155.109954 -285.672891) (xy 155.152002 -285.642341) (xy 155.198312 -285.618745)
			(xy 155.247742 -285.602684) (xy 155.299077 -285.594554) (xy 155.351051 -285.594554) (xy 155.402386 -285.602684)
			(xy 155.451816 -285.618745) (xy 155.498126 -285.642341) (xy 155.540174 -285.672891) (xy 155.576925 -285.709642)
			(xy 155.607475 -285.75169) (xy 155.631071 -285.798) (xy 155.647132 -285.84743) (xy 155.655262 -285.898765)
			(xy 155.655772 -285.924752) (xy 155.655262 -285.950739) (xy 155.647132 -286.002074) (xy 155.631071 -286.051504)
			(xy 155.607475 -286.097814) (xy 155.576925 -286.139862) (xy 155.540174 -286.176613) (xy 155.498126 -286.207163)
			(xy 155.451816 -286.230759) (xy 155.402386 -286.24682) (xy 155.351051 -286.25495) (xy 155.299077 -286.25495)
			(xy 155.247742 -286.24682) (xy 155.198312 -286.230759) (xy 155.152002 -286.207163) (xy 155.109954 -286.176613)
			(xy 155.073203 -286.139862) (xy 155.042653 -286.097814) (xy 155.019057 -286.051504) (xy 155.002996 -286.002074)
			(xy 154.994866 -285.950739) (xy 154.705302 -285.950739) (xy 154.697172 -286.002074) (xy 154.681111 -286.051504)
			(xy 154.657515 -286.097814) (xy 154.626965 -286.139862) (xy 154.590214 -286.176613) (xy 154.548166 -286.207163)
			(xy 154.501856 -286.230759) (xy 154.452426 -286.24682) (xy 154.401091 -286.25495) (xy 154.349117 -286.25495)
			(xy 154.297782 -286.24682) (xy 154.248352 -286.230759) (xy 154.202042 -286.207163) (xy 154.159994 -286.176613)
			(xy 154.123243 -286.139862) (xy 154.092693 -286.097814) (xy 154.069097 -286.051504) (xy 154.053036 -286.002074)
			(xy 154.044906 -285.950739) (xy 153.755088 -285.950739) (xy 153.746958 -286.002074) (xy 153.730897 -286.051504)
			(xy 153.707301 -286.097814) (xy 153.676751 -286.139862) (xy 153.64 -286.176613) (xy 153.597952 -286.207163)
			(xy 153.551642 -286.230759) (xy 153.502212 -286.24682) (xy 153.450877 -286.25495) (xy 153.398903 -286.25495)
			(xy 153.347568 -286.24682) (xy 153.298138 -286.230759) (xy 153.251828 -286.207163) (xy 153.20978 -286.176613)
			(xy 153.173029 -286.139862) (xy 153.142479 -286.097814) (xy 153.118883 -286.051504) (xy 153.102822 -286.002074)
			(xy 153.094692 -285.950739) (xy 152.805076 -285.950739) (xy 152.797413 -286.000262) (xy 152.782085 -286.048629)
			(xy 152.759548 -286.094087) (xy 152.730331 -286.135569) (xy 152.69512 -286.1721) (xy 152.654742 -286.202823)
			(xy 152.632664 -286.215328) (xy 152.621742 -286.22117) (xy 152.60828 -286.240728) (xy 152.594818 -286.333438)
			(xy 152.593785 -286.345279) (xy 152.601342 -286.367784) (xy 152.609296 -286.376618) (xy 152.704292 -286.471614)
			(xy 152.711633 -286.478435) (xy 152.730096 -286.486184) (xy 152.740106 -286.4866) (xy 152.745948 -286.4866)
			(xy 152.755912 -286.487083) (xy 152.774341 -286.494666) (xy 152.781762 -286.501332) (xy 152.991058 -286.710628)
			(xy 152.999517 -286.718185) (xy 153.020881 -286.72572) (xy 153.032206 -286.725106) (xy 153.122122 -286.715708)
			(xy 153.14168 -286.70377) (xy 153.14803 -286.694118) (xy 153.163465 -286.671524) (xy 153.200521 -286.631269)
			(xy 153.243698 -286.597663) (xy 153.291817 -286.57162) (xy 153.343566 -286.553854) (xy 153.397533 -286.544846)
			(xy 153.42489 -286.544258) (xy 153.450879 -286.544767) (xy 153.502216 -286.552896) (xy 153.55165 -286.568956)
			(xy 153.597964 -286.59255) (xy 153.640016 -286.623099) (xy 153.676772 -286.65985) (xy 153.707327 -286.701899)
			(xy 153.730928 -286.748209) (xy 153.746994 -286.797641) (xy 153.75513 -286.848977) (xy 153.755598 -286.874966)
			(xy 153.755093 -286.900953) (xy 154.044906 -286.900953) (xy 154.044906 -286.848979) (xy 154.053036 -286.797644)
			(xy 154.069097 -286.748214) (xy 154.092693 -286.701904) (xy 154.123243 -286.659856) (xy 154.159994 -286.623105)
			(xy 154.202042 -286.592555) (xy 154.248352 -286.568959) (xy 154.297782 -286.552898) (xy 154.349117 -286.544768)
			(xy 154.401091 -286.544768) (xy 154.452426 -286.552898) (xy 154.501856 -286.568959) (xy 154.548166 -286.592555)
			(xy 154.590214 -286.623105) (xy 154.626965 -286.659856) (xy 154.657515 -286.701904) (xy 154.681111 -286.748214)
			(xy 154.697172 -286.797644) (xy 154.705302 -286.848979) (xy 154.705812 -286.874966) (xy 154.705302 -286.900953)
			(xy 154.994866 -286.900953) (xy 154.994866 -286.848979) (xy 155.002996 -286.797644) (xy 155.019057 -286.748214)
			(xy 155.042653 -286.701904) (xy 155.073203 -286.659856) (xy 155.109954 -286.623105) (xy 155.152002 -286.592555)
			(xy 155.198312 -286.568959) (xy 155.247742 -286.552898) (xy 155.299077 -286.544768) (xy 155.351051 -286.544768)
			(xy 155.402386 -286.552898) (xy 155.451816 -286.568959) (xy 155.498126 -286.592555) (xy 155.540174 -286.623105)
			(xy 155.576925 -286.659856) (xy 155.607475 -286.701904) (xy 155.631071 -286.748214) (xy 155.647132 -286.797644)
			(xy 155.655262 -286.848979) (xy 155.655772 -286.874966) (xy 155.655262 -286.900953) (xy 155.944826 -286.900953)
			(xy 155.944826 -286.848979) (xy 155.952956 -286.797644) (xy 155.969017 -286.748214) (xy 155.992613 -286.701904)
			(xy 156.023163 -286.659856) (xy 156.059914 -286.623105) (xy 156.101962 -286.592555) (xy 156.148272 -286.568959)
			(xy 156.197702 -286.552898) (xy 156.249037 -286.544768) (xy 156.301011 -286.544768) (xy 156.352346 -286.552898)
			(xy 156.401776 -286.568959) (xy 156.448086 -286.592555) (xy 156.490134 -286.623105) (xy 156.526885 -286.659856)
			(xy 156.557435 -286.701904) (xy 156.581031 -286.748214) (xy 156.597092 -286.797644) (xy 156.605222 -286.848979)
			(xy 156.605732 -286.874966) (xy 156.605222 -286.900953) (xy 156.597092 -286.952288) (xy 156.581031 -287.001718)
			(xy 156.557435 -287.048028) (xy 156.526885 -287.090076) (xy 156.490134 -287.126827) (xy 156.448086 -287.157377)
			(xy 156.401776 -287.180973) (xy 156.352346 -287.197034) (xy 156.301011 -287.205164) (xy 156.249037 -287.205164)
			(xy 156.197702 -287.197034) (xy 156.148272 -287.180973) (xy 156.101962 -287.157377) (xy 156.059914 -287.126827)
			(xy 156.023163 -287.090076) (xy 155.992613 -287.048028) (xy 155.969017 -287.001718) (xy 155.952956 -286.952288)
			(xy 155.944826 -286.900953) (xy 155.655262 -286.900953) (xy 155.647132 -286.952288) (xy 155.631071 -287.001718)
			(xy 155.607475 -287.048028) (xy 155.576925 -287.090076) (xy 155.540174 -287.126827) (xy 155.498126 -287.157377)
			(xy 155.451816 -287.180973) (xy 155.402386 -287.197034) (xy 155.351051 -287.205164) (xy 155.299077 -287.205164)
			(xy 155.247742 -287.197034) (xy 155.198312 -287.180973) (xy 155.152002 -287.157377) (xy 155.109954 -287.126827)
			(xy 155.073203 -287.090076) (xy 155.042653 -287.048028) (xy 155.019057 -287.001718) (xy 155.002996 -286.952288)
			(xy 154.994866 -286.900953) (xy 154.705302 -286.900953) (xy 154.697172 -286.952288) (xy 154.681111 -287.001718)
			(xy 154.657515 -287.048028) (xy 154.626965 -287.090076) (xy 154.590214 -287.126827) (xy 154.548166 -287.157377)
			(xy 154.501856 -287.180973) (xy 154.452426 -287.197034) (xy 154.401091 -287.205164) (xy 154.349117 -287.205164)
			(xy 154.297782 -287.197034) (xy 154.248352 -287.180973) (xy 154.202042 -287.157377) (xy 154.159994 -287.126827)
			(xy 154.123243 -287.090076) (xy 154.092693 -287.048028) (xy 154.069097 -287.001718) (xy 154.053036 -286.952288)
			(xy 154.044906 -286.900953) (xy 153.755093 -286.900953) (xy 153.755066 -286.902327) (xy 153.746061 -286.956304)
			(xy 153.728291 -287.00806) (xy 153.702241 -287.056185) (xy 153.668622 -287.099363) (xy 153.628353 -287.136415)
			(xy 153.605738 -287.151826) (xy 153.596086 -287.158176) (xy 153.584148 -287.177734) (xy 153.57475 -287.26765)
			(xy 153.574162 -287.278975) (xy 153.581674 -287.300341) (xy 153.589228 -287.308798) (xy 153.941272 -287.660588)
			(xy 153.949699 -287.668217) (xy 153.971068 -287.675884) (xy 153.98242 -287.67532) (xy 154.072336 -287.665922)
			(xy 154.091894 -287.653984) (xy 154.09799 -287.644332) (xy 154.113436 -287.621709) (xy 154.150521 -287.581398)
			(xy 154.193734 -287.547738) (xy 154.241895 -287.521647) (xy 154.293694 -287.503836) (xy 154.347717 -287.494792)
			(xy 154.375104 -287.494218) (xy 154.401092 -287.494701) (xy 154.452429 -287.502833) (xy 154.501861 -287.518896)
			(xy 154.548172 -287.542495) (xy 154.590221 -287.573047) (xy 154.626972 -287.609802) (xy 154.657521 -287.651854)
			(xy 154.681115 -287.698167) (xy 154.697174 -287.7476) (xy 154.705301 -287.798938) (xy 154.705812 -287.824926)
			(xy 154.705309 -287.850913) (xy 156.894786 -287.850913) (xy 156.894786 -287.798939) (xy 156.902916 -287.747604)
			(xy 156.918977 -287.698174) (xy 156.942573 -287.651864) (xy 156.973123 -287.609816) (xy 157.009874 -287.573065)
			(xy 157.051922 -287.542515) (xy 157.098232 -287.518919) (xy 157.147662 -287.502858) (xy 157.198997 -287.494728)
			(xy 157.250971 -287.494728) (xy 157.302306 -287.502858) (xy 157.351736 -287.518919) (xy 157.398046 -287.542515)
			(xy 157.440094 -287.573065) (xy 157.476845 -287.609816) (xy 157.507395 -287.651864) (xy 157.530991 -287.698174)
			(xy 157.547052 -287.747604) (xy 157.555182 -287.798939) (xy 157.555692 -287.824926) (xy 157.555182 -287.850913)
			(xy 157.547052 -287.902248) (xy 157.530991 -287.951678) (xy 157.507395 -287.997988) (xy 157.476845 -288.040036)
			(xy 157.440094 -288.076787) (xy 157.398046 -288.107337) (xy 157.351736 -288.130933) (xy 157.302306 -288.146994)
			(xy 157.250971 -288.155124) (xy 157.198997 -288.155124) (xy 157.147662 -288.146994) (xy 157.098232 -288.130933)
			(xy 157.051922 -288.107337) (xy 157.009874 -288.076787) (xy 156.973123 -288.040036) (xy 156.942573 -287.997988)
			(xy 156.918977 -287.951678) (xy 156.902916 -287.902248) (xy 156.894786 -287.850913) (xy 154.705309 -287.850913)
			(xy 154.705282 -287.85232) (xy 154.696265 -287.906359) (xy 154.678466 -287.958175) (xy 154.652371 -288.006348)
			(xy 154.618694 -288.049562) (xy 154.578356 -288.086636) (xy 154.555698 -288.10204) (xy 154.546046 -288.108136)
			(xy 154.534108 -288.127694) (xy 154.52471 -288.21761) (xy 154.524181 -288.228961) (xy 154.531821 -288.25033)
			(xy 154.539442 -288.258758) (xy 154.891232 -288.610548) (xy 154.89966 -288.618171) (xy 154.921028 -288.625819)
			(xy 154.93238 -288.62528) (xy 155.022296 -288.615882) (xy 155.041854 -288.603944) (xy 155.04795 -288.594292)
			(xy 155.063395 -288.571669) (xy 155.100479 -288.531357) (xy 155.143691 -288.497699) (xy 155.191854 -288.471612)
			(xy 155.243654 -288.453807) (xy 155.297677 -288.44477) (xy 155.325064 -288.444178) (xy 155.351056 -288.444658)
			(xy 155.402399 -288.452785) (xy 155.451839 -288.468844) (xy 155.498159 -288.49244) (xy 155.540216 -288.522991)
			(xy 155.576977 -288.559746) (xy 155.607534 -288.601799) (xy 155.631137 -288.648114) (xy 155.647203 -288.697552)
			(xy 155.655338 -288.748895) (xy 155.655772 -288.774886) (xy 155.655264 -288.800873) (xy 155.944826 -288.800873)
			(xy 155.944826 -288.748899) (xy 155.952956 -288.697564) (xy 155.969017 -288.648134) (xy 155.992613 -288.601824)
			(xy 156.023163 -288.559776) (xy 156.059914 -288.523025) (xy 156.101962 -288.492475) (xy 156.148272 -288.468879)
			(xy 156.197702 -288.452818) (xy 156.249037 -288.444688) (xy 156.301011 -288.444688) (xy 156.352346 -288.452818)
			(xy 156.401776 -288.468879) (xy 156.448086 -288.492475) (xy 156.490134 -288.523025) (xy 156.526885 -288.559776)
			(xy 156.557435 -288.601824) (xy 156.581031 -288.648134) (xy 156.597092 -288.697564) (xy 156.605222 -288.748899)
			(xy 156.605732 -288.774886) (xy 156.605222 -288.800873) (xy 156.894786 -288.800873) (xy 156.894786 -288.748899)
			(xy 156.902916 -288.697564) (xy 156.918977 -288.648134) (xy 156.942573 -288.601824) (xy 156.973123 -288.559776)
			(xy 157.009874 -288.523025) (xy 157.051922 -288.492475) (xy 157.098232 -288.468879) (xy 157.147662 -288.452818)
			(xy 157.198997 -288.444688) (xy 157.250971 -288.444688) (xy 157.302306 -288.452818) (xy 157.351736 -288.468879)
			(xy 157.398046 -288.492475) (xy 157.440094 -288.523025) (xy 157.476845 -288.559776) (xy 157.507395 -288.601824)
			(xy 157.530991 -288.648134) (xy 157.547052 -288.697564) (xy 157.555182 -288.748899) (xy 157.555692 -288.774886)
			(xy 157.555182 -288.800873) (xy 157.844746 -288.800873) (xy 157.844746 -288.748899) (xy 157.852876 -288.697564)
			(xy 157.868937 -288.648134) (xy 157.892533 -288.601824) (xy 157.923083 -288.559776) (xy 157.959834 -288.523025)
			(xy 158.001882 -288.492475) (xy 158.048192 -288.468879) (xy 158.097622 -288.452818) (xy 158.148957 -288.444688)
			(xy 158.200931 -288.444688) (xy 158.252266 -288.452818) (xy 158.301696 -288.468879) (xy 158.348006 -288.492475)
			(xy 158.390054 -288.523025) (xy 158.426805 -288.559776) (xy 158.457355 -288.601824) (xy 158.480951 -288.648134)
			(xy 158.497012 -288.697564) (xy 158.505142 -288.748899) (xy 158.505652 -288.774886) (xy 158.505142 -288.800873)
			(xy 158.497012 -288.852208) (xy 158.480951 -288.901638) (xy 158.457355 -288.947948) (xy 158.426805 -288.989996)
			(xy 158.390054 -289.026747) (xy 158.348006 -289.057297) (xy 158.301696 -289.080893) (xy 158.252266 -289.096954)
			(xy 158.200931 -289.105084) (xy 158.148957 -289.105084) (xy 158.097622 -289.096954) (xy 158.048192 -289.080893)
			(xy 158.001882 -289.057297) (xy 157.959834 -289.026747) (xy 157.923083 -288.989996) (xy 157.892533 -288.947948)
			(xy 157.868937 -288.901638) (xy 157.852876 -288.852208) (xy 157.844746 -288.800873) (xy 157.555182 -288.800873)
			(xy 157.547052 -288.852208) (xy 157.530991 -288.901638) (xy 157.507395 -288.947948) (xy 157.476845 -288.989996)
			(xy 157.440094 -289.026747) (xy 157.398046 -289.057297) (xy 157.351736 -289.080893) (xy 157.302306 -289.096954)
			(xy 157.250971 -289.105084) (xy 157.198997 -289.105084) (xy 157.147662 -289.096954) (xy 157.098232 -289.080893)
			(xy 157.051922 -289.057297) (xy 157.009874 -289.026747) (xy 156.973123 -288.989996) (xy 156.942573 -288.947948)
			(xy 156.918977 -288.901638) (xy 156.902916 -288.852208) (xy 156.894786 -288.800873) (xy 156.605222 -288.800873)
			(xy 156.597092 -288.852208) (xy 156.581031 -288.901638) (xy 156.557435 -288.947948) (xy 156.526885 -288.989996)
			(xy 156.490134 -289.026747) (xy 156.448086 -289.057297) (xy 156.401776 -289.080893) (xy 156.352346 -289.096954)
			(xy 156.301011 -289.105084) (xy 156.249037 -289.105084) (xy 156.197702 -289.096954) (xy 156.148272 -289.080893)
			(xy 156.101962 -289.057297) (xy 156.059914 -289.026747) (xy 156.023163 -288.989996) (xy 155.992613 -288.947948)
			(xy 155.969017 -288.901638) (xy 155.952956 -288.852208) (xy 155.944826 -288.800873) (xy 155.655264 -288.800873)
			(xy 155.655237 -288.802278) (xy 155.646213 -288.856314) (xy 155.62841 -288.908124) (xy 155.602313 -288.956293)
			(xy 155.568637 -288.999504) (xy 155.528302 -289.036576) (xy 155.505658 -289.052) (xy 155.496006 -289.058096)
			(xy 155.484068 -289.077654) (xy 155.47467 -289.16757) (xy 155.474154 -289.178917) (xy 155.481807 -289.200271)
			(xy 155.489402 -289.208718) (xy 155.841192 -289.560508) (xy 155.849621 -289.568131) (xy 155.870988 -289.575786)
			(xy 155.88234 -289.57524) (xy 155.972256 -289.565842) (xy 155.991814 -289.553904) (xy 155.99791 -289.544252)
			(xy 156.013356 -289.521629) (xy 156.05044 -289.481318) (xy 156.093653 -289.447658) (xy 156.141815 -289.421569)
			(xy 156.193614 -289.40376) (xy 156.247637 -289.394718) (xy 156.275024 -289.394138) (xy 156.301011 -289.394623)
			(xy 156.352344 -289.402757) (xy 156.401772 -289.418822) (xy 156.448079 -289.442422) (xy 156.490123 -289.472976)
			(xy 156.52687 -289.50973) (xy 156.557414 -289.551781) (xy 156.581004 -289.598093) (xy 156.597059 -289.647524)
			(xy 156.605183 -289.698859) (xy 156.605732 -289.724846) (xy 156.605227 -289.750833) (xy 156.894786 -289.750833)
			(xy 156.894786 -289.698859) (xy 156.902916 -289.647524) (xy 156.918977 -289.598094) (xy 156.942573 -289.551784)
			(xy 156.973123 -289.509736) (xy 157.009874 -289.472985) (xy 157.051922 -289.442435) (xy 157.098232 -289.418839)
			(xy 157.147662 -289.402778) (xy 157.198997 -289.394648) (xy 157.250971 -289.394648) (xy 157.302306 -289.402778)
			(xy 157.351736 -289.418839) (xy 157.398046 -289.442435) (xy 157.440094 -289.472985) (xy 157.476845 -289.509736)
			(xy 157.507395 -289.551784) (xy 157.530991 -289.598094) (xy 157.547052 -289.647524) (xy 157.555182 -289.698859)
			(xy 157.555692 -289.724846) (xy 157.555182 -289.750833) (xy 157.844746 -289.750833) (xy 157.844746 -289.698859)
			(xy 157.852876 -289.647524) (xy 157.868937 -289.598094) (xy 157.892533 -289.551784) (xy 157.923083 -289.509736)
			(xy 157.959834 -289.472985) (xy 158.001882 -289.442435) (xy 158.048192 -289.418839) (xy 158.097622 -289.402778)
			(xy 158.148957 -289.394648) (xy 158.200931 -289.394648) (xy 158.252266 -289.402778) (xy 158.301696 -289.418839)
			(xy 158.348006 -289.442435) (xy 158.390054 -289.472985) (xy 158.426805 -289.509736) (xy 158.457355 -289.551784)
			(xy 158.480951 -289.598094) (xy 158.497012 -289.647524) (xy 158.505142 -289.698859) (xy 158.505652 -289.724846)
			(xy 158.505142 -289.750833) (xy 158.794706 -289.750833) (xy 158.794706 -289.698859) (xy 158.802836 -289.647524)
			(xy 158.818897 -289.598094) (xy 158.842493 -289.551784) (xy 158.873043 -289.509736) (xy 158.909794 -289.472985)
			(xy 158.951842 -289.442435) (xy 158.998152 -289.418839) (xy 159.047582 -289.402778) (xy 159.098917 -289.394648)
			(xy 159.150891 -289.394648) (xy 159.202226 -289.402778) (xy 159.251656 -289.418839) (xy 159.297966 -289.442435)
			(xy 159.340014 -289.472985) (xy 159.376765 -289.509736) (xy 159.407315 -289.551784) (xy 159.430911 -289.598094)
			(xy 159.446972 -289.647524) (xy 159.455102 -289.698859) (xy 159.455612 -289.724846) (xy 159.455102 -289.750833)
			(xy 159.744666 -289.750833) (xy 159.744666 -289.698859) (xy 159.752796 -289.647524) (xy 159.768857 -289.598094)
			(xy 159.792453 -289.551784) (xy 159.823003 -289.509736) (xy 159.859754 -289.472985) (xy 159.901802 -289.442435)
			(xy 159.948112 -289.418839) (xy 159.997542 -289.402778) (xy 160.048877 -289.394648) (xy 160.100851 -289.394648)
			(xy 160.152186 -289.402778) (xy 160.201616 -289.418839) (xy 160.247926 -289.442435) (xy 160.289974 -289.472985)
			(xy 160.326725 -289.509736) (xy 160.357275 -289.551784) (xy 160.380871 -289.598094) (xy 160.396932 -289.647524)
			(xy 160.405062 -289.698859) (xy 160.405572 -289.724846) (xy 160.405062 -289.750833) (xy 160.69488 -289.750833)
			(xy 160.69488 -289.698859) (xy 160.70301 -289.647524) (xy 160.719071 -289.598094) (xy 160.742667 -289.551784)
			(xy 160.773217 -289.509736) (xy 160.809968 -289.472985) (xy 160.852016 -289.442435) (xy 160.898326 -289.418839)
			(xy 160.947756 -289.402778) (xy 160.999091 -289.394648) (xy 161.051065 -289.394648) (xy 161.1024 -289.402778)
			(xy 161.15183 -289.418839) (xy 161.19814 -289.442435) (xy 161.240188 -289.472985) (xy 161.276939 -289.509736)
			(xy 161.307489 -289.551784) (xy 161.331085 -289.598094) (xy 161.347146 -289.647524) (xy 161.355276 -289.698859)
			(xy 161.355786 -289.724846) (xy 161.355276 -289.750833) (xy 161.64484 -289.750833) (xy 161.64484 -289.698859)
			(xy 161.65297 -289.647524) (xy 161.669031 -289.598094) (xy 161.692627 -289.551784) (xy 161.723177 -289.509736)
			(xy 161.759928 -289.472985) (xy 161.801976 -289.442435) (xy 161.848286 -289.418839) (xy 161.897716 -289.402778)
			(xy 161.949051 -289.394648) (xy 162.001025 -289.394648) (xy 162.05236 -289.402778) (xy 162.10179 -289.418839)
			(xy 162.1481 -289.442435) (xy 162.190148 -289.472985) (xy 162.226899 -289.509736) (xy 162.257449 -289.551784)
			(xy 162.281045 -289.598094) (xy 162.297106 -289.647524) (xy 162.305236 -289.698859) (xy 162.305746 -289.724846)
			(xy 162.305236 -289.750833) (xy 162.5948 -289.750833) (xy 162.5948 -289.698859) (xy 162.60293 -289.647524)
			(xy 162.618991 -289.598094) (xy 162.642587 -289.551784) (xy 162.673137 -289.509736) (xy 162.709888 -289.472985)
			(xy 162.751936 -289.442435) (xy 162.798246 -289.418839) (xy 162.847676 -289.402778) (xy 162.899011 -289.394648)
			(xy 162.950985 -289.394648) (xy 163.00232 -289.402778) (xy 163.05175 -289.418839) (xy 163.09806 -289.442435)
			(xy 163.140108 -289.472985) (xy 163.176859 -289.509736) (xy 163.207409 -289.551784) (xy 163.231005 -289.598094)
			(xy 163.247066 -289.647524) (xy 163.255196 -289.698859) (xy 163.255706 -289.724846) (xy 163.255196 -289.750833)
			(xy 163.247066 -289.802168) (xy 163.231005 -289.851598) (xy 163.207409 -289.897908) (xy 163.176859 -289.939956)
			(xy 163.140108 -289.976707) (xy 163.09806 -290.007257) (xy 163.05175 -290.030853) (xy 163.00232 -290.046914)
			(xy 162.950985 -290.055044) (xy 162.899011 -290.055044) (xy 162.847676 -290.046914) (xy 162.798246 -290.030853)
			(xy 162.751936 -290.007257) (xy 162.709888 -289.976707) (xy 162.673137 -289.939956) (xy 162.642587 -289.897908)
			(xy 162.618991 -289.851598) (xy 162.60293 -289.802168) (xy 162.5948 -289.750833) (xy 162.305236 -289.750833)
			(xy 162.297106 -289.802168) (xy 162.281045 -289.851598) (xy 162.257449 -289.897908) (xy 162.226899 -289.939956)
			(xy 162.190148 -289.976707) (xy 162.1481 -290.007257) (xy 162.10179 -290.030853) (xy 162.05236 -290.046914)
			(xy 162.001025 -290.055044) (xy 161.949051 -290.055044) (xy 161.897716 -290.046914) (xy 161.848286 -290.030853)
			(xy 161.801976 -290.007257) (xy 161.759928 -289.976707) (xy 161.723177 -289.939956) (xy 161.692627 -289.897908)
			(xy 161.669031 -289.851598) (xy 161.65297 -289.802168) (xy 161.64484 -289.750833) (xy 161.355276 -289.750833)
			(xy 161.347146 -289.802168) (xy 161.331085 -289.851598) (xy 161.307489 -289.897908) (xy 161.276939 -289.939956)
			(xy 161.240188 -289.976707) (xy 161.19814 -290.007257) (xy 161.15183 -290.030853) (xy 161.1024 -290.046914)
			(xy 161.051065 -290.055044) (xy 160.999091 -290.055044) (xy 160.947756 -290.046914) (xy 160.898326 -290.030853)
			(xy 160.852016 -290.007257) (xy 160.809968 -289.976707) (xy 160.773217 -289.939956) (xy 160.742667 -289.897908)
			(xy 160.719071 -289.851598) (xy 160.70301 -289.802168) (xy 160.69488 -289.750833) (xy 160.405062 -289.750833)
			(xy 160.396932 -289.802168) (xy 160.380871 -289.851598) (xy 160.357275 -289.897908) (xy 160.326725 -289.939956)
			(xy 160.289974 -289.976707) (xy 160.247926 -290.007257) (xy 160.201616 -290.030853) (xy 160.152186 -290.046914)
			(xy 160.100851 -290.055044) (xy 160.048877 -290.055044) (xy 159.997542 -290.046914) (xy 159.948112 -290.030853)
			(xy 159.901802 -290.007257) (xy 159.859754 -289.976707) (xy 159.823003 -289.939956) (xy 159.792453 -289.897908)
			(xy 159.768857 -289.851598) (xy 159.752796 -289.802168) (xy 159.744666 -289.750833) (xy 159.455102 -289.750833)
			(xy 159.446972 -289.802168) (xy 159.430911 -289.851598) (xy 159.407315 -289.897908) (xy 159.376765 -289.939956)
			(xy 159.340014 -289.976707) (xy 159.297966 -290.007257) (xy 159.251656 -290.030853) (xy 159.202226 -290.046914)
			(xy 159.150891 -290.055044) (xy 159.098917 -290.055044) (xy 159.047582 -290.046914) (xy 158.998152 -290.030853)
			(xy 158.951842 -290.007257) (xy 158.909794 -289.976707) (xy 158.873043 -289.939956) (xy 158.842493 -289.897908)
			(xy 158.818897 -289.851598) (xy 158.802836 -289.802168) (xy 158.794706 -289.750833) (xy 158.505142 -289.750833)
			(xy 158.497012 -289.802168) (xy 158.480951 -289.851598) (xy 158.457355 -289.897908) (xy 158.426805 -289.939956)
			(xy 158.390054 -289.976707) (xy 158.348006 -290.007257) (xy 158.301696 -290.030853) (xy 158.252266 -290.046914)
			(xy 158.200931 -290.055044) (xy 158.148957 -290.055044) (xy 158.097622 -290.046914) (xy 158.048192 -290.030853)
			(xy 158.001882 -290.007257) (xy 157.959834 -289.976707) (xy 157.923083 -289.939956) (xy 157.892533 -289.897908)
			(xy 157.868937 -289.851598) (xy 157.852876 -289.802168) (xy 157.844746 -289.750833) (xy 157.555182 -289.750833)
			(xy 157.547052 -289.802168) (xy 157.530991 -289.851598) (xy 157.507395 -289.897908) (xy 157.476845 -289.939956)
			(xy 157.440094 -289.976707) (xy 157.398046 -290.007257) (xy 157.351736 -290.030853) (xy 157.302306 -290.046914)
			(xy 157.250971 -290.055044) (xy 157.198997 -290.055044) (xy 157.147662 -290.046914) (xy 157.098232 -290.030853)
			(xy 157.051922 -290.007257) (xy 157.009874 -289.976707) (xy 156.973123 -289.939956) (xy 156.942573 -289.897908)
			(xy 156.918977 -289.851598) (xy 156.902916 -289.802168) (xy 156.894786 -289.750833) (xy 156.605227 -289.750833)
			(xy 156.6052 -289.752239) (xy 156.596181 -289.806278) (xy 156.57838 -289.858091) (xy 156.552285 -289.906263)
			(xy 156.518609 -289.949476) (xy 156.478271 -289.986549) (xy 156.455618 -290.00196) (xy 156.445966 -290.008056)
			(xy 156.434028 -290.027614) (xy 156.42463 -290.11753) (xy 156.424106 -290.128879) (xy 156.431754 -290.150241)
			(xy 156.439362 -290.158678) (xy 156.791152 -290.510468) (xy 156.799582 -290.518085) (xy 156.820949 -290.525721)
			(xy 156.8323 -290.5252) (xy 156.922216 -290.515802) (xy 156.941774 -290.503864) (xy 156.94787 -290.494212)
			(xy 156.963315 -290.471588) (xy 157.000398 -290.431277) (xy 157.043611 -290.39762) (xy 157.091774 -290.371533)
			(xy 157.143574 -290.35373) (xy 157.197597 -290.344696) (xy 157.224984 -290.344098) (xy 157.250974 -290.34458)
			(xy 157.302314 -290.352709) (xy 157.35175 -290.36877) (xy 157.398065 -290.392367) (xy 157.440119 -290.422919)
			(xy 157.476874 -290.459674) (xy 157.507428 -290.501726) (xy 157.531026 -290.54804) (xy 157.547088 -290.597476)
			(xy 157.555219 -290.648816) (xy 157.555692 -290.674806) (xy 157.55519 -290.700793) (xy 157.844746 -290.700793)
			(xy 157.844746 -290.648819) (xy 157.852876 -290.597484) (xy 157.868937 -290.548054) (xy 157.892533 -290.501744)
			(xy 157.923083 -290.459696) (xy 157.959834 -290.422945) (xy 158.001882 -290.392395) (xy 158.048192 -290.368799)
			(xy 158.097622 -290.352738) (xy 158.148957 -290.344608) (xy 158.200931 -290.344608) (xy 158.252266 -290.352738)
			(xy 158.301696 -290.368799) (xy 158.348006 -290.392395) (xy 158.390054 -290.422945) (xy 158.426805 -290.459696)
			(xy 158.457355 -290.501744) (xy 158.480951 -290.548054) (xy 158.497012 -290.597484) (xy 158.505142 -290.648819)
			(xy 158.505652 -290.674806) (xy 158.505142 -290.700793) (xy 158.794706 -290.700793) (xy 158.794706 -290.648819)
			(xy 158.802836 -290.597484) (xy 158.818897 -290.548054) (xy 158.842493 -290.501744) (xy 158.873043 -290.459696)
			(xy 158.909794 -290.422945) (xy 158.951842 -290.392395) (xy 158.998152 -290.368799) (xy 159.047582 -290.352738)
			(xy 159.098917 -290.344608) (xy 159.150891 -290.344608) (xy 159.202226 -290.352738) (xy 159.251656 -290.368799)
			(xy 159.297966 -290.392395) (xy 159.340014 -290.422945) (xy 159.376765 -290.459696) (xy 159.407315 -290.501744)
			(xy 159.430911 -290.548054) (xy 159.446972 -290.597484) (xy 159.455102 -290.648819) (xy 159.455612 -290.674806)
			(xy 159.455102 -290.700793) (xy 159.744666 -290.700793) (xy 159.744666 -290.648819) (xy 159.752796 -290.597484)
			(xy 159.768857 -290.548054) (xy 159.792453 -290.501744) (xy 159.823003 -290.459696) (xy 159.859754 -290.422945)
			(xy 159.901802 -290.392395) (xy 159.948112 -290.368799) (xy 159.997542 -290.352738) (xy 160.048877 -290.344608)
			(xy 160.100851 -290.344608) (xy 160.152186 -290.352738) (xy 160.201616 -290.368799) (xy 160.247926 -290.392395)
			(xy 160.289974 -290.422945) (xy 160.326725 -290.459696) (xy 160.357275 -290.501744) (xy 160.380871 -290.548054)
			(xy 160.396932 -290.597484) (xy 160.405062 -290.648819) (xy 160.405572 -290.674806) (xy 160.405062 -290.700793)
			(xy 160.69488 -290.700793) (xy 160.69488 -290.648819) (xy 160.70301 -290.597484) (xy 160.719071 -290.548054)
			(xy 160.742667 -290.501744) (xy 160.773217 -290.459696) (xy 160.809968 -290.422945) (xy 160.852016 -290.392395)
			(xy 160.898326 -290.368799) (xy 160.947756 -290.352738) (xy 160.999091 -290.344608) (xy 161.051065 -290.344608)
			(xy 161.1024 -290.352738) (xy 161.15183 -290.368799) (xy 161.19814 -290.392395) (xy 161.240188 -290.422945)
			(xy 161.276939 -290.459696) (xy 161.307489 -290.501744) (xy 161.331085 -290.548054) (xy 161.347146 -290.597484)
			(xy 161.355276 -290.648819) (xy 161.355786 -290.674806) (xy 161.355276 -290.700793) (xy 161.64484 -290.700793)
			(xy 161.64484 -290.648819) (xy 161.65297 -290.597484) (xy 161.669031 -290.548054) (xy 161.692627 -290.501744)
			(xy 161.723177 -290.459696) (xy 161.759928 -290.422945) (xy 161.801976 -290.392395) (xy 161.848286 -290.368799)
			(xy 161.897716 -290.352738) (xy 161.949051 -290.344608) (xy 162.001025 -290.344608) (xy 162.05236 -290.352738)
			(xy 162.10179 -290.368799) (xy 162.1481 -290.392395) (xy 162.190148 -290.422945) (xy 162.226899 -290.459696)
			(xy 162.257449 -290.501744) (xy 162.281045 -290.548054) (xy 162.297106 -290.597484) (xy 162.305236 -290.648819)
			(xy 162.305746 -290.674806) (xy 162.305236 -290.700793) (xy 162.5948 -290.700793) (xy 162.5948 -290.648819)
			(xy 162.60293 -290.597484) (xy 162.618991 -290.548054) (xy 162.642587 -290.501744) (xy 162.673137 -290.459696)
			(xy 162.709888 -290.422945) (xy 162.751936 -290.392395) (xy 162.798246 -290.368799) (xy 162.847676 -290.352738)
			(xy 162.899011 -290.344608) (xy 162.950985 -290.344608) (xy 163.00232 -290.352738) (xy 163.05175 -290.368799)
			(xy 163.09806 -290.392395) (xy 163.140108 -290.422945) (xy 163.176859 -290.459696) (xy 163.207409 -290.501744)
			(xy 163.231005 -290.548054) (xy 163.247066 -290.597484) (xy 163.255196 -290.648819) (xy 163.255706 -290.674806)
			(xy 163.255196 -290.700793) (xy 163.54476 -290.700793) (xy 163.54476 -290.648819) (xy 163.55289 -290.597484)
			(xy 163.568951 -290.548054) (xy 163.592547 -290.501744) (xy 163.623097 -290.459696) (xy 163.659848 -290.422945)
			(xy 163.701896 -290.392395) (xy 163.748206 -290.368799) (xy 163.797636 -290.352738) (xy 163.848971 -290.344608)
			(xy 163.900945 -290.344608) (xy 163.95228 -290.352738) (xy 164.00171 -290.368799) (xy 164.04802 -290.392395)
			(xy 164.090068 -290.422945) (xy 164.126819 -290.459696) (xy 164.157369 -290.501744) (xy 164.180965 -290.548054)
			(xy 164.197026 -290.597484) (xy 164.205156 -290.648819) (xy 164.205666 -290.674806) (xy 164.205156 -290.700793)
			(xy 164.197026 -290.752128) (xy 164.180965 -290.801558) (xy 164.157369 -290.847868) (xy 164.126819 -290.889916)
			(xy 164.090068 -290.926667) (xy 164.04802 -290.957217) (xy 164.00171 -290.980813) (xy 163.95228 -290.996874)
			(xy 163.900945 -291.005004) (xy 163.848971 -291.005004) (xy 163.797636 -290.996874) (xy 163.748206 -290.980813)
			(xy 163.701896 -290.957217) (xy 163.659848 -290.926667) (xy 163.623097 -290.889916) (xy 163.592547 -290.847868)
			(xy 163.568951 -290.801558) (xy 163.55289 -290.752128) (xy 163.54476 -290.700793) (xy 163.255196 -290.700793)
			(xy 163.247066 -290.752128) (xy 163.231005 -290.801558) (xy 163.207409 -290.847868) (xy 163.176859 -290.889916)
			(xy 163.140108 -290.926667) (xy 163.09806 -290.957217) (xy 163.05175 -290.980813) (xy 163.00232 -290.996874)
			(xy 162.950985 -291.005004) (xy 162.899011 -291.005004) (xy 162.847676 -290.996874) (xy 162.798246 -290.980813)
			(xy 162.751936 -290.957217) (xy 162.709888 -290.926667) (xy 162.673137 -290.889916) (xy 162.642587 -290.847868)
			(xy 162.618991 -290.801558) (xy 162.60293 -290.752128) (xy 162.5948 -290.700793) (xy 162.305236 -290.700793)
			(xy 162.297106 -290.752128) (xy 162.281045 -290.801558) (xy 162.257449 -290.847868) (xy 162.226899 -290.889916)
			(xy 162.190148 -290.926667) (xy 162.1481 -290.957217) (xy 162.10179 -290.980813) (xy 162.05236 -290.996874)
			(xy 162.001025 -291.005004) (xy 161.949051 -291.005004) (xy 161.897716 -290.996874) (xy 161.848286 -290.980813)
			(xy 161.801976 -290.957217) (xy 161.759928 -290.926667) (xy 161.723177 -290.889916) (xy 161.692627 -290.847868)
			(xy 161.669031 -290.801558) (xy 161.65297 -290.752128) (xy 161.64484 -290.700793) (xy 161.355276 -290.700793)
			(xy 161.347146 -290.752128) (xy 161.331085 -290.801558) (xy 161.307489 -290.847868) (xy 161.276939 -290.889916)
			(xy 161.240188 -290.926667) (xy 161.19814 -290.957217) (xy 161.15183 -290.980813) (xy 161.1024 -290.996874)
			(xy 161.051065 -291.005004) (xy 160.999091 -291.005004) (xy 160.947756 -290.996874) (xy 160.898326 -290.980813)
			(xy 160.852016 -290.957217) (xy 160.809968 -290.926667) (xy 160.773217 -290.889916) (xy 160.742667 -290.847868)
			(xy 160.719071 -290.801558) (xy 160.70301 -290.752128) (xy 160.69488 -290.700793) (xy 160.405062 -290.700793)
			(xy 160.396932 -290.752128) (xy 160.380871 -290.801558) (xy 160.357275 -290.847868) (xy 160.326725 -290.889916)
			(xy 160.289974 -290.926667) (xy 160.247926 -290.957217) (xy 160.201616 -290.980813) (xy 160.152186 -290.996874)
			(xy 160.100851 -291.005004) (xy 160.048877 -291.005004) (xy 159.997542 -290.996874) (xy 159.948112 -290.980813)
			(xy 159.901802 -290.957217) (xy 159.859754 -290.926667) (xy 159.823003 -290.889916) (xy 159.792453 -290.847868)
			(xy 159.768857 -290.801558) (xy 159.752796 -290.752128) (xy 159.744666 -290.700793) (xy 159.455102 -290.700793)
			(xy 159.446972 -290.752128) (xy 159.430911 -290.801558) (xy 159.407315 -290.847868) (xy 159.376765 -290.889916)
			(xy 159.340014 -290.926667) (xy 159.297966 -290.957217) (xy 159.251656 -290.980813) (xy 159.202226 -290.996874)
			(xy 159.150891 -291.005004) (xy 159.098917 -291.005004) (xy 159.047582 -290.996874) (xy 158.998152 -290.980813)
			(xy 158.951842 -290.957217) (xy 158.909794 -290.926667) (xy 158.873043 -290.889916) (xy 158.842493 -290.847868)
			(xy 158.818897 -290.801558) (xy 158.802836 -290.752128) (xy 158.794706 -290.700793) (xy 158.505142 -290.700793)
			(xy 158.497012 -290.752128) (xy 158.480951 -290.801558) (xy 158.457355 -290.847868) (xy 158.426805 -290.889916)
			(xy 158.390054 -290.926667) (xy 158.348006 -290.957217) (xy 158.301696 -290.980813) (xy 158.252266 -290.996874)
			(xy 158.200931 -291.005004) (xy 158.148957 -291.005004) (xy 158.097622 -290.996874) (xy 158.048192 -290.980813)
			(xy 158.001882 -290.957217) (xy 157.959834 -290.926667) (xy 157.923083 -290.889916) (xy 157.892533 -290.847868)
			(xy 157.868937 -290.801558) (xy 157.852876 -290.752128) (xy 157.844746 -290.700793) (xy 157.55519 -290.700793)
			(xy 157.555163 -290.7022) (xy 157.546149 -290.756241) (xy 157.528351 -290.808058) (xy 157.502257 -290.856233)
			(xy 157.46858 -290.899448) (xy 157.428241 -290.936522) (xy 157.405578 -290.95192) (xy 157.395926 -290.958016)
			(xy 157.383988 -290.977574) (xy 157.37459 -291.06749) (xy 157.374057 -291.078843) (xy 157.381688 -291.10022)
			(xy 157.389322 -291.108638) (xy 157.741112 -291.460428) (xy 157.749543 -291.468045) (xy 157.770909 -291.475689)
			(xy 157.78226 -291.47516) (xy 157.872176 -291.465762) (xy 157.891734 -291.453824) (xy 157.89783 -291.444172)
			(xy 157.913275 -291.421549) (xy 157.95036 -291.381237) (xy 157.993572 -291.347579) (xy 158.041735 -291.32149)
			(xy 158.093534 -291.303683) (xy 158.147557 -291.294644) (xy 158.174944 -291.294058) (xy 158.200021 -291.294526)
			(xy 158.249597 -291.302109) (xy 158.297459 -291.317095) (xy 158.342508 -291.33914) (xy 158.383709 -291.367737)
			(xy 158.420117 -291.40223) (xy 158.450897 -291.441828) (xy 158.475341 -291.485621) (xy 158.48457 -291.508942)
			(xy 158.490158 -291.523674) (xy 158.51632 -291.541708) (xy 158.783528 -291.541708) (xy 158.80969 -291.523674)
			(xy 158.815278 -291.508942) (xy 158.824484 -291.485608) (xy 158.848924 -291.441806) (xy 158.879702 -291.4022)
			(xy 158.916112 -291.367699) (xy 158.957318 -291.339097) (xy 159.002372 -291.31705) (xy 159.050241 -291.302065)
			(xy 159.099824 -291.294485) (xy 159.149984 -291.294485) (xy 159.199567 -291.302065) (xy 159.247436 -291.31705)
			(xy 159.29249 -291.339097) (xy 159.333696 -291.367699) (xy 159.370106 -291.4022) (xy 159.400884 -291.441806)
			(xy 159.425324 -291.485608) (xy 159.43453 -291.508942) (xy 159.440118 -291.523674) (xy 159.46628 -291.541708)
			(xy 159.733488 -291.541708) (xy 159.75965 -291.523674) (xy 159.765238 -291.508942) (xy 159.774444 -291.485608)
			(xy 159.798884 -291.441806) (xy 159.829662 -291.4022) (xy 159.866072 -291.367699) (xy 159.907278 -291.339097)
			(xy 159.952332 -291.31705) (xy 160.000201 -291.302065) (xy 160.049784 -291.294485) (xy 160.099944 -291.294485)
			(xy 160.149527 -291.302065) (xy 160.197396 -291.31705) (xy 160.24245 -291.339097) (xy 160.283656 -291.367699)
			(xy 160.320066 -291.4022) (xy 160.350844 -291.441806) (xy 160.375284 -291.485608) (xy 160.38449 -291.508942)
			(xy 160.390078 -291.523674) (xy 160.41624 -291.541708) (xy 160.683702 -291.541708) (xy 160.709864 -291.523674)
			(xy 160.715452 -291.508942) (xy 160.724658 -291.485608) (xy 160.749098 -291.441806) (xy 160.779876 -291.4022)
			(xy 160.816286 -291.367699) (xy 160.857492 -291.339097) (xy 160.902546 -291.31705) (xy 160.950415 -291.302065)
			(xy 160.999998 -291.294485) (xy 161.050158 -291.294485) (xy 161.099741 -291.302065) (xy 161.14761 -291.31705)
			(xy 161.192664 -291.339097) (xy 161.23387 -291.367699) (xy 161.27028 -291.4022) (xy 161.301058 -291.441806)
			(xy 161.325498 -291.485608) (xy 161.334704 -291.508942) (xy 161.340292 -291.523674) (xy 161.366454 -291.541708)
			(xy 161.633662 -291.541708) (xy 161.659824 -291.523674) (xy 161.665412 -291.508942) (xy 161.674618 -291.485608)
			(xy 161.699058 -291.441806) (xy 161.729836 -291.4022) (xy 161.766246 -291.367699) (xy 161.807452 -291.339097)
			(xy 161.852506 -291.31705) (xy 161.900375 -291.302065) (xy 161.949958 -291.294485) (xy 162.000118 -291.294485)
			(xy 162.049701 -291.302065) (xy 162.09757 -291.31705) (xy 162.142624 -291.339097) (xy 162.18383 -291.367699)
			(xy 162.22024 -291.4022) (xy 162.251018 -291.441806) (xy 162.275458 -291.485608) (xy 162.284664 -291.508942)
			(xy 162.290252 -291.523674) (xy 162.316414 -291.541708) (xy 162.583622 -291.541708) (xy 162.609784 -291.523674)
			(xy 162.615372 -291.508942) (xy 162.624574 -291.485606) (xy 162.649008 -291.441799) (xy 162.679784 -291.402189)
			(xy 162.716194 -291.367688) (xy 162.757401 -291.339087) (xy 162.802459 -291.317044) (xy 162.850331 -291.302066)
			(xy 162.899918 -291.294498) (xy 162.924998 -291.294058) (xy 162.950986 -291.294567) (xy 163.002323 -291.302697)
			(xy 163.051756 -291.318758) (xy 163.098068 -291.342353) (xy 163.140119 -291.372902) (xy 163.176874 -291.409653)
			(xy 163.207428 -291.451701) (xy 163.231028 -291.498011) (xy 163.247094 -291.547442) (xy 163.25523 -291.598778)
			(xy 163.255706 -291.624766) (xy 163.255706 -291.6301) (xy 163.255452 -291.640514) (xy 163.263326 -291.659564)
			(xy 163.563808 -291.960046) (xy 163.571151 -291.966861) (xy 163.589614 -291.974599) (xy 163.599622 -291.975032)
		)
		(stroke
			(width 0)
			(type solid)
		)
		(fill yes)
		(layer "In5.Cu")
		(net "PCEPLL7_VDDA18_PEX1")
	)
	(gr_poly
		(pts
			(xy 396.378684 -291.975032) (xy 396.388734 -291.974526) (xy 396.407294 -291.966804) (xy 396.414752 -291.960046)
			(xy 396.503906 -291.870892) (xy 396.510751 -291.863493) (xy 396.518481 -291.844895) (xy 396.518892 -291.834824)
			(xy 396.518892 -289.86988) (xy 396.518465 -289.859812) (xy 396.510745 -289.841213) (xy 396.503906 -289.833812)
			(xy 396.474442 -289.804348) (xy 396.467008 -289.797632) (xy 396.448508 -289.789996) (xy 396.428494 -289.789996)
			(xy 396.409994 -289.797632) (xy 396.40256 -289.804348) (xy 396.398242 -289.808666) (xy 396.391892 -289.818826)
			(xy 396.390114 -289.824922) (xy 396.381739 -289.84968) (xy 396.358294 -289.896388) (xy 396.327794 -289.938827)
			(xy 396.290999 -289.975941) (xy 396.248824 -290.006806) (xy 396.202319 -290.030653) (xy 396.152643 -290.046888)
			(xy 396.101031 -290.055108) (xy 396.0749 -290.055554) (xy 396.048912 -290.055044) (xy 395.997574 -290.046914)
			(xy 395.948141 -290.030854) (xy 395.901828 -290.007259) (xy 395.859776 -289.97671) (xy 395.82302 -289.939959)
			(xy 395.792465 -289.897911) (xy 395.768864 -289.851602) (xy 395.752797 -289.80217) (xy 395.744659 -289.750834)
			(xy 395.744192 -289.724846) (xy 395.744658 -289.699367) (xy 395.752468 -289.64901) (xy 395.76791 -289.600448)
			(xy 395.790618 -289.554829) (xy 395.820055 -289.513233) (xy 395.855525 -289.476645) (xy 395.896187 -289.445931)
			(xy 395.918436 -289.433508) (xy 395.929104 -289.427666) (xy 395.94282 -289.408108) (xy 395.956536 -289.315398)
			(xy 395.957648 -289.303577) (xy 395.950246 -289.281048) (xy 395.942312 -289.272218) (xy 395.820138 -289.150044)
			(xy 395.812738 -289.143203) (xy 395.79414 -289.135484) (xy 395.78407 -289.135058) (xy 391.81151 -289.135058)
			(xy 391.80144 -289.134635) (xy 391.782837 -289.126919) (xy 391.775442 -289.120072) (xy 391.682732 -289.027362)
			(xy 391.675613 -289.020789) (xy 391.657852 -289.013082) (xy 391.648188 -289.012376) (xy 391.569194 -289.009836)
			(xy 391.550906 -289.01644) (xy 391.54354 -289.02279) (xy 391.525339 -289.038305) (xy 391.485306 -289.064472)
			(xy 391.441919 -289.084592) (xy 391.396084 -289.098246) (xy 391.348759 -289.105149) (xy 391.324846 -289.105594)
			(xy 391.298855 -289.105114) (xy 391.247511 -289.096989) (xy 391.198072 -289.08093) (xy 391.151753 -289.057335)
			(xy 391.109696 -289.026783) (xy 391.072938 -288.990028) (xy 391.042382 -288.947974) (xy 391.018782 -288.901658)
			(xy 391.002719 -288.85222) (xy 390.994588 -288.800877) (xy 390.994138 -288.774886) (xy 390.994581 -288.750975)
			(xy 391.001507 -288.703656) (xy 391.01517 -288.657825) (xy 391.035284 -288.614438) (xy 391.061432 -288.574396)
			(xy 391.076942 -288.556192) (xy 391.083292 -288.548826) (xy 391.089896 -288.530538) (xy 391.087356 -288.451544)
			(xy 391.086639 -288.441883) (xy 391.078931 -288.424128) (xy 391.07237 -288.417) (xy 389.782812 -287.127442)
			(xy 389.775691 -287.120874) (xy 389.75793 -287.113177) (xy 389.748268 -287.112456) (xy 389.669274 -287.109916)
			(xy 389.650986 -287.11652) (xy 389.64362 -287.12287) (xy 389.625419 -287.138386) (xy 389.585386 -287.164556)
			(xy 389.542 -287.184682) (xy 389.496165 -287.198344) (xy 389.44884 -287.205256) (xy 389.424926 -287.205674)
			(xy 389.398936 -287.205193) (xy 389.347597 -287.197065) (xy 389.298161 -287.181004) (xy 389.251846 -287.157407)
			(xy 389.209794 -287.126855) (xy 389.17304 -287.0901) (xy 389.142489 -287.048047) (xy 389.118893 -287.001732)
			(xy 389.102834 -286.952296) (xy 389.094707 -286.900956) (xy 389.094218 -286.874966) (xy 389.094663 -286.851056)
			(xy 389.101593 -286.803739) (xy 389.11526 -286.757913) (xy 389.135381 -286.71453) (xy 389.161535 -286.674494)
			(xy 389.177022 -286.656272) (xy 389.183372 -286.648906) (xy 389.189976 -286.630618) (xy 389.187436 -286.551624)
			(xy 389.186715 -286.541965) (xy 389.178999 -286.524217) (xy 389.17245 -286.51708) (xy 388.832598 -286.177228)
			(xy 388.825505 -286.170761) (xy 388.807882 -286.163193) (xy 388.798308 -286.162496) (xy 388.71906 -286.159956)
			(xy 388.700772 -286.16656) (xy 388.69366 -286.17291) (xy 388.675441 -286.188387) (xy 388.635388 -286.21448)
			(xy 388.591998 -286.234539) (xy 388.546173 -286.248147) (xy 388.498867 -286.25502) (xy 388.474966 -286.25546)
			(xy 388.44898 -286.254974) (xy 388.397648 -286.246839) (xy 388.348221 -286.230773) (xy 388.301916 -286.207172)
			(xy 388.259873 -286.176619) (xy 388.223128 -286.139864) (xy 388.192585 -286.097814) (xy 388.168996 -286.051503)
			(xy 388.152942 -286.002072) (xy 388.144819 -285.950738) (xy 388.144258 -285.924752) (xy 388.144675 -285.900849)
			(xy 388.151546 -285.853539) (xy 388.165153 -285.807709) (xy 388.185213 -285.764315) (xy 388.211308 -285.724259)
			(xy 388.226808 -285.706058) (xy 388.233158 -285.698946) (xy 388.239762 -285.680658) (xy 388.237222 -285.60141)
			(xy 388.236535 -285.591833) (xy 388.228972 -285.574202) (xy 388.22249 -285.56712) (xy 387.882638 -285.227268)
			(xy 387.875549 -285.220791) (xy 387.857926 -285.213203) (xy 387.848348 -285.212536) (xy 387.7691 -285.209996)
			(xy 387.750812 -285.2166) (xy 387.7437 -285.22295) (xy 387.725481 -285.238427) (xy 387.685428 -285.264522)
			(xy 387.642039 -285.284584) (xy 387.596214 -285.298196) (xy 387.548908 -285.305073) (xy 387.525006 -285.3055)
			(xy 387.499017 -285.305017) (xy 387.447678 -285.296887) (xy 387.398243 -285.280825) (xy 387.35193 -285.257227)
			(xy 387.309878 -285.226675) (xy 387.273124 -285.189921) (xy 387.242572 -285.147869) (xy 387.218974 -285.101555)
			(xy 387.202913 -285.05212) (xy 387.194783 -285.000781) (xy 387.194298 -284.974792) (xy 387.194719 -284.95089)
			(xy 387.201597 -284.903583) (xy 387.215209 -284.857758) (xy 387.235271 -284.814367) (xy 387.261367 -284.774314)
			(xy 387.276848 -284.756098) (xy 387.283198 -284.748986) (xy 387.289802 -284.730698) (xy 387.287262 -284.65145)
			(xy 387.286566 -284.641877) (xy 387.278993 -284.624257) (xy 387.27253 -284.61716) (xy 386.932678 -284.277308)
			(xy 386.925588 -284.270836) (xy 386.907963 -284.263262) (xy 386.898388 -284.262576) (xy 386.81914 -284.260036)
			(xy 386.800852 -284.26664) (xy 386.79374 -284.27299) (xy 386.775523 -284.288472) (xy 386.735473 -284.314577)
			(xy 386.692083 -284.334647) (xy 386.646258 -284.348267) (xy 386.598949 -284.355152) (xy 386.575046 -284.35554)
			(xy 386.549053 -284.35506) (xy 386.497707 -284.346935) (xy 386.448265 -284.330877) (xy 386.401943 -284.307282)
			(xy 386.359882 -284.276732) (xy 386.323119 -284.239977) (xy 386.292558 -284.197924) (xy 386.268953 -284.151607)
			(xy 386.252883 -284.102169) (xy 386.244746 -284.050824) (xy 386.244338 -284.024832) (xy 386.244756 -284.000929)
			(xy 386.25163 -283.95362) (xy 386.265239 -283.907792) (xy 386.285299 -283.864399) (xy 386.311394 -283.824344)
			(xy 386.326888 -283.806138) (xy 386.333238 -283.799026) (xy 386.339842 -283.780738) (xy 386.337302 -283.70149)
			(xy 386.336611 -283.691915) (xy 386.329041 -283.67429) (xy 386.32257 -283.6672) (xy 386.036058 -283.380688)
			(xy 386.028662 -283.373838) (xy 386.010062 -283.366105) (xy 385.99999 -283.365702) (xy 385.788662 -283.365702)
			(xy 385.777486 -283.368242) (xy 385.772152 -283.371036) (xy 385.749142 -283.381939) (xy 385.700608 -283.397337)
			(xy 385.650291 -283.40513) (xy 385.624832 -283.40558) (xy 385.599372 -283.405133) (xy 385.549049 -283.397362)
			(xy 385.500517 -283.381953) (xy 385.477512 -283.371036) (xy 385.472178 -283.368242) (xy 385.461002 -283.365702)
			(xy 384.838702 -283.365702) (xy 384.827526 -283.368242) (xy 384.822192 -283.371036) (xy 384.799181 -283.381935)
			(xy 384.750647 -283.397324) (xy 384.70033 -283.405108) (xy 384.674872 -283.40558) (xy 384.649411 -283.405137)
			(xy 384.599086 -283.397371) (xy 384.550551 -283.381967) (xy 384.527552 -283.371036) (xy 384.522218 -283.368242)
			(xy 384.511042 -283.365702) (xy 380.35611 -283.365702) (xy 380.345207 -283.366161) (xy 380.325331 -283.375117)
			(xy 380.317756 -283.382974) (xy 380.300132 -283.40243) (xy 380.26045 -283.436797) (xy 380.216425 -283.465389)
			(xy 380.168891 -283.487665) (xy 380.118748 -283.503204) (xy 380.066947 -283.511709) (xy 380.014468 -283.513021)
			(xy 379.962306 -283.507114) (xy 379.936756 -283.501084) (xy 379.726444 -283.711396) (xy 379.726444 -283.893514)
			(xy 381.921002 -283.893514) (xy 381.925073 -283.837892) (xy 381.937199 -283.783455) (xy 381.957122 -283.731364)
			(xy 381.984418 -283.682729) (xy 382.018504 -283.638586) (xy 382.058653 -283.599877) (xy 382.104011 -283.567426)
			(xy 382.153611 -283.541925) (xy 382.206395 -283.523918) (xy 382.261238 -283.513788) (xy 382.316972 -283.511751)
			(xy 382.372409 -283.517851) (xy 382.426366 -283.531957) (xy 382.477695 -283.553769) (xy 382.525301 -283.582823)
			(xy 382.568169 -283.618498) (xy 382.605386 -283.660035) (xy 382.636159 -283.706548) (xy 382.659831 -283.757045)
			(xy 382.675899 -283.810452) (xy 382.684019 -283.865628) (xy 382.684528 -283.893514) (xy 382.684019 -283.9214)
			(xy 382.675899 -283.976576) (xy 382.659831 -284.029983) (xy 382.650063 -284.050819) (xy 384.344674 -284.050819)
			(xy 384.344674 -283.998845) (xy 384.352804 -283.94751) (xy 384.368865 -283.89808) (xy 384.392461 -283.85177)
			(xy 384.423011 -283.809722) (xy 384.459762 -283.772971) (xy 384.50181 -283.742421) (xy 384.54812 -283.718825)
			(xy 384.59755 -283.702764) (xy 384.648885 -283.694634) (xy 384.700859 -283.694634) (xy 384.752194 -283.702764)
			(xy 384.801624 -283.718825) (xy 384.847934 -283.742421) (xy 384.889982 -283.772971) (xy 384.926733 -283.809722)
			(xy 384.957283 -283.85177) (xy 384.980879 -283.89808) (xy 384.99694 -283.94751) (xy 385.00507 -283.998845)
			(xy 385.00558 -284.024832) (xy 385.00507 -284.050819) (xy 385.294634 -284.050819) (xy 385.294634 -283.998845)
			(xy 385.302764 -283.94751) (xy 385.318825 -283.89808) (xy 385.342421 -283.85177) (xy 385.372971 -283.809722)
			(xy 385.409722 -283.772971) (xy 385.45177 -283.742421) (xy 385.49808 -283.718825) (xy 385.54751 -283.702764)
			(xy 385.598845 -283.694634) (xy 385.650819 -283.694634) (xy 385.702154 -283.702764) (xy 385.751584 -283.718825)
			(xy 385.797894 -283.742421) (xy 385.839942 -283.772971) (xy 385.876693 -283.809722) (xy 385.907243 -283.85177)
			(xy 385.930839 -283.89808) (xy 385.9469 -283.94751) (xy 385.95503 -283.998845) (xy 385.95554 -284.024832)
			(xy 385.95503 -284.050819) (xy 385.9469 -284.102154) (xy 385.930839 -284.151584) (xy 385.907243 -284.197894)
			(xy 385.876693 -284.239942) (xy 385.839942 -284.276693) (xy 385.797894 -284.307243) (xy 385.751584 -284.330839)
			(xy 385.702154 -284.3469) (xy 385.650819 -284.35503) (xy 385.598845 -284.35503) (xy 385.54751 -284.3469)
			(xy 385.49808 -284.330839) (xy 385.45177 -284.307243) (xy 385.409722 -284.276693) (xy 385.372971 -284.239942)
			(xy 385.342421 -284.197894) (xy 385.318825 -284.151584) (xy 385.302764 -284.102154) (xy 385.294634 -284.050819)
			(xy 385.00507 -284.050819) (xy 384.99694 -284.102154) (xy 384.980879 -284.151584) (xy 384.957283 -284.197894)
			(xy 384.926733 -284.239942) (xy 384.889982 -284.276693) (xy 384.847934 -284.307243) (xy 384.801624 -284.330839)
			(xy 384.752194 -284.3469) (xy 384.700859 -284.35503) (xy 384.648885 -284.35503) (xy 384.59755 -284.3469)
			(xy 384.54812 -284.330839) (xy 384.50181 -284.307243) (xy 384.459762 -284.276693) (xy 384.423011 -284.239942)
			(xy 384.392461 -284.197894) (xy 384.368865 -284.151584) (xy 384.352804 -284.102154) (xy 384.344674 -284.050819)
			(xy 382.650063 -284.050819) (xy 382.636159 -284.08048) (xy 382.605386 -284.126993) (xy 382.568169 -284.16853)
			(xy 382.525301 -284.204205) (xy 382.477695 -284.233259) (xy 382.426366 -284.255071) (xy 382.372409 -284.269177)
			(xy 382.316972 -284.275277) (xy 382.261238 -284.27324) (xy 382.206395 -284.26311) (xy 382.153611 -284.245103)
			(xy 382.104011 -284.219602) (xy 382.058653 -284.187151) (xy 382.018504 -284.148442) (xy 381.984418 -284.104299)
			(xy 381.957122 -284.055664) (xy 381.937199 -284.003573) (xy 381.925073 -283.949136) (xy 381.921002 -283.893514)
			(xy 379.726444 -283.893514) (xy 379.726444 -285.000779) (xy 384.344674 -285.000779) (xy 384.344674 -284.948805)
			(xy 384.352804 -284.89747) (xy 384.368865 -284.84804) (xy 384.392461 -284.80173) (xy 384.423011 -284.759682)
			(xy 384.459762 -284.722931) (xy 384.50181 -284.692381) (xy 384.54812 -284.668785) (xy 384.59755 -284.652724)
			(xy 384.648885 -284.644594) (xy 384.700859 -284.644594) (xy 384.752194 -284.652724) (xy 384.801624 -284.668785)
			(xy 384.847934 -284.692381) (xy 384.889982 -284.722931) (xy 384.926733 -284.759682) (xy 384.957283 -284.80173)
			(xy 384.980879 -284.84804) (xy 384.99694 -284.89747) (xy 385.00507 -284.948805) (xy 385.00558 -284.974792)
			(xy 385.00507 -285.000779) (xy 385.294634 -285.000779) (xy 385.294634 -284.948805) (xy 385.302764 -284.89747)
			(xy 385.318825 -284.84804) (xy 385.342421 -284.80173) (xy 385.372971 -284.759682) (xy 385.409722 -284.722931)
			(xy 385.45177 -284.692381) (xy 385.49808 -284.668785) (xy 385.54751 -284.652724) (xy 385.598845 -284.644594)
			(xy 385.650819 -284.644594) (xy 385.702154 -284.652724) (xy 385.751584 -284.668785) (xy 385.797894 -284.692381)
			(xy 385.839942 -284.722931) (xy 385.876693 -284.759682) (xy 385.907243 -284.80173) (xy 385.930839 -284.84804)
			(xy 385.9469 -284.89747) (xy 385.95503 -284.948805) (xy 385.95554 -284.974792) (xy 385.95503 -285.000779)
			(xy 386.244848 -285.000779) (xy 386.244848 -284.948805) (xy 386.252978 -284.89747) (xy 386.269039 -284.84804)
			(xy 386.292635 -284.80173) (xy 386.323185 -284.759682) (xy 386.359936 -284.722931) (xy 386.401984 -284.692381)
			(xy 386.448294 -284.668785) (xy 386.497724 -284.652724) (xy 386.549059 -284.644594) (xy 386.601033 -284.644594)
			(xy 386.652368 -284.652724) (xy 386.701798 -284.668785) (xy 386.748108 -284.692381) (xy 386.790156 -284.722931)
			(xy 386.826907 -284.759682) (xy 386.857457 -284.80173) (xy 386.881053 -284.84804) (xy 386.897114 -284.89747)
			(xy 386.905244 -284.948805) (xy 386.905754 -284.974792) (xy 386.905244 -285.000779) (xy 386.897114 -285.052114)
			(xy 386.881053 -285.101544) (xy 386.857457 -285.147854) (xy 386.826907 -285.189902) (xy 386.790156 -285.226653)
			(xy 386.748108 -285.257203) (xy 386.701798 -285.280799) (xy 386.652368 -285.29686) (xy 386.601033 -285.30499)
			(xy 386.549059 -285.30499) (xy 386.497724 -285.29686) (xy 386.448294 -285.280799) (xy 386.401984 -285.257203)
			(xy 386.359936 -285.226653) (xy 386.323185 -285.189902) (xy 386.292635 -285.147854) (xy 386.269039 -285.101544)
			(xy 386.252978 -285.052114) (xy 386.244848 -285.000779) (xy 385.95503 -285.000779) (xy 385.9469 -285.052114)
			(xy 385.930839 -285.101544) (xy 385.907243 -285.147854) (xy 385.876693 -285.189902) (xy 385.839942 -285.226653)
			(xy 385.797894 -285.257203) (xy 385.751584 -285.280799) (xy 385.702154 -285.29686) (xy 385.650819 -285.30499)
			(xy 385.598845 -285.30499) (xy 385.54751 -285.29686) (xy 385.49808 -285.280799) (xy 385.45177 -285.257203)
			(xy 385.409722 -285.226653) (xy 385.372971 -285.189902) (xy 385.342421 -285.147854) (xy 385.318825 -285.101544)
			(xy 385.302764 -285.052114) (xy 385.294634 -285.000779) (xy 385.00507 -285.000779) (xy 384.99694 -285.052114)
			(xy 384.980879 -285.101544) (xy 384.957283 -285.147854) (xy 384.926733 -285.189902) (xy 384.889982 -285.226653)
			(xy 384.847934 -285.257203) (xy 384.801624 -285.280799) (xy 384.752194 -285.29686) (xy 384.700859 -285.30499)
			(xy 384.648885 -285.30499) (xy 384.59755 -285.29686) (xy 384.54812 -285.280799) (xy 384.50181 -285.257203)
			(xy 384.459762 -285.226653) (xy 384.423011 -285.189902) (xy 384.392461 -285.147854) (xy 384.368865 -285.101544)
			(xy 384.352804 -285.052114) (xy 384.344674 -285.000779) (xy 379.726444 -285.000779) (xy 379.726444 -285.67507)
			(xy 380.002796 -285.951422) (xy 380.031037 -285.949843) (xy 380.087441 -285.954035) (xy 380.142609 -285.966509)
			(xy 380.195331 -285.98699) (xy 380.244451 -286.01503) (xy 380.288893 -286.050016) (xy 380.327683 -286.091178)
			(xy 380.359971 -286.137617) (xy 380.385049 -286.188314) (xy 380.39421 -286.215074) (xy 380.39929 -286.231076)
			(xy 380.42596 -286.25038) (xy 384.305048 -286.25038) (xy 384.314078 -286.250073) (xy 384.331041 -286.243891)
			(xy 384.34478 -286.232178) (xy 384.349498 -286.224472) (xy 384.39979 -286.135318) (xy 384.399282 -286.10814)
			(xy 384.391916 -286.096202) (xy 384.380575 -286.076726) (xy 384.362693 -286.035357) (xy 384.350596 -285.991942)
			(xy 384.344508 -285.947287) (xy 384.344164 -285.924752) (xy 384.344674 -285.898765) (xy 384.352804 -285.84743)
			(xy 384.368865 -285.798) (xy 384.392461 -285.75169) (xy 384.423011 -285.709642) (xy 384.459762 -285.672891)
			(xy 384.50181 -285.642341) (xy 384.54812 -285.618745) (xy 384.59755 -285.602684) (xy 384.648885 -285.594554)
			(xy 384.700859 -285.594554) (xy 384.752194 -285.602684) (xy 384.801624 -285.618745) (xy 384.847934 -285.642341)
			(xy 384.889982 -285.672891) (xy 384.926733 -285.709642) (xy 384.957283 -285.75169) (xy 384.980879 -285.798)
			(xy 384.99694 -285.84743) (xy 385.00507 -285.898765) (xy 385.00558 -285.924752) (xy 385.005114 -285.950122)
			(xy 385.005019 -285.950739) (xy 385.294634 -285.950739) (xy 385.294634 -285.898765) (xy 385.302764 -285.84743)
			(xy 385.318825 -285.798) (xy 385.342421 -285.75169) (xy 385.372971 -285.709642) (xy 385.409722 -285.672891)
			(xy 385.45177 -285.642341) (xy 385.49808 -285.618745) (xy 385.54751 -285.602684) (xy 385.598845 -285.594554)
			(xy 385.650819 -285.594554) (xy 385.702154 -285.602684) (xy 385.751584 -285.618745) (xy 385.797894 -285.642341)
			(xy 385.839942 -285.672891) (xy 385.876693 -285.709642) (xy 385.907243 -285.75169) (xy 385.930839 -285.798)
			(xy 385.9469 -285.84743) (xy 385.95503 -285.898765) (xy 385.95554 -285.924752) (xy 385.95503 -285.950739)
			(xy 386.244848 -285.950739) (xy 386.244848 -285.898765) (xy 386.252978 -285.84743) (xy 386.269039 -285.798)
			(xy 386.292635 -285.75169) (xy 386.323185 -285.709642) (xy 386.359936 -285.672891) (xy 386.401984 -285.642341)
			(xy 386.448294 -285.618745) (xy 386.497724 -285.602684) (xy 386.549059 -285.594554) (xy 386.601033 -285.594554)
			(xy 386.652368 -285.602684) (xy 386.701798 -285.618745) (xy 386.748108 -285.642341) (xy 386.790156 -285.672891)
			(xy 386.826907 -285.709642) (xy 386.857457 -285.75169) (xy 386.881053 -285.798) (xy 386.897114 -285.84743)
			(xy 386.905244 -285.898765) (xy 386.905754 -285.924752) (xy 386.905244 -285.950739) (xy 387.194808 -285.950739)
			(xy 387.194808 -285.898765) (xy 387.202938 -285.84743) (xy 387.218999 -285.798) (xy 387.242595 -285.75169)
			(xy 387.273145 -285.709642) (xy 387.309896 -285.672891) (xy 387.351944 -285.642341) (xy 387.398254 -285.618745)
			(xy 387.447684 -285.602684) (xy 387.499019 -285.594554) (xy 387.550993 -285.594554) (xy 387.602328 -285.602684)
			(xy 387.651758 -285.618745) (xy 387.698068 -285.642341) (xy 387.740116 -285.672891) (xy 387.776867 -285.709642)
			(xy 387.807417 -285.75169) (xy 387.831013 -285.798) (xy 387.847074 -285.84743) (xy 387.855204 -285.898765)
			(xy 387.855714 -285.924752) (xy 387.855204 -285.950739) (xy 387.847074 -286.002074) (xy 387.831013 -286.051504)
			(xy 387.807417 -286.097814) (xy 387.776867 -286.139862) (xy 387.740116 -286.176613) (xy 387.698068 -286.207163)
			(xy 387.651758 -286.230759) (xy 387.602328 -286.24682) (xy 387.550993 -286.25495) (xy 387.499019 -286.25495)
			(xy 387.447684 -286.24682) (xy 387.398254 -286.230759) (xy 387.351944 -286.207163) (xy 387.309896 -286.176613)
			(xy 387.273145 -286.139862) (xy 387.242595 -286.097814) (xy 387.218999 -286.051504) (xy 387.202938 -286.002074)
			(xy 387.194808 -285.950739) (xy 386.905244 -285.950739) (xy 386.897114 -286.002074) (xy 386.881053 -286.051504)
			(xy 386.857457 -286.097814) (xy 386.826907 -286.139862) (xy 386.790156 -286.176613) (xy 386.748108 -286.207163)
			(xy 386.701798 -286.230759) (xy 386.652368 -286.24682) (xy 386.601033 -286.25495) (xy 386.549059 -286.25495)
			(xy 386.497724 -286.24682) (xy 386.448294 -286.230759) (xy 386.401984 -286.207163) (xy 386.359936 -286.176613)
			(xy 386.323185 -286.139862) (xy 386.292635 -286.097814) (xy 386.269039 -286.051504) (xy 386.252978 -286.002074)
			(xy 386.244848 -285.950739) (xy 385.95503 -285.950739) (xy 385.9469 -286.002074) (xy 385.930839 -286.051504)
			(xy 385.907243 -286.097814) (xy 385.876693 -286.139862) (xy 385.839942 -286.176613) (xy 385.797894 -286.207163)
			(xy 385.751584 -286.230759) (xy 385.702154 -286.24682) (xy 385.650819 -286.25495) (xy 385.598845 -286.25495)
			(xy 385.54751 -286.24682) (xy 385.49808 -286.230759) (xy 385.45177 -286.207163) (xy 385.409722 -286.176613)
			(xy 385.372971 -286.139862) (xy 385.342421 -286.097814) (xy 385.318825 -286.051504) (xy 385.302764 -286.002074)
			(xy 385.294634 -285.950739) (xy 385.005019 -285.950739) (xy 384.997356 -286.000264) (xy 384.982029 -286.048633)
			(xy 384.959494 -286.094093) (xy 384.930279 -286.135578) (xy 384.89507 -286.172112) (xy 384.854694 -286.20284)
			(xy 384.832606 -286.215328) (xy 384.821684 -286.22117) (xy 384.808222 -286.240728) (xy 384.79476 -286.333438)
			(xy 384.793727 -286.345278) (xy 384.80129 -286.367779) (xy 384.809238 -286.376618) (xy 384.904234 -286.471614)
			(xy 384.911577 -286.478429) (xy 384.93004 -286.486162) (xy 384.940048 -286.4866) (xy 384.94589 -286.4866)
			(xy 384.955858 -286.487072) (xy 384.974302 -286.494641) (xy 384.981704 -286.501332) (xy 385.191 -286.710628)
			(xy 385.199461 -286.718178) (xy 385.220824 -286.725695) (xy 385.232148 -286.725106) (xy 385.322064 -286.715708)
			(xy 385.341622 -286.70377) (xy 385.347972 -286.694118) (xy 385.363406 -286.671521) (xy 385.40046 -286.631259)
			(xy 385.443635 -286.597645) (xy 385.491754 -286.571594) (xy 385.543504 -286.553819) (xy 385.597473 -286.544802)
			(xy 385.624832 -286.544258) (xy 385.650819 -286.54477) (xy 385.702151 -286.552904) (xy 385.75158 -286.568968)
			(xy 385.797887 -286.592565) (xy 385.839934 -286.623114) (xy 385.876684 -286.659865) (xy 385.907234 -286.701911)
			(xy 385.930832 -286.748219) (xy 385.946895 -286.797647) (xy 385.95503 -286.848979) (xy 385.95554 -286.874966)
			(xy 385.955035 -286.900953) (xy 386.244848 -286.900953) (xy 386.244848 -286.848979) (xy 386.252978 -286.797644)
			(xy 386.269039 -286.748214) (xy 386.292635 -286.701904) (xy 386.323185 -286.659856) (xy 386.359936 -286.623105)
			(xy 386.401984 -286.592555) (xy 386.448294 -286.568959) (xy 386.497724 -286.552898) (xy 386.549059 -286.544768)
			(xy 386.601033 -286.544768) (xy 386.652368 -286.552898) (xy 386.701798 -286.568959) (xy 386.748108 -286.592555)
			(xy 386.790156 -286.623105) (xy 386.826907 -286.659856) (xy 386.857457 -286.701904) (xy 386.881053 -286.748214)
			(xy 386.897114 -286.797644) (xy 386.905244 -286.848979) (xy 386.905754 -286.874966) (xy 386.905244 -286.900953)
			(xy 387.194808 -286.900953) (xy 387.194808 -286.848979) (xy 387.202938 -286.797644) (xy 387.218999 -286.748214)
			(xy 387.242595 -286.701904) (xy 387.273145 -286.659856) (xy 387.309896 -286.623105) (xy 387.351944 -286.592555)
			(xy 387.398254 -286.568959) (xy 387.447684 -286.552898) (xy 387.499019 -286.544768) (xy 387.550993 -286.544768)
			(xy 387.602328 -286.552898) (xy 387.651758 -286.568959) (xy 387.698068 -286.592555) (xy 387.740116 -286.623105)
			(xy 387.776867 -286.659856) (xy 387.807417 -286.701904) (xy 387.831013 -286.748214) (xy 387.847074 -286.797644)
			(xy 387.855204 -286.848979) (xy 387.855714 -286.874966) (xy 387.855204 -286.900953) (xy 388.144768 -286.900953)
			(xy 388.144768 -286.848979) (xy 388.152898 -286.797644) (xy 388.168959 -286.748214) (xy 388.192555 -286.701904)
			(xy 388.223105 -286.659856) (xy 388.259856 -286.623105) (xy 388.301904 -286.592555) (xy 388.348214 -286.568959)
			(xy 388.397644 -286.552898) (xy 388.448979 -286.544768) (xy 388.500953 -286.544768) (xy 388.552288 -286.552898)
			(xy 388.601718 -286.568959) (xy 388.648028 -286.592555) (xy 388.690076 -286.623105) (xy 388.726827 -286.659856)
			(xy 388.757377 -286.701904) (xy 388.780973 -286.748214) (xy 388.797034 -286.797644) (xy 388.805164 -286.848979)
			(xy 388.805674 -286.874966) (xy 388.805164 -286.900953) (xy 388.797034 -286.952288) (xy 388.780973 -287.001718)
			(xy 388.757377 -287.048028) (xy 388.726827 -287.090076) (xy 388.690076 -287.126827) (xy 388.648028 -287.157377)
			(xy 388.601718 -287.180973) (xy 388.552288 -287.197034) (xy 388.500953 -287.205164) (xy 388.448979 -287.205164)
			(xy 388.397644 -287.197034) (xy 388.348214 -287.180973) (xy 388.301904 -287.157377) (xy 388.259856 -287.126827)
			(xy 388.223105 -287.090076) (xy 388.192555 -287.048028) (xy 388.168959 -287.001718) (xy 388.152898 -286.952288)
			(xy 388.144768 -286.900953) (xy 387.855204 -286.900953) (xy 387.847074 -286.952288) (xy 387.831013 -287.001718)
			(xy 387.807417 -287.048028) (xy 387.776867 -287.090076) (xy 387.740116 -287.126827) (xy 387.698068 -287.157377)
			(xy 387.651758 -287.180973) (xy 387.602328 -287.197034) (xy 387.550993 -287.205164) (xy 387.499019 -287.205164)
			(xy 387.447684 -287.197034) (xy 387.398254 -287.180973) (xy 387.351944 -287.157377) (xy 387.309896 -287.126827)
			(xy 387.273145 -287.090076) (xy 387.242595 -287.048028) (xy 387.218999 -287.001718) (xy 387.202938 -286.952288)
			(xy 387.194808 -286.900953) (xy 386.905244 -286.900953) (xy 386.897114 -286.952288) (xy 386.881053 -287.001718)
			(xy 386.857457 -287.048028) (xy 386.826907 -287.090076) (xy 386.790156 -287.126827) (xy 386.748108 -287.157377)
			(xy 386.701798 -287.180973) (xy 386.652368 -287.197034) (xy 386.601033 -287.205164) (xy 386.549059 -287.205164)
			(xy 386.497724 -287.197034) (xy 386.448294 -287.180973) (xy 386.401984 -287.157377) (xy 386.359936 -287.126827)
			(xy 386.323185 -287.090076) (xy 386.292635 -287.048028) (xy 386.269039 -287.001718) (xy 386.252978 -286.952288)
			(xy 386.244848 -286.900953) (xy 385.955035 -286.900953) (xy 385.955008 -286.902328) (xy 385.946004 -286.956305)
			(xy 385.928235 -287.008064) (xy 385.902187 -287.05619) (xy 385.868571 -287.099372) (xy 385.828304 -287.136429)
			(xy 385.80568 -287.151826) (xy 385.796028 -287.158176) (xy 385.78409 -287.177734) (xy 385.774692 -287.26765)
			(xy 385.774105 -287.278974) (xy 385.781621 -287.300337) (xy 385.78917 -287.308798) (xy 386.141214 -287.660588)
			(xy 386.149643 -287.66821) (xy 386.17101 -287.675859) (xy 386.182362 -287.67532) (xy 386.272278 -287.665922)
			(xy 386.291836 -287.653984) (xy 386.297932 -287.644332) (xy 386.313379 -287.621711) (xy 386.350465 -287.581405)
			(xy 386.393679 -287.54775) (xy 386.441841 -287.521665) (xy 386.493639 -287.503861) (xy 386.54766 -287.494823)
			(xy 386.575046 -287.494218) (xy 386.60103 -287.494731) (xy 386.652357 -287.502867) (xy 386.70178 -287.518933)
			(xy 386.748081 -287.542532) (xy 386.790121 -287.573083) (xy 386.826864 -287.609834) (xy 386.857406 -287.65188)
			(xy 386.880995 -287.698186) (xy 386.897049 -287.747613) (xy 386.905175 -287.798942) (xy 386.905754 -287.824926)
			(xy 386.905251 -287.850913) (xy 389.094728 -287.850913) (xy 389.094728 -287.798939) (xy 389.102858 -287.747604)
			(xy 389.118919 -287.698174) (xy 389.142515 -287.651864) (xy 389.173065 -287.609816) (xy 389.209816 -287.573065)
			(xy 389.251864 -287.542515) (xy 389.298174 -287.518919) (xy 389.347604 -287.502858) (xy 389.398939 -287.494728)
			(xy 389.450913 -287.494728) (xy 389.502248 -287.502858) (xy 389.551678 -287.518919) (xy 389.597988 -287.542515)
			(xy 389.640036 -287.573065) (xy 389.676787 -287.609816) (xy 389.707337 -287.651864) (xy 389.730933 -287.698174)
			(xy 389.746994 -287.747604) (xy 389.755124 -287.798939) (xy 389.755634 -287.824926) (xy 389.755124 -287.850913)
			(xy 389.746994 -287.902248) (xy 389.730933 -287.951678) (xy 389.707337 -287.997988) (xy 389.676787 -288.040036)
			(xy 389.640036 -288.076787) (xy 389.597988 -288.107337) (xy 389.551678 -288.130933) (xy 389.502248 -288.146994)
			(xy 389.450913 -288.155124) (xy 389.398939 -288.155124) (xy 389.347604 -288.146994) (xy 389.298174 -288.130933)
			(xy 389.251864 -288.107337) (xy 389.209816 -288.076787) (xy 389.173065 -288.040036) (xy 389.142515 -287.997988)
			(xy 389.118919 -287.951678) (xy 389.102858 -287.902248) (xy 389.094728 -287.850913) (xy 386.905251 -287.850913)
			(xy 386.905224 -287.85232) (xy 386.896208 -287.906361) (xy 386.87841 -287.958178) (xy 386.852318 -288.006354)
			(xy 386.818643 -288.049571) (xy 386.778307 -288.086649) (xy 386.75564 -288.10204) (xy 386.745988 -288.108136)
			(xy 386.73405 -288.127694) (xy 386.724652 -288.21761) (xy 386.724124 -288.22896) (xy 386.731768 -288.250326)
			(xy 386.739384 -288.258758) (xy 387.091174 -288.610548) (xy 387.099599 -288.618182) (xy 387.120969 -288.625854)
			(xy 387.132322 -288.62528) (xy 387.222238 -288.615882) (xy 387.241796 -288.603944) (xy 387.247892 -288.594292)
			(xy 387.263336 -288.571666) (xy 387.300418 -288.531348) (xy 387.343629 -288.497682) (xy 387.391792 -288.471586)
			(xy 387.443592 -288.453773) (xy 387.497617 -288.444726) (xy 387.525006 -288.444178) (xy 387.550993 -288.444688)
			(xy 387.602328 -288.452819) (xy 387.651758 -288.468881) (xy 387.698068 -288.492476) (xy 387.740117 -288.523026)
			(xy 387.776869 -288.559777) (xy 387.807419 -288.601825) (xy 387.831016 -288.648134) (xy 387.847079 -288.697564)
			(xy 387.855211 -288.748899) (xy 387.855714 -288.774886) (xy 387.855206 -288.800873) (xy 388.144768 -288.800873)
			(xy 388.144768 -288.748899) (xy 388.152898 -288.697564) (xy 388.168959 -288.648134) (xy 388.192555 -288.601824)
			(xy 388.223105 -288.559776) (xy 388.259856 -288.523025) (xy 388.301904 -288.492475) (xy 388.348214 -288.468879)
			(xy 388.397644 -288.452818) (xy 388.448979 -288.444688) (xy 388.500953 -288.444688) (xy 388.552288 -288.452818)
			(xy 388.601718 -288.468879) (xy 388.648028 -288.492475) (xy 388.690076 -288.523025) (xy 388.726827 -288.559776)
			(xy 388.757377 -288.601824) (xy 388.780973 -288.648134) (xy 388.797034 -288.697564) (xy 388.805164 -288.748899)
			(xy 388.805674 -288.774886) (xy 388.805164 -288.800873) (xy 389.094728 -288.800873) (xy 389.094728 -288.748899)
			(xy 389.102858 -288.697564) (xy 389.118919 -288.648134) (xy 389.142515 -288.601824) (xy 389.173065 -288.559776)
			(xy 389.209816 -288.523025) (xy 389.251864 -288.492475) (xy 389.298174 -288.468879) (xy 389.347604 -288.452818)
			(xy 389.398939 -288.444688) (xy 389.450913 -288.444688) (xy 389.502248 -288.452818) (xy 389.551678 -288.468879)
			(xy 389.597988 -288.492475) (xy 389.640036 -288.523025) (xy 389.676787 -288.559776) (xy 389.707337 -288.601824)
			(xy 389.730933 -288.648134) (xy 389.746994 -288.697564) (xy 389.755124 -288.748899) (xy 389.755634 -288.774886)
			(xy 389.755124 -288.800873) (xy 390.044688 -288.800873) (xy 390.044688 -288.748899) (xy 390.052818 -288.697564)
			(xy 390.068879 -288.648134) (xy 390.092475 -288.601824) (xy 390.123025 -288.559776) (xy 390.159776 -288.523025)
			(xy 390.201824 -288.492475) (xy 390.248134 -288.468879) (xy 390.297564 -288.452818) (xy 390.348899 -288.444688)
			(xy 390.400873 -288.444688) (xy 390.452208 -288.452818) (xy 390.501638 -288.468879) (xy 390.547948 -288.492475)
			(xy 390.589996 -288.523025) (xy 390.626747 -288.559776) (xy 390.657297 -288.601824) (xy 390.680893 -288.648134)
			(xy 390.696954 -288.697564) (xy 390.705084 -288.748899) (xy 390.705594 -288.774886) (xy 390.705084 -288.800873)
			(xy 390.696954 -288.852208) (xy 390.680893 -288.901638) (xy 390.657297 -288.947948) (xy 390.626747 -288.989996)
			(xy 390.589996 -289.026747) (xy 390.547948 -289.057297) (xy 390.501638 -289.080893) (xy 390.452208 -289.096954)
			(xy 390.400873 -289.105084) (xy 390.348899 -289.105084) (xy 390.297564 -289.096954) (xy 390.248134 -289.080893)
			(xy 390.201824 -289.057297) (xy 390.159776 -289.026747) (xy 390.123025 -288.989996) (xy 390.092475 -288.947948)
			(xy 390.068879 -288.901638) (xy 390.052818 -288.852208) (xy 390.044688 -288.800873) (xy 389.755124 -288.800873)
			(xy 389.746994 -288.852208) (xy 389.730933 -288.901638) (xy 389.707337 -288.947948) (xy 389.676787 -288.989996)
			(xy 389.640036 -289.026747) (xy 389.597988 -289.057297) (xy 389.551678 -289.080893) (xy 389.502248 -289.096954)
			(xy 389.450913 -289.105084) (xy 389.398939 -289.105084) (xy 389.347604 -289.096954) (xy 389.298174 -289.080893)
			(xy 389.251864 -289.057297) (xy 389.209816 -289.026747) (xy 389.173065 -288.989996) (xy 389.142515 -288.947948)
			(xy 389.118919 -288.901638) (xy 389.102858 -288.852208) (xy 389.094728 -288.800873) (xy 388.805164 -288.800873)
			(xy 388.797034 -288.852208) (xy 388.780973 -288.901638) (xy 388.757377 -288.947948) (xy 388.726827 -288.989996)
			(xy 388.690076 -289.026747) (xy 388.648028 -289.057297) (xy 388.601718 -289.080893) (xy 388.552288 -289.096954)
			(xy 388.500953 -289.105084) (xy 388.448979 -289.105084) (xy 388.397644 -289.096954) (xy 388.348214 -289.080893)
			(xy 388.301904 -289.057297) (xy 388.259856 -289.026747) (xy 388.223105 -288.989996) (xy 388.192555 -288.947948)
			(xy 388.168959 -288.901638) (xy 388.152898 -288.852208) (xy 388.144768 -288.800873) (xy 387.855206 -288.800873)
			(xy 387.855179 -288.802277) (xy 387.846154 -288.856311) (xy 387.828348 -288.908119) (xy 387.802249 -288.956285)
			(xy 387.76857 -288.999492) (xy 387.728231 -289.036558) (xy 387.7056 -289.052) (xy 387.695948 -289.058096)
			(xy 387.68401 -289.077654) (xy 387.674612 -289.16757) (xy 387.674096 -289.178916) (xy 387.681754 -289.200267)
			(xy 387.689344 -289.208718) (xy 388.041134 -289.560508) (xy 388.049565 -289.568124) (xy 388.070931 -289.575761)
			(xy 388.082282 -289.57524) (xy 388.172198 -289.565842) (xy 388.191756 -289.553904) (xy 388.197852 -289.544252)
			(xy 388.213299 -289.521631) (xy 388.250385 -289.481325) (xy 388.293598 -289.447671) (xy 388.34176 -289.421587)
			(xy 388.393559 -289.403785) (xy 388.44758 -289.394749) (xy 388.474966 -289.394138) (xy 388.500956 -289.394619)
			(xy 388.552296 -289.402746) (xy 388.601732 -289.418806) (xy 388.648046 -289.442402) (xy 388.690099 -289.472955)
			(xy 388.726853 -289.50971) (xy 388.757404 -289.551764) (xy 388.780999 -289.598079) (xy 388.797057 -289.647516)
			(xy 388.805182 -289.698856) (xy 388.805674 -289.724846) (xy 388.805169 -289.750833) (xy 389.094728 -289.750833)
			(xy 389.094728 -289.698859) (xy 389.102858 -289.647524) (xy 389.118919 -289.598094) (xy 389.142515 -289.551784)
			(xy 389.173065 -289.509736) (xy 389.209816 -289.472985) (xy 389.251864 -289.442435) (xy 389.298174 -289.418839)
			(xy 389.347604 -289.402778) (xy 389.398939 -289.394648) (xy 389.450913 -289.394648) (xy 389.502248 -289.402778)
			(xy 389.551678 -289.418839) (xy 389.597988 -289.442435) (xy 389.640036 -289.472985) (xy 389.676787 -289.509736)
			(xy 389.707337 -289.551784) (xy 389.730933 -289.598094) (xy 389.746994 -289.647524) (xy 389.755124 -289.698859)
			(xy 389.755634 -289.724846) (xy 389.755124 -289.750833) (xy 390.044688 -289.750833) (xy 390.044688 -289.698859)
			(xy 390.052818 -289.647524) (xy 390.068879 -289.598094) (xy 390.092475 -289.551784) (xy 390.123025 -289.509736)
			(xy 390.159776 -289.472985) (xy 390.201824 -289.442435) (xy 390.248134 -289.418839) (xy 390.297564 -289.402778)
			(xy 390.348899 -289.394648) (xy 390.400873 -289.394648) (xy 390.452208 -289.402778) (xy 390.501638 -289.418839)
			(xy 390.547948 -289.442435) (xy 390.589996 -289.472985) (xy 390.626747 -289.509736) (xy 390.657297 -289.551784)
			(xy 390.680893 -289.598094) (xy 390.696954 -289.647524) (xy 390.705084 -289.698859) (xy 390.705594 -289.724846)
			(xy 390.705084 -289.750833) (xy 390.994648 -289.750833) (xy 390.994648 -289.698859) (xy 391.002778 -289.647524)
			(xy 391.018839 -289.598094) (xy 391.042435 -289.551784) (xy 391.072985 -289.509736) (xy 391.109736 -289.472985)
			(xy 391.151784 -289.442435) (xy 391.198094 -289.418839) (xy 391.247524 -289.402778) (xy 391.298859 -289.394648)
			(xy 391.350833 -289.394648) (xy 391.402168 -289.402778) (xy 391.451598 -289.418839) (xy 391.497908 -289.442435)
			(xy 391.539956 -289.472985) (xy 391.576707 -289.509736) (xy 391.607257 -289.551784) (xy 391.630853 -289.598094)
			(xy 391.646914 -289.647524) (xy 391.655044 -289.698859) (xy 391.655554 -289.724846) (xy 391.655044 -289.750833)
			(xy 391.944608 -289.750833) (xy 391.944608 -289.698859) (xy 391.952738 -289.647524) (xy 391.968799 -289.598094)
			(xy 391.992395 -289.551784) (xy 392.022945 -289.509736) (xy 392.059696 -289.472985) (xy 392.101744 -289.442435)
			(xy 392.148054 -289.418839) (xy 392.197484 -289.402778) (xy 392.248819 -289.394648) (xy 392.300793 -289.394648)
			(xy 392.352128 -289.402778) (xy 392.401558 -289.418839) (xy 392.447868 -289.442435) (xy 392.489916 -289.472985)
			(xy 392.526667 -289.509736) (xy 392.557217 -289.551784) (xy 392.580813 -289.598094) (xy 392.596874 -289.647524)
			(xy 392.605004 -289.698859) (xy 392.605514 -289.724846) (xy 392.605004 -289.750833) (xy 392.894822 -289.750833)
			(xy 392.894822 -289.698859) (xy 392.902952 -289.647524) (xy 392.919013 -289.598094) (xy 392.942609 -289.551784)
			(xy 392.973159 -289.509736) (xy 393.00991 -289.472985) (xy 393.051958 -289.442435) (xy 393.098268 -289.418839)
			(xy 393.147698 -289.402778) (xy 393.199033 -289.394648) (xy 393.251007 -289.394648) (xy 393.302342 -289.402778)
			(xy 393.351772 -289.418839) (xy 393.398082 -289.442435) (xy 393.44013 -289.472985) (xy 393.476881 -289.509736)
			(xy 393.507431 -289.551784) (xy 393.531027 -289.598094) (xy 393.547088 -289.647524) (xy 393.555218 -289.698859)
			(xy 393.555728 -289.724846) (xy 393.555218 -289.750833) (xy 393.844782 -289.750833) (xy 393.844782 -289.698859)
			(xy 393.852912 -289.647524) (xy 393.868973 -289.598094) (xy 393.892569 -289.551784) (xy 393.923119 -289.509736)
			(xy 393.95987 -289.472985) (xy 394.001918 -289.442435) (xy 394.048228 -289.418839) (xy 394.097658 -289.402778)
			(xy 394.148993 -289.394648) (xy 394.200967 -289.394648) (xy 394.252302 -289.402778) (xy 394.301732 -289.418839)
			(xy 394.348042 -289.442435) (xy 394.39009 -289.472985) (xy 394.426841 -289.509736) (xy 394.457391 -289.551784)
			(xy 394.480987 -289.598094) (xy 394.497048 -289.647524) (xy 394.505178 -289.698859) (xy 394.505688 -289.724846)
			(xy 394.505178 -289.750833) (xy 394.794742 -289.750833) (xy 394.794742 -289.698859) (xy 394.802872 -289.647524)
			(xy 394.818933 -289.598094) (xy 394.842529 -289.551784) (xy 394.873079 -289.509736) (xy 394.90983 -289.472985)
			(xy 394.951878 -289.442435) (xy 394.998188 -289.418839) (xy 395.047618 -289.402778) (xy 395.098953 -289.394648)
			(xy 395.150927 -289.394648) (xy 395.202262 -289.402778) (xy 395.251692 -289.418839) (xy 395.298002 -289.442435)
			(xy 395.34005 -289.472985) (xy 395.376801 -289.509736) (xy 395.407351 -289.551784) (xy 395.430947 -289.598094)
			(xy 395.447008 -289.647524) (xy 395.455138 -289.698859) (xy 395.455648 -289.724846) (xy 395.455138 -289.750833)
			(xy 395.447008 -289.802168) (xy 395.430947 -289.851598) (xy 395.407351 -289.897908) (xy 395.376801 -289.939956)
			(xy 395.34005 -289.976707) (xy 395.298002 -290.007257) (xy 395.251692 -290.030853) (xy 395.202262 -290.046914)
			(xy 395.150927 -290.055044) (xy 395.098953 -290.055044) (xy 395.047618 -290.046914) (xy 394.998188 -290.030853)
			(xy 394.951878 -290.007257) (xy 394.90983 -289.976707) (xy 394.873079 -289.939956) (xy 394.842529 -289.897908)
			(xy 394.818933 -289.851598) (xy 394.802872 -289.802168) (xy 394.794742 -289.750833) (xy 394.505178 -289.750833)
			(xy 394.497048 -289.802168) (xy 394.480987 -289.851598) (xy 394.457391 -289.897908) (xy 394.426841 -289.939956)
			(xy 394.39009 -289.976707) (xy 394.348042 -290.007257) (xy 394.301732 -290.030853) (xy 394.252302 -290.046914)
			(xy 394.200967 -290.055044) (xy 394.148993 -290.055044) (xy 394.097658 -290.046914) (xy 394.048228 -290.030853)
			(xy 394.001918 -290.007257) (xy 393.95987 -289.976707) (xy 393.923119 -289.939956) (xy 393.892569 -289.897908)
			(xy 393.868973 -289.851598) (xy 393.852912 -289.802168) (xy 393.844782 -289.750833) (xy 393.555218 -289.750833)
			(xy 393.547088 -289.802168) (xy 393.531027 -289.851598) (xy 393.507431 -289.897908) (xy 393.476881 -289.939956)
			(xy 393.44013 -289.976707) (xy 393.398082 -290.007257) (xy 393.351772 -290.030853) (xy 393.302342 -290.046914)
			(xy 393.251007 -290.055044) (xy 393.199033 -290.055044) (xy 393.147698 -290.046914) (xy 393.098268 -290.030853)
			(xy 393.051958 -290.007257) (xy 393.00991 -289.976707) (xy 392.973159 -289.939956) (xy 392.942609 -289.897908)
			(xy 392.919013 -289.851598) (xy 392.902952 -289.802168) (xy 392.894822 -289.750833) (xy 392.605004 -289.750833)
			(xy 392.596874 -289.802168) (xy 392.580813 -289.851598) (xy 392.557217 -289.897908) (xy 392.526667 -289.939956)
			(xy 392.489916 -289.976707) (xy 392.447868 -290.007257) (xy 392.401558 -290.030853) (xy 392.352128 -290.046914)
			(xy 392.300793 -290.055044) (xy 392.248819 -290.055044) (xy 392.197484 -290.046914) (xy 392.148054 -290.030853)
			(xy 392.101744 -290.007257) (xy 392.059696 -289.976707) (xy 392.022945 -289.939956) (xy 391.992395 -289.897908)
			(xy 391.968799 -289.851598) (xy 391.952738 -289.802168) (xy 391.944608 -289.750833) (xy 391.655044 -289.750833)
			(xy 391.646914 -289.802168) (xy 391.630853 -289.851598) (xy 391.607257 -289.897908) (xy 391.576707 -289.939956)
			(xy 391.539956 -289.976707) (xy 391.497908 -290.007257) (xy 391.451598 -290.030853) (xy 391.402168 -290.046914)
			(xy 391.350833 -290.055044) (xy 391.298859 -290.055044) (xy 391.247524 -290.046914) (xy 391.198094 -290.030853)
			(xy 391.151784 -290.007257) (xy 391.109736 -289.976707) (xy 391.072985 -289.939956) (xy 391.042435 -289.897908)
			(xy 391.018839 -289.851598) (xy 391.002778 -289.802168) (xy 390.994648 -289.750833) (xy 390.705084 -289.750833)
			(xy 390.696954 -289.802168) (xy 390.680893 -289.851598) (xy 390.657297 -289.897908) (xy 390.626747 -289.939956)
			(xy 390.589996 -289.976707) (xy 390.547948 -290.007257) (xy 390.501638 -290.030853) (xy 390.452208 -290.046914)
			(xy 390.400873 -290.055044) (xy 390.348899 -290.055044) (xy 390.297564 -290.046914) (xy 390.248134 -290.030853)
			(xy 390.201824 -290.007257) (xy 390.159776 -289.976707) (xy 390.123025 -289.939956) (xy 390.092475 -289.897908)
			(xy 390.068879 -289.851598) (xy 390.052818 -289.802168) (xy 390.044688 -289.750833) (xy 389.755124 -289.750833)
			(xy 389.746994 -289.802168) (xy 389.730933 -289.851598) (xy 389.707337 -289.897908) (xy 389.676787 -289.939956)
			(xy 389.640036 -289.976707) (xy 389.597988 -290.007257) (xy 389.551678 -290.030853) (xy 389.502248 -290.046914)
			(xy 389.450913 -290.055044) (xy 389.398939 -290.055044) (xy 389.347604 -290.046914) (xy 389.298174 -290.030853)
			(xy 389.251864 -290.007257) (xy 389.209816 -289.976707) (xy 389.173065 -289.939956) (xy 389.142515 -289.897908)
			(xy 389.118919 -289.851598) (xy 389.102858 -289.802168) (xy 389.094728 -289.750833) (xy 388.805169 -289.750833)
			(xy 388.805142 -289.752238) (xy 388.796122 -289.806275) (xy 388.778319 -289.858086) (xy 388.752221 -289.906255)
			(xy 388.718541 -289.949464) (xy 388.678201 -289.986531) (xy 388.65556 -290.00196) (xy 388.645908 -290.008056)
			(xy 388.63397 -290.027614) (xy 388.624572 -290.11753) (xy 388.624047 -290.12888) (xy 388.631689 -290.150247)
			(xy 388.639304 -290.158678) (xy 388.991094 -290.510468) (xy 388.999521 -290.518096) (xy 389.02089 -290.525756)
			(xy 389.032242 -290.5252) (xy 389.122158 -290.515802) (xy 389.141716 -290.503864) (xy 389.147812 -290.494212)
			(xy 389.163255 -290.471585) (xy 389.200337 -290.431268) (xy 389.243548 -290.397602) (xy 389.291711 -290.371508)
			(xy 389.343512 -290.353696) (xy 389.397538 -290.344652) (xy 389.424926 -290.344098) (xy 389.450912 -290.344609)
			(xy 389.502243 -290.352743) (xy 389.551669 -290.368807) (xy 389.597975 -290.392404) (xy 389.640019 -290.422954)
			(xy 389.676766 -290.459705) (xy 389.707313 -290.501753) (xy 389.730906 -290.54806) (xy 389.746964 -290.597489)
			(xy 389.755093 -290.64882) (xy 389.755634 -290.674806) (xy 389.755132 -290.700793) (xy 390.044688 -290.700793)
			(xy 390.044688 -290.648819) (xy 390.052818 -290.597484) (xy 390.068879 -290.548054) (xy 390.092475 -290.501744)
			(xy 390.123025 -290.459696) (xy 390.159776 -290.422945) (xy 390.201824 -290.392395) (xy 390.248134 -290.368799)
			(xy 390.297564 -290.352738) (xy 390.348899 -290.344608) (xy 390.400873 -290.344608) (xy 390.452208 -290.352738)
			(xy 390.501638 -290.368799) (xy 390.547948 -290.392395) (xy 390.589996 -290.422945) (xy 390.626747 -290.459696)
			(xy 390.657297 -290.501744) (xy 390.680893 -290.548054) (xy 390.696954 -290.597484) (xy 390.705084 -290.648819)
			(xy 390.705594 -290.674806) (xy 390.705084 -290.700793) (xy 390.994648 -290.700793) (xy 390.994648 -290.648819)
			(xy 391.002778 -290.597484) (xy 391.018839 -290.548054) (xy 391.042435 -290.501744) (xy 391.072985 -290.459696)
			(xy 391.109736 -290.422945) (xy 391.151784 -290.392395) (xy 391.198094 -290.368799) (xy 391.247524 -290.352738)
			(xy 391.298859 -290.344608) (xy 391.350833 -290.344608) (xy 391.402168 -290.352738) (xy 391.451598 -290.368799)
			(xy 391.497908 -290.392395) (xy 391.539956 -290.422945) (xy 391.576707 -290.459696) (xy 391.607257 -290.501744)
			(xy 391.630853 -290.548054) (xy 391.646914 -290.597484) (xy 391.655044 -290.648819) (xy 391.655554 -290.674806)
			(xy 391.655044 -290.700793) (xy 391.944608 -290.700793) (xy 391.944608 -290.648819) (xy 391.952738 -290.597484)
			(xy 391.968799 -290.548054) (xy 391.992395 -290.501744) (xy 392.022945 -290.459696) (xy 392.059696 -290.422945)
			(xy 392.101744 -290.392395) (xy 392.148054 -290.368799) (xy 392.197484 -290.352738) (xy 392.248819 -290.344608)
			(xy 392.300793 -290.344608) (xy 392.352128 -290.352738) (xy 392.401558 -290.368799) (xy 392.447868 -290.392395)
			(xy 392.489916 -290.422945) (xy 392.526667 -290.459696) (xy 392.557217 -290.501744) (xy 392.580813 -290.548054)
			(xy 392.596874 -290.597484) (xy 392.605004 -290.648819) (xy 392.605514 -290.674806) (xy 392.605004 -290.700793)
			(xy 392.894822 -290.700793) (xy 392.894822 -290.648819) (xy 392.902952 -290.597484) (xy 392.919013 -290.548054)
			(xy 392.942609 -290.501744) (xy 392.973159 -290.459696) (xy 393.00991 -290.422945) (xy 393.051958 -290.392395)
			(xy 393.098268 -290.368799) (xy 393.147698 -290.352738) (xy 393.199033 -290.344608) (xy 393.251007 -290.344608)
			(xy 393.302342 -290.352738) (xy 393.351772 -290.368799) (xy 393.398082 -290.392395) (xy 393.44013 -290.422945)
			(xy 393.476881 -290.459696) (xy 393.507431 -290.501744) (xy 393.531027 -290.548054) (xy 393.547088 -290.597484)
			(xy 393.555218 -290.648819) (xy 393.555728 -290.674806) (xy 393.555218 -290.700793) (xy 393.844782 -290.700793)
			(xy 393.844782 -290.648819) (xy 393.852912 -290.597484) (xy 393.868973 -290.548054) (xy 393.892569 -290.501744)
			(xy 393.923119 -290.459696) (xy 393.95987 -290.422945) (xy 394.001918 -290.392395) (xy 394.048228 -290.368799)
			(xy 394.097658 -290.352738) (xy 394.148993 -290.344608) (xy 394.200967 -290.344608) (xy 394.252302 -290.352738)
			(xy 394.301732 -290.368799) (xy 394.348042 -290.392395) (xy 394.39009 -290.422945) (xy 394.426841 -290.459696)
			(xy 394.457391 -290.501744) (xy 394.480987 -290.548054) (xy 394.497048 -290.597484) (xy 394.505178 -290.648819)
			(xy 394.505688 -290.674806) (xy 394.505178 -290.700793) (xy 394.794742 -290.700793) (xy 394.794742 -290.648819)
			(xy 394.802872 -290.597484) (xy 394.818933 -290.548054) (xy 394.842529 -290.501744) (xy 394.873079 -290.459696)
			(xy 394.90983 -290.422945) (xy 394.951878 -290.392395) (xy 394.998188 -290.368799) (xy 395.047618 -290.352738)
			(xy 395.098953 -290.344608) (xy 395.150927 -290.344608) (xy 395.202262 -290.352738) (xy 395.251692 -290.368799)
			(xy 395.298002 -290.392395) (xy 395.34005 -290.422945) (xy 395.376801 -290.459696) (xy 395.407351 -290.501744)
			(xy 395.430947 -290.548054) (xy 395.447008 -290.597484) (xy 395.455138 -290.648819) (xy 395.455648 -290.674806)
			(xy 395.455138 -290.700793) (xy 395.744702 -290.700793) (xy 395.744702 -290.648819) (xy 395.752832 -290.597484)
			(xy 395.768893 -290.548054) (xy 395.792489 -290.501744) (xy 395.823039 -290.459696) (xy 395.85979 -290.422945)
			(xy 395.901838 -290.392395) (xy 395.948148 -290.368799) (xy 395.997578 -290.352738) (xy 396.048913 -290.344608)
			(xy 396.100887 -290.344608) (xy 396.152222 -290.352738) (xy 396.201652 -290.368799) (xy 396.247962 -290.392395)
			(xy 396.29001 -290.422945) (xy 396.326761 -290.459696) (xy 396.357311 -290.501744) (xy 396.380907 -290.548054)
			(xy 396.396968 -290.597484) (xy 396.405098 -290.648819) (xy 396.405608 -290.674806) (xy 396.405098 -290.700793)
			(xy 396.396968 -290.752128) (xy 396.380907 -290.801558) (xy 396.357311 -290.847868) (xy 396.326761 -290.889916)
			(xy 396.29001 -290.926667) (xy 396.247962 -290.957217) (xy 396.201652 -290.980813) (xy 396.152222 -290.996874)
			(xy 396.100887 -291.005004) (xy 396.048913 -291.005004) (xy 395.997578 -290.996874) (xy 395.948148 -290.980813)
			(xy 395.901838 -290.957217) (xy 395.85979 -290.926667) (xy 395.823039 -290.889916) (xy 395.792489 -290.847868)
			(xy 395.768893 -290.801558) (xy 395.752832 -290.752128) (xy 395.744702 -290.700793) (xy 395.455138 -290.700793)
			(xy 395.447008 -290.752128) (xy 395.430947 -290.801558) (xy 395.407351 -290.847868) (xy 395.376801 -290.889916)
			(xy 395.34005 -290.926667) (xy 395.298002 -290.957217) (xy 395.251692 -290.980813) (xy 395.202262 -290.996874)
			(xy 395.150927 -291.005004) (xy 395.098953 -291.005004) (xy 395.047618 -290.996874) (xy 394.998188 -290.980813)
			(xy 394.951878 -290.957217) (xy 394.90983 -290.926667) (xy 394.873079 -290.889916) (xy 394.842529 -290.847868)
			(xy 394.818933 -290.801558) (xy 394.802872 -290.752128) (xy 394.794742 -290.700793) (xy 394.505178 -290.700793)
			(xy 394.497048 -290.752128) (xy 394.480987 -290.801558) (xy 394.457391 -290.847868) (xy 394.426841 -290.889916)
			(xy 394.39009 -290.926667) (xy 394.348042 -290.957217) (xy 394.301732 -290.980813) (xy 394.252302 -290.996874)
			(xy 394.200967 -291.005004) (xy 394.148993 -291.005004) (xy 394.097658 -290.996874) (xy 394.048228 -290.980813)
			(xy 394.001918 -290.957217) (xy 393.95987 -290.926667) (xy 393.923119 -290.889916) (xy 393.892569 -290.847868)
			(xy 393.868973 -290.801558) (xy 393.852912 -290.752128) (xy 393.844782 -290.700793) (xy 393.555218 -290.700793)
			(xy 393.547088 -290.752128) (xy 393.531027 -290.801558) (xy 393.507431 -290.847868) (xy 393.476881 -290.889916)
			(xy 393.44013 -290.926667) (xy 393.398082 -290.957217) (xy 393.351772 -290.980813) (xy 393.302342 -290.996874)
			(xy 393.251007 -291.005004) (xy 393.199033 -291.005004) (xy 393.147698 -290.996874) (xy 393.098268 -290.980813)
			(xy 393.051958 -290.957217) (xy 393.00991 -290.926667) (xy 392.973159 -290.889916) (xy 392.942609 -290.847868)
			(xy 392.919013 -290.801558) (xy 392.902952 -290.752128) (xy 392.894822 -290.700793) (xy 392.605004 -290.700793)
			(xy 392.596874 -290.752128) (xy 392.580813 -290.801558) (xy 392.557217 -290.847868) (xy 392.526667 -290.889916)
			(xy 392.489916 -290.926667) (xy 392.447868 -290.957217) (xy 392.401558 -290.980813) (xy 392.352128 -290.996874)
			(xy 392.300793 -291.005004) (xy 392.248819 -291.005004) (xy 392.197484 -290.996874) (xy 392.148054 -290.980813)
			(xy 392.101744 -290.957217) (xy 392.059696 -290.926667) (xy 392.022945 -290.889916) (xy 391.992395 -290.847868)
			(xy 391.968799 -290.801558) (xy 391.952738 -290.752128) (xy 391.944608 -290.700793) (xy 391.655044 -290.700793)
			(xy 391.646914 -290.752128) (xy 391.630853 -290.801558) (xy 391.607257 -290.847868) (xy 391.576707 -290.889916)
			(xy 391.539956 -290.926667) (xy 391.497908 -290.957217) (xy 391.451598 -290.980813) (xy 391.402168 -290.996874)
			(xy 391.350833 -291.005004) (xy 391.298859 -291.005004) (xy 391.247524 -290.996874) (xy 391.198094 -290.980813)
			(xy 391.151784 -290.957217) (xy 391.109736 -290.926667) (xy 391.072985 -290.889916) (xy 391.042435 -290.847868)
			(xy 391.018839 -290.801558) (xy 391.002778 -290.752128) (xy 390.994648 -290.700793) (xy 390.705084 -290.700793)
			(xy 390.696954 -290.752128) (xy 390.680893 -290.801558) (xy 390.657297 -290.847868) (xy 390.626747 -290.889916)
			(xy 390.589996 -290.926667) (xy 390.547948 -290.957217) (xy 390.501638 -290.980813) (xy 390.452208 -290.996874)
			(xy 390.400873 -291.005004) (xy 390.348899 -291.005004) (xy 390.297564 -290.996874) (xy 390.248134 -290.980813)
			(xy 390.201824 -290.957217) (xy 390.159776 -290.926667) (xy 390.123025 -290.889916) (xy 390.092475 -290.847868)
			(xy 390.068879 -290.801558) (xy 390.052818 -290.752128) (xy 390.044688 -290.700793) (xy 389.755132 -290.700793)
			(xy 389.755105 -290.702201) (xy 389.746092 -290.756243) (xy 389.728296 -290.808061) (xy 389.702203 -290.856239)
			(xy 389.668529 -290.899457) (xy 389.628192 -290.936536) (xy 389.60552 -290.95192) (xy 389.595868 -290.958016)
			(xy 389.58393 -290.977574) (xy 389.574532 -291.06749) (xy 389.573999 -291.078842) (xy 389.581636 -291.100216)
			(xy 389.589264 -291.108638) (xy 389.941054 -291.460428) (xy 389.949487 -291.468037) (xy 389.970852 -291.475663)
			(xy 389.982202 -291.47516) (xy 390.072118 -291.465762) (xy 390.091676 -291.453824) (xy 390.097772 -291.444172)
			(xy 390.113218 -291.421551) (xy 390.150304 -291.381245) (xy 390.193517 -291.347591) (xy 390.24168 -291.321509)
			(xy 390.293479 -291.303708) (xy 390.3475 -291.294676) (xy 390.374886 -291.294058) (xy 390.399965 -291.294522)
			(xy 390.449547 -291.302098) (xy 390.497416 -291.317078) (xy 390.542472 -291.339119) (xy 390.58368 -291.367714)
			(xy 390.620096 -291.402206) (xy 390.650881 -291.441805) (xy 390.675331 -291.4856) (xy 390.684512 -291.508942)
			(xy 390.6901 -291.523674) (xy 390.716262 -291.541708) (xy 390.98347 -291.541708) (xy 391.009632 -291.523674)
			(xy 391.01522 -291.508942) (xy 391.024426 -291.485608) (xy 391.048866 -291.441806) (xy 391.079644 -291.4022)
			(xy 391.116054 -291.367699) (xy 391.15726 -291.339097) (xy 391.202314 -291.31705) (xy 391.250183 -291.302065)
			(xy 391.299766 -291.294485) (xy 391.349926 -291.294485) (xy 391.399509 -291.302065) (xy 391.447378 -291.31705)
			(xy 391.492432 -291.339097) (xy 391.533638 -291.367699) (xy 391.570048 -291.4022) (xy 391.600826 -291.441806)
			(xy 391.625266 -291.485608) (xy 391.634472 -291.508942) (xy 391.64006 -291.523674) (xy 391.666222 -291.541708)
			(xy 391.93343 -291.541708) (xy 391.959592 -291.523674) (xy 391.96518 -291.508942) (xy 391.974386 -291.485608)
			(xy 391.998826 -291.441806) (xy 392.029604 -291.4022) (xy 392.066014 -291.367699) (xy 392.10722 -291.339097)
			(xy 392.152274 -291.31705) (xy 392.200143 -291.302065) (xy 392.249726 -291.294485) (xy 392.299886 -291.294485)
			(xy 392.349469 -291.302065) (xy 392.397338 -291.31705) (xy 392.442392 -291.339097) (xy 392.483598 -291.367699)
			(xy 392.520008 -291.4022) (xy 392.550786 -291.441806) (xy 392.575226 -291.485608) (xy 392.584432 -291.508942)
			(xy 392.59002 -291.523674) (xy 392.616182 -291.541708) (xy 392.883644 -291.541708) (xy 392.909806 -291.523674)
			(xy 392.915394 -291.508942) (xy 392.9246 -291.485608) (xy 392.94904 -291.441806) (xy 392.979818 -291.4022)
			(xy 393.016228 -291.367699) (xy 393.057434 -291.339097) (xy 393.102488 -291.31705) (xy 393.150357 -291.302065)
			(xy 393.19994 -291.294485) (xy 393.2501 -291.294485) (xy 393.299683 -291.302065) (xy 393.347552 -291.31705)
			(xy 393.392606 -291.339097) (xy 393.433812 -291.367699) (xy 393.470222 -291.4022) (xy 393.501 -291.441806)
			(xy 393.52544 -291.485608) (xy 393.534646 -291.508942) (xy 393.540234 -291.523674) (xy 393.566396 -291.541708)
			(xy 393.833604 -291.541708) (xy 393.859766 -291.523674) (xy 393.865354 -291.508942) (xy 393.87456 -291.485608)
			(xy 393.899 -291.441806) (xy 393.929778 -291.4022) (xy 393.966188 -291.367699) (xy 394.007394 -291.339097)
			(xy 394.052448 -291.31705) (xy 394.100317 -291.302065) (xy 394.1499 -291.294485) (xy 394.20006 -291.294485)
			(xy 394.249643 -291.302065) (xy 394.297512 -291.31705) (xy 394.342566 -291.339097) (xy 394.383772 -291.367699)
			(xy 394.420182 -291.4022) (xy 394.45096 -291.441806) (xy 394.4754 -291.485608) (xy 394.484606 -291.508942)
			(xy 394.490194 -291.523674) (xy 394.516356 -291.541708) (xy 394.783564 -291.541708) (xy 394.809726 -291.523674)
			(xy 394.815314 -291.508942) (xy 394.824515 -291.485604) (xy 394.848948 -291.441792) (xy 394.879722 -291.402177)
			(xy 394.916131 -291.367669) (xy 394.957338 -291.339061) (xy 395.002396 -291.317011) (xy 395.050269 -291.302025)
			(xy 395.099858 -291.294448) (xy 395.12494 -291.294058) (xy 395.150926 -291.29457) (xy 395.202258 -291.302706)
			(xy 395.251685 -291.31877) (xy 395.297992 -291.342367) (xy 395.340037 -291.372917) (xy 395.376787 -291.409668)
			(xy 395.407336 -291.451714) (xy 395.430932 -291.49802) (xy 395.446996 -291.547448) (xy 395.45513 -291.59878)
			(xy 395.455648 -291.624766) (xy 395.455648 -291.6301) (xy 395.455394 -291.640514) (xy 395.463268 -291.659564)
			(xy 395.76375 -291.960046) (xy 395.771095 -291.966855) (xy 395.789559 -291.974577) (xy 395.799564 -291.975032)
		)
		(stroke
			(width 0)
			(type solid)
		)
		(fill yes)
		(layer "In5.Cu")
		(net "PCEPLL7_VDDA18_PEX3")
	)
	(gr_poly
		(pts
			(xy 135.650478 -190.119) (xy 135.660542 -190.118562) (xy 135.679126 -190.110828) (xy 135.686546 -190.104014)
			(xy 137.721086 -188.069728) (xy 137.727922 -188.062326) (xy 137.735633 -188.043728) (xy 137.736072 -188.03366)
			(xy 137.736072 -183.126126) (xy 137.735546 -183.115629) (xy 137.727145 -183.096387) (xy 137.711767 -183.082093)
			(xy 137.702036 -183.07812) (xy 137.596118 -183.04129) (xy 137.56513 -183.05018) (xy 137.55497 -183.06288)
			(xy 137.536761 -183.084943) (xy 137.49486 -183.123886) (xy 137.447617 -183.156141) (xy 137.39609 -183.180985)
			(xy 137.341432 -183.197862) (xy 137.284868 -183.206393) (xy 137.256266 -183.206898) (xy 137.229017 -183.206409)
			(xy 137.175075 -183.198649) (xy 137.122785 -183.183292) (xy 137.073214 -183.160649) (xy 137.027369 -183.131183)
			(xy 136.986184 -183.095492) (xy 136.950497 -183.054304) (xy 136.921035 -183.008456) (xy 136.898397 -182.958883)
			(xy 136.883044 -182.906592) (xy 136.875288 -182.852649) (xy 136.875288 -182.798151) (xy 136.883044 -182.744208)
			(xy 136.898397 -182.691917) (xy 136.921035 -182.642344) (xy 136.950497 -182.596496) (xy 136.986184 -182.555308)
			(xy 137.027369 -182.519617) (xy 137.073214 -182.490151) (xy 137.122785 -182.467508) (xy 137.175075 -182.452151)
			(xy 137.229017 -182.444391) (xy 137.256266 -182.443882) (xy 137.284869 -182.444389) (xy 137.341435 -182.452918)
			(xy 137.396096 -182.469791) (xy 137.447629 -182.494629) (xy 137.494878 -182.526878) (xy 137.536789 -182.565814)
			(xy 137.55497 -182.5879) (xy 137.56513 -182.6006) (xy 137.596118 -182.60949) (xy 137.702036 -182.57266)
			(xy 137.711788 -182.568717) (xy 137.727197 -182.554431) (xy 137.735576 -182.535162) (xy 137.736072 -182.524654)
			(xy 137.736072 -178.793648) (xy 137.735639 -178.783583) (xy 137.727908 -178.764994) (xy 137.721086 -178.75758)
			(xy 137.145522 -178.18227) (xy 137.127407 -178.16349) (xy 137.096719 -178.121294) (xy 137.073016 -178.074813)
			(xy 137.056883 -178.025195) (xy 137.048717 -177.973662) (xy 137.04824 -177.947574) (xy 137.04824 -177.176684)
			(xy 137.048727 -177.150597) (xy 137.056896 -177.099067) (xy 137.07303 -177.049451) (xy 137.096731 -177.002971)
			(xy 137.127415 -176.960774) (xy 137.145522 -176.941988) (xy 137.552938 -176.534826) (xy 137.55978 -176.527427)
			(xy 137.567497 -176.508828) (xy 137.567924 -176.498758) (xy 137.567924 -174.092108) (xy 137.567503 -174.082037)
			(xy 137.559793 -174.063428) (xy 137.552938 -174.05604) (xy 137.334498 -173.837854) (xy 137.316385 -173.819074)
			(xy 137.285701 -173.776876) (xy 137.262002 -173.730395) (xy 137.245872 -173.680777) (xy 137.23771 -173.629245)
			(xy 137.237216 -173.603158) (xy 137.237216 -167.86606) (xy 137.236786 -167.855993) (xy 137.229063 -167.837397)
			(xy 137.22223 -167.829992) (xy 136.943338 -167.550846) (xy 136.935938 -167.544004) (xy 136.91734 -167.536285)
			(xy 136.90727 -167.53586) (xy 136.806686 -167.53586) (xy 136.796677 -167.53635) (xy 136.778183 -167.544011)
			(xy 136.764025 -167.558162) (xy 136.756355 -167.576652) (xy 136.755886 -167.58666) (xy 136.756231 -167.595842)
			(xy 136.76262 -167.613054) (xy 136.774665 -167.62691) (xy 136.782556 -167.631618) (xy 136.78281 -167.631618)
			(xy 136.809789 -167.64666) (xy 136.859809 -167.682903) (xy 136.904503 -167.725541) (xy 136.943059 -167.7738)
			(xy 136.974779 -167.826804) (xy 136.999085 -167.883591) (xy 137.015538 -167.943129) (xy 137.023838 -168.004339)
			(xy 137.024364 -168.035224) (xy 137.023893 -168.065191) (xy 137.016067 -168.124612) (xy 137.000552 -168.182503)
			(xy 136.977612 -168.237873) (xy 136.947642 -168.289775) (xy 136.911153 -168.337321) (xy 136.86877 -168.379698)
			(xy 136.821219 -168.41618) (xy 136.769312 -168.446142) (xy 136.713938 -168.469073) (xy 136.656045 -168.48458)
			(xy 136.596623 -168.492398) (xy 136.566656 -168.492932) (xy 135.703056 -168.492932) (xy 135.67309 -168.492439)
			(xy 135.61367 -168.484611) (xy 135.555781 -168.469096) (xy 135.500411 -168.446157) (xy 135.44851 -168.416188)
			(xy 135.400963 -168.379702) (xy 135.358585 -168.337322) (xy 135.322101 -168.289774) (xy 135.292134 -168.237871)
			(xy 135.269198 -168.1825) (xy 135.253685 -168.12461) (xy 135.245859 -168.06519) (xy 135.245348 -168.035224)
			(xy 135.245348 -168.03497) (xy 135.245826 -168.004823) (xy 135.253741 -167.94505) (xy 135.269443 -167.886837)
			(xy 135.292661 -167.831192) (xy 135.32299 -167.779081) (xy 135.359905 -167.731408) (xy 135.380984 -167.70985)
			(xy 135.391906 -167.698928) (xy 135.398002 -167.668702) (xy 135.3566 -167.567356) (xy 135.352386 -167.55823)
			(xy 135.338205 -167.544004) (xy 135.319653 -167.5363) (xy 135.30961 -167.53586) (xy 129.04597 -167.53586)
			(xy 129.035904 -167.53629) (xy 129.017313 -167.544019) (xy 129.009902 -167.550846) (xy 128.190865 -168.369996)
			(xy 131.39623 -168.369996) (xy 131.400301 -168.314374) (xy 131.412427 -168.259937) (xy 131.43235 -168.207846)
			(xy 131.459646 -168.159211) (xy 131.493732 -168.115068) (xy 131.533881 -168.076359) (xy 131.579239 -168.043908)
			(xy 131.628839 -168.018407) (xy 131.681623 -168.0004) (xy 131.736466 -167.99027) (xy 131.7922 -167.988233)
			(xy 131.847637 -167.994333) (xy 131.901594 -168.008439) (xy 131.952923 -168.030251) (xy 132.000529 -168.059305)
			(xy 132.043397 -168.09498) (xy 132.080614 -168.136517) (xy 132.111387 -168.18303) (xy 132.135059 -168.233527)
			(xy 132.151127 -168.286934) (xy 132.159247 -168.34211) (xy 132.159756 -168.369996) (xy 132.159247 -168.397882)
			(xy 132.151127 -168.453058) (xy 132.135059 -168.506465) (xy 132.111387 -168.556962) (xy 132.080614 -168.603475)
			(xy 132.043397 -168.645012) (xy 132.000529 -168.680687) (xy 131.968615 -168.700164) (xy 133.213906 -168.700164)
			(xy 133.213906 -168.640236) (xy 133.221728 -168.58082) (xy 133.237237 -168.522933) (xy 133.26017 -168.467566)
			(xy 133.290132 -168.415665) (xy 133.326612 -168.368119) (xy 133.368986 -168.325742) (xy 133.416529 -168.289257)
			(xy 133.468426 -168.259289) (xy 133.523791 -168.236351) (xy 133.581677 -168.220836) (xy 133.641092 -168.213009)
			(xy 133.671056 -168.212516) (xy 134.534656 -168.212516) (xy 134.564628 -168.212934) (xy 134.624061 -168.220754)
			(xy 134.681965 -168.236264) (xy 134.737348 -168.2592) (xy 134.789264 -168.289169) (xy 134.836823 -168.325658)
			(xy 134.879213 -168.368044) (xy 134.915707 -168.4156) (xy 134.945681 -168.467512) (xy 134.968622 -168.522894)
			(xy 134.984138 -168.580796) (xy 134.991963 -168.640228) (xy 134.991963 -168.700172) (xy 134.984138 -168.759604)
			(xy 134.968622 -168.817506) (xy 134.945681 -168.872888) (xy 134.915707 -168.9248) (xy 134.879213 -168.972356)
			(xy 134.836823 -169.014742) (xy 134.789264 -169.051231) (xy 134.737348 -169.0812) (xy 134.681965 -169.104136)
			(xy 134.624061 -169.119646) (xy 134.564628 -169.127466) (xy 134.534656 -169.127932) (xy 133.671056 -169.127932)
			(xy 133.641092 -169.127391) (xy 133.581677 -169.119564) (xy 133.523791 -169.104049) (xy 133.468426 -169.081111)
			(xy 133.416529 -169.051143) (xy 133.368986 -169.014658) (xy 133.326612 -168.972281) (xy 133.290132 -168.924735)
			(xy 133.26017 -168.872834) (xy 133.237237 -168.817467) (xy 133.221728 -168.75958) (xy 133.213906 -168.700164)
			(xy 131.968615 -168.700164) (xy 131.952923 -168.709741) (xy 131.901594 -168.731553) (xy 131.847637 -168.745659)
			(xy 131.7922 -168.751759) (xy 131.736466 -168.749722) (xy 131.681623 -168.739592) (xy 131.628839 -168.721585)
			(xy 131.579239 -168.696084) (xy 131.533881 -168.663633) (xy 131.493732 -168.624924) (xy 131.459646 -168.580781)
			(xy 131.43235 -168.532146) (xy 131.412427 -168.480055) (xy 131.400301 -168.425618) (xy 131.39623 -168.369996)
			(xy 128.190865 -168.369996) (xy 127.250433 -169.310558) (xy 132.172454 -169.310558) (xy 132.176525 -169.254936)
			(xy 132.188651 -169.200499) (xy 132.208574 -169.148408) (xy 132.23587 -169.099773) (xy 132.269956 -169.05563)
			(xy 132.310105 -169.016921) (xy 132.355463 -168.98447) (xy 132.405063 -168.958969) (xy 132.457847 -168.940962)
			(xy 132.51269 -168.930832) (xy 132.568424 -168.928795) (xy 132.623861 -168.934895) (xy 132.677818 -168.949001)
			(xy 132.729147 -168.970813) (xy 132.776753 -168.999867) (xy 132.819621 -169.035542) (xy 132.856838 -169.077079)
			(xy 132.887611 -169.123592) (xy 132.911283 -169.174089) (xy 132.927351 -169.227496) (xy 132.935471 -169.282672)
			(xy 132.93598 -169.310558) (xy 132.935471 -169.338444) (xy 132.927351 -169.39362) (xy 132.911283 -169.447027)
			(xy 132.887611 -169.497524) (xy 132.856838 -169.544037) (xy 132.819621 -169.585574) (xy 132.776753 -169.621249)
			(xy 132.729147 -169.650303) (xy 132.677818 -169.672115) (xy 132.623861 -169.686221) (xy 132.568424 -169.692321)
			(xy 132.51269 -169.690284) (xy 132.457847 -169.680154) (xy 132.405063 -169.662147) (xy 132.355463 -169.636646)
			(xy 132.310105 -169.604195) (xy 132.269956 -169.565486) (xy 132.23587 -169.521343) (xy 132.208574 -169.472708)
			(xy 132.188651 -169.420617) (xy 132.176525 -169.36618) (xy 132.172454 -169.310558) (xy 127.250433 -169.310558)
			(xy 127.168402 -169.3926) (xy 127.14963 -169.41063) (xy 127.107512 -169.441206) (xy 127.061136 -169.464829)
			(xy 127.011639 -169.480919) (xy 126.960237 -169.489081) (xy 126.934214 -169.489628) (xy 126.202948 -169.489628)
			(xy 126.196794 -169.489795) (xy 126.184846 -169.492745) (xy 126.179326 -169.49547) (xy 126.151799 -169.509308)
			(xy 126.093386 -169.528891) (xy 126.032584 -169.538826) (xy 126.00178 -169.539412) (xy 125.974529 -169.538925)
			(xy 125.920583 -169.531166) (xy 125.86829 -169.515809) (xy 125.818715 -169.493166) (xy 125.772867 -169.463699)
			(xy 125.731678 -169.428007) (xy 125.695989 -169.386817) (xy 125.666524 -169.340967) (xy 125.643884 -169.291391)
			(xy 125.62853 -169.239097) (xy 125.620774 -169.185151) (xy 125.620774 -169.130649) (xy 125.62853 -169.076703)
			(xy 125.643884 -169.024409) (xy 125.666524 -168.974833) (xy 125.695989 -168.928983) (xy 125.731678 -168.887793)
			(xy 125.772867 -168.852101) (xy 125.818715 -168.822634) (xy 125.86829 -168.799991) (xy 125.920583 -168.784634)
			(xy 125.974529 -168.776875) (xy 126.00178 -168.776396) (xy 126.032582 -168.777006) (xy 126.093381 -168.786942)
			(xy 126.151796 -168.80651) (xy 126.179326 -168.820338) (xy 126.184859 -168.823027) (xy 126.196799 -168.825969)
			(xy 126.202948 -168.82618) (xy 126.77521 -168.82618) (xy 126.785279 -168.825755) (xy 126.803879 -168.818035)
			(xy 126.811278 -168.811194) (xy 128.652778 -166.96944) (xy 128.671548 -166.951407) (xy 128.713664 -166.920825)
			(xy 128.760041 -166.897196) (xy 128.809538 -166.881101) (xy 128.860942 -166.872935) (xy 128.886966 -166.872412)
			(xy 137.066274 -166.872412) (xy 137.092297 -166.872941) (xy 137.143699 -166.88111) (xy 137.193195 -166.897206)
			(xy 137.239571 -166.920833) (xy 137.281689 -166.951411) (xy 137.300462 -166.96944) (xy 137.530332 -167.199564)
			(xy 137.537764 -167.206361) (xy 137.556378 -167.214011) (xy 137.576502 -167.213956) (xy 137.585958 -167.210486)
			(xy 137.594985 -167.206226) (xy 137.609092 -167.192135) (xy 137.616737 -167.173719) (xy 137.6172 -167.16375)
			(xy 137.6172 -166.317676) (xy 137.616772 -166.307608) (xy 137.609052 -166.28901) (xy 137.602214 -166.281608)
			(xy 135.904224 -164.583618) (xy 135.896822 -164.576782) (xy 135.878224 -164.569072) (xy 135.868156 -164.568632)
			(xy 125.353572 -164.568632) (xy 125.327486 -164.568144) (xy 125.275957 -164.559973) (xy 125.226343 -164.543836)
			(xy 125.179866 -164.520133) (xy 125.137672 -164.489446) (xy 125.118876 -164.47135) (xy 123.048268 -162.400488)
			(xy 123.040839 -162.393685) (xy 123.022223 -162.386027) (xy 123.002094 -162.386083) (xy 122.992642 -162.389566)
			(xy 122.983582 -162.393771) (xy 122.96947 -162.407884) (xy 122.961833 -162.426323) (xy 122.9614 -162.436302)
			(xy 122.9614 -167.074088) (xy 125.212092 -167.074088) (xy 125.216163 -167.018466) (xy 125.228289 -166.964029)
			(xy 125.248212 -166.911938) (xy 125.275508 -166.863303) (xy 125.309594 -166.81916) (xy 125.349743 -166.780451)
			(xy 125.395101 -166.748) (xy 125.444701 -166.722499) (xy 125.497485 -166.704492) (xy 125.552328 -166.694362)
			(xy 125.608062 -166.692325) (xy 125.663499 -166.698425) (xy 125.717456 -166.712531) (xy 125.768785 -166.734343)
			(xy 125.816391 -166.763397) (xy 125.859259 -166.799072) (xy 125.896476 -166.840609) (xy 125.927249 -166.887122)
			(xy 125.950921 -166.937619) (xy 125.966989 -166.991026) (xy 125.975109 -167.046202) (xy 125.975618 -167.074088)
			(xy 125.975109 -167.101974) (xy 125.972552 -167.119352) (xy 126.499077 -167.119352) (xy 126.499077 -167.064848)
			(xy 126.506834 -167.010899) (xy 126.52219 -166.958604) (xy 126.544832 -166.909025) (xy 126.574299 -166.863174)
			(xy 126.609992 -166.821984) (xy 126.651184 -166.786292) (xy 126.697036 -166.756826) (xy 126.746615 -166.734186)
			(xy 126.798911 -166.718832) (xy 126.85286 -166.711076) (xy 126.880112 -166.710614) (xy 126.906518 -166.711069)
			(xy 126.958824 -166.718361) (xy 127.009626 -166.732791) (xy 127.057955 -166.754084) (xy 127.102889 -166.781833)
			(xy 127.143571 -166.81551) (xy 127.179224 -166.85447) (xy 127.194564 -166.875968) (xy 127.203292 -166.887861)
			(xy 127.226243 -166.906378) (xy 127.25353 -166.917563) (xy 127.282875 -166.920481) (xy 127.31183 -166.91489)
			(xy 127.337978 -166.901256) (xy 127.359139 -166.880717) (xy 127.366776 -166.868094) (xy 127.381373 -166.843114)
			(xy 127.416906 -166.79746) (xy 127.458926 -166.757694) (xy 127.506467 -166.724728) (xy 127.55844 -166.699317)
			(xy 127.613655 -166.682044) (xy 127.670844 -166.673305) (xy 127.69977 -166.672768) (xy 127.727023 -166.673277)
			(xy 127.780973 -166.68103) (xy 127.833271 -166.696383) (xy 127.882852 -166.719022) (xy 127.928706 -166.748487)
			(xy 127.9699 -166.784179) (xy 128.005595 -166.82537) (xy 128.035064 -166.871221) (xy 128.057707 -166.9208)
			(xy 128.073063 -166.973097) (xy 128.080821 -167.027047) (xy 128.080821 -167.081553) (xy 128.073063 -167.135503)
			(xy 128.057707 -167.1878) (xy 128.035064 -167.237379) (xy 128.005595 -167.28323) (xy 127.9699 -167.324421)
			(xy 127.928706 -167.360113) (xy 127.882852 -167.389578) (xy 127.833271 -167.412217) (xy 127.780973 -167.42757)
			(xy 127.727023 -167.435323) (xy 127.69977 -167.435784) (xy 127.673364 -167.435344) (xy 127.621057 -167.428049)
			(xy 127.570255 -167.413616) (xy 127.521926 -167.392321) (xy 127.476992 -167.364569) (xy 127.43631 -167.330891)
			(xy 127.400658 -167.291929) (xy 127.385318 -167.27043) (xy 127.376612 -167.25852) (xy 127.353656 -167.240002)
			(xy 127.326364 -167.228819) (xy 127.297015 -167.225902) (xy 127.268057 -167.231497) (xy 127.241905 -167.245135)
			(xy 127.220743 -167.265679) (xy 127.213106 -167.278304) (xy 127.198521 -167.303291) (xy 127.162986 -167.348945)
			(xy 127.120965 -167.388711) (xy 127.073421 -167.421677) (xy 127.021446 -167.447086) (xy 126.96623 -167.464357)
			(xy 126.909039 -167.473094) (xy 126.880112 -167.47363) (xy 126.85286 -167.473124) (xy 126.798911 -167.465368)
			(xy 126.746615 -167.450014) (xy 126.697036 -167.427374) (xy 126.651184 -167.397908) (xy 126.609992 -167.362216)
			(xy 126.574299 -167.321026) (xy 126.544832 -167.275175) (xy 126.52219 -167.225596) (xy 126.506834 -167.173301)
			(xy 126.499077 -167.119352) (xy 125.972552 -167.119352) (xy 125.966989 -167.15715) (xy 125.950921 -167.210557)
			(xy 125.927249 -167.261054) (xy 125.896476 -167.307567) (xy 125.859259 -167.349104) (xy 125.816391 -167.384779)
			(xy 125.768785 -167.413833) (xy 125.717456 -167.435645) (xy 125.663499 -167.449751) (xy 125.608062 -167.455851)
			(xy 125.552328 -167.453814) (xy 125.497485 -167.443684) (xy 125.444701 -167.425677) (xy 125.395101 -167.400176)
			(xy 125.349743 -167.367725) (xy 125.309594 -167.329016) (xy 125.275508 -167.284873) (xy 125.248212 -167.236238)
			(xy 125.228289 -167.184147) (xy 125.216163 -167.12971) (xy 125.212092 -167.074088) (xy 122.9614 -167.074088)
			(xy 122.9614 -167.759634) (xy 122.96175 -167.768588) (xy 122.967901 -167.785408) (xy 122.979445 -167.799099)
			(xy 122.987054 -167.80383) (xy 123.016606 -167.821216) (xy 123.071824 -167.861864) (xy 123.121918 -167.908683)
			(xy 123.166202 -167.96103) (xy 123.204071 -168.018191) (xy 123.235006 -168.079382) (xy 123.258584 -168.143767)
			(xy 123.274482 -168.210465) (xy 123.282483 -168.278563) (xy 123.282964 -168.312846) (xy 123.282485 -168.345723)
			(xy 123.275091 -168.411061) (xy 123.260436 -168.475162) (xy 123.238702 -168.537221) (xy 123.210162 -168.59646)
			(xy 123.175176 -168.652134) (xy 123.134182 -168.703546) (xy 123.11126 -168.72712) (xy 123.10491 -168.733216)
			(xy 123.098029 -168.740668) (xy 123.090298 -168.759402) (xy 123.089924 -168.769538) (xy 123.089924 -169.474896)
			(xy 123.764292 -169.474896) (xy 123.768363 -169.419274) (xy 123.780489 -169.364837) (xy 123.800412 -169.312746)
			(xy 123.827708 -169.264111) (xy 123.861794 -169.219968) (xy 123.901943 -169.181259) (xy 123.947301 -169.148808)
			(xy 123.996901 -169.123307) (xy 124.049685 -169.1053) (xy 124.104528 -169.09517) (xy 124.160262 -169.093133)
			(xy 124.215699 -169.099233) (xy 124.269656 -169.113339) (xy 124.320985 -169.135151) (xy 124.368591 -169.164205)
			(xy 124.411459 -169.19988) (xy 124.448676 -169.241417) (xy 124.479449 -169.28793) (xy 124.503121 -169.338427)
			(xy 124.519189 -169.391834) (xy 124.527309 -169.44701) (xy 124.527818 -169.474896) (xy 124.527309 -169.502782)
			(xy 124.519189 -169.557958) (xy 124.503121 -169.611365) (xy 124.479449 -169.661862) (xy 124.448676 -169.708375)
			(xy 124.411459 -169.749912) (xy 124.368591 -169.785587) (xy 124.320985 -169.814641) (xy 124.269656 -169.836453)
			(xy 124.215699 -169.850559) (xy 124.160262 -169.856659) (xy 124.104528 -169.854622) (xy 124.049685 -169.844492)
			(xy 123.996901 -169.826485) (xy 123.947301 -169.800984) (xy 123.901943 -169.768533) (xy 123.861794 -169.729824)
			(xy 123.827708 -169.685681) (xy 123.800412 -169.637046) (xy 123.780489 -169.584955) (xy 123.768363 -169.530518)
			(xy 123.764292 -169.474896) (xy 123.089924 -169.474896) (xy 123.089924 -173.089062) (xy 126.182628 -173.089062)
			(xy 126.183124 -173.061693) (xy 126.190933 -173.007515) (xy 126.206415 -172.955012) (xy 126.22925 -172.905264)
			(xy 126.258969 -172.859296) (xy 126.276608 -172.838364) (xy 126.276862 -172.83811) (xy 126.282458 -172.83103)
			(xy 126.288697 -172.814108) (xy 126.289054 -172.80509) (xy 126.289054 -172.738034) (xy 126.288691 -172.729018)
			(xy 126.282449 -172.7121) (xy 126.276862 -172.705014) (xy 126.276608 -172.705014) (xy 126.276608 -172.70476)
			(xy 126.258985 -172.683815) (xy 126.22927 -172.637846) (xy 126.206431 -172.588102) (xy 126.190936 -172.535604)
			(xy 126.183104 -172.48143) (xy 126.182628 -172.454062) (xy 126.183114 -172.426811) (xy 126.19087 -172.372863)
			(xy 126.206225 -172.320568) (xy 126.228867 -172.270991) (xy 126.258333 -172.225141) (xy 126.294024 -172.18395)
			(xy 126.335215 -172.148259) (xy 126.381065 -172.118793) (xy 126.430642 -172.096151) (xy 126.482937 -172.080796)
			(xy 126.536885 -172.07304) (xy 126.591387 -172.07304) (xy 126.645335 -172.080796) (xy 126.69763 -172.096151)
			(xy 126.747207 -172.118793) (xy 126.793057 -172.148259) (xy 126.834248 -172.18395) (xy 126.869939 -172.225141)
			(xy 126.877491 -172.236892) (xy 127.879346 -172.236892) (xy 127.883417 -172.18127) (xy 127.895543 -172.126833)
			(xy 127.915466 -172.074742) (xy 127.942762 -172.026107) (xy 127.976848 -171.981964) (xy 128.016997 -171.943255)
			(xy 128.062355 -171.910804) (xy 128.111955 -171.885303) (xy 128.164739 -171.867296) (xy 128.219582 -171.857166)
			(xy 128.275316 -171.855129) (xy 128.330753 -171.861229) (xy 128.38471 -171.875335) (xy 128.436039 -171.897147)
			(xy 128.483645 -171.926201) (xy 128.526513 -171.961876) (xy 128.56373 -172.003413) (xy 128.594503 -172.049926)
			(xy 128.618175 -172.100423) (xy 128.62217 -172.113702) (xy 132.256782 -172.113702) (xy 132.260853 -172.05808)
			(xy 132.272979 -172.003643) (xy 132.292902 -171.951552) (xy 132.320198 -171.902917) (xy 132.354284 -171.858774)
			(xy 132.394433 -171.820065) (xy 132.439791 -171.787614) (xy 132.489391 -171.762113) (xy 132.542175 -171.744106)
			(xy 132.597018 -171.733976) (xy 132.652752 -171.731939) (xy 132.708189 -171.738039) (xy 132.762146 -171.752145)
			(xy 132.813475 -171.773957) (xy 132.861081 -171.803011) (xy 132.903949 -171.838686) (xy 132.941166 -171.880223)
			(xy 132.971939 -171.926736) (xy 132.995611 -171.977233) (xy 133.011679 -172.03064) (xy 133.019799 -172.085816)
			(xy 133.020308 -172.113702) (xy 133.019799 -172.141588) (xy 133.011679 -172.196764) (xy 132.995611 -172.250171)
			(xy 132.971939 -172.300668) (xy 132.941166 -172.347181) (xy 132.903949 -172.388718) (xy 132.861081 -172.424393)
			(xy 132.813475 -172.453447) (xy 132.762146 -172.475259) (xy 132.708189 -172.489365) (xy 132.652752 -172.495465)
			(xy 132.597018 -172.493428) (xy 132.542175 -172.483298) (xy 132.489391 -172.465291) (xy 132.439791 -172.43979)
			(xy 132.394433 -172.407339) (xy 132.354284 -172.36863) (xy 132.320198 -172.324487) (xy 132.292902 -172.275852)
			(xy 132.272979 -172.223761) (xy 132.260853 -172.169324) (xy 132.256782 -172.113702) (xy 128.62217 -172.113702)
			(xy 128.634243 -172.15383) (xy 128.642363 -172.209006) (xy 128.642872 -172.236892) (xy 128.642363 -172.264778)
			(xy 128.634243 -172.319954) (xy 128.618175 -172.373361) (xy 128.594503 -172.423858) (xy 128.56373 -172.470371)
			(xy 128.526513 -172.511908) (xy 128.483645 -172.547583) (xy 128.436039 -172.576637) (xy 128.38471 -172.598449)
			(xy 128.330753 -172.612555) (xy 128.275316 -172.618655) (xy 128.219582 -172.616618) (xy 128.164739 -172.606488)
			(xy 128.111955 -172.588481) (xy 128.062355 -172.56298) (xy 128.016997 -172.530529) (xy 127.976848 -172.49182)
			(xy 127.942762 -172.447677) (xy 127.915466 -172.399042) (xy 127.895543 -172.346951) (xy 127.883417 -172.292514)
			(xy 127.879346 -172.236892) (xy 126.877491 -172.236892) (xy 126.899405 -172.270991) (xy 126.922047 -172.320568)
			(xy 126.937402 -172.372863) (xy 126.945158 -172.426811) (xy 126.945644 -172.454062) (xy 126.945169 -172.481432)
			(xy 126.937356 -172.535611) (xy 126.921869 -172.588115) (xy 126.899029 -172.637862) (xy 126.869305 -172.683829)
			(xy 126.851664 -172.70476) (xy 126.85141 -172.705014) (xy 126.845813 -172.712093) (xy 126.839572 -172.729016)
			(xy 126.839218 -172.738034) (xy 126.839218 -172.80509) (xy 126.839576 -172.814107) (xy 126.845822 -172.831024)
			(xy 126.85141 -172.83811) (xy 126.851664 -172.83811) (xy 126.851664 -172.838364) (xy 126.869294 -172.859303)
			(xy 126.899009 -172.905274) (xy 126.921847 -172.955019) (xy 126.93734 -173.007518) (xy 126.945169 -173.061693)
			(xy 126.945644 -173.089062) (xy 126.945158 -173.116313) (xy 126.937402 -173.170261) (xy 126.922047 -173.222556)
			(xy 126.899405 -173.272133) (xy 126.869939 -173.317983) (xy 126.834248 -173.359174) (xy 126.793057 -173.394865)
			(xy 126.747207 -173.424331) (xy 126.69763 -173.446973) (xy 126.645335 -173.462328) (xy 126.591387 -173.470084)
			(xy 126.536885 -173.470084) (xy 126.482937 -173.462328) (xy 126.430642 -173.446973) (xy 126.381065 -173.424331)
			(xy 126.335215 -173.394865) (xy 126.294024 -173.359174) (xy 126.258333 -173.317983) (xy 126.228867 -173.272133)
			(xy 126.206225 -173.222556) (xy 126.19087 -173.170261) (xy 126.183114 -173.116313) (xy 126.182628 -173.089062)
			(xy 123.089924 -173.089062) (xy 123.089924 -173.544484) (xy 129.265932 -173.544484) (xy 129.270003 -173.488862)
			(xy 129.282129 -173.434425) (xy 129.302052 -173.382334) (xy 129.329348 -173.333699) (xy 129.363434 -173.289556)
			(xy 129.403583 -173.250847) (xy 129.448941 -173.218396) (xy 129.498541 -173.192895) (xy 129.551325 -173.174888)
			(xy 129.606168 -173.164758) (xy 129.661902 -173.162721) (xy 129.717339 -173.168821) (xy 129.771296 -173.182927)
			(xy 129.822625 -173.204739) (xy 129.870231 -173.233793) (xy 129.913099 -173.269468) (xy 129.950316 -173.311005)
			(xy 129.981089 -173.357518) (xy 130.004761 -173.408015) (xy 130.020829 -173.461422) (xy 130.028949 -173.516598)
			(xy 130.029458 -173.544484) (xy 130.028949 -173.57237) (xy 130.020829 -173.627546) (xy 130.004761 -173.680953)
			(xy 129.981089 -173.73145) (xy 129.950316 -173.777963) (xy 129.913099 -173.8195) (xy 129.870231 -173.855175)
			(xy 129.822625 -173.884229) (xy 129.771296 -173.906041) (xy 129.717339 -173.920147) (xy 129.661902 -173.926247)
			(xy 129.606168 -173.92421) (xy 129.551325 -173.91408) (xy 129.498541 -173.896073) (xy 129.448941 -173.870572)
			(xy 129.403583 -173.838121) (xy 129.363434 -173.799412) (xy 129.329348 -173.755269) (xy 129.302052 -173.706634)
			(xy 129.282129 -173.654543) (xy 129.270003 -173.600106) (xy 129.265932 -173.544484) (xy 123.089924 -173.544484)
			(xy 123.089924 -174.325026) (xy 132.089142 -174.325026) (xy 132.093213 -174.269404) (xy 132.105339 -174.214967)
			(xy 132.125262 -174.162876) (xy 132.152558 -174.114241) (xy 132.186644 -174.070098) (xy 132.226793 -174.031389)
			(xy 132.272151 -173.998938) (xy 132.321751 -173.973437) (xy 132.374535 -173.95543) (xy 132.429378 -173.9453)
			(xy 132.485112 -173.943263) (xy 132.540549 -173.949363) (xy 132.594506 -173.963469) (xy 132.645835 -173.985281)
			(xy 132.693441 -174.014335) (xy 132.736309 -174.05001) (xy 132.773526 -174.091547) (xy 132.804299 -174.13806)
			(xy 132.827971 -174.188557) (xy 132.844039 -174.241964) (xy 132.852159 -174.29714) (xy 132.852668 -174.325026)
			(xy 132.852159 -174.352912) (xy 132.844039 -174.408088) (xy 132.827971 -174.461495) (xy 132.804299 -174.511992)
			(xy 132.773526 -174.558505) (xy 132.736309 -174.600042) (xy 132.693441 -174.635717) (xy 132.670941 -174.649449)
			(xy 135.696484 -174.649449) (xy 135.696484 -174.594951) (xy 135.704239 -174.541009) (xy 135.719591 -174.488719)
			(xy 135.742229 -174.439145) (xy 135.77169 -174.393298) (xy 135.807376 -174.35211) (xy 135.848559 -174.316419)
			(xy 135.894403 -174.286952) (xy 135.943974 -174.264308) (xy 135.996262 -174.248949) (xy 136.050203 -174.241187)
			(xy 136.077452 -174.240698) (xy 136.077706 -174.240698) (xy 136.104205 -174.241155) (xy 136.15669 -174.248524)
			(xy 136.207652 -174.263076) (xy 136.256114 -174.284534) (xy 136.301143 -174.312484) (xy 136.3218 -174.32909)
			(xy 136.329166 -174.335186) (xy 136.3472 -174.341282) (xy 136.425686 -174.337218) (xy 136.435172 -174.336332)
			(xy 136.452526 -174.328503) (xy 136.459468 -174.321978) (xy 136.477489 -174.304161) (xy 136.517399 -174.272933)
			(xy 136.561092 -174.247263) (xy 136.607799 -174.227604) (xy 136.656697 -174.2143) (xy 136.706926 -174.207587)
			(xy 136.732264 -174.20717) (xy 136.759517 -174.207675) (xy 136.813469 -174.215427) (xy 136.865768 -174.230779)
			(xy 136.91535 -174.253418) (xy 136.961205 -174.282884) (xy 137.002399 -174.318575) (xy 137.038095 -174.359767)
			(xy 137.067564 -174.405619) (xy 137.090208 -174.455198) (xy 137.105565 -174.507496) (xy 137.113323 -174.561447)
			(xy 137.113323 -174.615953) (xy 137.105565 -174.669904) (xy 137.090208 -174.722202) (xy 137.067564 -174.771781)
			(xy 137.038095 -174.817633) (xy 137.002399 -174.858825) (xy 136.961205 -174.894516) (xy 136.91535 -174.923982)
			(xy 136.865768 -174.946621) (xy 136.813469 -174.961973) (xy 136.759517 -174.969725) (xy 136.732264 -174.970186)
			(xy 136.73201 -174.970186) (xy 136.705511 -174.969723) (xy 136.653026 -174.962357) (xy 136.602064 -174.947806)
			(xy 136.553603 -174.926349) (xy 136.508573 -174.898399) (xy 136.487916 -174.881794) (xy 136.48055 -174.875698)
			(xy 136.462516 -174.869602) (xy 136.38403 -174.873666) (xy 136.374546 -174.874564) (xy 136.357191 -174.882385)
			(xy 136.350248 -174.888906) (xy 136.332263 -174.906761) (xy 136.292345 -174.937986) (xy 136.248645 -174.963651)
			(xy 136.201931 -174.983304) (xy 136.153026 -174.996599) (xy 136.102792 -175.003303) (xy 136.077452 -175.003714)
			(xy 136.050203 -175.003213) (xy 135.996262 -174.995451) (xy 135.943974 -174.980092) (xy 135.894403 -174.957448)
			(xy 135.848559 -174.927981) (xy 135.807376 -174.89229) (xy 135.77169 -174.851102) (xy 135.742229 -174.805255)
			(xy 135.719591 -174.755681) (xy 135.704239 -174.703391) (xy 135.696484 -174.649449) (xy 132.670941 -174.649449)
			(xy 132.645835 -174.664771) (xy 132.594506 -174.686583) (xy 132.540549 -174.700689) (xy 132.485112 -174.706789)
			(xy 132.429378 -174.704752) (xy 132.374535 -174.694622) (xy 132.321751 -174.676615) (xy 132.272151 -174.651114)
			(xy 132.226793 -174.618663) (xy 132.186644 -174.579954) (xy 132.152558 -174.535811) (xy 132.125262 -174.487176)
			(xy 132.105339 -174.435085) (xy 132.093213 -174.380648) (xy 132.089142 -174.325026) (xy 123.089924 -174.325026)
			(xy 123.089924 -176.722278) (xy 130.560318 -176.722278) (xy 130.560719 -176.696161) (xy 130.568017 -176.64444)
			(xy 130.582466 -176.594244) (xy 130.603785 -176.546558) (xy 130.631554 -176.502317) (xy 130.665229 -176.462388)
			(xy 130.704151 -176.427553) (xy 130.747556 -176.398495) (xy 130.770884 -176.386744) (xy 130.783584 -176.380648)
			(xy 130.799078 -176.357026) (xy 130.803142 -176.25314) (xy 130.803054 -176.24395) (xy 130.797134 -176.226565)
			(xy 130.785492 -176.21236) (xy 130.777742 -176.20742) (xy 130.777488 -176.207166) (xy 130.754665 -176.193402)
			(xy 130.712988 -176.160184) (xy 130.67673 -176.121124) (xy 130.6467 -176.077096) (xy 130.623569 -176.029082)
			(xy 130.607855 -175.978156) (xy 130.599908 -175.925457) (xy 130.599434 -175.89881) (xy 130.599922 -175.870823)
			(xy 130.608677 -175.815538) (xy 130.625975 -175.762303) (xy 130.651387 -175.71243) (xy 130.684289 -175.667147)
			(xy 130.723871 -175.627569) (xy 130.769157 -175.59467) (xy 130.819032 -175.569262) (xy 130.872269 -175.55197)
			(xy 130.927555 -175.543219) (xy 130.955542 -175.542702) (xy 130.95605 -175.542702) (xy 130.984909 -175.543265)
			(xy 131.041862 -175.552626) (xy 131.096562 -175.571047) (xy 131.147576 -175.598046) (xy 131.19357 -175.632916)
			(xy 131.21386 -175.653446) (xy 131.22148 -175.661574) (xy 131.242054 -175.669956) (xy 131.329684 -175.665638)
			(xy 131.340595 -175.664593) (xy 131.360076 -175.654597) (xy 131.367276 -175.646334) (xy 131.36753 -175.64608)
			(xy 131.384499 -175.625173) (xy 131.423683 -175.588242) (xy 131.467983 -175.557635) (xy 131.516387 -175.534049)
			(xy 131.567792 -175.518021) (xy 131.621023 -175.509919) (xy 131.647946 -175.509428) (xy 131.6482 -175.509428)
			(xy 131.675496 -175.509931) (xy 131.729445 -175.518299) (xy 131.781487 -175.534795) (xy 131.830405 -175.559033)
			(xy 131.875057 -175.590445) (xy 131.895088 -175.608996) (xy 131.902454 -175.616108) (xy 131.920234 -175.62322)
			(xy 132.010658 -175.62322) (xy 132.028438 -175.616108) (xy 132.035804 -175.608996) (xy 132.055803 -175.590405)
			(xy 132.100448 -175.558971) (xy 132.149374 -175.534729) (xy 132.201429 -175.518249) (xy 132.255391 -175.509919)
			(xy 132.282692 -175.509428) (xy 132.282946 -175.509428) (xy 132.309596 -175.509857) (xy 132.362299 -175.517807)
			(xy 132.413229 -175.533523) (xy 132.461248 -175.556653) (xy 132.505284 -175.586681) (xy 132.544353 -175.622937)
			(xy 132.577583 -175.66461) (xy 132.60423 -175.71077) (xy 132.623701 -175.760386) (xy 132.635561 -175.812349)
			(xy 132.639544 -175.8655) (xy 132.635561 -175.918651) (xy 132.623701 -175.970614) (xy 132.60423 -176.02023)
			(xy 132.577583 -176.06639) (xy 132.544353 -176.108063) (xy 132.505284 -176.144319) (xy 132.461248 -176.174347)
			(xy 132.413229 -176.197477) (xy 132.362299 -176.213193) (xy 132.309596 -176.221143) (xy 132.282946 -176.221644)
			(xy 132.282692 -176.221644) (xy 132.255399 -176.221065) (xy 132.201455 -176.212712) (xy 132.149414 -176.196233)
			(xy 132.100494 -176.172013) (xy 132.055839 -176.140619) (xy 132.035804 -176.122076) (xy 132.028438 -176.114964)
			(xy 132.010658 -176.107852) (xy 131.920234 -176.107852) (xy 131.902454 -176.114964) (xy 131.895088 -176.122076)
			(xy 131.875069 -176.140682) (xy 131.830378 -176.17214) (xy 131.781401 -176.196391) (xy 131.72929 -176.212864)
			(xy 131.675273 -176.221171) (xy 131.647946 -176.221644) (xy 131.619036 -176.221112) (xy 131.561973 -176.211799)
			(xy 131.507162 -176.193393) (xy 131.456043 -176.166378) (xy 131.409957 -176.131462) (xy 131.389628 -176.1109)
			(xy 131.382008 -176.102772) (xy 131.361434 -176.09439) (xy 131.273804 -176.098708) (xy 131.262896 -176.099765)
			(xy 131.243415 -176.109754) (xy 131.236212 -176.118012) (xy 131.235958 -176.118266) (xy 131.219566 -176.138489)
			(xy 131.181872 -176.174391) (xy 131.139345 -176.204411) (xy 131.116324 -176.216564) (xy 131.103624 -176.222914)
			(xy 131.088892 -176.246536) (xy 131.086606 -176.365154) (xy 131.100576 -176.389284) (xy 131.113022 -176.396142)
			(xy 131.137625 -176.410325) (xy 131.18261 -176.444981) (xy 131.221811 -176.486066) (xy 131.25432 -176.532626)
			(xy 131.279381 -176.583583) (xy 131.296415 -176.637755) (xy 131.305025 -176.693885) (xy 131.305554 -176.722278)
			(xy 131.305033 -176.750163) (xy 131.296721 -176.80531) (xy 131.280283 -176.858602) (xy 131.256085 -176.908848)
			(xy 131.224669 -176.954927) (xy 131.186736 -176.995809) (xy 131.143134 -177.030581) (xy 131.094836 -177.058466)
			(xy 131.042921 -177.078841) (xy 130.98855 -177.091251) (xy 130.932936 -177.095419) (xy 130.877322 -177.091251)
			(xy 130.822951 -177.078841) (xy 130.771036 -177.058466) (xy 130.722738 -177.030581) (xy 130.679136 -176.995809)
			(xy 130.641203 -176.954927) (xy 130.609787 -176.908848) (xy 130.585589 -176.858602) (xy 130.569151 -176.80531)
			(xy 130.560839 -176.750163) (xy 130.560318 -176.722278) (xy 123.089924 -176.722278) (xy 123.089924 -177.518314)
			(xy 123.09041 -177.529348) (xy 123.099558 -177.549425) (xy 123.116289 -177.563806) (xy 123.126754 -177.567336)
			(xy 123.153192 -177.575322) (xy 123.203607 -177.597866) (xy 123.250239 -177.627453) (xy 123.29211 -177.663465)
			(xy 123.328342 -177.705145) (xy 123.34367 -177.728118) (xy 123.349427 -177.736218) (xy 123.365696 -177.747593)
			(xy 123.385071 -177.751913) (xy 123.404632 -177.748528) (xy 123.413266 -177.743612) (xy 123.440682 -177.727074)
			(xy 123.49915 -177.700982) (xy 123.560681 -177.683284) (xy 123.624077 -177.674327) (xy 123.65609 -177.673762)
			(xy 123.656598 -177.673762) (xy 123.686583 -177.674231) (xy 123.74604 -177.682059) (xy 123.803967 -177.697581)
			(xy 123.859372 -177.720531) (xy 123.911308 -177.750517) (xy 123.958885 -177.787025) (xy 124.001289 -177.829432)
			(xy 124.037796 -177.87701) (xy 124.067779 -177.928947) (xy 124.090727 -177.984354) (xy 124.106246 -178.042281)
			(xy 124.11407 -178.101739) (xy 124.11456 -178.131724) (xy 124.11456 -178.143154) (xy 130.5649 -178.143154)
			(xy 130.568876 -178.088828) (xy 130.580719 -178.035659) (xy 130.600178 -177.984782) (xy 130.626838 -177.93728)
			(xy 130.660129 -177.894166) (xy 130.699343 -177.856359) (xy 130.743645 -177.824664) (xy 130.792088 -177.799758)
			(xy 130.843642 -177.78217) (xy 130.897208 -177.772276) (xy 130.951643 -177.770286) (xy 131.005788 -177.776244)
			(xy 131.058488 -177.790022) (xy 131.108621 -177.811326) (xy 131.155117 -177.839702) (xy 131.196987 -177.874546)
			(xy 131.233336 -177.915115) (xy 131.263392 -177.960544) (xy 131.286513 -178.009865) (xy 131.302206 -178.062027)
			(xy 131.310137 -178.115918) (xy 131.310634 -178.143154) (xy 131.310137 -178.17039) (xy 131.302206 -178.224281)
			(xy 131.286513 -178.276443) (xy 131.263392 -178.325764) (xy 131.233336 -178.371193) (xy 131.196987 -178.411762)
			(xy 131.155117 -178.446606) (xy 131.108621 -178.474982) (xy 131.058488 -178.496286) (xy 131.005788 -178.510064)
			(xy 130.951643 -178.516022) (xy 130.897208 -178.514032) (xy 130.843642 -178.504138) (xy 130.792088 -178.48655)
			(xy 130.743645 -178.461644) (xy 130.699343 -178.429949) (xy 130.660129 -178.392142) (xy 130.626838 -178.349028)
			(xy 130.600178 -178.301526) (xy 130.580719 -178.250649) (xy 130.568876 -178.19748) (xy 130.5649 -178.143154)
			(xy 124.11456 -178.143154) (xy 124.11456 -178.995324) (xy 124.114068 -179.025307) (xy 124.106238 -179.08476)
			(xy 124.090715 -179.142683) (xy 124.067765 -179.198084) (xy 124.03778 -179.250015) (xy 124.001273 -179.297589)
			(xy 123.958869 -179.33999) (xy 123.911293 -179.376494) (xy 123.85936 -179.406476) (xy 123.803958 -179.429424)
			(xy 123.746035 -179.444943) (xy 123.686581 -179.45277) (xy 123.656598 -179.453286) (xy 123.65609 -179.453286)
			(xy 123.624076 -179.452736) (xy 123.560676 -179.443785) (xy 123.499142 -179.426087) (xy 123.440675 -179.399987)
			(xy 123.413266 -179.383436) (xy 123.404611 -179.378571) (xy 123.385063 -179.375207) (xy 123.3657 -179.37951)
			(xy 123.349415 -179.390835) (xy 123.34367 -179.39893) (xy 123.328322 -179.421886) (xy 123.292069 -179.463537)
			(xy 123.250195 -179.499532) (xy 123.203574 -179.529122) (xy 123.153177 -179.551689) (xy 123.126754 -179.559712)
			(xy 123.116309 -179.563274) (xy 123.099606 -179.57766) (xy 123.090444 -179.59771) (xy 123.089924 -179.608734)
			(xy 123.089924 -180.02377) (xy 126.799338 -180.02377) (xy 126.803409 -179.968148) (xy 126.815535 -179.913711)
			(xy 126.835458 -179.86162) (xy 126.862754 -179.812985) (xy 126.89684 -179.768842) (xy 126.936989 -179.730133)
			(xy 126.982347 -179.697682) (xy 127.031947 -179.672181) (xy 127.084731 -179.654174) (xy 127.139574 -179.644044)
			(xy 127.195308 -179.642007) (xy 127.250745 -179.648107) (xy 127.304702 -179.662213) (xy 127.356031 -179.684025)
			(xy 127.403637 -179.713079) (xy 127.446505 -179.748754) (xy 127.483722 -179.790291) (xy 127.514495 -179.836804)
			(xy 127.538167 -179.887301) (xy 127.554235 -179.940708) (xy 127.562355 -179.995884) (xy 127.562864 -180.02377)
			(xy 127.562355 -180.051656) (xy 127.554235 -180.106832) (xy 127.538167 -180.160239) (xy 127.514495 -180.210736)
			(xy 127.483722 -180.257249) (xy 127.446505 -180.298786) (xy 127.403637 -180.334461) (xy 127.356031 -180.363515)
			(xy 127.304702 -180.385327) (xy 127.250745 -180.399433) (xy 127.195308 -180.405533) (xy 127.139574 -180.403496)
			(xy 127.084731 -180.393366) (xy 127.031947 -180.375359) (xy 126.982347 -180.349858) (xy 126.936989 -180.317407)
			(xy 126.89684 -180.278698) (xy 126.862754 -180.234555) (xy 126.835458 -180.18592) (xy 126.815535 -180.133829)
			(xy 126.803409 -180.079392) (xy 126.799338 -180.02377) (xy 123.089924 -180.02377) (xy 123.089924 -181.117748)
			(xy 123.090356 -181.127814) (xy 123.098086 -181.146403) (xy 123.10491 -181.153816) (xy 124.426946 -182.475757)
			(xy 129.801509 -182.475757) (xy 129.801509 -182.421243) (xy 129.809267 -182.367284) (xy 129.824626 -182.314978)
			(xy 129.847273 -182.26539) (xy 129.876747 -182.219531) (xy 129.912447 -182.178333) (xy 129.953647 -182.142635)
			(xy 129.999508 -182.113163) (xy 130.049097 -182.090519) (xy 130.101403 -182.075163) (xy 130.155363 -182.067408)
			(xy 130.18262 -182.066946) (xy 130.182874 -182.066946) (xy 130.202432 -182.067454) (xy 130.212846 -182.067962)
			(xy 130.232658 -182.06085) (xy 130.293618 -182.002684) (xy 130.300754 -181.995193) (xy 130.308881 -181.976188)
			(xy 130.309366 -181.965854) (xy 130.309797 -181.938567) (xy 130.317466 -181.884535) (xy 130.332755 -181.832148)
			(xy 130.355353 -181.782474) (xy 130.384799 -181.736526) (xy 130.420491 -181.695243) (xy 130.461701 -181.659467)
			(xy 130.507588 -181.629928) (xy 130.557216 -181.607228) (xy 130.609572 -181.591831) (xy 130.663588 -181.584052)
			(xy 130.690874 -181.583584) (xy 130.718127 -181.584062) (xy 130.77208 -181.591815) (xy 130.82438 -181.607169)
			(xy 130.873962 -181.629809) (xy 130.919818 -181.659276) (xy 130.961013 -181.694969) (xy 130.996708 -181.736161)
			(xy 131.026178 -181.782015) (xy 131.048822 -181.831596) (xy 131.064179 -181.883894) (xy 131.071937 -181.937847)
			(xy 131.071937 -181.992353) (xy 131.064179 -182.046306) (xy 131.048822 -182.098604) (xy 131.026178 -182.148185)
			(xy 130.996708 -182.194039) (xy 130.961013 -182.235231) (xy 130.919818 -182.270924) (xy 130.873962 -182.300391)
			(xy 130.82438 -182.323031) (xy 130.77208 -182.338385) (xy 130.718127 -182.346138) (xy 130.690874 -182.3466)
			(xy 130.69062 -182.3466) (xy 130.671062 -182.346092) (xy 130.660648 -182.345584) (xy 130.640836 -182.352696)
			(xy 130.579876 -182.410862) (xy 130.572719 -182.418335) (xy 130.564605 -182.437354) (xy 130.564128 -182.447692)
			(xy 130.563653 -182.474978) (xy 130.555991 -182.529009) (xy 130.540708 -182.581395) (xy 130.518116 -182.63107)
			(xy 130.488675 -182.677018) (xy 130.452988 -182.718302) (xy 130.411782 -182.754079) (xy 130.365898 -182.783619)
			(xy 130.316272 -182.806319) (xy 130.263919 -182.821716) (xy 130.209905 -182.829495) (xy 130.18262 -182.829962)
			(xy 130.155363 -182.829592) (xy 130.101403 -182.821837) (xy 130.049097 -182.806481) (xy 129.999508 -182.783837)
			(xy 129.953647 -182.754365) (xy 129.912447 -182.718667) (xy 129.876747 -182.677469) (xy 129.847273 -182.63161)
			(xy 129.824626 -182.582022) (xy 129.809267 -182.529716) (xy 129.801509 -182.475757) (xy 124.426946 -182.475757)
			(xy 124.955941 -183.004714) (xy 127.33731 -183.004714) (xy 127.341381 -182.949092) (xy 127.353507 -182.894655)
			(xy 127.37343 -182.842564) (xy 127.400726 -182.793929) (xy 127.434812 -182.749786) (xy 127.474961 -182.711077)
			(xy 127.520319 -182.678626) (xy 127.569919 -182.653125) (xy 127.622703 -182.635118) (xy 127.677546 -182.624988)
			(xy 127.73328 -182.622951) (xy 127.788717 -182.629051) (xy 127.842674 -182.643157) (xy 127.894003 -182.664969)
			(xy 127.941609 -182.694023) (xy 127.984477 -182.729698) (xy 128.021694 -182.771235) (xy 128.052467 -182.817748)
			(xy 128.076139 -182.868245) (xy 128.092207 -182.921652) (xy 128.100327 -182.976828) (xy 128.100836 -183.004714)
			(xy 128.100327 -183.0326) (xy 128.092207 -183.087776) (xy 128.076139 -183.141183) (xy 128.052467 -183.19168)
			(xy 128.021694 -183.238193) (xy 127.984477 -183.27973) (xy 127.941609 -183.315405) (xy 127.894003 -183.344459)
			(xy 127.842674 -183.366271) (xy 127.788717 -183.380377) (xy 127.73328 -183.386477) (xy 127.677546 -183.38444)
			(xy 127.622703 -183.37431) (xy 127.569919 -183.356303) (xy 127.520319 -183.330802) (xy 127.474961 -183.298351)
			(xy 127.434812 -183.259642) (xy 127.400726 -183.215499) (xy 127.37343 -183.166864) (xy 127.353507 -183.114773)
			(xy 127.341381 -183.060336) (xy 127.33731 -183.004714) (xy 124.955941 -183.004714) (xy 126.626874 -184.675526)
			(xy 126.649772 -184.69909) (xy 126.690726 -184.750474) (xy 126.725674 -184.806117) (xy 126.754178 -184.86532)
			(xy 126.775879 -184.92734) (xy 126.790506 -184.991399) (xy 126.797874 -185.056692) (xy 126.798324 -185.089546)
			(xy 126.798324 -187.000642) (xy 126.798755 -187.010708) (xy 126.806483 -187.029299) (xy 126.81331 -187.03671)
			(xy 126.99873 -187.22213) (xy 127.006142 -187.228814) (xy 127.024575 -187.236411) (xy 127.044513 -187.236411)
			(xy 127.062946 -187.228814) (xy 127.070358 -187.22213) (xy 133.434582 -180.857652) (xy 133.441423 -180.850252)
			(xy 133.449143 -180.831653) (xy 133.449568 -180.821584) (xy 133.449568 -179.812188) (xy 133.449167 -179.802958)
			(xy 133.442616 -179.785699) (xy 133.430372 -179.771884) (xy 133.42239 -179.76723) (xy 133.330188 -179.71897)
			(xy 133.301994 -179.720748) (xy 133.29031 -179.728876) (xy 133.266813 -179.744513) (xy 133.216098 -179.76928)
			(xy 133.16223 -179.786124) (xy 133.10644 -179.79466) (xy 133.07822 -179.79517) (xy 133.077966 -179.79517)
			(xy 133.052012 -179.794719) (xy 133.000606 -179.787508) (xy 132.950699 -179.773231) (xy 132.903257 -179.752164)
			(xy 132.859199 -179.724716) (xy 132.819378 -179.691417) (xy 132.801614 -179.672488) (xy 132.794067 -179.664983)
			(xy 132.774649 -179.656327) (xy 132.764022 -179.655724) (xy 132.68833 -179.655724) (xy 132.677669 -179.656178)
			(xy 132.658195 -179.664856) (xy 132.650738 -179.672488) (xy 132.631359 -179.693148) (xy 132.587459 -179.728943)
			(xy 132.538645 -179.757678) (xy 132.486043 -179.778689) (xy 132.430866 -179.791493) (xy 132.374386 -179.795794)
			(xy 132.317906 -179.791493) (xy 132.262729 -179.778689) (xy 132.210127 -179.757678) (xy 132.161313 -179.728943)
			(xy 132.117413 -179.693148) (xy 132.098034 -179.672488) (xy 132.090488 -179.66498) (xy 132.07107 -179.656316)
			(xy 132.060442 -179.655724) (xy 131.98475 -179.655724) (xy 131.974087 -179.656174) (xy 131.954607 -179.664847)
			(xy 131.947158 -179.672488) (xy 131.929414 -179.691435) (xy 131.889585 -179.724725) (xy 131.845522 -179.752166)
			(xy 131.798076 -179.773225) (xy 131.748167 -179.787495) (xy 131.696761 -179.7947) (xy 131.670806 -179.79517)
			(xy 131.645215 -179.794733) (xy 131.594517 -179.7877) (xy 131.545259 -179.773793) (xy 131.498368 -179.753275)
			(xy 131.454728 -179.726531) (xy 131.415159 -179.694065) (xy 131.397502 -179.675536) (xy 131.389982 -179.668157)
			(xy 131.370689 -179.65975) (xy 131.360164 -179.65928) (xy 131.285488 -179.65928) (xy 131.274977 -179.659809)
			(xy 131.255704 -179.668208) (xy 131.24815 -179.675536) (xy 131.230465 -179.694038) (xy 131.190902 -179.726509)
			(xy 131.147268 -179.75326) (xy 131.100383 -179.77379) (xy 131.051131 -179.78771) (xy 131.000437 -179.794761)
			(xy 130.974846 -179.79517) (xy 130.946961 -179.794678) (xy 130.891812 -179.786372) (xy 130.838517 -179.769939)
			(xy 130.788268 -179.745745) (xy 130.742185 -179.714332) (xy 130.7013 -179.676401) (xy 130.666525 -179.632799)
			(xy 130.638638 -179.584502) (xy 130.618261 -179.532587) (xy 130.60585 -179.478215) (xy 130.601682 -179.4226)
			(xy 130.60585 -179.366985) (xy 130.618261 -179.312613) (xy 130.638638 -179.260698) (xy 130.666525 -179.212401)
			(xy 130.7013 -179.168799) (xy 130.742185 -179.130868) (xy 130.788268 -179.099455) (xy 130.838517 -179.075261)
			(xy 130.891812 -179.058828) (xy 130.946961 -179.050522) (xy 130.974846 -179.049934) (xy 131.000436 -179.050375)
			(xy 131.05113 -179.057414) (xy 131.100384 -179.071326) (xy 131.147269 -179.091849) (xy 131.190904 -179.118597)
			(xy 131.230467 -179.151065) (xy 131.24815 -179.169568) (xy 131.255668 -179.176954) (xy 131.27496 -179.185379)
			(xy 131.285488 -179.185824) (xy 131.360164 -179.185824) (xy 131.370679 -179.185304) (xy 131.389966 -179.176918)
			(xy 131.397502 -179.169568) (xy 131.415188 -179.151069) (xy 131.454752 -179.118603) (xy 131.498387 -179.091857)
			(xy 131.545272 -179.071334) (xy 131.594524 -179.05742) (xy 131.645217 -179.050376) (xy 131.670806 -179.049934)
			(xy 131.696761 -179.050384) (xy 131.748169 -179.057591) (xy 131.798078 -179.071865) (xy 131.845522 -179.092929)
			(xy 131.889583 -179.120376) (xy 131.929407 -179.153674) (xy 131.947158 -179.172616) (xy 131.954703 -179.180125)
			(xy 131.974122 -179.188791) (xy 131.98475 -179.18938) (xy 132.060442 -179.18938) (xy 132.071106 -179.188931)
			(xy 132.090588 -179.180261) (xy 132.098034 -179.172616) (xy 132.117413 -179.151956) (xy 132.161313 -179.116161)
			(xy 132.210127 -179.087426) (xy 132.262729 -179.066415) (xy 132.317906 -179.053611) (xy 132.374386 -179.04931)
			(xy 132.430866 -179.053611) (xy 132.486043 -179.066415) (xy 132.538645 -179.087426) (xy 132.587459 -179.116161)
			(xy 132.631359 -179.151956) (xy 132.650738 -179.172616) (xy 132.658288 -179.180112) (xy 132.677707 -179.188748)
			(xy 132.68833 -179.18938) (xy 132.764022 -179.18938) (xy 132.774678 -179.188916) (xy 132.794137 -179.180225)
			(xy 132.801614 -179.172616) (xy 132.820993 -179.151956) (xy 132.864893 -179.116161) (xy 132.913707 -179.087426)
			(xy 132.966309 -179.066415) (xy 133.021486 -179.053611) (xy 133.077966 -179.04931) (xy 133.134446 -179.053611)
			(xy 133.189623 -179.066415) (xy 133.242225 -179.087426) (xy 133.291039 -179.116161) (xy 133.334939 -179.151956)
			(xy 133.354318 -179.172616) (xy 133.361867 -179.180116) (xy 133.381286 -179.188759) (xy 133.39191 -179.18938)
			(xy 133.467602 -179.18938) (xy 133.47826 -179.18892) (xy 133.497725 -179.180234) (xy 133.505194 -179.172616)
			(xy 133.522937 -179.153667) (xy 133.562764 -179.120371) (xy 133.606827 -179.092924) (xy 133.654272 -179.071859)
			(xy 133.704182 -179.057582) (xy 133.75559 -179.05037) (xy 133.781546 -179.049934) (xy 133.810604 -179.050516)
			(xy 133.86801 -179.059581) (xy 133.923316 -179.077439) (xy 133.975184 -179.103658) (xy 134.022358 -179.137602)
			(xy 134.04342 -179.15763) (xy 134.043928 -179.158138) (xy 134.051897 -179.165091) (xy 134.071706 -179.172435)
			(xy 134.082282 -179.172362) (xy 134.157974 -179.168044) (xy 134.168548 -179.166874) (xy 134.187455 -179.157173)
			(xy 134.19455 -179.149248) (xy 134.212193 -179.128018) (xy 134.25268 -179.090495) (xy 134.298261 -179.059359)
			(xy 134.347938 -179.03529) (xy 134.374128 -179.026566) (xy 134.387082 -179.022756) (xy 134.405116 -179.003452)
			(xy 134.429246 -178.905916) (xy 134.430937 -178.897372) (xy 134.429128 -178.880062) (xy 134.42166 -178.86434)
			(xy 134.415784 -178.85791) (xy 134.350252 -178.792124) (xy 134.342124 -178.788314) (xy 134.319474 -178.777231)
			(xy 134.277278 -178.749624) (xy 134.239403 -178.716336) (xy 134.206608 -178.678034) (xy 134.17955 -178.635484)
			(xy 134.158772 -178.58954) (xy 134.144689 -178.541122) (xy 134.137585 -178.4912) (xy 134.137146 -178.465988)
			(xy 134.137575 -178.441204) (xy 134.144452 -178.392115) (xy 134.158072 -178.344454) (xy 134.178172 -178.299143)
			(xy 134.204362 -178.257059) (xy 134.236136 -178.219014) (xy 134.25424 -178.202082) (xy 134.261899 -178.194565)
			(xy 134.270579 -178.17496) (xy 134.271004 -178.164236) (xy 134.27075 -178.077876) (xy 134.26186 -178.058064)
			(xy 134.253732 -178.050952) (xy 134.235414 -178.033982) (xy 134.203233 -177.995801) (xy 134.176695 -177.953503)
			(xy 134.156318 -177.907916) (xy 134.142503 -177.859932) (xy 134.135518 -177.810489) (xy 134.135114 -177.785522)
			(xy 134.135114 -177.785268) (xy 134.135606 -177.757968) (xy 134.14394 -177.704007) (xy 134.160422 -177.651954)
			(xy 134.184665 -177.603031) (xy 134.2161 -177.558387) (xy 134.234682 -177.53838) (xy 134.241794 -177.531014)
			(xy 134.248906 -177.513234) (xy 134.248906 -177.42281) (xy 134.241794 -177.40503) (xy 134.234682 -177.397664)
			(xy 134.216117 -177.377612) (xy 134.184686 -177.332914) (xy 134.160444 -177.283943) (xy 134.143959 -177.231846)
			(xy 134.135618 -177.177843) (xy 134.135114 -177.150522) (xy 134.135589 -177.123196) (xy 134.143899 -177.06918)
			(xy 134.160374 -177.017072) (xy 134.184626 -176.968096) (xy 134.216084 -176.923406) (xy 134.234682 -176.90338)
			(xy 134.241794 -176.896014) (xy 134.248906 -176.878234) (xy 134.248906 -176.78781) (xy 134.241794 -176.77003)
			(xy 134.234682 -176.762664) (xy 134.216117 -176.742612) (xy 134.184686 -176.697914) (xy 134.160444 -176.648943)
			(xy 134.143959 -176.596846) (xy 134.135618 -176.542843) (xy 134.135114 -176.515522) (xy 134.135589 -176.488196)
			(xy 134.143899 -176.43418) (xy 134.160374 -176.382072) (xy 134.184626 -176.333096) (xy 134.216084 -176.288406)
			(xy 134.234682 -176.26838) (xy 134.241794 -176.261014) (xy 134.248906 -176.243234) (xy 134.248906 -176.15281)
			(xy 134.241794 -176.13503) (xy 134.234682 -176.127664) (xy 134.22757 -176.120044) (xy 134.220024 -176.112539)
			(xy 134.200604 -176.10389) (xy 134.189978 -176.10328) (xy 134.157466 -176.10328) (xy 134.14681 -176.103745)
			(xy 134.12735 -176.112434) (xy 134.119874 -176.120044) (xy 134.102913 -176.138061) (xy 134.064872 -176.169707)
			(xy 134.022819 -176.195784) (xy 133.977562 -176.215791) (xy 133.929971 -176.229343) (xy 133.880963 -176.23618)
			(xy 133.856222 -176.23663) (xy 133.855968 -176.23663) (xy 133.828668 -176.236137) (xy 133.774708 -176.227803)
			(xy 133.722657 -176.211319) (xy 133.673736 -176.187073) (xy 133.629096 -176.155634) (xy 133.60908 -176.137062)
			(xy 133.601714 -176.12995) (xy 133.583934 -176.122838) (xy 133.49351 -176.122838) (xy 133.47573 -176.12995)
			(xy 133.468364 -176.137062) (xy 133.448331 -176.155609) (xy 133.403677 -176.187013) (xy 133.354758 -176.211243)
			(xy 133.302717 -176.227733) (xy 133.248771 -176.236097) (xy 133.221476 -176.23663) (xy 133.221222 -176.23663)
			(xy 133.194568 -176.236158) (xy 133.141855 -176.228216) (xy 133.090915 -176.212506) (xy 133.042886 -176.189379)
			(xy 132.99884 -176.159351) (xy 132.959761 -176.123094) (xy 132.926523 -176.081417) (xy 132.899869 -176.035252)
			(xy 132.880392 -175.98563) (xy 132.86853 -175.933659) (xy 132.864546 -175.8805) (xy 132.86853 -175.827341)
			(xy 132.880392 -175.77537) (xy 132.899869 -175.725748) (xy 132.926523 -175.679583) (xy 132.959761 -175.637906)
			(xy 132.99884 -175.601649) (xy 133.042886 -175.571621) (xy 133.090915 -175.548494) (xy 133.141855 -175.532784)
			(xy 133.194568 -175.524842) (xy 133.221222 -175.524414) (xy 133.221476 -175.524414) (xy 133.248778 -175.524902)
			(xy 133.302743 -175.533228) (xy 133.354802 -175.549704) (xy 133.403731 -175.573942) (xy 133.448381 -175.605374)
			(xy 133.468364 -175.623982) (xy 133.47573 -175.631094) (xy 133.49351 -175.638206) (xy 133.583934 -175.638206)
			(xy 133.601714 -175.631094) (xy 133.60908 -175.623982) (xy 133.629132 -175.605419) (xy 133.673832 -175.573994)
			(xy 133.722804 -175.549758) (xy 133.7749 -175.53328) (xy 133.828902 -175.524945) (xy 133.856222 -175.524414)
			(xy 133.88355 -175.524885) (xy 133.93757 -175.533188) (xy 133.989684 -175.549656) (xy 134.038665 -175.573903)
			(xy 134.083361 -175.605357) (xy 134.103364 -175.623982) (xy 134.11073 -175.631094) (xy 134.12851 -175.638206)
			(xy 134.218934 -175.638206) (xy 134.236714 -175.631094) (xy 134.24408 -175.623982) (xy 134.264113 -175.605435)
			(xy 134.308766 -175.574033) (xy 134.357686 -175.549806) (xy 134.409727 -175.53332) (xy 134.463673 -175.524962)
			(xy 134.490968 -175.524414) (xy 134.491222 -175.524414) (xy 134.519203 -175.524965) (xy 134.574477 -175.533723)
			(xy 134.627699 -175.551019) (xy 134.677561 -175.576429) (xy 134.722834 -175.609326) (xy 134.762403 -175.6489)
			(xy 134.795294 -175.694177) (xy 134.820698 -175.744041) (xy 134.837988 -175.797266) (xy 134.846739 -175.852541)
			(xy 134.84733 -175.880522) (xy 134.84733 -175.880776) (xy 134.846842 -175.908078) (xy 134.838514 -175.962042)
			(xy 134.822037 -176.014099) (xy 134.797796 -176.063025) (xy 134.766361 -176.107672) (xy 134.747762 -176.127664)
			(xy 134.74065 -176.13503) (xy 134.733538 -176.15281) (xy 134.733538 -176.243234) (xy 134.74065 -176.261014)
			(xy 134.747762 -176.26838) (xy 134.766323 -176.288433) (xy 134.797744 -176.333134) (xy 134.821977 -176.382106)
			(xy 134.838453 -176.434202) (xy 134.846787 -176.488202) (xy 134.84733 -176.515522) (xy 134.846859 -176.542849)
			(xy 134.838555 -176.596868) (xy 134.822084 -176.648981) (xy 134.797835 -176.69796) (xy 134.766377 -176.742653)
			(xy 134.747762 -176.762664) (xy 134.74065 -176.77003) (xy 134.733538 -176.78781) (xy 134.733538 -176.878234)
			(xy 134.74065 -176.896014) (xy 134.747762 -176.90338) (xy 134.766323 -176.923433) (xy 134.797744 -176.968134)
			(xy 134.821977 -177.017106) (xy 134.838453 -177.069202) (xy 134.846787 -177.123202) (xy 134.84733 -177.150522)
			(xy 134.846859 -177.177849) (xy 134.838555 -177.231868) (xy 134.822084 -177.283981) (xy 134.797835 -177.33296)
			(xy 134.766377 -177.377653) (xy 134.747762 -177.397664) (xy 134.74065 -177.40503) (xy 134.733538 -177.42281)
			(xy 134.733538 -177.513234) (xy 134.74065 -177.531014) (xy 134.747762 -177.53838) (xy 134.766307 -177.558414)
			(xy 134.797705 -177.603069) (xy 134.821929 -177.651988) (xy 134.838413 -177.704029) (xy 134.84677 -177.757974)
			(xy 134.84733 -177.785268) (xy 134.84733 -177.785522) (xy 134.8469 -177.810306) (xy 134.840021 -177.859394)
			(xy 134.8264 -177.907053) (xy 134.806299 -177.952362) (xy 134.780107 -177.994444) (xy 134.74833 -178.032487)
			(xy 134.730236 -178.049428) (xy 134.722581 -178.056947) (xy 134.713909 -178.076552) (xy 134.713472 -178.087274)
			(xy 134.713726 -178.173634) (xy 134.722616 -178.193446) (xy 134.730744 -178.200558) (xy 134.748281 -178.216794)
			(xy 134.779278 -178.253169) (xy 134.805122 -178.293369) (xy 134.81558 -178.314858) (xy 134.81939 -178.322986)
			(xy 134.896911 -178.400456) (xy 135.78408 -178.400456) (xy 135.788151 -178.344834) (xy 135.800277 -178.290397)
			(xy 135.8202 -178.238306) (xy 135.847496 -178.189671) (xy 135.881582 -178.145528) (xy 135.921731 -178.106819)
			(xy 135.967089 -178.074368) (xy 136.016689 -178.048867) (xy 136.069473 -178.03086) (xy 136.124316 -178.02073)
			(xy 136.18005 -178.018693) (xy 136.235487 -178.024793) (xy 136.289444 -178.038899) (xy 136.340773 -178.060711)
			(xy 136.388379 -178.089765) (xy 136.431247 -178.12544) (xy 136.468464 -178.166977) (xy 136.499237 -178.21349)
			(xy 136.522909 -178.263987) (xy 136.538977 -178.317394) (xy 136.547097 -178.37257) (xy 136.547606 -178.400456)
			(xy 136.547097 -178.428342) (xy 136.538977 -178.483518) (xy 136.522909 -178.536925) (xy 136.499237 -178.587422)
			(xy 136.468464 -178.633935) (xy 136.431247 -178.675472) (xy 136.388379 -178.711147) (xy 136.340773 -178.740201)
			(xy 136.289444 -178.762013) (xy 136.235487 -178.776119) (xy 136.18005 -178.782219) (xy 136.124316 -178.780182)
			(xy 136.069473 -178.770052) (xy 136.016689 -178.752045) (xy 135.967089 -178.726544) (xy 135.921731 -178.694093)
			(xy 135.881582 -178.655384) (xy 135.847496 -178.611241) (xy 135.8202 -178.562606) (xy 135.800277 -178.510515)
			(xy 135.788151 -178.456078) (xy 135.78408 -178.400456) (xy 134.896911 -178.400456) (xy 135.206486 -178.709828)
			(xy 135.2246 -178.728608) (xy 135.255288 -178.770804) (xy 135.278991 -178.817285) (xy 135.295124 -178.866904)
			(xy 135.30329 -178.918436) (xy 135.303768 -178.944524) (xy 135.303768 -180.30952) (xy 135.30328 -180.335607)
			(xy 135.295111 -180.387137) (xy 135.278977 -180.436753) (xy 135.255276 -180.483233) (xy 135.224592 -180.525429)
			(xy 135.206486 -180.544216) (xy 128.625894 -187.124582) (xy 135.58115 -187.124582) (xy 135.58115 -187.064618)
			(xy 135.588977 -187.005166) (xy 135.604497 -186.947244) (xy 135.627444 -186.891844) (xy 135.657426 -186.839912)
			(xy 135.69393 -186.792339) (xy 135.736331 -186.749937) (xy 135.783904 -186.713432) (xy 135.835835 -186.683448)
			(xy 135.891235 -186.6605) (xy 135.949156 -186.644979) (xy 136.008608 -186.637151) (xy 136.03859 -186.63666)
			(xy 136.90219 -186.63666) (xy 136.932178 -186.637085) (xy 136.99164 -186.644912) (xy 137.049571 -186.660433)
			(xy 137.104981 -186.683384) (xy 137.156922 -186.713371) (xy 137.204504 -186.749881) (xy 137.246913 -186.792289)
			(xy 137.283424 -186.83987) (xy 137.313412 -186.89181) (xy 137.336363 -186.947219) (xy 137.351886 -187.005151)
			(xy 137.359715 -187.064612) (xy 137.359715 -187.124588) (xy 137.351886 -187.184049) (xy 137.336363 -187.241981)
			(xy 137.313412 -187.29739) (xy 137.283424 -187.34933) (xy 137.246913 -187.396911) (xy 137.204504 -187.439319)
			(xy 137.156922 -187.475829) (xy 137.104981 -187.505816) (xy 137.049571 -187.528767) (xy 136.99164 -187.544288)
			(xy 136.932178 -187.552115) (xy 136.90219 -187.552584) (xy 136.03859 -187.552584) (xy 136.008608 -187.552049)
			(xy 135.949156 -187.544221) (xy 135.891235 -187.5287) (xy 135.835835 -187.505752) (xy 135.783904 -187.475768)
			(xy 135.736331 -187.439263) (xy 135.69393 -187.396861) (xy 135.657426 -187.349288) (xy 135.627444 -187.297356)
			(xy 135.604497 -187.241956) (xy 135.588977 -187.184034) (xy 135.58115 -187.124582) (xy 128.625894 -187.124582)
			(xy 127.799338 -187.95111) (xy 127.792658 -187.958521) (xy 127.785069 -187.976951) (xy 127.785076 -187.996883)
			(xy 127.792677 -188.015307) (xy 127.799338 -188.022738) (xy 128.029485 -188.252885) (xy 128.656818 -188.252885)
			(xy 128.656818 -188.192915) (xy 128.664646 -188.133459) (xy 128.680167 -188.075533) (xy 128.703116 -188.020128)
			(xy 128.733101 -187.968193) (xy 128.769608 -187.920615) (xy 128.812012 -187.87821) (xy 128.859589 -187.841703)
			(xy 128.911524 -187.811718) (xy 128.966929 -187.788768) (xy 129.024855 -187.773246) (xy 129.084311 -187.765418)
			(xy 129.114296 -187.764928) (xy 129.977896 -187.764928) (xy 130.007881 -187.765417) (xy 130.067339 -187.773244)
			(xy 130.125266 -187.788765) (xy 130.180671 -187.811714) (xy 130.232607 -187.841699) (xy 130.280185 -187.878207)
			(xy 130.322591 -187.920612) (xy 130.359098 -187.96819) (xy 130.389084 -188.020125) (xy 130.412034 -188.075531)
			(xy 130.427555 -188.133458) (xy 130.435383 -188.192915) (xy 130.435383 -188.252885) (xy 130.434185 -188.261981)
			(xy 131.046262 -188.261981) (xy 131.046262 -188.202019) (xy 131.054088 -188.14257) (xy 131.069607 -188.084651)
			(xy 131.092553 -188.029253) (xy 131.122533 -187.977324) (xy 131.159034 -187.929752) (xy 131.201432 -187.887351)
			(xy 131.249002 -187.850847) (xy 131.30093 -187.820864) (xy 131.356326 -187.797915) (xy 131.414244 -187.782393)
			(xy 131.473693 -187.774564) (xy 131.503674 -187.774072) (xy 132.367274 -187.774072) (xy 132.397263 -187.774472)
			(xy 132.456728 -187.782297) (xy 132.514663 -187.797818) (xy 132.570077 -187.820768) (xy 132.62202 -187.850755)
			(xy 132.669605 -187.887266) (xy 132.712017 -187.929675) (xy 132.74853 -187.977258) (xy 132.77852 -188.0292)
			(xy 132.801474 -188.084612) (xy 132.816998 -188.142546) (xy 132.824827 -188.202011) (xy 132.824827 -188.261989)
			(xy 132.816998 -188.321454) (xy 132.801474 -188.379388) (xy 132.79518 -188.394582) (xy 133.54915 -188.394582)
			(xy 133.54915 -188.334618) (xy 133.556977 -188.275166) (xy 133.572497 -188.217244) (xy 133.595444 -188.161844)
			(xy 133.625426 -188.109912) (xy 133.66193 -188.062339) (xy 133.704331 -188.019937) (xy 133.751904 -187.983432)
			(xy 133.803835 -187.953448) (xy 133.859235 -187.9305) (xy 133.917156 -187.914979) (xy 133.976608 -187.907151)
			(xy 134.00659 -187.90666) (xy 134.87019 -187.90666) (xy 134.900178 -187.907085) (xy 134.95964 -187.914912)
			(xy 135.017571 -187.930433) (xy 135.072981 -187.953384) (xy 135.124922 -187.983371) (xy 135.172504 -188.019881)
			(xy 135.214913 -188.062289) (xy 135.251424 -188.10987) (xy 135.281412 -188.16181) (xy 135.304363 -188.217219)
			(xy 135.319886 -188.275151) (xy 135.327715 -188.334612) (xy 135.327715 -188.394588) (xy 135.319886 -188.454049)
			(xy 135.304363 -188.511981) (xy 135.281412 -188.56739) (xy 135.251424 -188.61933) (xy 135.214913 -188.666911)
			(xy 135.172504 -188.709319) (xy 135.124922 -188.745829) (xy 135.072981 -188.775816) (xy 135.017571 -188.798767)
			(xy 134.95964 -188.814288) (xy 134.900178 -188.822115) (xy 134.87019 -188.822584) (xy 134.00659 -188.822584)
			(xy 133.976608 -188.822049) (xy 133.917156 -188.814221) (xy 133.859235 -188.7987) (xy 133.803835 -188.775752)
			(xy 133.751904 -188.745768) (xy 133.704331 -188.709263) (xy 133.66193 -188.666861) (xy 133.625426 -188.619288)
			(xy 133.595444 -188.567356) (xy 133.572497 -188.511956) (xy 133.556977 -188.454034) (xy 133.54915 -188.394582)
			(xy 132.79518 -188.394582) (xy 132.77852 -188.4348) (xy 132.74853 -188.486742) (xy 132.712017 -188.534325)
			(xy 132.669605 -188.576734) (xy 132.62202 -188.613245) (xy 132.570077 -188.643232) (xy 132.514663 -188.666182)
			(xy 132.456728 -188.681703) (xy 132.397263 -188.689528) (xy 132.367274 -188.689996) (xy 131.503674 -188.689996)
			(xy 131.473693 -188.689436) (xy 131.414244 -188.681607) (xy 131.356326 -188.666085) (xy 131.30093 -188.643136)
			(xy 131.249002 -188.613153) (xy 131.201432 -188.576649) (xy 131.159034 -188.534248) (xy 131.122533 -188.486676)
			(xy 131.092553 -188.434747) (xy 131.069607 -188.379349) (xy 131.054088 -188.32143) (xy 131.046262 -188.261981)
			(xy 130.434185 -188.261981) (xy 130.427555 -188.312342) (xy 130.412034 -188.370269) (xy 130.389084 -188.425675)
			(xy 130.359098 -188.47761) (xy 130.322591 -188.525188) (xy 130.280185 -188.567593) (xy 130.232607 -188.604101)
			(xy 130.180671 -188.634086) (xy 130.125266 -188.657035) (xy 130.067339 -188.672556) (xy 130.007881 -188.680383)
			(xy 129.977896 -188.680852) (xy 129.114296 -188.680852) (xy 129.084311 -188.680382) (xy 129.024855 -188.672554)
			(xy 128.966929 -188.657032) (xy 128.911524 -188.634082) (xy 128.859589 -188.604097) (xy 128.812012 -188.56759)
			(xy 128.769608 -188.525185) (xy 128.733101 -188.477607) (xy 128.703116 -188.425672) (xy 128.680167 -188.370267)
			(xy 128.664646 -188.312341) (xy 128.656818 -188.252885) (xy 128.029485 -188.252885) (xy 129.880614 -190.104014)
			(xy 129.888009 -190.110868) (xy 129.906608 -190.11861) (xy 129.916682 -190.119)
		)
		(stroke
			(width 0)
			(type solid)
		)
		(fill yes)
		(layer "In5.Cu")
		(net "GND")
	)
	(gr_poly
		(pts
			(xy 383.894076 -304.466244) (xy 383.89433 -304.445162) (xy 383.895226 -304.420168) (xy 383.904154 -304.370962)
			(xy 383.920981 -304.323868) (xy 383.945257 -304.280146) (xy 383.976334 -304.240964) (xy 384.01338 -304.207369)
			(xy 384.055405 -304.180261) (xy 384.101286 -304.160363) (xy 384.149796 -304.148207) (xy 384.199638 -304.144119)
			(xy 384.24948 -304.148207) (xy 384.29799 -304.160363) (xy 384.343871 -304.180261) (xy 384.385896 -304.207369)
			(xy 384.422942 -304.240964) (xy 384.454019 -304.280146) (xy 384.478295 -304.323868) (xy 384.495122 -304.370962)
			(xy 384.50405 -304.420168) (xy 384.504946 -304.445162) (xy 384.5052 -304.466244) (xy 384.534664 -304.4952)
			(xy 384.814572 -304.4952) (xy 384.84429 -304.46599) (xy 384.844544 -304.445162) (xy 384.84542 -304.420154)
			(xy 384.854317 -304.370916) (xy 384.871121 -304.323786) (xy 384.895385 -304.280027) (xy 384.926459 -304.24081)
			(xy 384.963511 -304.207184) (xy 385.00555 -304.180048) (xy 385.05145 -304.16013) (xy 385.099984 -304.147961)
			(xy 385.149852 -304.143869) (xy 385.19972 -304.147961) (xy 385.248254 -304.16013) (xy 385.294154 -304.180048)
			(xy 385.336193 -304.207184) (xy 385.373245 -304.24081) (xy 385.404319 -304.280027) (xy 385.428583 -304.323786)
			(xy 385.445387 -304.370916) (xy 385.454284 -304.420154) (xy 385.45516 -304.445162) (xy 385.455414 -304.46599)
			(xy 385.485132 -304.4952) (xy 385.764532 -304.4952) (xy 385.79425 -304.46599) (xy 385.794504 -304.445162)
			(xy 385.79538 -304.420154) (xy 385.804277 -304.370916) (xy 385.821081 -304.323786) (xy 385.845345 -304.280027)
			(xy 385.876419 -304.24081) (xy 385.913471 -304.207184) (xy 385.95551 -304.180048) (xy 386.00141 -304.16013)
			(xy 386.049944 -304.147961) (xy 386.099812 -304.143869) (xy 386.14968 -304.147961) (xy 386.198214 -304.16013)
			(xy 386.244114 -304.180048) (xy 386.286153 -304.207184) (xy 386.323205 -304.24081) (xy 386.354279 -304.280027)
			(xy 386.378543 -304.323786) (xy 386.395347 -304.370916) (xy 386.404244 -304.420154) (xy 386.40512 -304.445162)
			(xy 386.405374 -304.46599) (xy 386.435092 -304.4952) (xy 386.714746 -304.4952) (xy 386.744464 -304.46599)
			(xy 386.744718 -304.445162) (xy 386.745594 -304.420154) (xy 386.754491 -304.370916) (xy 386.771295 -304.323786)
			(xy 386.795559 -304.280027) (xy 386.826633 -304.24081) (xy 386.863685 -304.207184) (xy 386.905724 -304.180048)
			(xy 386.951624 -304.16013) (xy 387.000158 -304.147961) (xy 387.050026 -304.143869) (xy 387.099894 -304.147961)
			(xy 387.148428 -304.16013) (xy 387.194328 -304.180048) (xy 387.236367 -304.207184) (xy 387.273419 -304.24081)
			(xy 387.304493 -304.280027) (xy 387.328757 -304.323786) (xy 387.345561 -304.370916) (xy 387.354458 -304.420154)
			(xy 387.355334 -304.445162) (xy 387.355588 -304.46599) (xy 387.385306 -304.4952) (xy 387.664706 -304.4952)
			(xy 387.694424 -304.46599) (xy 387.694678 -304.445162) (xy 387.695554 -304.420154) (xy 387.704451 -304.370916)
			(xy 387.721255 -304.323786) (xy 387.745519 -304.280027) (xy 387.776593 -304.24081) (xy 387.813645 -304.207184)
			(xy 387.855684 -304.180048) (xy 387.901584 -304.16013) (xy 387.950118 -304.147961) (xy 387.999986 -304.143869)
			(xy 388.049854 -304.147961) (xy 388.098388 -304.16013) (xy 388.144288 -304.180048) (xy 388.186327 -304.207184)
			(xy 388.223379 -304.24081) (xy 388.254453 -304.280027) (xy 388.278717 -304.323786) (xy 388.295521 -304.370916)
			(xy 388.304418 -304.420154) (xy 388.305294 -304.445162) (xy 388.305548 -304.46599) (xy 388.335266 -304.4952)
			(xy 388.614666 -304.4952) (xy 388.644384 -304.46599) (xy 388.644638 -304.445162) (xy 388.645514 -304.420154)
			(xy 388.654411 -304.370916) (xy 388.671215 -304.323786) (xy 388.695479 -304.280027) (xy 388.726553 -304.24081)
			(xy 388.763605 -304.207184) (xy 388.805644 -304.180048) (xy 388.851544 -304.16013) (xy 388.900078 -304.147961)
			(xy 388.949946 -304.143869) (xy 388.999814 -304.147961) (xy 389.048348 -304.16013) (xy 389.094248 -304.180048)
			(xy 389.136287 -304.207184) (xy 389.173339 -304.24081) (xy 389.204413 -304.280027) (xy 389.228677 -304.323786)
			(xy 389.245481 -304.370916) (xy 389.254378 -304.420154) (xy 389.255254 -304.445162) (xy 389.255508 -304.46599)
			(xy 389.285226 -304.4952) (xy 389.564626 -304.4952) (xy 389.594344 -304.46599) (xy 389.594598 -304.445162)
			(xy 389.595474 -304.420154) (xy 389.604371 -304.370916) (xy 389.621175 -304.323786) (xy 389.645439 -304.280027)
			(xy 389.676513 -304.24081) (xy 389.713565 -304.207184) (xy 389.755604 -304.180048) (xy 389.801504 -304.16013)
			(xy 389.850038 -304.147961) (xy 389.899906 -304.143869) (xy 389.949774 -304.147961) (xy 389.998308 -304.16013)
			(xy 390.044208 -304.180048) (xy 390.086247 -304.207184) (xy 390.123299 -304.24081) (xy 390.154373 -304.280027)
			(xy 390.178637 -304.323786) (xy 390.195441 -304.370916) (xy 390.204338 -304.420154) (xy 390.205214 -304.445162)
			(xy 390.205468 -304.46599) (xy 390.235186 -304.4952) (xy 390.514586 -304.4952) (xy 390.544304 -304.46599)
			(xy 390.544558 -304.445162) (xy 390.545434 -304.420154) (xy 390.554331 -304.370916) (xy 390.571135 -304.323786)
			(xy 390.595399 -304.280027) (xy 390.626473 -304.24081) (xy 390.663525 -304.207184) (xy 390.705564 -304.180048)
			(xy 390.751464 -304.16013) (xy 390.799998 -304.147961) (xy 390.849866 -304.143869) (xy 390.899734 -304.147961)
			(xy 390.948268 -304.16013) (xy 390.994168 -304.180048) (xy 391.036207 -304.207184) (xy 391.073259 -304.24081)
			(xy 391.104333 -304.280027) (xy 391.128597 -304.323786) (xy 391.145401 -304.370916) (xy 391.154298 -304.420154)
			(xy 391.155174 -304.445162) (xy 391.155428 -304.46599) (xy 391.185146 -304.4952) (xy 391.464546 -304.4952)
			(xy 391.494264 -304.46599) (xy 391.494518 -304.445162) (xy 391.495394 -304.420154) (xy 391.504291 -304.370916)
			(xy 391.521095 -304.323786) (xy 391.545359 -304.280027) (xy 391.576433 -304.24081) (xy 391.613485 -304.207184)
			(xy 391.655524 -304.180048) (xy 391.701424 -304.16013) (xy 391.749958 -304.147961) (xy 391.799826 -304.143869)
			(xy 391.849694 -304.147961) (xy 391.898228 -304.16013) (xy 391.944128 -304.180048) (xy 391.986167 -304.207184)
			(xy 392.023219 -304.24081) (xy 392.054293 -304.280027) (xy 392.078557 -304.323786) (xy 392.095361 -304.370916)
			(xy 392.104258 -304.420154) (xy 392.105134 -304.445162) (xy 392.105388 -304.46599) (xy 392.135106 -304.4952)
			(xy 392.414506 -304.4952) (xy 392.444224 -304.46599) (xy 392.444478 -304.445162) (xy 392.445354 -304.420154)
			(xy 392.454251 -304.370916) (xy 392.471055 -304.323786) (xy 392.495319 -304.280027) (xy 392.526393 -304.24081)
			(xy 392.563445 -304.207184) (xy 392.605484 -304.180048) (xy 392.651384 -304.16013) (xy 392.699918 -304.147961)
			(xy 392.749786 -304.143869) (xy 392.799654 -304.147961) (xy 392.848188 -304.16013) (xy 392.894088 -304.180048)
			(xy 392.936127 -304.207184) (xy 392.973179 -304.24081) (xy 393.004253 -304.280027) (xy 393.028517 -304.323786)
			(xy 393.045321 -304.370916) (xy 393.054218 -304.420154) (xy 393.055094 -304.445162) (xy 393.055348 -304.46599)
			(xy 393.085066 -304.4952) (xy 393.36472 -304.4952) (xy 393.394438 -304.46599) (xy 393.394692 -304.445162)
			(xy 393.395568 -304.420154) (xy 393.404465 -304.370916) (xy 393.421269 -304.323786) (xy 393.445533 -304.280027)
			(xy 393.476607 -304.24081) (xy 393.513659 -304.207184) (xy 393.555698 -304.180048) (xy 393.601598 -304.16013)
			(xy 393.650132 -304.147961) (xy 393.7 -304.143869) (xy 393.749868 -304.147961) (xy 393.798402 -304.16013)
			(xy 393.844302 -304.180048) (xy 393.886341 -304.207184) (xy 393.923393 -304.24081) (xy 393.954467 -304.280027)
			(xy 393.978731 -304.323786) (xy 393.995535 -304.370916) (xy 394.004432 -304.420154) (xy 394.005308 -304.445162)
			(xy 394.005562 -304.46599) (xy 394.03528 -304.4952) (xy 396.99946 -304.4952) (xy 397.009525 -304.494766)
			(xy 397.028114 -304.487036) (xy 397.035528 -304.480214) (xy 397.063722 -304.45202) (xy 397.070221 -304.444883)
			(xy 397.077813 -304.427152) (xy 397.078351 -304.407871) (xy 397.075406 -304.39868) (xy 397.038322 -304.298096)
			(xy 397.014954 -304.280316) (xy 396.999968 -304.279046) (xy 396.974821 -304.27649) (xy 396.925813 -304.26412)
			(xy 396.879512 -304.243848) (xy 396.837183 -304.216227) (xy 396.799981 -304.18201) (xy 396.768923 -304.142133)
			(xy 396.744858 -304.097686) (xy 396.728442 -304.049882) (xy 396.720124 -304.000026) (xy 396.719552 -303.974754)
			(xy 396.720026 -303.950764) (xy 396.727538 -303.903376) (xy 396.742369 -303.857745) (xy 396.764154 -303.814996)
			(xy 396.792357 -303.77618) (xy 396.826285 -303.742253) (xy 396.865101 -303.714051) (xy 396.907851 -303.692266)
			(xy 396.953481 -303.677436) (xy 397.00087 -303.669926) (xy 397.02486 -303.669446) (xy 397.050881 -303.66995)
			(xy 397.102178 -303.678724) (xy 397.151248 -303.696061) (xy 397.174212 -303.708308) (xy 397.185896 -303.715166)
			(xy 397.21282 -303.714912) (xy 397.300196 -303.663604) (xy 397.307694 -303.658854) (xy 397.31905 -303.645227)
			(xy 397.325049 -303.628533) (xy 397.325342 -303.619662) (xy 397.325342 -303.379886) (xy 397.324951 -303.371037)
			(xy 397.318925 -303.354394) (xy 397.307624 -303.340771) (xy 397.300196 -303.335944) (xy 397.21282 -303.284636)
			(xy 397.185896 -303.284382) (xy 397.174212 -303.29124) (xy 397.151248 -303.303489) (xy 397.102181 -303.320835)
			(xy 397.050882 -303.329606) (xy 397.02486 -303.330102) (xy 396.999607 -303.329577) (xy 396.949792 -303.321259)
			(xy 396.902024 -303.304855) (xy 396.857608 -303.280813) (xy 396.817755 -303.249788) (xy 396.783551 -303.212628)
			(xy 396.755929 -303.170345) (xy 396.735643 -303.124093) (xy 396.723245 -303.075133) (xy 396.719075 -303.0248)
			(xy 396.723245 -302.974467) (xy 396.735643 -302.925507) (xy 396.755929 -302.879255) (xy 396.783551 -302.836972)
			(xy 396.817755 -302.799812) (xy 396.857608 -302.768787) (xy 396.902024 -302.744745) (xy 396.949792 -302.728341)
			(xy 396.999607 -302.720023) (xy 397.02486 -302.719486) (xy 397.050882 -302.71999) (xy 397.102179 -302.728763)
			(xy 397.15125 -302.746096) (xy 397.174212 -302.758348) (xy 397.185896 -302.765206) (xy 397.21282 -302.764952)
			(xy 397.300196 -302.713644) (xy 397.307698 -302.708896) (xy 397.319065 -302.69527) (xy 397.325077 -302.678575)
			(xy 397.325342 -302.669702) (xy 397.325342 -301.479966) (xy 397.324964 -301.47111) (xy 397.318955 -301.454447)
			(xy 397.30766 -301.440802) (xy 397.300196 -301.436024) (xy 397.21282 -301.384716) (xy 397.185896 -301.384462)
			(xy 397.174212 -301.39132) (xy 397.151248 -301.40357) (xy 397.102181 -301.420916) (xy 397.050882 -301.429688)
			(xy 397.02486 -301.430182) (xy 396.999609 -301.429657) (xy 396.949797 -301.421339) (xy 396.902032 -301.404936)
			(xy 396.857619 -301.380896) (xy 396.817768 -301.349874) (xy 396.783567 -301.312716) (xy 396.755947 -301.270436)
			(xy 396.735662 -301.224187) (xy 396.723265 -301.17523) (xy 396.719095 -301.1249) (xy 396.723265 -301.07457)
			(xy 396.735662 -301.025613) (xy 396.755947 -300.979364) (xy 396.783567 -300.937084) (xy 396.817768 -300.899926)
			(xy 396.857619 -300.868904) (xy 396.902032 -300.844864) (xy 396.949797 -300.828461) (xy 396.999609 -300.820143)
			(xy 397.02486 -300.819566) (xy 397.050881 -300.82007) (xy 397.102178 -300.828845) (xy 397.151247 -300.846182)
			(xy 397.174212 -300.858428) (xy 397.185896 -300.865286) (xy 397.21282 -300.865032) (xy 397.300196 -300.813724)
			(xy 397.307696 -300.808975) (xy 397.319057 -300.795348) (xy 397.325063 -300.778654) (xy 397.325342 -300.769782)
			(xy 397.325342 -300.530006) (xy 397.324954 -300.521155) (xy 397.318933 -300.504507) (xy 397.307633 -300.490879)
			(xy 397.300196 -300.486064) (xy 397.21282 -300.434756) (xy 397.185896 -300.434502) (xy 397.174212 -300.44136)
			(xy 397.151249 -300.453612) (xy 397.102182 -300.470962) (xy 397.050883 -300.479735) (xy 397.02486 -300.480222)
			(xy 396.999606 -300.479697) (xy 396.949787 -300.471378) (xy 396.902016 -300.454973) (xy 396.857597 -300.430929)
			(xy 396.817741 -300.399903) (xy 396.783535 -300.362741) (xy 396.755911 -300.320455) (xy 396.735624 -300.2742)
			(xy 396.723226 -300.225236) (xy 396.719055 -300.1749) (xy 396.723226 -300.124564) (xy 396.735624 -300.0756)
			(xy 396.755911 -300.029345) (xy 396.783535 -299.987059) (xy 396.817741 -299.949897) (xy 396.857597 -299.918871)
			(xy 396.902016 -299.894827) (xy 396.949787 -299.878422) (xy 396.999606 -299.870103) (xy 397.02486 -299.869606)
			(xy 397.050881 -299.87011) (xy 397.102179 -299.878883) (xy 397.151249 -299.896218) (xy 397.174212 -299.908468)
			(xy 397.185896 -299.915326) (xy 397.21282 -299.915072) (xy 397.300196 -299.863764) (xy 397.307701 -299.859017)
			(xy 397.319072 -299.845392) (xy 397.32509 -299.828696) (xy 397.325342 -299.819822) (xy 397.325342 -299.580046)
			(xy 397.324961 -299.571191) (xy 397.318948 -299.554533) (xy 397.307651 -299.540895) (xy 397.300196 -299.536104)
			(xy 397.21282 -299.484796) (xy 397.185896 -299.484542) (xy 397.174212 -299.4914) (xy 397.151248 -299.50365)
			(xy 397.102181 -299.520998) (xy 397.050882 -299.52977) (xy 397.02486 -299.530262) (xy 396.999611 -299.529737)
			(xy 396.949802 -299.52142) (xy 396.902041 -299.505018) (xy 396.85763 -299.480979) (xy 396.817782 -299.449959)
			(xy 396.783582 -299.412804) (xy 396.755964 -299.370526) (xy 396.735681 -299.32428) (xy 396.723285 -299.275326)
			(xy 396.719115 -299.225) (xy 396.723285 -299.174674) (xy 396.735681 -299.12572) (xy 396.755964 -299.079474)
			(xy 396.783582 -299.037196) (xy 396.817782 -299.000041) (xy 396.85763 -298.969021) (xy 396.902041 -298.944982)
			(xy 396.949802 -298.92858) (xy 396.999611 -298.920263) (xy 397.02486 -298.919646) (xy 397.050881 -298.92015)
			(xy 397.102178 -298.928924) (xy 397.151248 -298.946261) (xy 397.174212 -298.958508) (xy 397.185896 -298.965366)
			(xy 397.21282 -298.965112) (xy 397.300196 -298.913804) (xy 397.307694 -298.909054) (xy 397.31905 -298.895427)
			(xy 397.325049 -298.878733) (xy 397.325342 -298.869862) (xy 397.325342 -298.801282) (xy 397.324914 -298.791215)
			(xy 397.317189 -298.77262) (xy 397.310356 -298.765214) (xy 397.162528 -298.617386) (xy 397.15513 -298.610542)
			(xy 397.13653 -298.60282) (xy 397.12646 -298.6024) (xy 395.644624 -298.6024) (xy 395.63456 -298.602837)
			(xy 395.615976 -298.610571) (xy 395.608556 -298.617386) (xy 395.511528 -298.714414) (xy 395.504681 -298.721812)
			(xy 395.496947 -298.74041) (xy 395.496542 -298.750482) (xy 395.496542 -299.224954) (xy 395.769096 -299.224954)
			(xy 395.773056 -299.1759) (xy 395.784833 -299.128116) (xy 395.804124 -299.08284) (xy 395.830427 -299.041244)
			(xy 395.863062 -299.004407) (xy 395.901183 -298.973282) (xy 395.943804 -298.948675) (xy 395.98982 -298.931223)
			(xy 396.038039 -298.921379) (xy 396.087214 -298.919398) (xy 396.136069 -298.92533) (xy 396.18334 -298.939022)
			(xy 396.227802 -298.96012) (xy 396.268305 -298.988076) (xy 396.303798 -299.022168) (xy 396.333363 -299.061512)
			(xy 396.356234 -299.105089) (xy 396.371818 -299.15177) (xy 396.379713 -299.200347) (xy 396.380208 -299.224954)
			(xy 396.379713 -299.249561) (xy 396.371818 -299.298138) (xy 396.356234 -299.344819) (xy 396.333363 -299.388396)
			(xy 396.303798 -299.42774) (xy 396.268305 -299.461832) (xy 396.227802 -299.489788) (xy 396.18334 -299.510886)
			(xy 396.136069 -299.524578) (xy 396.087214 -299.53051) (xy 396.038039 -299.528529) (xy 395.98982 -299.518685)
			(xy 395.943804 -299.501233) (xy 395.901183 -299.476626) (xy 395.863062 -299.445501) (xy 395.830427 -299.408664)
			(xy 395.804124 -299.367068) (xy 395.784833 -299.321792) (xy 395.773056 -299.274008) (xy 395.769096 -299.224954)
			(xy 395.496542 -299.224954) (xy 395.496542 -300.816518) (xy 395.496114 -300.826585) (xy 395.488389 -300.84518)
			(xy 395.481556 -300.852586) (xy 395.394688 -300.939454) (xy 395.389608 -300.971712) (xy 395.397228 -300.986698)
			(xy 395.407625 -301.008233) (xy 395.422335 -301.053731) (xy 395.429775 -301.100965) (xy 395.430248 -301.124874)
			(xy 395.769096 -301.124874) (xy 395.773056 -301.07582) (xy 395.784833 -301.028036) (xy 395.804124 -300.98276)
			(xy 395.830427 -300.941164) (xy 395.863062 -300.904327) (xy 395.901183 -300.873202) (xy 395.943804 -300.848595)
			(xy 395.98982 -300.831143) (xy 396.038039 -300.821299) (xy 396.087214 -300.819318) (xy 396.136069 -300.82525)
			(xy 396.18334 -300.838942) (xy 396.227802 -300.86004) (xy 396.268305 -300.887996) (xy 396.303798 -300.922088)
			(xy 396.333363 -300.961432) (xy 396.356234 -301.005009) (xy 396.371818 -301.05169) (xy 396.379713 -301.100267)
			(xy 396.380208 -301.124874) (xy 396.379713 -301.149481) (xy 396.371818 -301.198058) (xy 396.356234 -301.244739)
			(xy 396.333363 -301.288316) (xy 396.303798 -301.32766) (xy 396.268305 -301.361752) (xy 396.227802 -301.389708)
			(xy 396.18334 -301.410806) (xy 396.136069 -301.424498) (xy 396.087214 -301.43043) (xy 396.038039 -301.428449)
			(xy 395.98982 -301.418605) (xy 395.943804 -301.401153) (xy 395.901183 -301.376546) (xy 395.863062 -301.345421)
			(xy 395.830427 -301.308584) (xy 395.804124 -301.266988) (xy 395.784833 -301.221712) (xy 395.773056 -301.173928)
			(xy 395.769096 -301.124874) (xy 395.430248 -301.124874) (xy 395.429779 -301.148868) (xy 395.422277 -301.196265)
			(xy 395.407452 -301.241905) (xy 395.385671 -301.284664) (xy 395.357468 -301.32349) (xy 395.32354 -301.357425)
			(xy 395.28472 -301.385636) (xy 395.241966 -301.407427) (xy 395.196329 -301.422261) (xy 395.148934 -301.429774)
			(xy 395.12494 -301.430182) (xy 395.101218 -301.429736) (xy 395.054346 -301.422402) (xy 395.009172 -301.407906)
			(xy 394.966784 -301.386596) (xy 394.928203 -301.358985) (xy 394.894358 -301.325739) (xy 394.866064 -301.287656)
			(xy 394.844002 -301.245655) (xy 394.828703 -301.200747) (xy 394.824204 -301.177452) (xy 394.820902 -301.159164)
			(xy 394.792708 -301.135288) (xy 394.507212 -301.135288) (xy 394.479018 -301.159164) (xy 394.475716 -301.177452)
			(xy 394.47119 -301.20074) (xy 394.455893 -301.245646) (xy 394.433833 -301.287645) (xy 394.405542 -301.325725)
			(xy 394.3717 -301.358971) (xy 394.333123 -301.386582) (xy 394.290739 -301.407892) (xy 394.245569 -301.42239)
			(xy 394.1987 -301.429725) (xy 394.17498 -301.430182) (xy 394.160798 -301.429995) (xy 394.132559 -301.427319)
			(xy 394.118592 -301.424848) (xy 394.106146 -301.422562) (xy 394.082524 -301.429928) (xy 394.005054 -301.507398)
			(xy 393.997688 -301.53102) (xy 393.999974 -301.543466) (xy 394.002457 -301.557431) (xy 394.005124 -301.585671)
			(xy 394.005308 -301.599854) (xy 394.005124 -301.614037) (xy 394.002454 -301.642277) (xy 393.999974 -301.656242)
			(xy 393.997688 -301.668688) (xy 394.005054 -301.69231) (xy 394.082524 -301.76978) (xy 394.106146 -301.777146)
			(xy 394.118592 -301.77486) (xy 394.132557 -301.772374) (xy 394.160797 -301.769699) (xy 394.17498 -301.769526)
			(xy 394.200236 -301.770017) (xy 394.250059 -301.778328) (xy 394.297835 -301.794727) (xy 394.34226 -301.818766)
			(xy 394.382123 -301.849789) (xy 394.416335 -301.886951) (xy 394.443963 -301.929237) (xy 394.464254 -301.975494)
			(xy 394.476655 -302.024461) (xy 394.480826 -302.0748) (xy 394.476655 -302.125139) (xy 394.464254 -302.174106)
			(xy 394.443963 -302.220363) (xy 394.416335 -302.262649) (xy 394.382123 -302.299811) (xy 394.34226 -302.330834)
			(xy 394.297835 -302.354873) (xy 394.250059 -302.371272) (xy 394.200236 -302.379583) (xy 394.17498 -302.380142)
			(xy 394.160798 -302.379955) (xy 394.132559 -302.37728) (xy 394.118592 -302.374808) (xy 394.106146 -302.372522)
			(xy 394.082524 -302.379888) (xy 394.005054 -302.457358) (xy 393.997688 -302.48098) (xy 393.999974 -302.493426)
			(xy 394.002459 -302.507391) (xy 394.005129 -302.535631) (xy 394.005308 -302.549814) (xy 394.005121 -302.563996)
			(xy 394.002446 -302.592235) (xy 393.999974 -302.606202) (xy 393.997688 -302.618648) (xy 394.005054 -302.64227)
			(xy 394.082524 -302.71974) (xy 394.106146 -302.727106) (xy 394.118592 -302.72482) (xy 394.132557 -302.722334)
			(xy 394.160797 -302.71966) (xy 394.17498 -302.719486) (xy 394.200239 -302.719977) (xy 394.250069 -302.728289)
			(xy 394.297851 -302.74469) (xy 394.342282 -302.768732) (xy 394.38215 -302.79976) (xy 394.416366 -302.836927)
			(xy 394.443998 -302.879218) (xy 394.464292 -302.925481) (xy 394.476694 -302.974454) (xy 394.480866 -303.024794)
			(xy 394.819136 -303.024794) (xy 394.823096 -302.97574) (xy 394.834873 -302.927956) (xy 394.854164 -302.88268)
			(xy 394.880467 -302.841084) (xy 394.913102 -302.804247) (xy 394.951223 -302.773122) (xy 394.993844 -302.748515)
			(xy 395.03986 -302.731063) (xy 395.088079 -302.721219) (xy 395.137254 -302.719238) (xy 395.186109 -302.72517)
			(xy 395.23338 -302.738862) (xy 395.277842 -302.75996) (xy 395.318345 -302.787916) (xy 395.353838 -302.822008)
			(xy 395.383403 -302.861352) (xy 395.406274 -302.904929) (xy 395.421858 -302.95161) (xy 395.429753 -303.000187)
			(xy 395.430248 -303.024794) (xy 395.769096 -303.024794) (xy 395.773056 -302.97574) (xy 395.784833 -302.927956)
			(xy 395.804124 -302.88268) (xy 395.830427 -302.841084) (xy 395.863062 -302.804247) (xy 395.901183 -302.773122)
			(xy 395.943804 -302.748515) (xy 395.98982 -302.731063) (xy 396.038039 -302.721219) (xy 396.087214 -302.719238)
			(xy 396.136069 -302.72517) (xy 396.18334 -302.738862) (xy 396.227802 -302.75996) (xy 396.268305 -302.787916)
			(xy 396.303798 -302.822008) (xy 396.333363 -302.861352) (xy 396.356234 -302.904929) (xy 396.371818 -302.95161)
			(xy 396.379713 -303.000187) (xy 396.380208 -303.024794) (xy 396.379713 -303.049401) (xy 396.371818 -303.097978)
			(xy 396.356234 -303.144659) (xy 396.333363 -303.188236) (xy 396.303798 -303.22758) (xy 396.268305 -303.261672)
			(xy 396.227802 -303.289628) (xy 396.18334 -303.310726) (xy 396.136069 -303.324418) (xy 396.087214 -303.33035)
			(xy 396.038039 -303.328369) (xy 395.98982 -303.318525) (xy 395.943804 -303.301073) (xy 395.901183 -303.276466)
			(xy 395.863062 -303.245341) (xy 395.830427 -303.208504) (xy 395.804124 -303.166908) (xy 395.784833 -303.121632)
			(xy 395.773056 -303.073848) (xy 395.769096 -303.024794) (xy 395.430248 -303.024794) (xy 395.429753 -303.049401)
			(xy 395.421858 -303.097978) (xy 395.406274 -303.144659) (xy 395.383403 -303.188236) (xy 395.353838 -303.22758)
			(xy 395.318345 -303.261672) (xy 395.277842 -303.289628) (xy 395.23338 -303.310726) (xy 395.186109 -303.324418)
			(xy 395.137254 -303.33035) (xy 395.088079 -303.328369) (xy 395.03986 -303.318525) (xy 394.993844 -303.301073)
			(xy 394.951223 -303.276466) (xy 394.913102 -303.245341) (xy 394.880467 -303.208504) (xy 394.854164 -303.166908)
			(xy 394.834873 -303.121632) (xy 394.823096 -303.073848) (xy 394.819136 -303.024794) (xy 394.480866 -303.024794)
			(xy 394.480866 -303.0248) (xy 394.476694 -303.075146) (xy 394.464292 -303.124119) (xy 394.443998 -303.170382)
			(xy 394.416366 -303.212673) (xy 394.38215 -303.24984) (xy 394.342282 -303.280868) (xy 394.297851 -303.30491)
			(xy 394.250069 -303.321311) (xy 394.200239 -303.329623) (xy 394.17498 -303.330102) (xy 394.160798 -303.329915)
			(xy 394.132559 -303.327239) (xy 394.118592 -303.324768) (xy 394.106146 -303.322482) (xy 394.082524 -303.329848)
			(xy 394.005054 -303.407318) (xy 393.997688 -303.43094) (xy 393.999974 -303.443386) (xy 394.00246 -303.457351)
			(xy 394.005135 -303.485591) (xy 394.005308 -303.499774) (xy 394.004824 -303.524595) (xy 393.996797 -303.573585)
			(xy 393.98095 -303.62063) (xy 393.9577 -303.664491) (xy 393.927661 -303.704014) (xy 393.891623 -303.738156)
			(xy 393.850536 -303.766017) (xy 393.805483 -303.786864) (xy 393.757651 -303.800148) (xy 393.708299 -303.805518)
			(xy 393.658729 -303.802834) (xy 393.610247 -303.792164) (xy 393.564129 -303.773792) (xy 393.521591 -303.748201)
			(xy 393.483754 -303.716064) (xy 393.451615 -303.67823) (xy 393.426019 -303.635694) (xy 393.407643 -303.589578)
			(xy 393.39697 -303.541097) (xy 393.394281 -303.491527) (xy 393.399647 -303.442175) (xy 393.412927 -303.394342)
			(xy 393.43377 -303.349287) (xy 393.461628 -303.308198) (xy 393.495767 -303.272157) (xy 393.535287 -303.242114)
			(xy 393.579146 -303.218861) (xy 393.62619 -303.203009) (xy 393.675179 -303.194978) (xy 393.7 -303.194466)
			(xy 393.714182 -303.194653) (xy 393.742422 -303.197326) (xy 393.756388 -303.1998) (xy 393.768834 -303.202086)
			(xy 393.792456 -303.19472) (xy 393.869926 -303.11725) (xy 393.877292 -303.093628) (xy 393.875006 -303.081182)
			(xy 393.872521 -303.067217) (xy 393.86985 -303.038977) (xy 393.869672 -303.024794) (xy 393.869859 -303.010612)
			(xy 393.872533 -302.982372) (xy 393.875006 -302.968406) (xy 393.877292 -302.95596) (xy 393.869926 -302.932338)
			(xy 393.792456 -302.854868) (xy 393.768834 -302.847502) (xy 393.756388 -302.849788) (xy 393.742423 -302.852273)
			(xy 393.714183 -302.854945) (xy 393.7 -302.855122) (xy 393.674744 -302.8546) (xy 393.624919 -302.846286)
			(xy 393.577143 -302.829885) (xy 393.532719 -302.805843) (xy 393.492857 -302.774817) (xy 393.458645 -302.737654)
			(xy 393.431017 -302.695366) (xy 393.410727 -302.649108) (xy 393.398326 -302.60014) (xy 393.394155 -302.5498)
			(xy 393.398326 -302.49946) (xy 393.410727 -302.450492) (xy 393.431017 -302.404234) (xy 393.458645 -302.361946)
			(xy 393.492857 -302.324783) (xy 393.532719 -302.293757) (xy 393.577143 -302.269715) (xy 393.624919 -302.253314)
			(xy 393.674744 -302.245) (xy 393.7 -302.244506) (xy 393.714182 -302.244693) (xy 393.742422 -302.247366)
			(xy 393.756388 -302.24984) (xy 393.768834 -302.252126) (xy 393.792456 -302.24476) (xy 393.869926 -302.16729)
			(xy 393.877292 -302.143668) (xy 393.875006 -302.131222) (xy 393.872519 -302.117257) (xy 393.869844 -302.089017)
			(xy 393.869672 -302.074834) (xy 393.869857 -302.060651) (xy 393.872527 -302.032412) (xy 393.875006 -302.018446)
			(xy 393.877292 -302.006) (xy 393.869926 -301.982378) (xy 393.792456 -301.904908) (xy 393.768834 -301.897542)
			(xy 393.756388 -301.899828) (xy 393.742423 -301.902314) (xy 393.714183 -301.904986) (xy 393.7 -301.905162)
			(xy 393.676008 -301.904716) (xy 393.628615 -301.897209) (xy 393.582981 -301.88238) (xy 393.540228 -301.860594)
			(xy 393.50141 -301.832387) (xy 393.467483 -301.798455) (xy 393.439282 -301.759633) (xy 393.417503 -301.716877)
			(xy 393.40268 -301.67124) (xy 393.395181 -301.623846) (xy 393.394692 -301.599854) (xy 393.394876 -301.585671)
			(xy 393.397545 -301.557431) (xy 393.400026 -301.543466) (xy 393.402312 -301.53102) (xy 393.394946 -301.507398)
			(xy 393.317476 -301.429928) (xy 393.293854 -301.422562) (xy 393.281408 -301.424848) (xy 393.267443 -301.427334)
			(xy 393.239203 -301.430009) (xy 393.22502 -301.430182) (xy 393.210774 -301.430003) (xy 393.182408 -301.427328)
			(xy 393.168378 -301.424848) (xy 393.156186 -301.422562) (xy 393.132056 -301.429928) (xy 393.05484 -301.507144)
			(xy 393.047474 -301.53102) (xy 393.04976 -301.543466) (xy 393.052243 -301.557431) (xy 393.05491 -301.585671)
			(xy 393.055094 -301.599854) (xy 393.054612 -301.624674) (xy 393.046588 -301.673662) (xy 393.030745 -301.720706)
			(xy 393.007499 -301.764568) (xy 392.977463 -301.80409) (xy 392.941429 -301.838233) (xy 392.900345 -301.866096)
			(xy 392.855295 -301.886945) (xy 392.807466 -301.900231) (xy 392.758117 -301.905604) (xy 392.708549 -301.902922)
			(xy 392.660068 -301.892256) (xy 392.613951 -301.873887) (xy 392.571413 -301.848299) (xy 392.533576 -301.816167)
			(xy 392.501436 -301.778335) (xy 392.475839 -301.735803) (xy 392.457461 -301.68969) (xy 392.446786 -301.641211)
			(xy 392.444094 -301.591643) (xy 392.449458 -301.542293) (xy 392.462734 -301.494461) (xy 392.483575 -301.449407)
			(xy 392.51143 -301.408318) (xy 392.545565 -301.372277) (xy 392.585082 -301.342234) (xy 392.628938 -301.318979)
			(xy 392.67598 -301.303126) (xy 392.724966 -301.295093) (xy 392.749786 -301.294546) (xy 392.764032 -301.294725)
			(xy 392.792398 -301.297402) (xy 392.806428 -301.29988) (xy 392.81862 -301.302166) (xy 392.84275 -301.2948)
			(xy 392.919966 -301.217584) (xy 392.927332 -301.193708) (xy 392.925046 -301.181262) (xy 392.924284 -301.177452)
			(xy 392.920982 -301.159164) (xy 392.892788 -301.135288) (xy 379.97384 -301.135288) (xy 379.96385 -301.134757)
			(xy 379.945408 -301.127053) (xy 379.938026 -301.120302) (xy 379.564138 -300.746414) (xy 379.557321 -300.739071)
			(xy 379.549578 -300.720609) (xy 379.549152 -300.7106) (xy 379.549152 -298.803822) (xy 379.549687 -298.793834)
			(xy 379.557401 -298.775401) (xy 379.564138 -298.768008) (xy 380.022608 -298.309538) (xy 380.029222 -298.303347)
			(xy 380.045621 -298.295674) (xy 380.054612 -298.294552) (xy 380.063756 -298.294044) (xy 380.079758 -298.286678)
			(xy 380.091442 -298.275248) (xy 380.09195 -298.27474) (xy 380.099349 -298.267897) (xy 380.117948 -298.260175)
			(xy 380.128018 -298.259754) (xy 381.25908 -298.259754) (xy 381.269143 -298.259315) (xy 381.287722 -298.251575)
			(xy 381.295148 -298.244768) (xy 381.611378 -297.928538) (xy 381.618217 -297.921137) (xy 381.625932 -297.902539)
			(xy 381.626364 -297.89247) (xy 381.626364 -296.450512) (xy 381.625942 -296.440442) (xy 381.618227 -296.421837)
			(xy 381.611378 -296.414444) (xy 381.40132 -296.204386) (xy 381.393921 -296.197543) (xy 381.375322 -296.189824)
			(xy 381.365252 -296.1894) (xy 380.335536 -296.1894) (xy 380.325574 -296.189886) (xy 380.307149 -296.197473)
			(xy 380.299722 -296.204132) (xy 380.280138 -296.222897) (xy 380.236618 -296.255267) (xy 380.188952 -296.281146)
			(xy 380.138102 -296.300014) (xy 380.085091 -296.311488) (xy 380.03099 -296.315339) (xy 379.976889 -296.311488)
			(xy 379.923878 -296.300014) (xy 379.873028 -296.281146) (xy 379.825362 -296.255267) (xy 379.781842 -296.222897)
			(xy 379.762258 -296.204132) (xy 379.754886 -296.197393) (xy 379.736424 -296.189811) (xy 379.726444 -296.1894)
			(xy 377.171712 -296.1894) (xy 377.167037 -296.189486) (xy 377.157837 -296.191154) (xy 377.153424 -296.192702)
			(xy 377.128786 -296.202354) (xy 377.12142 -296.209212) (xy 377.09602 -296.23131) (xy 377.074176 -296.247566)
			(xy 377.063818 -296.254527) (xy 377.042337 -296.267236) (xy 377.03125 -296.272966) (xy 377.024138 -296.276776)
			(xy 376.81408 -296.486834) (xy 376.813826 -296.487088) (xy 376.809508 -296.491406) (xy 376.809254 -296.49166)
			(xy 376.797316 -296.503598) (xy 376.773186 -296.527982) (xy 376.766501 -296.535391) (xy 376.758914 -296.553827)
			(xy 376.758454 -296.563796) (xy 376.758454 -298.65066) (xy 376.75889 -298.660724) (xy 376.766625 -298.679308)
			(xy 376.77344 -298.686728) (xy 376.790458 -298.703746) (xy 376.823478 -298.73702) (xy 376.828808 -298.741971)
			(xy 376.841577 -298.748926) (xy 376.848624 -298.750736) (xy 376.854212 -298.752006) (xy 376.881519 -298.752202)
			(xy 376.935644 -298.759451) (xy 376.988183 -298.774343) (xy 377.038061 -298.796574) (xy 377.08426 -298.825689)
			(xy 377.125836 -298.861094) (xy 377.161939 -298.902064) (xy 377.191832 -298.947764) (xy 377.214903 -298.997259)
			(xy 377.230682 -299.049538) (xy 377.238846 -299.103533) (xy 377.239227 -299.15814) (xy 377.231819 -299.212243)
			(xy 377.216773 -299.264737) (xy 377.194396 -299.31455) (xy 377.165145 -299.360664) (xy 377.129618 -299.402135)
			(xy 377.088541 -299.438118) (xy 377.042754 -299.467876) (xy 376.993191 -299.490802) (xy 376.940866 -299.506427)
			(xy 376.886848 -299.514432) (xy 376.859546 -299.515022) (xy 376.848624 -299.516292) (xy 376.841559 -299.518053)
			(xy 376.828782 -299.52502) (xy 376.823478 -299.530008) (xy 376.790458 -299.563282) (xy 376.77344 -299.5803)
			(xy 376.766589 -299.587697) (xy 376.758848 -299.606295) (xy 376.758454 -299.616368) (xy 376.758454 -301.599854)
			(xy 384.844048 -301.599854) (xy 384.848008 -301.5508) (xy 384.859785 -301.503016) (xy 384.879076 -301.45774)
			(xy 384.905379 -301.416144) (xy 384.938014 -301.379307) (xy 384.976135 -301.348182) (xy 385.018756 -301.323575)
			(xy 385.064772 -301.306123) (xy 385.112991 -301.296279) (xy 385.162166 -301.294298) (xy 385.211021 -301.30023)
			(xy 385.258292 -301.313922) (xy 385.302754 -301.33502) (xy 385.343257 -301.362976) (xy 385.37875 -301.397068)
			(xy 385.408315 -301.436412) (xy 385.431186 -301.479989) (xy 385.44677 -301.52667) (xy 385.454665 -301.575247)
			(xy 385.45516 -301.599854) (xy 385.794008 -301.599854) (xy 385.797968 -301.5508) (xy 385.809745 -301.503016)
			(xy 385.829036 -301.45774) (xy 385.855339 -301.416144) (xy 385.887974 -301.379307) (xy 385.926095 -301.348182)
			(xy 385.968716 -301.323575) (xy 386.014732 -301.306123) (xy 386.062951 -301.296279) (xy 386.112126 -301.294298)
			(xy 386.160981 -301.30023) (xy 386.208252 -301.313922) (xy 386.252714 -301.33502) (xy 386.293217 -301.362976)
			(xy 386.32871 -301.397068) (xy 386.358275 -301.436412) (xy 386.381146 -301.479989) (xy 386.39673 -301.52667)
			(xy 386.404625 -301.575247) (xy 386.40512 -301.599854) (xy 386.744222 -301.599854) (xy 386.748182 -301.5508)
			(xy 386.759959 -301.503016) (xy 386.77925 -301.45774) (xy 386.805553 -301.416144) (xy 386.838188 -301.379307)
			(xy 386.876309 -301.348182) (xy 386.91893 -301.323575) (xy 386.964946 -301.306123) (xy 387.013165 -301.296279)
			(xy 387.06234 -301.294298) (xy 387.111195 -301.30023) (xy 387.158466 -301.313922) (xy 387.202928 -301.33502)
			(xy 387.243431 -301.362976) (xy 387.278924 -301.397068) (xy 387.308489 -301.436412) (xy 387.33136 -301.479989)
			(xy 387.346944 -301.52667) (xy 387.354839 -301.575247) (xy 387.355334 -301.599854) (xy 387.694182 -301.599854)
			(xy 387.698142 -301.5508) (xy 387.709919 -301.503016) (xy 387.72921 -301.45774) (xy 387.755513 -301.416144)
			(xy 387.788148 -301.379307) (xy 387.826269 -301.348182) (xy 387.86889 -301.323575) (xy 387.914906 -301.306123)
			(xy 387.963125 -301.296279) (xy 388.0123 -301.294298) (xy 388.061155 -301.30023) (xy 388.108426 -301.313922)
			(xy 388.152888 -301.33502) (xy 388.193391 -301.362976) (xy 388.228884 -301.397068) (xy 388.258449 -301.436412)
			(xy 388.28132 -301.479989) (xy 388.296904 -301.52667) (xy 388.304799 -301.575247) (xy 388.305294 -301.599854)
			(xy 388.644142 -301.599854) (xy 388.648102 -301.5508) (xy 388.659879 -301.503016) (xy 388.67917 -301.45774)
			(xy 388.705473 -301.416144) (xy 388.738108 -301.379307) (xy 388.776229 -301.348182) (xy 388.81885 -301.323575)
			(xy 388.864866 -301.306123) (xy 388.913085 -301.296279) (xy 388.96226 -301.294298) (xy 389.011115 -301.30023)
			(xy 389.058386 -301.313922) (xy 389.102848 -301.33502) (xy 389.143351 -301.362976) (xy 389.178844 -301.397068)
			(xy 389.208409 -301.436412) (xy 389.23128 -301.479989) (xy 389.246864 -301.52667) (xy 389.254759 -301.575247)
			(xy 389.255254 -301.599854) (xy 389.594102 -301.599854) (xy 389.598062 -301.5508) (xy 389.609839 -301.503016)
			(xy 389.62913 -301.45774) (xy 389.655433 -301.416144) (xy 389.688068 -301.379307) (xy 389.726189 -301.348182)
			(xy 389.76881 -301.323575) (xy 389.814826 -301.306123) (xy 389.863045 -301.296279) (xy 389.91222 -301.294298)
			(xy 389.961075 -301.30023) (xy 390.008346 -301.313922) (xy 390.052808 -301.33502) (xy 390.093311 -301.362976)
			(xy 390.128804 -301.397068) (xy 390.158369 -301.436412) (xy 390.18124 -301.479989) (xy 390.196824 -301.52667)
			(xy 390.204719 -301.575247) (xy 390.205214 -301.599854) (xy 390.544062 -301.599854) (xy 390.548022 -301.5508)
			(xy 390.559799 -301.503016) (xy 390.57909 -301.45774) (xy 390.605393 -301.416144) (xy 390.638028 -301.379307)
			(xy 390.676149 -301.348182) (xy 390.71877 -301.323575) (xy 390.764786 -301.306123) (xy 390.813005 -301.296279)
			(xy 390.86218 -301.294298) (xy 390.911035 -301.30023) (xy 390.958306 -301.313922) (xy 391.002768 -301.33502)
			(xy 391.043271 -301.362976) (xy 391.078764 -301.397068) (xy 391.108329 -301.436412) (xy 391.1312 -301.479989)
			(xy 391.146784 -301.52667) (xy 391.154679 -301.575247) (xy 391.155174 -301.599854) (xy 391.494022 -301.599854)
			(xy 391.497982 -301.5508) (xy 391.509759 -301.503016) (xy 391.52905 -301.45774) (xy 391.555353 -301.416144)
			(xy 391.587988 -301.379307) (xy 391.626109 -301.348182) (xy 391.66873 -301.323575) (xy 391.714746 -301.306123)
			(xy 391.762965 -301.296279) (xy 391.81214 -301.294298) (xy 391.860995 -301.30023) (xy 391.908266 -301.313922)
			(xy 391.952728 -301.33502) (xy 391.993231 -301.362976) (xy 392.028724 -301.397068) (xy 392.058289 -301.436412)
			(xy 392.08116 -301.479989) (xy 392.096744 -301.52667) (xy 392.104639 -301.575247) (xy 392.105134 -301.599854)
			(xy 392.104639 -301.624461) (xy 392.096744 -301.673038) (xy 392.08116 -301.719719) (xy 392.058289 -301.763296)
			(xy 392.028724 -301.80264) (xy 391.993231 -301.836732) (xy 391.952728 -301.864688) (xy 391.908266 -301.885786)
			(xy 391.860995 -301.899478) (xy 391.81214 -301.90541) (xy 391.762965 -301.903429) (xy 391.714746 -301.893585)
			(xy 391.66873 -301.876133) (xy 391.626109 -301.851526) (xy 391.587988 -301.820401) (xy 391.555353 -301.783564)
			(xy 391.52905 -301.741968) (xy 391.509759 -301.696692) (xy 391.497982 -301.648908) (xy 391.494022 -301.599854)
			(xy 391.155174 -301.599854) (xy 391.154679 -301.624461) (xy 391.146784 -301.673038) (xy 391.1312 -301.719719)
			(xy 391.108329 -301.763296) (xy 391.078764 -301.80264) (xy 391.043271 -301.836732) (xy 391.002768 -301.864688)
			(xy 390.958306 -301.885786) (xy 390.911035 -301.899478) (xy 390.86218 -301.90541) (xy 390.813005 -301.903429)
			(xy 390.764786 -301.893585) (xy 390.71877 -301.876133) (xy 390.676149 -301.851526) (xy 390.638028 -301.820401)
			(xy 390.605393 -301.783564) (xy 390.57909 -301.741968) (xy 390.559799 -301.696692) (xy 390.548022 -301.648908)
			(xy 390.544062 -301.599854) (xy 390.205214 -301.599854) (xy 390.204719 -301.624461) (xy 390.196824 -301.673038)
			(xy 390.18124 -301.719719) (xy 390.158369 -301.763296) (xy 390.128804 -301.80264) (xy 390.093311 -301.836732)
			(xy 390.052808 -301.864688) (xy 390.008346 -301.885786) (xy 389.961075 -301.899478) (xy 389.91222 -301.90541)
			(xy 389.863045 -301.903429) (xy 389.814826 -301.893585) (xy 389.76881 -301.876133) (xy 389.726189 -301.851526)
			(xy 389.688068 -301.820401) (xy 389.655433 -301.783564) (xy 389.62913 -301.741968) (xy 389.609839 -301.696692)
			(xy 389.598062 -301.648908) (xy 389.594102 -301.599854) (xy 389.255254 -301.599854) (xy 389.254759 -301.624461)
			(xy 389.246864 -301.673038) (xy 389.23128 -301.719719) (xy 389.208409 -301.763296) (xy 389.178844 -301.80264)
			(xy 389.143351 -301.836732) (xy 389.102848 -301.864688) (xy 389.058386 -301.885786) (xy 389.011115 -301.899478)
			(xy 388.96226 -301.90541) (xy 388.913085 -301.903429) (xy 388.864866 -301.893585) (xy 388.81885 -301.876133)
			(xy 388.776229 -301.851526) (xy 388.738108 -301.820401) (xy 388.705473 -301.783564) (xy 388.67917 -301.741968)
			(xy 388.659879 -301.696692) (xy 388.648102 -301.648908) (xy 388.644142 -301.599854) (xy 388.305294 -301.599854)
			(xy 388.304799 -301.624461) (xy 388.296904 -301.673038) (xy 388.28132 -301.719719) (xy 388.258449 -301.763296)
			(xy 388.228884 -301.80264) (xy 388.193391 -301.836732) (xy 388.152888 -301.864688) (xy 388.108426 -301.885786)
			(xy 388.061155 -301.899478) (xy 388.0123 -301.90541) (xy 387.963125 -301.903429) (xy 387.914906 -301.893585)
			(xy 387.86889 -301.876133) (xy 387.826269 -301.851526) (xy 387.788148 -301.820401) (xy 387.755513 -301.783564)
			(xy 387.72921 -301.741968) (xy 387.709919 -301.696692) (xy 387.698142 -301.648908) (xy 387.694182 -301.599854)
			(xy 387.355334 -301.599854) (xy 387.354839 -301.624461) (xy 387.346944 -301.673038) (xy 387.33136 -301.719719)
			(xy 387.308489 -301.763296) (xy 387.278924 -301.80264) (xy 387.243431 -301.836732) (xy 387.202928 -301.864688)
			(xy 387.158466 -301.885786) (xy 387.111195 -301.899478) (xy 387.06234 -301.90541) (xy 387.013165 -301.903429)
			(xy 386.964946 -301.893585) (xy 386.91893 -301.876133) (xy 386.876309 -301.851526) (xy 386.838188 -301.820401)
			(xy 386.805553 -301.783564) (xy 386.77925 -301.741968) (xy 386.759959 -301.696692) (xy 386.748182 -301.648908)
			(xy 386.744222 -301.599854) (xy 386.40512 -301.599854) (xy 386.404625 -301.624461) (xy 386.39673 -301.673038)
			(xy 386.381146 -301.719719) (xy 386.358275 -301.763296) (xy 386.32871 -301.80264) (xy 386.293217 -301.836732)
			(xy 386.252714 -301.864688) (xy 386.208252 -301.885786) (xy 386.160981 -301.899478) (xy 386.112126 -301.90541)
			(xy 386.062951 -301.903429) (xy 386.014732 -301.893585) (xy 385.968716 -301.876133) (xy 385.926095 -301.851526)
			(xy 385.887974 -301.820401) (xy 385.855339 -301.783564) (xy 385.829036 -301.741968) (xy 385.809745 -301.696692)
			(xy 385.797968 -301.648908) (xy 385.794008 -301.599854) (xy 385.45516 -301.599854) (xy 385.454665 -301.624461)
			(xy 385.44677 -301.673038) (xy 385.431186 -301.719719) (xy 385.408315 -301.763296) (xy 385.37875 -301.80264)
			(xy 385.343257 -301.836732) (xy 385.302754 -301.864688) (xy 385.258292 -301.885786) (xy 385.211021 -301.899478)
			(xy 385.162166 -301.90541) (xy 385.112991 -301.903429) (xy 385.064772 -301.893585) (xy 385.018756 -301.876133)
			(xy 384.976135 -301.851526) (xy 384.938014 -301.820401) (xy 384.905379 -301.783564) (xy 384.879076 -301.741968)
			(xy 384.859785 -301.696692) (xy 384.848008 -301.648908) (xy 384.844048 -301.599854) (xy 376.758454 -301.599854)
			(xy 376.758454 -302.47463) (xy 376.758884 -302.484697) (xy 376.766612 -302.503288) (xy 376.77344 -302.510698)
			(xy 376.81281 -302.550068) (xy 383.893834 -302.550068) (xy 383.897794 -302.501014) (xy 383.909571 -302.45323)
			(xy 383.928862 -302.407954) (xy 383.955165 -302.366358) (xy 383.9878 -302.329521) (xy 384.025921 -302.298396)
			(xy 384.068542 -302.273789) (xy 384.114558 -302.256337) (xy 384.162777 -302.246493) (xy 384.211952 -302.244512)
			(xy 384.260807 -302.250444) (xy 384.308078 -302.264136) (xy 384.35254 -302.285234) (xy 384.393043 -302.31319)
			(xy 384.428536 -302.347282) (xy 384.458101 -302.386626) (xy 384.480972 -302.430203) (xy 384.496556 -302.476884)
			(xy 384.504451 -302.525461) (xy 384.504941 -302.549814) (xy 384.844048 -302.549814) (xy 384.848008 -302.50076)
			(xy 384.859785 -302.452976) (xy 384.879076 -302.4077) (xy 384.905379 -302.366104) (xy 384.938014 -302.329267)
			(xy 384.976135 -302.298142) (xy 385.018756 -302.273535) (xy 385.064772 -302.256083) (xy 385.112991 -302.246239)
			(xy 385.162166 -302.244258) (xy 385.211021 -302.25019) (xy 385.258292 -302.263882) (xy 385.302754 -302.28498)
			(xy 385.343257 -302.312936) (xy 385.37875 -302.347028) (xy 385.408315 -302.386372) (xy 385.431186 -302.429949)
			(xy 385.44677 -302.47663) (xy 385.454665 -302.525207) (xy 385.45516 -302.549814) (xy 385.794008 -302.549814)
			(xy 385.797968 -302.50076) (xy 385.809745 -302.452976) (xy 385.829036 -302.4077) (xy 385.855339 -302.366104)
			(xy 385.887974 -302.329267) (xy 385.926095 -302.298142) (xy 385.968716 -302.273535) (xy 386.014732 -302.256083)
			(xy 386.062951 -302.246239) (xy 386.112126 -302.244258) (xy 386.160981 -302.25019) (xy 386.208252 -302.263882)
			(xy 386.252714 -302.28498) (xy 386.293217 -302.312936) (xy 386.32871 -302.347028) (xy 386.358275 -302.386372)
			(xy 386.381146 -302.429949) (xy 386.39673 -302.47663) (xy 386.404625 -302.525207) (xy 386.40512 -302.549814)
			(xy 386.744222 -302.549814) (xy 386.748182 -302.50076) (xy 386.759959 -302.452976) (xy 386.77925 -302.4077)
			(xy 386.805553 -302.366104) (xy 386.838188 -302.329267) (xy 386.876309 -302.298142) (xy 386.91893 -302.273535)
			(xy 386.964946 -302.256083) (xy 387.013165 -302.246239) (xy 387.06234 -302.244258) (xy 387.111195 -302.25019)
			(xy 387.158466 -302.263882) (xy 387.202928 -302.28498) (xy 387.243431 -302.312936) (xy 387.278924 -302.347028)
			(xy 387.308489 -302.386372) (xy 387.33136 -302.429949) (xy 387.346944 -302.47663) (xy 387.354839 -302.525207)
			(xy 387.355334 -302.549814) (xy 387.694182 -302.549814) (xy 387.698142 -302.50076) (xy 387.709919 -302.452976)
			(xy 387.72921 -302.4077) (xy 387.755513 -302.366104) (xy 387.788148 -302.329267) (xy 387.826269 -302.298142)
			(xy 387.86889 -302.273535) (xy 387.914906 -302.256083) (xy 387.963125 -302.246239) (xy 388.0123 -302.244258)
			(xy 388.061155 -302.25019) (xy 388.108426 -302.263882) (xy 388.152888 -302.28498) (xy 388.193391 -302.312936)
			(xy 388.228884 -302.347028) (xy 388.258449 -302.386372) (xy 388.28132 -302.429949) (xy 388.296904 -302.47663)
			(xy 388.304799 -302.525207) (xy 388.305294 -302.549814) (xy 388.644142 -302.549814) (xy 388.648102 -302.50076)
			(xy 388.659879 -302.452976) (xy 388.67917 -302.4077) (xy 388.705473 -302.366104) (xy 388.738108 -302.329267)
			(xy 388.776229 -302.298142) (xy 388.81885 -302.273535) (xy 388.864866 -302.256083) (xy 388.913085 -302.246239)
			(xy 388.96226 -302.244258) (xy 389.011115 -302.25019) (xy 389.058386 -302.263882) (xy 389.102848 -302.28498)
			(xy 389.143351 -302.312936) (xy 389.178844 -302.347028) (xy 389.208409 -302.386372) (xy 389.23128 -302.429949)
			(xy 389.246864 -302.47663) (xy 389.254759 -302.525207) (xy 389.255254 -302.549814) (xy 389.594102 -302.549814)
			(xy 389.598062 -302.50076) (xy 389.609839 -302.452976) (xy 389.62913 -302.4077) (xy 389.655433 -302.366104)
			(xy 389.688068 -302.329267) (xy 389.726189 -302.298142) (xy 389.76881 -302.273535) (xy 389.814826 -302.256083)
			(xy 389.863045 -302.246239) (xy 389.91222 -302.244258) (xy 389.961075 -302.25019) (xy 390.008346 -302.263882)
			(xy 390.052808 -302.28498) (xy 390.093311 -302.312936) (xy 390.128804 -302.347028) (xy 390.158369 -302.386372)
			(xy 390.18124 -302.429949) (xy 390.196824 -302.47663) (xy 390.204719 -302.525207) (xy 390.205214 -302.549814)
			(xy 390.544062 -302.549814) (xy 390.548022 -302.50076) (xy 390.559799 -302.452976) (xy 390.57909 -302.4077)
			(xy 390.605393 -302.366104) (xy 390.638028 -302.329267) (xy 390.676149 -302.298142) (xy 390.71877 -302.273535)
			(xy 390.764786 -302.256083) (xy 390.813005 -302.246239) (xy 390.86218 -302.244258) (xy 390.911035 -302.25019)
			(xy 390.958306 -302.263882) (xy 391.002768 -302.28498) (xy 391.043271 -302.312936) (xy 391.078764 -302.347028)
			(xy 391.108329 -302.386372) (xy 391.1312 -302.429949) (xy 391.146784 -302.47663) (xy 391.154679 -302.525207)
			(xy 391.155174 -302.549814) (xy 391.494022 -302.549814) (xy 391.497982 -302.50076) (xy 391.509759 -302.452976)
			(xy 391.52905 -302.4077) (xy 391.555353 -302.366104) (xy 391.587988 -302.329267) (xy 391.626109 -302.298142)
			(xy 391.66873 -302.273535) (xy 391.714746 -302.256083) (xy 391.762965 -302.246239) (xy 391.81214 -302.244258)
			(xy 391.860995 -302.25019) (xy 391.908266 -302.263882) (xy 391.952728 -302.28498) (xy 391.993231 -302.312936)
			(xy 392.028724 -302.347028) (xy 392.058289 -302.386372) (xy 392.08116 -302.429949) (xy 392.096744 -302.47663)
			(xy 392.104639 -302.525207) (xy 392.105134 -302.549814) (xy 392.443982 -302.549814) (xy 392.447942 -302.50076)
			(xy 392.459719 -302.452976) (xy 392.47901 -302.4077) (xy 392.505313 -302.366104) (xy 392.537948 -302.329267)
			(xy 392.576069 -302.298142) (xy 392.61869 -302.273535) (xy 392.664706 -302.256083) (xy 392.712925 -302.246239)
			(xy 392.7621 -302.244258) (xy 392.810955 -302.25019) (xy 392.858226 -302.263882) (xy 392.902688 -302.28498)
			(xy 392.943191 -302.312936) (xy 392.978684 -302.347028) (xy 393.008249 -302.386372) (xy 393.03112 -302.429949)
			(xy 393.046704 -302.47663) (xy 393.054599 -302.525207) (xy 393.055094 -302.549814) (xy 393.054599 -302.574421)
			(xy 393.046704 -302.622998) (xy 393.03112 -302.669679) (xy 393.008249 -302.713256) (xy 392.978684 -302.7526)
			(xy 392.943191 -302.786692) (xy 392.902688 -302.814648) (xy 392.858226 -302.835746) (xy 392.810955 -302.849438)
			(xy 392.7621 -302.85537) (xy 392.712925 -302.853389) (xy 392.664706 -302.843545) (xy 392.61869 -302.826093)
			(xy 392.576069 -302.801486) (xy 392.537948 -302.770361) (xy 392.505313 -302.733524) (xy 392.47901 -302.691928)
			(xy 392.459719 -302.646652) (xy 392.447942 -302.598868) (xy 392.443982 -302.549814) (xy 392.105134 -302.549814)
			(xy 392.104639 -302.574421) (xy 392.096744 -302.622998) (xy 392.08116 -302.669679) (xy 392.058289 -302.713256)
			(xy 392.028724 -302.7526) (xy 391.993231 -302.786692) (xy 391.952728 -302.814648) (xy 391.908266 -302.835746)
			(xy 391.860995 -302.849438) (xy 391.81214 -302.85537) (xy 391.762965 -302.853389) (xy 391.714746 -302.843545)
			(xy 391.66873 -302.826093) (xy 391.626109 -302.801486) (xy 391.587988 -302.770361) (xy 391.555353 -302.733524)
			(xy 391.52905 -302.691928) (xy 391.509759 -302.646652) (xy 391.497982 -302.598868) (xy 391.494022 -302.549814)
			(xy 391.155174 -302.549814) (xy 391.154679 -302.574421) (xy 391.146784 -302.622998) (xy 391.1312 -302.669679)
			(xy 391.108329 -302.713256) (xy 391.078764 -302.7526) (xy 391.043271 -302.786692) (xy 391.002768 -302.814648)
			(xy 390.958306 -302.835746) (xy 390.911035 -302.849438) (xy 390.86218 -302.85537) (xy 390.813005 -302.853389)
			(xy 390.764786 -302.843545) (xy 390.71877 -302.826093) (xy 390.676149 -302.801486) (xy 390.638028 -302.770361)
			(xy 390.605393 -302.733524) (xy 390.57909 -302.691928) (xy 390.559799 -302.646652) (xy 390.548022 -302.598868)
			(xy 390.544062 -302.549814) (xy 390.205214 -302.549814) (xy 390.204719 -302.574421) (xy 390.196824 -302.622998)
			(xy 390.18124 -302.669679) (xy 390.158369 -302.713256) (xy 390.128804 -302.7526) (xy 390.093311 -302.786692)
			(xy 390.052808 -302.814648) (xy 390.008346 -302.835746) (xy 389.961075 -302.849438) (xy 389.91222 -302.85537)
			(xy 389.863045 -302.853389) (xy 389.814826 -302.843545) (xy 389.76881 -302.826093) (xy 389.726189 -302.801486)
			(xy 389.688068 -302.770361) (xy 389.655433 -302.733524) (xy 389.62913 -302.691928) (xy 389.609839 -302.646652)
			(xy 389.598062 -302.598868) (xy 389.594102 -302.549814) (xy 389.255254 -302.549814) (xy 389.254759 -302.574421)
			(xy 389.246864 -302.622998) (xy 389.23128 -302.669679) (xy 389.208409 -302.713256) (xy 389.178844 -302.7526)
			(xy 389.143351 -302.786692) (xy 389.102848 -302.814648) (xy 389.058386 -302.835746) (xy 389.011115 -302.849438)
			(xy 388.96226 -302.85537) (xy 388.913085 -302.853389) (xy 388.864866 -302.843545) (xy 388.81885 -302.826093)
			(xy 388.776229 -302.801486) (xy 388.738108 -302.770361) (xy 388.705473 -302.733524) (xy 388.67917 -302.691928)
			(xy 388.659879 -302.646652) (xy 388.648102 -302.598868) (xy 388.644142 -302.549814) (xy 388.305294 -302.549814)
			(xy 388.304799 -302.574421) (xy 388.296904 -302.622998) (xy 388.28132 -302.669679) (xy 388.258449 -302.713256)
			(xy 388.228884 -302.7526) (xy 388.193391 -302.786692) (xy 388.152888 -302.814648) (xy 388.108426 -302.835746)
			(xy 388.061155 -302.849438) (xy 388.0123 -302.85537) (xy 387.963125 -302.853389) (xy 387.914906 -302.843545)
			(xy 387.86889 -302.826093) (xy 387.826269 -302.801486) (xy 387.788148 -302.770361) (xy 387.755513 -302.733524)
			(xy 387.72921 -302.691928) (xy 387.709919 -302.646652) (xy 387.698142 -302.598868) (xy 387.694182 -302.549814)
			(xy 387.355334 -302.549814) (xy 387.354839 -302.574421) (xy 387.346944 -302.622998) (xy 387.33136 -302.669679)
			(xy 387.308489 -302.713256) (xy 387.278924 -302.7526) (xy 387.243431 -302.786692) (xy 387.202928 -302.814648)
			(xy 387.158466 -302.835746) (xy 387.111195 -302.849438) (xy 387.06234 -302.85537) (xy 387.013165 -302.853389)
			(xy 386.964946 -302.843545) (xy 386.91893 -302.826093) (xy 386.876309 -302.801486) (xy 386.838188 -302.770361)
			(xy 386.805553 -302.733524) (xy 386.77925 -302.691928) (xy 386.759959 -302.646652) (xy 386.748182 -302.598868)
			(xy 386.744222 -302.549814) (xy 386.40512 -302.549814) (xy 386.404625 -302.574421) (xy 386.39673 -302.622998)
			(xy 386.381146 -302.669679) (xy 386.358275 -302.713256) (xy 386.32871 -302.7526) (xy 386.293217 -302.786692)
			(xy 386.252714 -302.814648) (xy 386.208252 -302.835746) (xy 386.160981 -302.849438) (xy 386.112126 -302.85537)
			(xy 386.062951 -302.853389) (xy 386.014732 -302.843545) (xy 385.968716 -302.826093) (xy 385.926095 -302.801486)
			(xy 385.887974 -302.770361) (xy 385.855339 -302.733524) (xy 385.829036 -302.691928) (xy 385.809745 -302.646652)
			(xy 385.797968 -302.598868) (xy 385.794008 -302.549814) (xy 385.45516 -302.549814) (xy 385.454665 -302.574421)
			(xy 385.44677 -302.622998) (xy 385.431186 -302.669679) (xy 385.408315 -302.713256) (xy 385.37875 -302.7526)
			(xy 385.343257 -302.786692) (xy 385.302754 -302.814648) (xy 385.258292 -302.835746) (xy 385.211021 -302.849438)
			(xy 385.162166 -302.85537) (xy 385.112991 -302.853389) (xy 385.064772 -302.843545) (xy 385.018756 -302.826093)
			(xy 384.976135 -302.801486) (xy 384.938014 -302.770361) (xy 384.905379 -302.733524) (xy 384.879076 -302.691928)
			(xy 384.859785 -302.646652) (xy 384.848008 -302.598868) (xy 384.844048 -302.549814) (xy 384.504941 -302.549814)
			(xy 384.504946 -302.550068) (xy 384.504451 -302.574675) (xy 384.496556 -302.623252) (xy 384.480972 -302.669933)
			(xy 384.458101 -302.71351) (xy 384.428536 -302.752854) (xy 384.393043 -302.786946) (xy 384.35254 -302.814902)
			(xy 384.308078 -302.836) (xy 384.260807 -302.849692) (xy 384.211952 -302.855624) (xy 384.162777 -302.853643)
			(xy 384.114558 -302.843799) (xy 384.068542 -302.826347) (xy 384.025921 -302.80174) (xy 383.9878 -302.770615)
			(xy 383.955165 -302.733778) (xy 383.928862 -302.692182) (xy 383.909571 -302.646906) (xy 383.897794 -302.599122)
			(xy 383.893834 -302.550068) (xy 376.81281 -302.550068) (xy 377.762516 -303.499774) (xy 384.844048 -303.499774)
			(xy 384.848008 -303.45072) (xy 384.859785 -303.402936) (xy 384.879076 -303.35766) (xy 384.905379 -303.316064)
			(xy 384.938014 -303.279227) (xy 384.976135 -303.248102) (xy 385.018756 -303.223495) (xy 385.064772 -303.206043)
			(xy 385.112991 -303.196199) (xy 385.162166 -303.194218) (xy 385.211021 -303.20015) (xy 385.258292 -303.213842)
			(xy 385.302754 -303.23494) (xy 385.343257 -303.262896) (xy 385.37875 -303.296988) (xy 385.408315 -303.336332)
			(xy 385.431186 -303.379909) (xy 385.44677 -303.42659) (xy 385.454665 -303.475167) (xy 385.45516 -303.499774)
			(xy 385.794008 -303.499774) (xy 385.797968 -303.45072) (xy 385.809745 -303.402936) (xy 385.829036 -303.35766)
			(xy 385.855339 -303.316064) (xy 385.887974 -303.279227) (xy 385.926095 -303.248102) (xy 385.968716 -303.223495)
			(xy 386.014732 -303.206043) (xy 386.062951 -303.196199) (xy 386.112126 -303.194218) (xy 386.160981 -303.20015)
			(xy 386.208252 -303.213842) (xy 386.252714 -303.23494) (xy 386.293217 -303.262896) (xy 386.32871 -303.296988)
			(xy 386.358275 -303.336332) (xy 386.381146 -303.379909) (xy 386.39673 -303.42659) (xy 386.404625 -303.475167)
			(xy 386.40512 -303.499774) (xy 386.744222 -303.499774) (xy 386.748182 -303.45072) (xy 386.759959 -303.402936)
			(xy 386.77925 -303.35766) (xy 386.805553 -303.316064) (xy 386.838188 -303.279227) (xy 386.876309 -303.248102)
			(xy 386.91893 -303.223495) (xy 386.964946 -303.206043) (xy 387.013165 -303.196199) (xy 387.06234 -303.194218)
			(xy 387.111195 -303.20015) (xy 387.158466 -303.213842) (xy 387.202928 -303.23494) (xy 387.243431 -303.262896)
			(xy 387.278924 -303.296988) (xy 387.308489 -303.336332) (xy 387.33136 -303.379909) (xy 387.346944 -303.42659)
			(xy 387.354839 -303.475167) (xy 387.355334 -303.499774) (xy 387.694182 -303.499774) (xy 387.698142 -303.45072)
			(xy 387.709919 -303.402936) (xy 387.72921 -303.35766) (xy 387.755513 -303.316064) (xy 387.788148 -303.279227)
			(xy 387.826269 -303.248102) (xy 387.86889 -303.223495) (xy 387.914906 -303.206043) (xy 387.963125 -303.196199)
			(xy 388.0123 -303.194218) (xy 388.061155 -303.20015) (xy 388.108426 -303.213842) (xy 388.152888 -303.23494)
			(xy 388.193391 -303.262896) (xy 388.228884 -303.296988) (xy 388.258449 -303.336332) (xy 388.28132 -303.379909)
			(xy 388.296904 -303.42659) (xy 388.304799 -303.475167) (xy 388.305294 -303.499774) (xy 388.644142 -303.499774)
			(xy 388.648102 -303.45072) (xy 388.659879 -303.402936) (xy 388.67917 -303.35766) (xy 388.705473 -303.316064)
			(xy 388.738108 -303.279227) (xy 388.776229 -303.248102) (xy 388.81885 -303.223495) (xy 388.864866 -303.206043)
			(xy 388.913085 -303.196199) (xy 388.96226 -303.194218) (xy 389.011115 -303.20015) (xy 389.058386 -303.213842)
			(xy 389.102848 -303.23494) (xy 389.143351 -303.262896) (xy 389.178844 -303.296988) (xy 389.208409 -303.336332)
			(xy 389.23128 -303.379909) (xy 389.246864 -303.42659) (xy 389.254759 -303.475167) (xy 389.255254 -303.499774)
			(xy 389.594102 -303.499774) (xy 389.598062 -303.45072) (xy 389.609839 -303.402936) (xy 389.62913 -303.35766)
			(xy 389.655433 -303.316064) (xy 389.688068 -303.279227) (xy 389.726189 -303.248102) (xy 389.76881 -303.223495)
			(xy 389.814826 -303.206043) (xy 389.863045 -303.196199) (xy 389.91222 -303.194218) (xy 389.961075 -303.20015)
			(xy 390.008346 -303.213842) (xy 390.052808 -303.23494) (xy 390.093311 -303.262896) (xy 390.128804 -303.296988)
			(xy 390.158369 -303.336332) (xy 390.18124 -303.379909) (xy 390.196824 -303.42659) (xy 390.204719 -303.475167)
			(xy 390.205214 -303.499774) (xy 390.544062 -303.499774) (xy 390.548022 -303.45072) (xy 390.559799 -303.402936)
			(xy 390.57909 -303.35766) (xy 390.605393 -303.316064) (xy 390.638028 -303.279227) (xy 390.676149 -303.248102)
			(xy 390.71877 -303.223495) (xy 390.764786 -303.206043) (xy 390.813005 -303.196199) (xy 390.86218 -303.194218)
			(xy 390.911035 -303.20015) (xy 390.958306 -303.213842) (xy 391.002768 -303.23494) (xy 391.043271 -303.262896)
			(xy 391.078764 -303.296988) (xy 391.108329 -303.336332) (xy 391.1312 -303.379909) (xy 391.146784 -303.42659)
			(xy 391.154679 -303.475167) (xy 391.155174 -303.499774) (xy 391.494022 -303.499774) (xy 391.497982 -303.45072)
			(xy 391.509759 -303.402936) (xy 391.52905 -303.35766) (xy 391.555353 -303.316064) (xy 391.587988 -303.279227)
			(xy 391.626109 -303.248102) (xy 391.66873 -303.223495) (xy 391.714746 -303.206043) (xy 391.762965 -303.196199)
			(xy 391.81214 -303.194218) (xy 391.860995 -303.20015) (xy 391.908266 -303.213842) (xy 391.952728 -303.23494)
			(xy 391.993231 -303.262896) (xy 392.028724 -303.296988) (xy 392.058289 -303.336332) (xy 392.08116 -303.379909)
			(xy 392.096744 -303.42659) (xy 392.104639 -303.475167) (xy 392.105134 -303.499774) (xy 392.443982 -303.499774)
			(xy 392.447942 -303.45072) (xy 392.459719 -303.402936) (xy 392.47901 -303.35766) (xy 392.505313 -303.316064)
			(xy 392.537948 -303.279227) (xy 392.576069 -303.248102) (xy 392.61869 -303.223495) (xy 392.664706 -303.206043)
			(xy 392.712925 -303.196199) (xy 392.7621 -303.194218) (xy 392.810955 -303.20015) (xy 392.858226 -303.213842)
			(xy 392.902688 -303.23494) (xy 392.943191 -303.262896) (xy 392.978684 -303.296988) (xy 393.008249 -303.336332)
			(xy 393.03112 -303.379909) (xy 393.046704 -303.42659) (xy 393.054599 -303.475167) (xy 393.055094 -303.499774)
			(xy 393.054599 -303.524381) (xy 393.046704 -303.572958) (xy 393.03112 -303.619639) (xy 393.008249 -303.663216)
			(xy 392.978684 -303.70256) (xy 392.943191 -303.736652) (xy 392.902688 -303.764608) (xy 392.858226 -303.785706)
			(xy 392.810955 -303.799398) (xy 392.7621 -303.80533) (xy 392.712925 -303.803349) (xy 392.664706 -303.793505)
			(xy 392.61869 -303.776053) (xy 392.576069 -303.751446) (xy 392.537948 -303.720321) (xy 392.505313 -303.683484)
			(xy 392.47901 -303.641888) (xy 392.459719 -303.596612) (xy 392.447942 -303.548828) (xy 392.443982 -303.499774)
			(xy 392.105134 -303.499774) (xy 392.104639 -303.524381) (xy 392.096744 -303.572958) (xy 392.08116 -303.619639)
			(xy 392.058289 -303.663216) (xy 392.028724 -303.70256) (xy 391.993231 -303.736652) (xy 391.952728 -303.764608)
			(xy 391.908266 -303.785706) (xy 391.860995 -303.799398) (xy 391.81214 -303.80533) (xy 391.762965 -303.803349)
			(xy 391.714746 -303.793505) (xy 391.66873 -303.776053) (xy 391.626109 -303.751446) (xy 391.587988 -303.720321)
			(xy 391.555353 -303.683484) (xy 391.52905 -303.641888) (xy 391.509759 -303.596612) (xy 391.497982 -303.548828)
			(xy 391.494022 -303.499774) (xy 391.155174 -303.499774) (xy 391.154679 -303.524381) (xy 391.146784 -303.572958)
			(xy 391.1312 -303.619639) (xy 391.108329 -303.663216) (xy 391.078764 -303.70256) (xy 391.043271 -303.736652)
			(xy 391.002768 -303.764608) (xy 390.958306 -303.785706) (xy 390.911035 -303.799398) (xy 390.86218 -303.80533)
			(xy 390.813005 -303.803349) (xy 390.764786 -303.793505) (xy 390.71877 -303.776053) (xy 390.676149 -303.751446)
			(xy 390.638028 -303.720321) (xy 390.605393 -303.683484) (xy 390.57909 -303.641888) (xy 390.559799 -303.596612)
			(xy 390.548022 -303.548828) (xy 390.544062 -303.499774) (xy 390.205214 -303.499774) (xy 390.204719 -303.524381)
			(xy 390.196824 -303.572958) (xy 390.18124 -303.619639) (xy 390.158369 -303.663216) (xy 390.128804 -303.70256)
			(xy 390.093311 -303.736652) (xy 390.052808 -303.764608) (xy 390.008346 -303.785706) (xy 389.961075 -303.799398)
			(xy 389.91222 -303.80533) (xy 389.863045 -303.803349) (xy 389.814826 -303.793505) (xy 389.76881 -303.776053)
			(xy 389.726189 -303.751446) (xy 389.688068 -303.720321) (xy 389.655433 -303.683484) (xy 389.62913 -303.641888)
			(xy 389.609839 -303.596612) (xy 389.598062 -303.548828) (xy 389.594102 -303.499774) (xy 389.255254 -303.499774)
			(xy 389.254759 -303.524381) (xy 389.246864 -303.572958) (xy 389.23128 -303.619639) (xy 389.208409 -303.663216)
			(xy 389.178844 -303.70256) (xy 389.143351 -303.736652) (xy 389.102848 -303.764608) (xy 389.058386 -303.785706)
			(xy 389.011115 -303.799398) (xy 388.96226 -303.80533) (xy 388.913085 -303.803349) (xy 388.864866 -303.793505)
			(xy 388.81885 -303.776053) (xy 388.776229 -303.751446) (xy 388.738108 -303.720321) (xy 388.705473 -303.683484)
			(xy 388.67917 -303.641888) (xy 388.659879 -303.596612) (xy 388.648102 -303.548828) (xy 388.644142 -303.499774)
			(xy 388.305294 -303.499774) (xy 388.304799 -303.524381) (xy 388.296904 -303.572958) (xy 388.28132 -303.619639)
			(xy 388.258449 -303.663216) (xy 388.228884 -303.70256) (xy 388.193391 -303.736652) (xy 388.152888 -303.764608)
			(xy 388.108426 -303.785706) (xy 388.061155 -303.799398) (xy 388.0123 -303.80533) (xy 387.963125 -303.803349)
			(xy 387.914906 -303.793505) (xy 387.86889 -303.776053) (xy 387.826269 -303.751446) (xy 387.788148 -303.720321)
			(xy 387.755513 -303.683484) (xy 387.72921 -303.641888) (xy 387.709919 -303.596612) (xy 387.698142 -303.548828)
			(xy 387.694182 -303.499774) (xy 387.355334 -303.499774) (xy 387.354839 -303.524381) (xy 387.346944 -303.572958)
			(xy 387.33136 -303.619639) (xy 387.308489 -303.663216) (xy 387.278924 -303.70256) (xy 387.243431 -303.736652)
			(xy 387.202928 -303.764608) (xy 387.158466 -303.785706) (xy 387.111195 -303.799398) (xy 387.06234 -303.80533)
			(xy 387.013165 -303.803349) (xy 386.964946 -303.793505) (xy 386.91893 -303.776053) (xy 386.876309 -303.751446)
			(xy 386.838188 -303.720321) (xy 386.805553 -303.683484) (xy 386.77925 -303.641888) (xy 386.759959 -303.596612)
			(xy 386.748182 -303.548828) (xy 386.744222 -303.499774) (xy 386.40512 -303.499774) (xy 386.404625 -303.524381)
			(xy 386.39673 -303.572958) (xy 386.381146 -303.619639) (xy 386.358275 -303.663216) (xy 386.32871 -303.70256)
			(xy 386.293217 -303.736652) (xy 386.252714 -303.764608) (xy 386.208252 -303.785706) (xy 386.160981 -303.799398)
			(xy 386.112126 -303.80533) (xy 386.062951 -303.803349) (xy 386.014732 -303.793505) (xy 385.968716 -303.776053)
			(xy 385.926095 -303.751446) (xy 385.887974 -303.720321) (xy 385.855339 -303.683484) (xy 385.829036 -303.641888)
			(xy 385.809745 -303.596612) (xy 385.797968 -303.548828) (xy 385.794008 -303.499774) (xy 385.45516 -303.499774)
			(xy 385.454665 -303.524381) (xy 385.44677 -303.572958) (xy 385.431186 -303.619639) (xy 385.408315 -303.663216)
			(xy 385.37875 -303.70256) (xy 385.343257 -303.736652) (xy 385.302754 -303.764608) (xy 385.258292 -303.785706)
			(xy 385.211021 -303.799398) (xy 385.162166 -303.80533) (xy 385.112991 -303.803349) (xy 385.064772 -303.793505)
			(xy 385.018756 -303.776053) (xy 384.976135 -303.751446) (xy 384.938014 -303.720321) (xy 384.905379 -303.683484)
			(xy 384.879076 -303.641888) (xy 384.859785 -303.596612) (xy 384.848008 -303.548828) (xy 384.844048 -303.499774)
			(xy 377.762516 -303.499774) (xy 378.237496 -303.974754) (xy 394.819136 -303.974754) (xy 394.823096 -303.9257)
			(xy 394.834873 -303.877916) (xy 394.854164 -303.83264) (xy 394.880467 -303.791044) (xy 394.913102 -303.754207)
			(xy 394.951223 -303.723082) (xy 394.993844 -303.698475) (xy 395.03986 -303.681023) (xy 395.088079 -303.671179)
			(xy 395.137254 -303.669198) (xy 395.186109 -303.67513) (xy 395.23338 -303.688822) (xy 395.277842 -303.70992)
			(xy 395.318345 -303.737876) (xy 395.353838 -303.771968) (xy 395.383403 -303.811312) (xy 395.406274 -303.854889)
			(xy 395.421858 -303.90157) (xy 395.429753 -303.950147) (xy 395.430248 -303.974754) (xy 395.769096 -303.974754)
			(xy 395.773056 -303.9257) (xy 395.784833 -303.877916) (xy 395.804124 -303.83264) (xy 395.830427 -303.791044)
			(xy 395.863062 -303.754207) (xy 395.901183 -303.723082) (xy 395.943804 -303.698475) (xy 395.98982 -303.681023)
			(xy 396.038039 -303.671179) (xy 396.087214 -303.669198) (xy 396.136069 -303.67513) (xy 396.18334 -303.688822)
			(xy 396.227802 -303.70992) (xy 396.268305 -303.737876) (xy 396.303798 -303.771968) (xy 396.333363 -303.811312)
			(xy 396.356234 -303.854889) (xy 396.371818 -303.90157) (xy 396.379713 -303.950147) (xy 396.380208 -303.974754)
			(xy 396.379713 -303.999361) (xy 396.371818 -304.047938) (xy 396.356234 -304.094619) (xy 396.333363 -304.138196)
			(xy 396.303798 -304.17754) (xy 396.268305 -304.211632) (xy 396.227802 -304.239588) (xy 396.18334 -304.260686)
			(xy 396.136069 -304.274378) (xy 396.087214 -304.28031) (xy 396.038039 -304.278329) (xy 395.98982 -304.268485)
			(xy 395.943804 -304.251033) (xy 395.901183 -304.226426) (xy 395.863062 -304.195301) (xy 395.830427 -304.158464)
			(xy 395.804124 -304.116868) (xy 395.784833 -304.071592) (xy 395.773056 -304.023808) (xy 395.769096 -303.974754)
			(xy 395.430248 -303.974754) (xy 395.429753 -303.999361) (xy 395.421858 -304.047938) (xy 395.406274 -304.094619)
			(xy 395.383403 -304.138196) (xy 395.353838 -304.17754) (xy 395.318345 -304.211632) (xy 395.277842 -304.239588)
			(xy 395.23338 -304.260686) (xy 395.186109 -304.274378) (xy 395.137254 -304.28031) (xy 395.088079 -304.278329)
			(xy 395.03986 -304.268485) (xy 394.993844 -304.251033) (xy 394.951223 -304.226426) (xy 394.913102 -304.195301)
			(xy 394.880467 -304.158464) (xy 394.854164 -304.116868) (xy 394.834873 -304.071592) (xy 394.823096 -304.023808)
			(xy 394.819136 -303.974754) (xy 378.237496 -303.974754) (xy 378.742956 -304.480214) (xy 378.750353 -304.487061)
			(xy 378.768953 -304.494788) (xy 378.779024 -304.4952) (xy 383.864612 -304.4952)
		)
		(stroke
			(width 0)
			(type solid)
		)
		(fill yes)
		(layer "In5.Cu")
		(net "PCEPLL0_VDDA18_PEX3")
	)
	(gr_poly
		(pts
			(xy 151.694134 -304.466244) (xy 151.694388 -304.445162) (xy 151.695284 -304.420168) (xy 151.704212 -304.370962)
			(xy 151.721039 -304.323868) (xy 151.745315 -304.280146) (xy 151.776392 -304.240964) (xy 151.813438 -304.207369)
			(xy 151.855463 -304.180261) (xy 151.901344 -304.160363) (xy 151.949854 -304.148207) (xy 151.999696 -304.144119)
			(xy 152.049538 -304.148207) (xy 152.098048 -304.160363) (xy 152.143929 -304.180261) (xy 152.185954 -304.207369)
			(xy 152.223 -304.240964) (xy 152.254077 -304.280146) (xy 152.278353 -304.323868) (xy 152.29518 -304.370962)
			(xy 152.304108 -304.420168) (xy 152.305004 -304.445162) (xy 152.305258 -304.466244) (xy 152.334722 -304.4952)
			(xy 152.61463 -304.4952) (xy 152.644348 -304.46599) (xy 152.644602 -304.445162) (xy 152.645478 -304.420154)
			(xy 152.654375 -304.370916) (xy 152.671179 -304.323786) (xy 152.695443 -304.280027) (xy 152.726517 -304.24081)
			(xy 152.763569 -304.207184) (xy 152.805608 -304.180048) (xy 152.851508 -304.16013) (xy 152.900042 -304.147961)
			(xy 152.94991 -304.143869) (xy 152.999778 -304.147961) (xy 153.048312 -304.16013) (xy 153.094212 -304.180048)
			(xy 153.136251 -304.207184) (xy 153.173303 -304.24081) (xy 153.204377 -304.280027) (xy 153.228641 -304.323786)
			(xy 153.245445 -304.370916) (xy 153.254342 -304.420154) (xy 153.255218 -304.445162) (xy 153.255472 -304.46599)
			(xy 153.28519 -304.4952) (xy 153.56459 -304.4952) (xy 153.594308 -304.46599) (xy 153.594562 -304.445162)
			(xy 153.595438 -304.420154) (xy 153.604335 -304.370916) (xy 153.621139 -304.323786) (xy 153.645403 -304.280027)
			(xy 153.676477 -304.24081) (xy 153.713529 -304.207184) (xy 153.755568 -304.180048) (xy 153.801468 -304.16013)
			(xy 153.850002 -304.147961) (xy 153.89987 -304.143869) (xy 153.949738 -304.147961) (xy 153.998272 -304.16013)
			(xy 154.044172 -304.180048) (xy 154.086211 -304.207184) (xy 154.123263 -304.24081) (xy 154.154337 -304.280027)
			(xy 154.178601 -304.323786) (xy 154.195405 -304.370916) (xy 154.204302 -304.420154) (xy 154.205178 -304.445162)
			(xy 154.205432 -304.46599) (xy 154.23515 -304.4952) (xy 154.514804 -304.4952) (xy 154.544522 -304.46599)
			(xy 154.544776 -304.445162) (xy 154.545652 -304.420154) (xy 154.554549 -304.370916) (xy 154.571353 -304.323786)
			(xy 154.595617 -304.280027) (xy 154.626691 -304.24081) (xy 154.663743 -304.207184) (xy 154.705782 -304.180048)
			(xy 154.751682 -304.16013) (xy 154.800216 -304.147961) (xy 154.850084 -304.143869) (xy 154.899952 -304.147961)
			(xy 154.948486 -304.16013) (xy 154.994386 -304.180048) (xy 155.036425 -304.207184) (xy 155.073477 -304.24081)
			(xy 155.104551 -304.280027) (xy 155.128815 -304.323786) (xy 155.145619 -304.370916) (xy 155.154516 -304.420154)
			(xy 155.155392 -304.445162) (xy 155.155646 -304.46599) (xy 155.185364 -304.4952) (xy 155.464764 -304.4952)
			(xy 155.494482 -304.46599) (xy 155.494736 -304.445162) (xy 155.495612 -304.420154) (xy 155.504509 -304.370916)
			(xy 155.521313 -304.323786) (xy 155.545577 -304.280027) (xy 155.576651 -304.24081) (xy 155.613703 -304.207184)
			(xy 155.655742 -304.180048) (xy 155.701642 -304.16013) (xy 155.750176 -304.147961) (xy 155.800044 -304.143869)
			(xy 155.849912 -304.147961) (xy 155.898446 -304.16013) (xy 155.944346 -304.180048) (xy 155.986385 -304.207184)
			(xy 156.023437 -304.24081) (xy 156.054511 -304.280027) (xy 156.078775 -304.323786) (xy 156.095579 -304.370916)
			(xy 156.104476 -304.420154) (xy 156.105352 -304.445162) (xy 156.105606 -304.46599) (xy 156.135324 -304.4952)
			(xy 156.414724 -304.4952) (xy 156.444442 -304.46599) (xy 156.444696 -304.445162) (xy 156.445572 -304.420154)
			(xy 156.454469 -304.370916) (xy 156.471273 -304.323786) (xy 156.495537 -304.280027) (xy 156.526611 -304.24081)
			(xy 156.563663 -304.207184) (xy 156.605702 -304.180048) (xy 156.651602 -304.16013) (xy 156.700136 -304.147961)
			(xy 156.750004 -304.143869) (xy 156.799872 -304.147961) (xy 156.848406 -304.16013) (xy 156.894306 -304.180048)
			(xy 156.936345 -304.207184) (xy 156.973397 -304.24081) (xy 157.004471 -304.280027) (xy 157.028735 -304.323786)
			(xy 157.045539 -304.370916) (xy 157.054436 -304.420154) (xy 157.055312 -304.445162) (xy 157.055566 -304.46599)
			(xy 157.085284 -304.4952) (xy 157.364684 -304.4952) (xy 157.394402 -304.46599) (xy 157.394656 -304.445162)
			(xy 157.395532 -304.420154) (xy 157.404429 -304.370916) (xy 157.421233 -304.323786) (xy 157.445497 -304.280027)
			(xy 157.476571 -304.24081) (xy 157.513623 -304.207184) (xy 157.555662 -304.180048) (xy 157.601562 -304.16013)
			(xy 157.650096 -304.147961) (xy 157.699964 -304.143869) (xy 157.749832 -304.147961) (xy 157.798366 -304.16013)
			(xy 157.844266 -304.180048) (xy 157.886305 -304.207184) (xy 157.923357 -304.24081) (xy 157.954431 -304.280027)
			(xy 157.978695 -304.323786) (xy 157.995499 -304.370916) (xy 158.004396 -304.420154) (xy 158.005272 -304.445162)
			(xy 158.005526 -304.46599) (xy 158.035244 -304.4952) (xy 158.314644 -304.4952) (xy 158.344362 -304.46599)
			(xy 158.344616 -304.445162) (xy 158.345492 -304.420154) (xy 158.354389 -304.370916) (xy 158.371193 -304.323786)
			(xy 158.395457 -304.280027) (xy 158.426531 -304.24081) (xy 158.463583 -304.207184) (xy 158.505622 -304.180048)
			(xy 158.551522 -304.16013) (xy 158.600056 -304.147961) (xy 158.649924 -304.143869) (xy 158.699792 -304.147961)
			(xy 158.748326 -304.16013) (xy 158.794226 -304.180048) (xy 158.836265 -304.207184) (xy 158.873317 -304.24081)
			(xy 158.904391 -304.280027) (xy 158.928655 -304.323786) (xy 158.945459 -304.370916) (xy 158.954356 -304.420154)
			(xy 158.955232 -304.445162) (xy 158.955486 -304.46599) (xy 158.985204 -304.4952) (xy 159.264604 -304.4952)
			(xy 159.294322 -304.46599) (xy 159.294576 -304.445162) (xy 159.295452 -304.420154) (xy 159.304349 -304.370916)
			(xy 159.321153 -304.323786) (xy 159.345417 -304.280027) (xy 159.376491 -304.24081) (xy 159.413543 -304.207184)
			(xy 159.455582 -304.180048) (xy 159.501482 -304.16013) (xy 159.550016 -304.147961) (xy 159.599884 -304.143869)
			(xy 159.649752 -304.147961) (xy 159.698286 -304.16013) (xy 159.744186 -304.180048) (xy 159.786225 -304.207184)
			(xy 159.823277 -304.24081) (xy 159.854351 -304.280027) (xy 159.878615 -304.323786) (xy 159.895419 -304.370916)
			(xy 159.904316 -304.420154) (xy 159.905192 -304.445162) (xy 159.905446 -304.46599) (xy 159.935164 -304.4952)
			(xy 160.214564 -304.4952) (xy 160.244282 -304.46599) (xy 160.244536 -304.445162) (xy 160.245412 -304.420154)
			(xy 160.254309 -304.370916) (xy 160.271113 -304.323786) (xy 160.295377 -304.280027) (xy 160.326451 -304.24081)
			(xy 160.363503 -304.207184) (xy 160.405542 -304.180048) (xy 160.451442 -304.16013) (xy 160.499976 -304.147961)
			(xy 160.549844 -304.143869) (xy 160.599712 -304.147961) (xy 160.648246 -304.16013) (xy 160.694146 -304.180048)
			(xy 160.736185 -304.207184) (xy 160.773237 -304.24081) (xy 160.804311 -304.280027) (xy 160.828575 -304.323786)
			(xy 160.845379 -304.370916) (xy 160.854276 -304.420154) (xy 160.855152 -304.445162) (xy 160.855406 -304.46599)
			(xy 160.885124 -304.4952) (xy 161.164778 -304.4952) (xy 161.194496 -304.46599) (xy 161.19475 -304.445162)
			(xy 161.195626 -304.420154) (xy 161.204523 -304.370916) (xy 161.221327 -304.323786) (xy 161.245591 -304.280027)
			(xy 161.276665 -304.24081) (xy 161.313717 -304.207184) (xy 161.355756 -304.180048) (xy 161.401656 -304.16013)
			(xy 161.45019 -304.147961) (xy 161.500058 -304.143869) (xy 161.549926 -304.147961) (xy 161.59846 -304.16013)
			(xy 161.64436 -304.180048) (xy 161.686399 -304.207184) (xy 161.723451 -304.24081) (xy 161.754525 -304.280027)
			(xy 161.778789 -304.323786) (xy 161.795593 -304.370916) (xy 161.80449 -304.420154) (xy 161.805366 -304.445162)
			(xy 161.80562 -304.46599) (xy 161.835338 -304.4952) (xy 164.799518 -304.4952) (xy 164.809587 -304.494773)
			(xy 164.828186 -304.487054) (xy 164.835586 -304.480214) (xy 164.86378 -304.45202) (xy 164.870283 -304.444885)
			(xy 164.877882 -304.427153) (xy 164.87842 -304.407869) (xy 164.875464 -304.39868) (xy 164.83838 -304.298096)
			(xy 164.815012 -304.280316) (xy 164.800026 -304.279046) (xy 164.774875 -304.276494) (xy 164.72586 -304.264132)
			(xy 164.679551 -304.243864) (xy 164.637214 -304.216245) (xy 164.600004 -304.182028) (xy 164.56894 -304.14215)
			(xy 164.544869 -304.097699) (xy 164.528449 -304.04989) (xy 164.520129 -304.000029) (xy 164.51961 -303.974754)
			(xy 164.520084 -303.950766) (xy 164.527596 -303.903381) (xy 164.542428 -303.857754) (xy 164.564214 -303.815009)
			(xy 164.592418 -303.776198) (xy 164.626347 -303.742277) (xy 164.665164 -303.71408) (xy 164.707913 -303.692303)
			(xy 164.753543 -303.677481) (xy 164.80093 -303.669979) (xy 164.824918 -303.669446) (xy 164.850938 -303.669955)
			(xy 164.902231 -303.678738) (xy 164.951295 -303.696082) (xy 164.97427 -303.708308) (xy 164.985954 -303.715166)
			(xy 165.012878 -303.714912) (xy 165.100254 -303.663604) (xy 165.107745 -303.658849) (xy 165.119087 -303.645219)
			(xy 165.125079 -303.62853) (xy 165.1254 -303.619662) (xy 165.1254 -303.379886) (xy 165.125008 -303.371038)
			(xy 165.118979 -303.354399) (xy 165.107673 -303.340784) (xy 165.100254 -303.335944) (xy 165.012878 -303.284636)
			(xy 164.985954 -303.284382) (xy 164.97427 -303.29124) (xy 164.951305 -303.303486) (xy 164.902237 -303.320825)
			(xy 164.850939 -303.329589) (xy 164.824918 -303.330102) (xy 164.79966 -303.329611) (xy 164.749832 -303.321299)
			(xy 164.702052 -303.304898) (xy 164.657623 -303.280857) (xy 164.617758 -303.249831) (xy 164.583543 -303.212665)
			(xy 164.555912 -303.170375) (xy 164.535619 -303.124114) (xy 164.523218 -303.075144) (xy 164.519046 -303.0248)
			(xy 164.523218 -302.974456) (xy 164.535619 -302.925486) (xy 164.555912 -302.879225) (xy 164.583543 -302.836935)
			(xy 164.617758 -302.799769) (xy 164.657623 -302.768743) (xy 164.702052 -302.744702) (xy 164.749832 -302.728301)
			(xy 164.79966 -302.719989) (xy 164.824918 -302.719486) (xy 164.850938 -302.719995) (xy 164.902232 -302.728776)
			(xy 164.951297 -302.746118) (xy 164.97427 -302.758348) (xy 164.985954 -302.765206) (xy 165.012878 -302.764952)
			(xy 165.100254 -302.713644) (xy 165.10775 -302.708891) (xy 165.119103 -302.695263) (xy 165.125107 -302.678572)
			(xy 165.1254 -302.669702) (xy 165.1254 -301.479966) (xy 165.125021 -301.471111) (xy 165.119009 -301.454452)
			(xy 165.107709 -301.440815) (xy 165.100254 -301.436024) (xy 165.012878 -301.384716) (xy 164.985954 -301.384462)
			(xy 164.97427 -301.39132) (xy 164.951305 -301.403566) (xy 164.902238 -301.420907) (xy 164.850939 -301.429671)
			(xy 164.824918 -301.430182) (xy 164.799661 -301.429691) (xy 164.749837 -301.421379) (xy 164.70206 -301.40498)
			(xy 164.657634 -301.38094) (xy 164.617771 -301.349916) (xy 164.583559 -301.312753) (xy 164.55593 -301.270466)
			(xy 164.535638 -301.224208) (xy 164.523237 -301.17524) (xy 164.519066 -301.1249) (xy 164.523237 -301.07456)
			(xy 164.535638 -301.025592) (xy 164.55593 -300.979334) (xy 164.583559 -300.937047) (xy 164.617771 -300.899884)
			(xy 164.657634 -300.86886) (xy 164.70206 -300.84482) (xy 164.749837 -300.828421) (xy 164.799661 -300.820109)
			(xy 164.824918 -300.819566) (xy 164.850938 -300.820075) (xy 164.902231 -300.828859) (xy 164.951294 -300.846204)
			(xy 164.97427 -300.858428) (xy 164.985954 -300.865286) (xy 165.012878 -300.865032) (xy 165.100254 -300.813724)
			(xy 165.107747 -300.80897) (xy 165.119095 -300.795341) (xy 165.125093 -300.778651) (xy 165.1254 -300.769782)
			(xy 165.1254 -300.530006) (xy 165.125011 -300.521156) (xy 165.118987 -300.504512) (xy 165.107682 -300.490892)
			(xy 165.100254 -300.486064) (xy 165.012878 -300.434756) (xy 164.985954 -300.434502) (xy 164.97427 -300.44136)
			(xy 164.951306 -300.453609) (xy 164.902239 -300.470952) (xy 164.85094 -300.479718) (xy 164.824918 -300.480222)
			(xy 164.799658 -300.479731) (xy 164.749827 -300.471418) (xy 164.702044 -300.455017) (xy 164.657612 -300.430974)
			(xy 164.617744 -300.399945) (xy 164.583527 -300.362778) (xy 164.555895 -300.320485) (xy 164.5356 -300.274221)
			(xy 164.523198 -300.225247) (xy 164.519026 -300.1749) (xy 164.523198 -300.124553) (xy 164.5356 -300.075579)
			(xy 164.555895 -300.029315) (xy 164.583527 -299.987022) (xy 164.617744 -299.949855) (xy 164.657612 -299.918826)
			(xy 164.702044 -299.894783) (xy 164.749827 -299.878382) (xy 164.799658 -299.870069) (xy 164.824918 -299.869606)
			(xy 164.850938 -299.870115) (xy 164.902231 -299.878897) (xy 164.951297 -299.896239) (xy 164.97427 -299.908468)
			(xy 164.985954 -299.915326) (xy 165.012878 -299.915072) (xy 165.100254 -299.863764) (xy 165.107752 -299.859012)
			(xy 165.11911 -299.845385) (xy 165.125121 -299.828693) (xy 165.1254 -299.819822) (xy 165.1254 -299.580046)
			(xy 165.125018 -299.571193) (xy 165.119002 -299.554539) (xy 165.1077 -299.540907) (xy 165.100254 -299.536104)
			(xy 165.012878 -299.484796) (xy 164.985954 -299.484542) (xy 164.97427 -299.4914) (xy 164.951305 -299.503647)
			(xy 164.902238 -299.520988) (xy 164.85094 -299.529754) (xy 164.824918 -299.530262) (xy 164.799663 -299.529771)
			(xy 164.749842 -299.52146) (xy 164.702068 -299.505062) (xy 164.657645 -299.481023) (xy 164.617785 -299.450001)
			(xy 164.583574 -299.412841) (xy 164.555947 -299.370556) (xy 164.535657 -299.324301) (xy 164.523257 -299.275337)
			(xy 164.519086 -299.225) (xy 164.523257 -299.174663) (xy 164.535657 -299.125699) (xy 164.555947 -299.079444)
			(xy 164.583574 -299.037159) (xy 164.617785 -298.999999) (xy 164.657645 -298.968977) (xy 164.702068 -298.944938)
			(xy 164.749842 -298.92854) (xy 164.799663 -298.920229) (xy 164.824918 -298.919646) (xy 164.850938 -298.920155)
			(xy 164.902231 -298.928938) (xy 164.951295 -298.946282) (xy 164.97427 -298.958508) (xy 164.985954 -298.965366)
			(xy 165.012878 -298.965112) (xy 165.100254 -298.913804) (xy 165.107745 -298.909049) (xy 165.119087 -298.895419)
			(xy 165.125079 -298.87873) (xy 165.1254 -298.869862) (xy 165.1254 -298.801282) (xy 165.124973 -298.791213)
			(xy 165.117254 -298.772614) (xy 165.110414 -298.765214) (xy 164.962586 -298.617386) (xy 164.955191 -298.610532)
			(xy 164.936592 -298.60279) (xy 164.926518 -298.6024) (xy 163.444682 -298.6024) (xy 163.434613 -298.602827)
			(xy 163.416014 -298.610546) (xy 163.408614 -298.617386) (xy 163.39312 -298.63288) (xy 163.385246 -298.65447)
			(xy 163.386516 -298.6659) (xy 163.38804 -298.696888) (xy 163.38804 -299.224954) (xy 163.569154 -299.224954)
			(xy 163.573114 -299.1759) (xy 163.584891 -299.128116) (xy 163.604182 -299.08284) (xy 163.630485 -299.041244)
			(xy 163.66312 -299.004407) (xy 163.701241 -298.973282) (xy 163.743862 -298.948675) (xy 163.789878 -298.931223)
			(xy 163.838097 -298.921379) (xy 163.887272 -298.919398) (xy 163.936127 -298.92533) (xy 163.983398 -298.939022)
			(xy 164.02786 -298.96012) (xy 164.068363 -298.988076) (xy 164.103856 -299.022168) (xy 164.133421 -299.061512)
			(xy 164.156292 -299.105089) (xy 164.171876 -299.15177) (xy 164.179771 -299.200347) (xy 164.180266 -299.224954)
			(xy 164.179771 -299.249561) (xy 164.171876 -299.298138) (xy 164.156292 -299.344819) (xy 164.133421 -299.388396)
			(xy 164.103856 -299.42774) (xy 164.068363 -299.461832) (xy 164.02786 -299.489788) (xy 163.983398 -299.510886)
			(xy 163.936127 -299.524578) (xy 163.887272 -299.53051) (xy 163.838097 -299.528529) (xy 163.789878 -299.518685)
			(xy 163.743862 -299.501233) (xy 163.701241 -299.476626) (xy 163.66312 -299.445501) (xy 163.630485 -299.408664)
			(xy 163.604182 -299.367068) (xy 163.584891 -299.321792) (xy 163.573114 -299.274008) (xy 163.569154 -299.224954)
			(xy 163.38804 -299.224954) (xy 163.38804 -299.756322) (xy 163.387651 -299.778711) (xy 163.381112 -299.82301)
			(xy 163.368162 -299.865876) (xy 163.349081 -299.906385) (xy 163.324279 -299.943668) (xy 163.309554 -299.960538)
			(xy 163.303657 -299.967787) (xy 163.29702 -299.985239) (xy 163.2966 -299.994574) (xy 163.2966 -300.355254)
			(xy 163.296912 -300.36461) (xy 163.303564 -300.382096) (xy 163.309554 -300.38929) (xy 163.324247 -300.406184)
			(xy 163.349036 -300.443468) (xy 163.368113 -300.483973) (xy 163.381067 -300.52683) (xy 163.387621 -300.57112)
			(xy 163.38804 -300.593506) (xy 163.38804 -300.71822) (xy 163.387563 -300.742505) (xy 163.379862 -300.790461)
			(xy 163.364674 -300.836596) (xy 163.34238 -300.879748) (xy 163.32835 -300.899576) (xy 163.322601 -300.907276)
			(xy 163.310275 -300.922021) (xy 163.303712 -300.92904) (xy 163.223956 -301.008796) (xy 163.217098 -301.034704)
			(xy 163.2204 -301.047912) (xy 163.225025 -301.066816) (xy 163.229992 -301.105415) (xy 163.230306 -301.124874)
			(xy 163.569154 -301.124874) (xy 163.573114 -301.07582) (xy 163.584891 -301.028036) (xy 163.604182 -300.98276)
			(xy 163.630485 -300.941164) (xy 163.66312 -300.904327) (xy 163.701241 -300.873202) (xy 163.743862 -300.848595)
			(xy 163.789878 -300.831143) (xy 163.838097 -300.821299) (xy 163.887272 -300.819318) (xy 163.936127 -300.82525)
			(xy 163.983398 -300.838942) (xy 164.02786 -300.86004) (xy 164.068363 -300.887996) (xy 164.103856 -300.922088)
			(xy 164.133421 -300.961432) (xy 164.156292 -301.005009) (xy 164.171876 -301.05169) (xy 164.179771 -301.100267)
			(xy 164.180266 -301.124874) (xy 164.179771 -301.149481) (xy 164.171876 -301.198058) (xy 164.156292 -301.244739)
			(xy 164.133421 -301.288316) (xy 164.103856 -301.32766) (xy 164.068363 -301.361752) (xy 164.02786 -301.389708)
			(xy 163.983398 -301.410806) (xy 163.936127 -301.424498) (xy 163.887272 -301.43043) (xy 163.838097 -301.428449)
			(xy 163.789878 -301.418605) (xy 163.743862 -301.401153) (xy 163.701241 -301.376546) (xy 163.66312 -301.345421)
			(xy 163.630485 -301.308584) (xy 163.604182 -301.266988) (xy 163.584891 -301.221712) (xy 163.573114 -301.173928)
			(xy 163.569154 -301.124874) (xy 163.230306 -301.124874) (xy 163.229862 -301.148868) (xy 163.222358 -301.196267)
			(xy 163.207532 -301.241908) (xy 163.185748 -301.284668) (xy 163.157543 -301.323493) (xy 163.123611 -301.357427)
			(xy 163.084788 -301.385635) (xy 163.04203 -301.407423) (xy 162.99639 -301.422253) (xy 162.948992 -301.42976)
			(xy 162.924998 -301.430182) (xy 162.901278 -301.429732) (xy 162.85441 -301.422394) (xy 162.809242 -301.407894)
			(xy 162.76686 -301.386581) (xy 162.728285 -301.358969) (xy 162.694445 -301.325723) (xy 162.666155 -301.287642)
			(xy 162.644097 -301.245643) (xy 162.628801 -301.200738) (xy 162.624262 -301.177452) (xy 162.62096 -301.159164)
			(xy 162.592766 -301.135288) (xy 162.30727 -301.135288) (xy 162.279076 -301.159164) (xy 162.275774 -301.177452)
			(xy 162.271248 -301.200742) (xy 162.255952 -301.245652) (xy 162.233894 -301.287655) (xy 162.205603 -301.325741)
			(xy 162.171763 -301.358993) (xy 162.133186 -301.38661) (xy 162.090802 -301.407928) (xy 162.045631 -301.422434)
			(xy 161.99876 -301.429778) (xy 161.975038 -301.430182) (xy 161.960855 -301.429997) (xy 161.932615 -301.427327)
			(xy 161.91865 -301.424848) (xy 161.906204 -301.422562) (xy 161.882582 -301.429928) (xy 161.805112 -301.507398)
			(xy 161.797746 -301.53102) (xy 161.800032 -301.543466) (xy 161.802515 -301.557431) (xy 161.805183 -301.585671)
			(xy 161.805366 -301.599854) (xy 161.805182 -301.614037) (xy 161.802513 -301.642277) (xy 161.800032 -301.656242)
			(xy 161.797746 -301.668688) (xy 161.805112 -301.69231) (xy 161.882582 -301.76978) (xy 161.906204 -301.777146)
			(xy 161.91865 -301.77486) (xy 161.932615 -301.772376) (xy 161.960855 -301.769707) (xy 161.975038 -301.769526)
			(xy 162.000288 -301.77005) (xy 162.0501 -301.778368) (xy 162.097863 -301.794771) (xy 162.142275 -301.81881)
			(xy 162.182125 -301.849831) (xy 162.216327 -301.886988) (xy 162.243946 -301.929267) (xy 162.264231 -301.975515)
			(xy 162.276627 -302.024471) (xy 162.280797 -302.0748) (xy 162.276627 -302.125129) (xy 162.264231 -302.174085)
			(xy 162.243946 -302.220333) (xy 162.216327 -302.262612) (xy 162.182125 -302.299769) (xy 162.142275 -302.33079)
			(xy 162.097863 -302.354829) (xy 162.0501 -302.371232) (xy 162.000288 -302.37955) (xy 161.975038 -302.380142)
			(xy 161.960855 -302.379957) (xy 161.932615 -302.377287) (xy 161.91865 -302.374808) (xy 161.906204 -302.372522)
			(xy 161.882582 -302.379888) (xy 161.805112 -302.457358) (xy 161.797746 -302.48098) (xy 161.800032 -302.493426)
			(xy 161.802517 -302.507391) (xy 161.805188 -302.535631) (xy 161.805366 -302.549814) (xy 161.805179 -302.563996)
			(xy 161.802505 -302.592236) (xy 161.800032 -302.606202) (xy 161.797746 -302.618648) (xy 161.805112 -302.64227)
			(xy 161.882582 -302.71974) (xy 161.906204 -302.727106) (xy 161.91865 -302.72482) (xy 161.932615 -302.722337)
			(xy 161.960855 -302.719668) (xy 161.975038 -302.719486) (xy 162.000292 -302.720011) (xy 162.05011 -302.728329)
			(xy 162.097879 -302.744734) (xy 162.142297 -302.768777) (xy 162.182153 -302.799802) (xy 162.216358 -302.836964)
			(xy 162.243981 -302.879248) (xy 162.264269 -302.925502) (xy 162.276666 -302.974465) (xy 162.280837 -303.024794)
			(xy 162.619194 -303.024794) (xy 162.623154 -302.97574) (xy 162.634931 -302.927956) (xy 162.654222 -302.88268)
			(xy 162.680525 -302.841084) (xy 162.71316 -302.804247) (xy 162.751281 -302.773122) (xy 162.793902 -302.748515)
			(xy 162.839918 -302.731063) (xy 162.888137 -302.721219) (xy 162.937312 -302.719238) (xy 162.986167 -302.72517)
			(xy 163.033438 -302.738862) (xy 163.0779 -302.75996) (xy 163.118403 -302.787916) (xy 163.153896 -302.822008)
			(xy 163.183461 -302.861352) (xy 163.206332 -302.904929) (xy 163.221916 -302.95161) (xy 163.229811 -303.000187)
			(xy 163.230306 -303.024794) (xy 163.569154 -303.024794) (xy 163.573114 -302.97574) (xy 163.584891 -302.927956)
			(xy 163.604182 -302.88268) (xy 163.630485 -302.841084) (xy 163.66312 -302.804247) (xy 163.701241 -302.773122)
			(xy 163.743862 -302.748515) (xy 163.789878 -302.731063) (xy 163.838097 -302.721219) (xy 163.887272 -302.719238)
			(xy 163.936127 -302.72517) (xy 163.983398 -302.738862) (xy 164.02786 -302.75996) (xy 164.068363 -302.787916)
			(xy 164.103856 -302.822008) (xy 164.133421 -302.861352) (xy 164.156292 -302.904929) (xy 164.171876 -302.95161)
			(xy 164.179771 -303.000187) (xy 164.180266 -303.024794) (xy 164.179771 -303.049401) (xy 164.171876 -303.097978)
			(xy 164.156292 -303.144659) (xy 164.133421 -303.188236) (xy 164.103856 -303.22758) (xy 164.068363 -303.261672)
			(xy 164.02786 -303.289628) (xy 163.983398 -303.310726) (xy 163.936127 -303.324418) (xy 163.887272 -303.33035)
			(xy 163.838097 -303.328369) (xy 163.789878 -303.318525) (xy 163.743862 -303.301073) (xy 163.701241 -303.276466)
			(xy 163.66312 -303.245341) (xy 163.630485 -303.208504) (xy 163.604182 -303.166908) (xy 163.584891 -303.121632)
			(xy 163.573114 -303.073848) (xy 163.569154 -303.024794) (xy 163.230306 -303.024794) (xy 163.229811 -303.049401)
			(xy 163.221916 -303.097978) (xy 163.206332 -303.144659) (xy 163.183461 -303.188236) (xy 163.153896 -303.22758)
			(xy 163.118403 -303.261672) (xy 163.0779 -303.289628) (xy 163.033438 -303.310726) (xy 162.986167 -303.324418)
			(xy 162.937312 -303.33035) (xy 162.888137 -303.328369) (xy 162.839918 -303.318525) (xy 162.793902 -303.301073)
			(xy 162.751281 -303.276466) (xy 162.71316 -303.245341) (xy 162.680525 -303.208504) (xy 162.654222 -303.166908)
			(xy 162.634931 -303.121632) (xy 162.623154 -303.073848) (xy 162.619194 -303.024794) (xy 162.280837 -303.024794)
			(xy 162.280837 -303.0248) (xy 162.276666 -303.075135) (xy 162.264269 -303.124098) (xy 162.243981 -303.170352)
			(xy 162.216358 -303.212636) (xy 162.182153 -303.249798) (xy 162.142297 -303.280823) (xy 162.097879 -303.304866)
			(xy 162.05011 -303.321271) (xy 162.000292 -303.329589) (xy 161.975038 -303.330102) (xy 161.960855 -303.329917)
			(xy 161.932615 -303.327247) (xy 161.91865 -303.324768) (xy 161.906204 -303.322482) (xy 161.882582 -303.329848)
			(xy 161.805112 -303.407318) (xy 161.797746 -303.43094) (xy 161.800032 -303.443386) (xy 161.802519 -303.457351)
			(xy 161.805194 -303.485591) (xy 161.805366 -303.499774) (xy 161.804882 -303.524591) (xy 161.796857 -303.573572)
			(xy 161.781013 -303.62061) (xy 161.757767 -303.664465) (xy 161.727734 -303.703981) (xy 161.691703 -303.738118)
			(xy 161.650623 -303.765976) (xy 161.605579 -303.786821) (xy 161.557755 -303.800105) (xy 161.508412 -303.805476)
			(xy 161.45885 -303.802794) (xy 161.410375 -303.792129) (xy 161.364264 -303.773763) (xy 161.321732 -303.748178)
			(xy 161.283899 -303.71605) (xy 161.251762 -303.678224) (xy 161.226168 -303.635697) (xy 161.207791 -303.58959)
			(xy 161.197115 -303.541117) (xy 161.194422 -303.491556) (xy 161.199783 -303.442212) (xy 161.213055 -303.394385)
			(xy 161.233891 -303.349336) (xy 161.26174 -303.308251) (xy 161.295868 -303.272212) (xy 161.335378 -303.242169)
			(xy 161.379227 -303.218914) (xy 161.426262 -303.20306) (xy 161.475241 -303.195023) (xy 161.500058 -303.194466)
			(xy 161.514241 -303.194651) (xy 161.542481 -303.19732) (xy 161.556446 -303.1998) (xy 161.568892 -303.202086)
			(xy 161.592514 -303.19472) (xy 161.669984 -303.11725) (xy 161.67735 -303.093628) (xy 161.675064 -303.081182)
			(xy 161.672579 -303.067217) (xy 161.669907 -303.038977) (xy 161.66973 -303.024794) (xy 161.669917 -303.010612)
			(xy 161.672591 -302.982372) (xy 161.675064 -302.968406) (xy 161.67735 -302.95596) (xy 161.669984 -302.932338)
			(xy 161.592514 -302.854868) (xy 161.568892 -302.847502) (xy 161.556446 -302.849788) (xy 161.542481 -302.852271)
			(xy 161.514241 -302.854939) (xy 161.500058 -302.855122) (xy 161.474804 -302.854597) (xy 161.424985 -302.846278)
			(xy 161.377215 -302.829872) (xy 161.332796 -302.805829) (xy 161.292941 -302.774802) (xy 161.258734 -302.73764)
			(xy 161.231111 -302.695354) (xy 161.210824 -302.649099) (xy 161.198426 -302.600136) (xy 161.194255 -302.5498)
			(xy 161.198426 -302.499464) (xy 161.210824 -302.450501) (xy 161.231111 -302.404246) (xy 161.258734 -302.36196)
			(xy 161.292941 -302.324798) (xy 161.332796 -302.293771) (xy 161.377215 -302.269728) (xy 161.424985 -302.253322)
			(xy 161.474804 -302.245003) (xy 161.500058 -302.244506) (xy 161.514241 -302.244691) (xy 161.542481 -302.24736)
			(xy 161.556446 -302.24984) (xy 161.568892 -302.252126) (xy 161.592514 -302.24476) (xy 161.669984 -302.16729)
			(xy 161.67735 -302.143668) (xy 161.675064 -302.131222) (xy 161.672577 -302.117257) (xy 161.669901 -302.089017)
			(xy 161.66973 -302.074834) (xy 161.669915 -302.060651) (xy 161.672586 -302.032412) (xy 161.675064 -302.018446)
			(xy 161.67735 -302.006) (xy 161.669984 -301.982378) (xy 161.592514 -301.904908) (xy 161.568892 -301.897542)
			(xy 161.556446 -301.899828) (xy 161.542481 -301.902312) (xy 161.514241 -301.90498) (xy 161.500058 -301.905162)
			(xy 161.476068 -301.904713) (xy 161.428681 -301.8972) (xy 161.383051 -301.882368) (xy 161.340305 -301.860579)
			(xy 161.301492 -301.832372) (xy 161.267571 -301.798441) (xy 161.239375 -301.75962) (xy 161.217599 -301.716867)
			(xy 161.202779 -301.671234) (xy 161.19528 -301.623844) (xy 161.19475 -301.599854) (xy 161.194934 -301.585671)
			(xy 161.197602 -301.557431) (xy 161.200084 -301.543466) (xy 161.20237 -301.53102) (xy 161.195004 -301.507398)
			(xy 161.117534 -301.429928) (xy 161.093912 -301.422562) (xy 161.081466 -301.424848) (xy 161.067501 -301.427332)
			(xy 161.039261 -301.430003) (xy 161.025078 -301.430182) (xy 161.010832 -301.430005) (xy 160.982464 -301.427335)
			(xy 160.968436 -301.424848) (xy 160.956244 -301.422562) (xy 160.932114 -301.429928) (xy 160.854898 -301.507144)
			(xy 160.847532 -301.53102) (xy 160.849818 -301.543466) (xy 160.8523 -301.557431) (xy 160.854967 -301.585671)
			(xy 160.855152 -301.599854) (xy 160.85467 -301.62468) (xy 160.846644 -301.673679) (xy 160.830796 -301.720734)
			(xy 160.807544 -301.764605) (xy 160.7775 -301.804136) (xy 160.741457 -301.838285) (xy 160.700363 -301.866153)
			(xy 160.655301 -301.887005) (xy 160.60746 -301.900292) (xy 160.558099 -301.905663) (xy 160.50852 -301.902977)
			(xy 160.460029 -301.892305) (xy 160.413902 -301.873929) (xy 160.371357 -301.848331) (xy 160.333514 -301.816187)
			(xy 160.30137 -301.778344) (xy 160.275772 -301.735799) (xy 160.257395 -301.689673) (xy 160.246723 -301.641182)
			(xy 160.244037 -301.591603) (xy 160.249408 -301.542242) (xy 160.262694 -301.4944) (xy 160.283546 -301.449339)
			(xy 160.311413 -301.408245) (xy 160.345562 -301.372201) (xy 160.385093 -301.342157) (xy 160.428964 -301.318904)
			(xy 160.476019 -301.303056) (xy 160.525018 -301.29503) (xy 160.549844 -301.294546) (xy 160.56409 -301.294724)
			(xy 160.592457 -301.297396) (xy 160.606486 -301.29988) (xy 160.618678 -301.302166) (xy 160.642808 -301.2948)
			(xy 160.720024 -301.217584) (xy 160.72739 -301.193708) (xy 160.725104 -301.181262) (xy 160.724342 -301.177452)
			(xy 160.72104 -301.159164) (xy 160.692846 -301.135288) (xy 147.773898 -301.135288) (xy 147.763911 -301.13475)
			(xy 147.745481 -301.127035) (xy 147.738084 -301.120302) (xy 147.364196 -300.746414) (xy 147.357384 -300.739069)
			(xy 147.349647 -300.720607) (xy 147.34921 -300.7106) (xy 147.34921 -298.803822) (xy 147.349744 -298.793833)
			(xy 147.357453 -298.775396) (xy 147.364196 -298.768008) (xy 147.70989 -298.422314) (xy 147.710398 -298.421806)
			(xy 147.713954 -298.417996) (xy 147.75307 -298.379134) (xy 147.754086 -298.378118) (xy 147.754594 -298.37761)
			(xy 147.822666 -298.309538) (xy 147.829278 -298.303341) (xy 147.845676 -298.295654) (xy 147.85467 -298.294552)
			(xy 147.863814 -298.294044) (xy 147.879816 -298.286678) (xy 147.8915 -298.275248) (xy 147.892008 -298.27474)
			(xy 147.899405 -298.26789) (xy 147.918003 -298.260153) (xy 147.928076 -298.259754) (xy 149.059138 -298.259754)
			(xy 149.069204 -298.259323) (xy 149.087794 -298.251593) (xy 149.095206 -298.244768) (xy 149.411436 -297.928538)
			(xy 149.41828 -297.921139) (xy 149.426002 -297.90254) (xy 149.426422 -297.89247) (xy 149.426422 -296.450512)
			(xy 149.426002 -296.44044) (xy 149.418293 -296.421831) (xy 149.411436 -296.414444) (xy 149.201378 -296.204386)
			(xy 149.193982 -296.197534) (xy 149.175383 -296.189794) (xy 149.16531 -296.1894) (xy 148.135594 -296.1894)
			(xy 148.125627 -296.189875) (xy 148.107187 -296.197448) (xy 148.09978 -296.204132) (xy 148.080196 -296.222897)
			(xy 148.036676 -296.255267) (xy 147.98901 -296.281146) (xy 147.93816 -296.300014) (xy 147.885149 -296.311488)
			(xy 147.831048 -296.315339) (xy 147.776947 -296.311488) (xy 147.723936 -296.300014) (xy 147.673086 -296.281146)
			(xy 147.62542 -296.255267) (xy 147.5819 -296.222897) (xy 147.562316 -296.204132) (xy 147.554909 -296.197442)
			(xy 147.536472 -296.189849) (xy 147.526502 -296.1894) (xy 144.97177 -296.1894) (xy 144.967094 -296.189481)
			(xy 144.95789 -296.191139) (xy 144.953482 -296.192702) (xy 144.928844 -296.202354) (xy 144.921478 -296.209212)
			(xy 144.896078 -296.23131) (xy 144.874234 -296.247566) (xy 144.863877 -296.254529) (xy 144.842397 -296.26724)
			(xy 144.831308 -296.272966) (xy 144.824196 -296.276776) (xy 144.614138 -296.486834) (xy 144.613884 -296.487088)
			(xy 144.609566 -296.491406) (xy 144.609312 -296.49166) (xy 144.597374 -296.503598) (xy 144.573244 -296.527982)
			(xy 144.566563 -296.535393) (xy 144.558983 -296.553829) (xy 144.558512 -296.563796) (xy 144.558512 -298.65066)
			(xy 144.558946 -298.660725) (xy 144.566677 -298.679313) (xy 144.573498 -298.686728) (xy 144.590516 -298.703746)
			(xy 144.623536 -298.73702) (xy 144.628864 -298.741975) (xy 144.641631 -298.74894) (xy 144.648682 -298.750736)
			(xy 144.65427 -298.752006) (xy 144.681579 -298.752199) (xy 144.735709 -298.759443) (xy 144.788252 -298.774331)
			(xy 144.838136 -298.79656) (xy 144.88434 -298.825674) (xy 144.925921 -298.861078) (xy 144.962029 -298.902051)
			(xy 144.991926 -298.947752) (xy 145.015 -298.99725) (xy 145.030781 -299.049533) (xy 145.038946 -299.103531)
			(xy 145.039328 -299.158142) (xy 145.031919 -299.212249) (xy 145.01687 -299.264747) (xy 144.99449 -299.314562)
			(xy 144.965235 -299.360678) (xy 144.929704 -299.402151) (xy 144.888622 -299.438133) (xy 144.842829 -299.46789)
			(xy 144.793261 -299.490814) (xy 144.740931 -299.506435) (xy 144.686908 -299.514435) (xy 144.659604 -299.515022)
			(xy 144.648682 -299.516292) (xy 144.64162 -299.518058) (xy 144.628851 -299.525033) (xy 144.623536 -299.530008)
			(xy 144.590516 -299.563282) (xy 144.573498 -299.5803) (xy 144.566652 -299.587699) (xy 144.558918 -299.606296)
			(xy 144.558512 -299.616368) (xy 144.558512 -301.599854) (xy 152.644106 -301.599854) (xy 152.648066 -301.5508)
			(xy 152.659843 -301.503016) (xy 152.679134 -301.45774) (xy 152.705437 -301.416144) (xy 152.738072 -301.379307)
			(xy 152.776193 -301.348182) (xy 152.818814 -301.323575) (xy 152.86483 -301.306123) (xy 152.913049 -301.296279)
			(xy 152.962224 -301.294298) (xy 153.011079 -301.30023) (xy 153.05835 -301.313922) (xy 153.102812 -301.33502)
			(xy 153.143315 -301.362976) (xy 153.178808 -301.397068) (xy 153.208373 -301.436412) (xy 153.231244 -301.479989)
			(xy 153.246828 -301.52667) (xy 153.254723 -301.575247) (xy 153.255218 -301.599854) (xy 153.594066 -301.599854)
			(xy 153.598026 -301.5508) (xy 153.609803 -301.503016) (xy 153.629094 -301.45774) (xy 153.655397 -301.416144)
			(xy 153.688032 -301.379307) (xy 153.726153 -301.348182) (xy 153.768774 -301.323575) (xy 153.81479 -301.306123)
			(xy 153.863009 -301.296279) (xy 153.912184 -301.294298) (xy 153.961039 -301.30023) (xy 154.00831 -301.313922)
			(xy 154.052772 -301.33502) (xy 154.093275 -301.362976) (xy 154.128768 -301.397068) (xy 154.158333 -301.436412)
			(xy 154.181204 -301.479989) (xy 154.196788 -301.52667) (xy 154.204683 -301.575247) (xy 154.205178 -301.599854)
			(xy 154.54428 -301.599854) (xy 154.54824 -301.5508) (xy 154.560017 -301.503016) (xy 154.579308 -301.45774)
			(xy 154.605611 -301.416144) (xy 154.638246 -301.379307) (xy 154.676367 -301.348182) (xy 154.718988 -301.323575)
			(xy 154.765004 -301.306123) (xy 154.813223 -301.296279) (xy 154.862398 -301.294298) (xy 154.911253 -301.30023)
			(xy 154.958524 -301.313922) (xy 155.002986 -301.33502) (xy 155.043489 -301.362976) (xy 155.078982 -301.397068)
			(xy 155.108547 -301.436412) (xy 155.131418 -301.479989) (xy 155.147002 -301.52667) (xy 155.154897 -301.575247)
			(xy 155.155392 -301.599854) (xy 155.49424 -301.599854) (xy 155.4982 -301.5508) (xy 155.509977 -301.503016)
			(xy 155.529268 -301.45774) (xy 155.555571 -301.416144) (xy 155.588206 -301.379307) (xy 155.626327 -301.348182)
			(xy 155.668948 -301.323575) (xy 155.714964 -301.306123) (xy 155.763183 -301.296279) (xy 155.812358 -301.294298)
			(xy 155.861213 -301.30023) (xy 155.908484 -301.313922) (xy 155.952946 -301.33502) (xy 155.993449 -301.362976)
			(xy 156.028942 -301.397068) (xy 156.058507 -301.436412) (xy 156.081378 -301.479989) (xy 156.096962 -301.52667)
			(xy 156.104857 -301.575247) (xy 156.105352 -301.599854) (xy 156.4442 -301.599854) (xy 156.44816 -301.5508)
			(xy 156.459937 -301.503016) (xy 156.479228 -301.45774) (xy 156.505531 -301.416144) (xy 156.538166 -301.379307)
			(xy 156.576287 -301.348182) (xy 156.618908 -301.323575) (xy 156.664924 -301.306123) (xy 156.713143 -301.296279)
			(xy 156.762318 -301.294298) (xy 156.811173 -301.30023) (xy 156.858444 -301.313922) (xy 156.902906 -301.33502)
			(xy 156.943409 -301.362976) (xy 156.978902 -301.397068) (xy 157.008467 -301.436412) (xy 157.031338 -301.479989)
			(xy 157.046922 -301.52667) (xy 157.054817 -301.575247) (xy 157.055312 -301.599854) (xy 157.39416 -301.599854)
			(xy 157.39812 -301.5508) (xy 157.409897 -301.503016) (xy 157.429188 -301.45774) (xy 157.455491 -301.416144)
			(xy 157.488126 -301.379307) (xy 157.526247 -301.348182) (xy 157.568868 -301.323575) (xy 157.614884 -301.306123)
			(xy 157.663103 -301.296279) (xy 157.712278 -301.294298) (xy 157.761133 -301.30023) (xy 157.808404 -301.313922)
			(xy 157.852866 -301.33502) (xy 157.893369 -301.362976) (xy 157.928862 -301.397068) (xy 157.958427 -301.436412)
			(xy 157.981298 -301.479989) (xy 157.996882 -301.52667) (xy 158.004777 -301.575247) (xy 158.005272 -301.599854)
			(xy 158.34412 -301.599854) (xy 158.34808 -301.5508) (xy 158.359857 -301.503016) (xy 158.379148 -301.45774)
			(xy 158.405451 -301.416144) (xy 158.438086 -301.379307) (xy 158.476207 -301.348182) (xy 158.518828 -301.323575)
			(xy 158.564844 -301.306123) (xy 158.613063 -301.296279) (xy 158.662238 -301.294298) (xy 158.711093 -301.30023)
			(xy 158.758364 -301.313922) (xy 158.802826 -301.33502) (xy 158.843329 -301.362976) (xy 158.878822 -301.397068)
			(xy 158.908387 -301.436412) (xy 158.931258 -301.479989) (xy 158.946842 -301.52667) (xy 158.954737 -301.575247)
			(xy 158.955232 -301.599854) (xy 159.29408 -301.599854) (xy 159.29804 -301.5508) (xy 159.309817 -301.503016)
			(xy 159.329108 -301.45774) (xy 159.355411 -301.416144) (xy 159.388046 -301.379307) (xy 159.426167 -301.348182)
			(xy 159.468788 -301.323575) (xy 159.514804 -301.306123) (xy 159.563023 -301.296279) (xy 159.612198 -301.294298)
			(xy 159.661053 -301.30023) (xy 159.708324 -301.313922) (xy 159.752786 -301.33502) (xy 159.793289 -301.362976)
			(xy 159.828782 -301.397068) (xy 159.858347 -301.436412) (xy 159.881218 -301.479989) (xy 159.896802 -301.52667)
			(xy 159.904697 -301.575247) (xy 159.905192 -301.599854) (xy 159.904697 -301.624461) (xy 159.896802 -301.673038)
			(xy 159.881218 -301.719719) (xy 159.858347 -301.763296) (xy 159.828782 -301.80264) (xy 159.793289 -301.836732)
			(xy 159.752786 -301.864688) (xy 159.708324 -301.885786) (xy 159.661053 -301.899478) (xy 159.612198 -301.90541)
			(xy 159.563023 -301.903429) (xy 159.514804 -301.893585) (xy 159.468788 -301.876133) (xy 159.426167 -301.851526)
			(xy 159.388046 -301.820401) (xy 159.355411 -301.783564) (xy 159.329108 -301.741968) (xy 159.309817 -301.696692)
			(xy 159.29804 -301.648908) (xy 159.29408 -301.599854) (xy 158.955232 -301.599854) (xy 158.954737 -301.624461)
			(xy 158.946842 -301.673038) (xy 158.931258 -301.719719) (xy 158.908387 -301.763296) (xy 158.878822 -301.80264)
			(xy 158.843329 -301.836732) (xy 158.802826 -301.864688) (xy 158.758364 -301.885786) (xy 158.711093 -301.899478)
			(xy 158.662238 -301.90541) (xy 158.613063 -301.903429) (xy 158.564844 -301.893585) (xy 158.518828 -301.876133)
			(xy 158.476207 -301.851526) (xy 158.438086 -301.820401) (xy 158.405451 -301.783564) (xy 158.379148 -301.741968)
			(xy 158.359857 -301.696692) (xy 158.34808 -301.648908) (xy 158.34412 -301.599854) (xy 158.005272 -301.599854)
			(xy 158.004777 -301.624461) (xy 157.996882 -301.673038) (xy 157.981298 -301.719719) (xy 157.958427 -301.763296)
			(xy 157.928862 -301.80264) (xy 157.893369 -301.836732) (xy 157.852866 -301.864688) (xy 157.808404 -301.885786)
			(xy 157.761133 -301.899478) (xy 157.712278 -301.90541) (xy 157.663103 -301.903429) (xy 157.614884 -301.893585)
			(xy 157.568868 -301.876133) (xy 157.526247 -301.851526) (xy 157.488126 -301.820401) (xy 157.455491 -301.783564)
			(xy 157.429188 -301.741968) (xy 157.409897 -301.696692) (xy 157.39812 -301.648908) (xy 157.39416 -301.599854)
			(xy 157.055312 -301.599854) (xy 157.054817 -301.624461) (xy 157.046922 -301.673038) (xy 157.031338 -301.719719)
			(xy 157.008467 -301.763296) (xy 156.978902 -301.80264) (xy 156.943409 -301.836732) (xy 156.902906 -301.864688)
			(xy 156.858444 -301.885786) (xy 156.811173 -301.899478) (xy 156.762318 -301.90541) (xy 156.713143 -301.903429)
			(xy 156.664924 -301.893585) (xy 156.618908 -301.876133) (xy 156.576287 -301.851526) (xy 156.538166 -301.820401)
			(xy 156.505531 -301.783564) (xy 156.479228 -301.741968) (xy 156.459937 -301.696692) (xy 156.44816 -301.648908)
			(xy 156.4442 -301.599854) (xy 156.105352 -301.599854) (xy 156.104857 -301.624461) (xy 156.096962 -301.673038)
			(xy 156.081378 -301.719719) (xy 156.058507 -301.763296) (xy 156.028942 -301.80264) (xy 155.993449 -301.836732)
			(xy 155.952946 -301.864688) (xy 155.908484 -301.885786) (xy 155.861213 -301.899478) (xy 155.812358 -301.90541)
			(xy 155.763183 -301.903429) (xy 155.714964 -301.893585) (xy 155.668948 -301.876133) (xy 155.626327 -301.851526)
			(xy 155.588206 -301.820401) (xy 155.555571 -301.783564) (xy 155.529268 -301.741968) (xy 155.509977 -301.696692)
			(xy 155.4982 -301.648908) (xy 155.49424 -301.599854) (xy 155.155392 -301.599854) (xy 155.154897 -301.624461)
			(xy 155.147002 -301.673038) (xy 155.131418 -301.719719) (xy 155.108547 -301.763296) (xy 155.078982 -301.80264)
			(xy 155.043489 -301.836732) (xy 155.002986 -301.864688) (xy 154.958524 -301.885786) (xy 154.911253 -301.899478)
			(xy 154.862398 -301.90541) (xy 154.813223 -301.903429) (xy 154.765004 -301.893585) (xy 154.718988 -301.876133)
			(xy 154.676367 -301.851526) (xy 154.638246 -301.820401) (xy 154.605611 -301.783564) (xy 154.579308 -301.741968)
			(xy 154.560017 -301.696692) (xy 154.54824 -301.648908) (xy 154.54428 -301.599854) (xy 154.205178 -301.599854)
			(xy 154.204683 -301.624461) (xy 154.196788 -301.673038) (xy 154.181204 -301.719719) (xy 154.158333 -301.763296)
			(xy 154.128768 -301.80264) (xy 154.093275 -301.836732) (xy 154.052772 -301.864688) (xy 154.00831 -301.885786)
			(xy 153.961039 -301.899478) (xy 153.912184 -301.90541) (xy 153.863009 -301.903429) (xy 153.81479 -301.893585)
			(xy 153.768774 -301.876133) (xy 153.726153 -301.851526) (xy 153.688032 -301.820401) (xy 153.655397 -301.783564)
			(xy 153.629094 -301.741968) (xy 153.609803 -301.696692) (xy 153.598026 -301.648908) (xy 153.594066 -301.599854)
			(xy 153.255218 -301.599854) (xy 153.254723 -301.624461) (xy 153.246828 -301.673038) (xy 153.231244 -301.719719)
			(xy 153.208373 -301.763296) (xy 153.178808 -301.80264) (xy 153.143315 -301.836732) (xy 153.102812 -301.864688)
			(xy 153.05835 -301.885786) (xy 153.011079 -301.899478) (xy 152.962224 -301.90541) (xy 152.913049 -301.903429)
			(xy 152.86483 -301.893585) (xy 152.818814 -301.876133) (xy 152.776193 -301.851526) (xy 152.738072 -301.820401)
			(xy 152.705437 -301.783564) (xy 152.679134 -301.741968) (xy 152.659843 -301.696692) (xy 152.648066 -301.648908)
			(xy 152.644106 -301.599854) (xy 144.558512 -301.599854) (xy 144.558512 -302.47463) (xy 144.558941 -302.484698)
			(xy 144.566664 -302.503293) (xy 144.573498 -302.510698) (xy 144.612868 -302.550068) (xy 151.693892 -302.550068)
			(xy 151.697852 -302.501014) (xy 151.709629 -302.45323) (xy 151.72892 -302.407954) (xy 151.755223 -302.366358)
			(xy 151.787858 -302.329521) (xy 151.825979 -302.298396) (xy 151.8686 -302.273789) (xy 151.914616 -302.256337)
			(xy 151.962835 -302.246493) (xy 152.01201 -302.244512) (xy 152.060865 -302.250444) (xy 152.108136 -302.264136)
			(xy 152.152598 -302.285234) (xy 152.193101 -302.31319) (xy 152.228594 -302.347282) (xy 152.258159 -302.386626)
			(xy 152.28103 -302.430203) (xy 152.296614 -302.476884) (xy 152.304509 -302.525461) (xy 152.304999 -302.549814)
			(xy 152.644106 -302.549814) (xy 152.648066 -302.50076) (xy 152.659843 -302.452976) (xy 152.679134 -302.4077)
			(xy 152.705437 -302.366104) (xy 152.738072 -302.329267) (xy 152.776193 -302.298142) (xy 152.818814 -302.273535)
			(xy 152.86483 -302.256083) (xy 152.913049 -302.246239) (xy 152.962224 -302.244258) (xy 153.011079 -302.25019)
			(xy 153.05835 -302.263882) (xy 153.102812 -302.28498) (xy 153.143315 -302.312936) (xy 153.178808 -302.347028)
			(xy 153.208373 -302.386372) (xy 153.231244 -302.429949) (xy 153.246828 -302.47663) (xy 153.254723 -302.525207)
			(xy 153.255218 -302.549814) (xy 153.594066 -302.549814) (xy 153.598026 -302.50076) (xy 153.609803 -302.452976)
			(xy 153.629094 -302.4077) (xy 153.655397 -302.366104) (xy 153.688032 -302.329267) (xy 153.726153 -302.298142)
			(xy 153.768774 -302.273535) (xy 153.81479 -302.256083) (xy 153.863009 -302.246239) (xy 153.912184 -302.244258)
			(xy 153.961039 -302.25019) (xy 154.00831 -302.263882) (xy 154.052772 -302.28498) (xy 154.093275 -302.312936)
			(xy 154.128768 -302.347028) (xy 154.158333 -302.386372) (xy 154.181204 -302.429949) (xy 154.196788 -302.47663)
			(xy 154.204683 -302.525207) (xy 154.205178 -302.549814) (xy 154.54428 -302.549814) (xy 154.54824 -302.50076)
			(xy 154.560017 -302.452976) (xy 154.579308 -302.4077) (xy 154.605611 -302.366104) (xy 154.638246 -302.329267)
			(xy 154.676367 -302.298142) (xy 154.718988 -302.273535) (xy 154.765004 -302.256083) (xy 154.813223 -302.246239)
			(xy 154.862398 -302.244258) (xy 154.911253 -302.25019) (xy 154.958524 -302.263882) (xy 155.002986 -302.28498)
			(xy 155.043489 -302.312936) (xy 155.078982 -302.347028) (xy 155.108547 -302.386372) (xy 155.131418 -302.429949)
			(xy 155.147002 -302.47663) (xy 155.154897 -302.525207) (xy 155.155392 -302.549814) (xy 155.49424 -302.549814)
			(xy 155.4982 -302.50076) (xy 155.509977 -302.452976) (xy 155.529268 -302.4077) (xy 155.555571 -302.366104)
			(xy 155.588206 -302.329267) (xy 155.626327 -302.298142) (xy 155.668948 -302.273535) (xy 155.714964 -302.256083)
			(xy 155.763183 -302.246239) (xy 155.812358 -302.244258) (xy 155.861213 -302.25019) (xy 155.908484 -302.263882)
			(xy 155.952946 -302.28498) (xy 155.993449 -302.312936) (xy 156.028942 -302.347028) (xy 156.058507 -302.386372)
			(xy 156.081378 -302.429949) (xy 156.096962 -302.47663) (xy 156.104857 -302.525207) (xy 156.105352 -302.549814)
			(xy 156.4442 -302.549814) (xy 156.44816 -302.50076) (xy 156.459937 -302.452976) (xy 156.479228 -302.4077)
			(xy 156.505531 -302.366104) (xy 156.538166 -302.329267) (xy 156.576287 -302.298142) (xy 156.618908 -302.273535)
			(xy 156.664924 -302.256083) (xy 156.713143 -302.246239) (xy 156.762318 -302.244258) (xy 156.811173 -302.25019)
			(xy 156.858444 -302.263882) (xy 156.902906 -302.28498) (xy 156.943409 -302.312936) (xy 156.978902 -302.347028)
			(xy 157.008467 -302.386372) (xy 157.031338 -302.429949) (xy 157.046922 -302.47663) (xy 157.054817 -302.525207)
			(xy 157.055312 -302.549814) (xy 157.39416 -302.549814) (xy 157.39812 -302.50076) (xy 157.409897 -302.452976)
			(xy 157.429188 -302.4077) (xy 157.455491 -302.366104) (xy 157.488126 -302.329267) (xy 157.526247 -302.298142)
			(xy 157.568868 -302.273535) (xy 157.614884 -302.256083) (xy 157.663103 -302.246239) (xy 157.712278 -302.244258)
			(xy 157.761133 -302.25019) (xy 157.808404 -302.263882) (xy 157.852866 -302.28498) (xy 157.893369 -302.312936)
			(xy 157.928862 -302.347028) (xy 157.958427 -302.386372) (xy 157.981298 -302.429949) (xy 157.996882 -302.47663)
			(xy 158.004777 -302.525207) (xy 158.005272 -302.549814) (xy 158.34412 -302.549814) (xy 158.34808 -302.50076)
			(xy 158.359857 -302.452976) (xy 158.379148 -302.4077) (xy 158.405451 -302.366104) (xy 158.438086 -302.329267)
			(xy 158.476207 -302.298142) (xy 158.518828 -302.273535) (xy 158.564844 -302.256083) (xy 158.613063 -302.246239)
			(xy 158.662238 -302.244258) (xy 158.711093 -302.25019) (xy 158.758364 -302.263882) (xy 158.802826 -302.28498)
			(xy 158.843329 -302.312936) (xy 158.878822 -302.347028) (xy 158.908387 -302.386372) (xy 158.931258 -302.429949)
			(xy 158.946842 -302.47663) (xy 158.954737 -302.525207) (xy 158.955232 -302.549814) (xy 159.29408 -302.549814)
			(xy 159.29804 -302.50076) (xy 159.309817 -302.452976) (xy 159.329108 -302.4077) (xy 159.355411 -302.366104)
			(xy 159.388046 -302.329267) (xy 159.426167 -302.298142) (xy 159.468788 -302.273535) (xy 159.514804 -302.256083)
			(xy 159.563023 -302.246239) (xy 159.612198 -302.244258) (xy 159.661053 -302.25019) (xy 159.708324 -302.263882)
			(xy 159.752786 -302.28498) (xy 159.793289 -302.312936) (xy 159.828782 -302.347028) (xy 159.858347 -302.386372)
			(xy 159.881218 -302.429949) (xy 159.896802 -302.47663) (xy 159.904697 -302.525207) (xy 159.905192 -302.549814)
			(xy 160.24404 -302.549814) (xy 160.248 -302.50076) (xy 160.259777 -302.452976) (xy 160.279068 -302.4077)
			(xy 160.305371 -302.366104) (xy 160.338006 -302.329267) (xy 160.376127 -302.298142) (xy 160.418748 -302.273535)
			(xy 160.464764 -302.256083) (xy 160.512983 -302.246239) (xy 160.562158 -302.244258) (xy 160.611013 -302.25019)
			(xy 160.658284 -302.263882) (xy 160.702746 -302.28498) (xy 160.743249 -302.312936) (xy 160.778742 -302.347028)
			(xy 160.808307 -302.386372) (xy 160.831178 -302.429949) (xy 160.846762 -302.47663) (xy 160.854657 -302.525207)
			(xy 160.855152 -302.549814) (xy 160.854657 -302.574421) (xy 160.846762 -302.622998) (xy 160.831178 -302.669679)
			(xy 160.808307 -302.713256) (xy 160.778742 -302.7526) (xy 160.743249 -302.786692) (xy 160.702746 -302.814648)
			(xy 160.658284 -302.835746) (xy 160.611013 -302.849438) (xy 160.562158 -302.85537) (xy 160.512983 -302.853389)
			(xy 160.464764 -302.843545) (xy 160.418748 -302.826093) (xy 160.376127 -302.801486) (xy 160.338006 -302.770361)
			(xy 160.305371 -302.733524) (xy 160.279068 -302.691928) (xy 160.259777 -302.646652) (xy 160.248 -302.598868)
			(xy 160.24404 -302.549814) (xy 159.905192 -302.549814) (xy 159.904697 -302.574421) (xy 159.896802 -302.622998)
			(xy 159.881218 -302.669679) (xy 159.858347 -302.713256) (xy 159.828782 -302.7526) (xy 159.793289 -302.786692)
			(xy 159.752786 -302.814648) (xy 159.708324 -302.835746) (xy 159.661053 -302.849438) (xy 159.612198 -302.85537)
			(xy 159.563023 -302.853389) (xy 159.514804 -302.843545) (xy 159.468788 -302.826093) (xy 159.426167 -302.801486)
			(xy 159.388046 -302.770361) (xy 159.355411 -302.733524) (xy 159.329108 -302.691928) (xy 159.309817 -302.646652)
			(xy 159.29804 -302.598868) (xy 159.29408 -302.549814) (xy 158.955232 -302.549814) (xy 158.954737 -302.574421)
			(xy 158.946842 -302.622998) (xy 158.931258 -302.669679) (xy 158.908387 -302.713256) (xy 158.878822 -302.7526)
			(xy 158.843329 -302.786692) (xy 158.802826 -302.814648) (xy 158.758364 -302.835746) (xy 158.711093 -302.849438)
			(xy 158.662238 -302.85537) (xy 158.613063 -302.853389) (xy 158.564844 -302.843545) (xy 158.518828 -302.826093)
			(xy 158.476207 -302.801486) (xy 158.438086 -302.770361) (xy 158.405451 -302.733524) (xy 158.379148 -302.691928)
			(xy 158.359857 -302.646652) (xy 158.34808 -302.598868) (xy 158.34412 -302.549814) (xy 158.005272 -302.549814)
			(xy 158.004777 -302.574421) (xy 157.996882 -302.622998) (xy 157.981298 -302.669679) (xy 157.958427 -302.713256)
			(xy 157.928862 -302.7526) (xy 157.893369 -302.786692) (xy 157.852866 -302.814648) (xy 157.808404 -302.835746)
			(xy 157.761133 -302.849438) (xy 157.712278 -302.85537) (xy 157.663103 -302.853389) (xy 157.614884 -302.843545)
			(xy 157.568868 -302.826093) (xy 157.526247 -302.801486) (xy 157.488126 -302.770361) (xy 157.455491 -302.733524)
			(xy 157.429188 -302.691928) (xy 157.409897 -302.646652) (xy 157.39812 -302.598868) (xy 157.39416 -302.549814)
			(xy 157.055312 -302.549814) (xy 157.054817 -302.574421) (xy 157.046922 -302.622998) (xy 157.031338 -302.669679)
			(xy 157.008467 -302.713256) (xy 156.978902 -302.7526) (xy 156.943409 -302.786692) (xy 156.902906 -302.814648)
			(xy 156.858444 -302.835746) (xy 156.811173 -302.849438) (xy 156.762318 -302.85537) (xy 156.713143 -302.853389)
			(xy 156.664924 -302.843545) (xy 156.618908 -302.826093) (xy 156.576287 -302.801486) (xy 156.538166 -302.770361)
			(xy 156.505531 -302.733524) (xy 156.479228 -302.691928) (xy 156.459937 -302.646652) (xy 156.44816 -302.598868)
			(xy 156.4442 -302.549814) (xy 156.105352 -302.549814) (xy 156.104857 -302.574421) (xy 156.096962 -302.622998)
			(xy 156.081378 -302.669679) (xy 156.058507 -302.713256) (xy 156.028942 -302.7526) (xy 155.993449 -302.786692)
			(xy 155.952946 -302.814648) (xy 155.908484 -302.835746) (xy 155.861213 -302.849438) (xy 155.812358 -302.85537)
			(xy 155.763183 -302.853389) (xy 155.714964 -302.843545) (xy 155.668948 -302.826093) (xy 155.626327 -302.801486)
			(xy 155.588206 -302.770361) (xy 155.555571 -302.733524) (xy 155.529268 -302.691928) (xy 155.509977 -302.646652)
			(xy 155.4982 -302.598868) (xy 155.49424 -302.549814) (xy 155.155392 -302.549814) (xy 155.154897 -302.574421)
			(xy 155.147002 -302.622998) (xy 155.131418 -302.669679) (xy 155.108547 -302.713256) (xy 155.078982 -302.7526)
			(xy 155.043489 -302.786692) (xy 155.002986 -302.814648) (xy 154.958524 -302.835746) (xy 154.911253 -302.849438)
			(xy 154.862398 -302.85537) (xy 154.813223 -302.853389) (xy 154.765004 -302.843545) (xy 154.718988 -302.826093)
			(xy 154.676367 -302.801486) (xy 154.638246 -302.770361) (xy 154.605611 -302.733524) (xy 154.579308 -302.691928)
			(xy 154.560017 -302.646652) (xy 154.54824 -302.598868) (xy 154.54428 -302.549814) (xy 154.205178 -302.549814)
			(xy 154.204683 -302.574421) (xy 154.196788 -302.622998) (xy 154.181204 -302.669679) (xy 154.158333 -302.713256)
			(xy 154.128768 -302.7526) (xy 154.093275 -302.786692) (xy 154.052772 -302.814648) (xy 154.00831 -302.835746)
			(xy 153.961039 -302.849438) (xy 153.912184 -302.85537) (xy 153.863009 -302.853389) (xy 153.81479 -302.843545)
			(xy 153.768774 -302.826093) (xy 153.726153 -302.801486) (xy 153.688032 -302.770361) (xy 153.655397 -302.733524)
			(xy 153.629094 -302.691928) (xy 153.609803 -302.646652) (xy 153.598026 -302.598868) (xy 153.594066 -302.549814)
			(xy 153.255218 -302.549814) (xy 153.254723 -302.574421) (xy 153.246828 -302.622998) (xy 153.231244 -302.669679)
			(xy 153.208373 -302.713256) (xy 153.178808 -302.7526) (xy 153.143315 -302.786692) (xy 153.102812 -302.814648)
			(xy 153.05835 -302.835746) (xy 153.011079 -302.849438) (xy 152.962224 -302.85537) (xy 152.913049 -302.853389)
			(xy 152.86483 -302.843545) (xy 152.818814 -302.826093) (xy 152.776193 -302.801486) (xy 152.738072 -302.770361)
			(xy 152.705437 -302.733524) (xy 152.679134 -302.691928) (xy 152.659843 -302.646652) (xy 152.648066 -302.598868)
			(xy 152.644106 -302.549814) (xy 152.304999 -302.549814) (xy 152.305004 -302.550068) (xy 152.304509 -302.574675)
			(xy 152.296614 -302.623252) (xy 152.28103 -302.669933) (xy 152.258159 -302.71351) (xy 152.228594 -302.752854)
			(xy 152.193101 -302.786946) (xy 152.152598 -302.814902) (xy 152.108136 -302.836) (xy 152.060865 -302.849692)
			(xy 152.01201 -302.855624) (xy 151.962835 -302.853643) (xy 151.914616 -302.843799) (xy 151.8686 -302.826347)
			(xy 151.825979 -302.80174) (xy 151.787858 -302.770615) (xy 151.755223 -302.733778) (xy 151.72892 -302.692182)
			(xy 151.709629 -302.646906) (xy 151.697852 -302.599122) (xy 151.693892 -302.550068) (xy 144.612868 -302.550068)
			(xy 145.562574 -303.499774) (xy 152.644106 -303.499774) (xy 152.648066 -303.45072) (xy 152.659843 -303.402936)
			(xy 152.679134 -303.35766) (xy 152.705437 -303.316064) (xy 152.738072 -303.279227) (xy 152.776193 -303.248102)
			(xy 152.818814 -303.223495) (xy 152.86483 -303.206043) (xy 152.913049 -303.196199) (xy 152.962224 -303.194218)
			(xy 153.011079 -303.20015) (xy 153.05835 -303.213842) (xy 153.102812 -303.23494) (xy 153.143315 -303.262896)
			(xy 153.178808 -303.296988) (xy 153.208373 -303.336332) (xy 153.231244 -303.379909) (xy 153.246828 -303.42659)
			(xy 153.254723 -303.475167) (xy 153.255218 -303.499774) (xy 153.594066 -303.499774) (xy 153.598026 -303.45072)
			(xy 153.609803 -303.402936) (xy 153.629094 -303.35766) (xy 153.655397 -303.316064) (xy 153.688032 -303.279227)
			(xy 153.726153 -303.248102) (xy 153.768774 -303.223495) (xy 153.81479 -303.206043) (xy 153.863009 -303.196199)
			(xy 153.912184 -303.194218) (xy 153.961039 -303.20015) (xy 154.00831 -303.213842) (xy 154.052772 -303.23494)
			(xy 154.093275 -303.262896) (xy 154.128768 -303.296988) (xy 154.158333 -303.336332) (xy 154.181204 -303.379909)
			(xy 154.196788 -303.42659) (xy 154.204683 -303.475167) (xy 154.205178 -303.499774) (xy 154.54428 -303.499774)
			(xy 154.54824 -303.45072) (xy 154.560017 -303.402936) (xy 154.579308 -303.35766) (xy 154.605611 -303.316064)
			(xy 154.638246 -303.279227) (xy 154.676367 -303.248102) (xy 154.718988 -303.223495) (xy 154.765004 -303.206043)
			(xy 154.813223 -303.196199) (xy 154.862398 -303.194218) (xy 154.911253 -303.20015) (xy 154.958524 -303.213842)
			(xy 155.002986 -303.23494) (xy 155.043489 -303.262896) (xy 155.078982 -303.296988) (xy 155.108547 -303.336332)
			(xy 155.131418 -303.379909) (xy 155.147002 -303.42659) (xy 155.154897 -303.475167) (xy 155.155392 -303.499774)
			(xy 155.49424 -303.499774) (xy 155.4982 -303.45072) (xy 155.509977 -303.402936) (xy 155.529268 -303.35766)
			(xy 155.555571 -303.316064) (xy 155.588206 -303.279227) (xy 155.626327 -303.248102) (xy 155.668948 -303.223495)
			(xy 155.714964 -303.206043) (xy 155.763183 -303.196199) (xy 155.812358 -303.194218) (xy 155.861213 -303.20015)
			(xy 155.908484 -303.213842) (xy 155.952946 -303.23494) (xy 155.993449 -303.262896) (xy 156.028942 -303.296988)
			(xy 156.058507 -303.336332) (xy 156.081378 -303.379909) (xy 156.096962 -303.42659) (xy 156.104857 -303.475167)
			(xy 156.105352 -303.499774) (xy 156.4442 -303.499774) (xy 156.44816 -303.45072) (xy 156.459937 -303.402936)
			(xy 156.479228 -303.35766) (xy 156.505531 -303.316064) (xy 156.538166 -303.279227) (xy 156.576287 -303.248102)
			(xy 156.618908 -303.223495) (xy 156.664924 -303.206043) (xy 156.713143 -303.196199) (xy 156.762318 -303.194218)
			(xy 156.811173 -303.20015) (xy 156.858444 -303.213842) (xy 156.902906 -303.23494) (xy 156.943409 -303.262896)
			(xy 156.978902 -303.296988) (xy 157.008467 -303.336332) (xy 157.031338 -303.379909) (xy 157.046922 -303.42659)
			(xy 157.054817 -303.475167) (xy 157.055312 -303.499774) (xy 157.39416 -303.499774) (xy 157.39812 -303.45072)
			(xy 157.409897 -303.402936) (xy 157.429188 -303.35766) (xy 157.455491 -303.316064) (xy 157.488126 -303.279227)
			(xy 157.526247 -303.248102) (xy 157.568868 -303.223495) (xy 157.614884 -303.206043) (xy 157.663103 -303.196199)
			(xy 157.712278 -303.194218) (xy 157.761133 -303.20015) (xy 157.808404 -303.213842) (xy 157.852866 -303.23494)
			(xy 157.893369 -303.262896) (xy 157.928862 -303.296988) (xy 157.958427 -303.336332) (xy 157.981298 -303.379909)
			(xy 157.996882 -303.42659) (xy 158.004777 -303.475167) (xy 158.005272 -303.499774) (xy 158.34412 -303.499774)
			(xy 158.34808 -303.45072) (xy 158.359857 -303.402936) (xy 158.379148 -303.35766) (xy 158.405451 -303.316064)
			(xy 158.438086 -303.279227) (xy 158.476207 -303.248102) (xy 158.518828 -303.223495) (xy 158.564844 -303.206043)
			(xy 158.613063 -303.196199) (xy 158.662238 -303.194218) (xy 158.711093 -303.20015) (xy 158.758364 -303.213842)
			(xy 158.802826 -303.23494) (xy 158.843329 -303.262896) (xy 158.878822 -303.296988) (xy 158.908387 -303.336332)
			(xy 158.931258 -303.379909) (xy 158.946842 -303.42659) (xy 158.954737 -303.475167) (xy 158.955232 -303.499774)
			(xy 159.29408 -303.499774) (xy 159.29804 -303.45072) (xy 159.309817 -303.402936) (xy 159.329108 -303.35766)
			(xy 159.355411 -303.316064) (xy 159.388046 -303.279227) (xy 159.426167 -303.248102) (xy 159.468788 -303.223495)
			(xy 159.514804 -303.206043) (xy 159.563023 -303.196199) (xy 159.612198 -303.194218) (xy 159.661053 -303.20015)
			(xy 159.708324 -303.213842) (xy 159.752786 -303.23494) (xy 159.793289 -303.262896) (xy 159.828782 -303.296988)
			(xy 159.858347 -303.336332) (xy 159.881218 -303.379909) (xy 159.896802 -303.42659) (xy 159.904697 -303.475167)
			(xy 159.905192 -303.499774) (xy 160.24404 -303.499774) (xy 160.248 -303.45072) (xy 160.259777 -303.402936)
			(xy 160.279068 -303.35766) (xy 160.305371 -303.316064) (xy 160.338006 -303.279227) (xy 160.376127 -303.248102)
			(xy 160.418748 -303.223495) (xy 160.464764 -303.206043) (xy 160.512983 -303.196199) (xy 160.562158 -303.194218)
			(xy 160.611013 -303.20015) (xy 160.658284 -303.213842) (xy 160.702746 -303.23494) (xy 160.743249 -303.262896)
			(xy 160.778742 -303.296988) (xy 160.808307 -303.336332) (xy 160.831178 -303.379909) (xy 160.846762 -303.42659)
			(xy 160.854657 -303.475167) (xy 160.855152 -303.499774) (xy 160.854657 -303.524381) (xy 160.846762 -303.572958)
			(xy 160.831178 -303.619639) (xy 160.808307 -303.663216) (xy 160.778742 -303.70256) (xy 160.743249 -303.736652)
			(xy 160.702746 -303.764608) (xy 160.658284 -303.785706) (xy 160.611013 -303.799398) (xy 160.562158 -303.80533)
			(xy 160.512983 -303.803349) (xy 160.464764 -303.793505) (xy 160.418748 -303.776053) (xy 160.376127 -303.751446)
			(xy 160.338006 -303.720321) (xy 160.305371 -303.683484) (xy 160.279068 -303.641888) (xy 160.259777 -303.596612)
			(xy 160.248 -303.548828) (xy 160.24404 -303.499774) (xy 159.905192 -303.499774) (xy 159.904697 -303.524381)
			(xy 159.896802 -303.572958) (xy 159.881218 -303.619639) (xy 159.858347 -303.663216) (xy 159.828782 -303.70256)
			(xy 159.793289 -303.736652) (xy 159.752786 -303.764608) (xy 159.708324 -303.785706) (xy 159.661053 -303.799398)
			(xy 159.612198 -303.80533) (xy 159.563023 -303.803349) (xy 159.514804 -303.793505) (xy 159.468788 -303.776053)
			(xy 159.426167 -303.751446) (xy 159.388046 -303.720321) (xy 159.355411 -303.683484) (xy 159.329108 -303.641888)
			(xy 159.309817 -303.596612) (xy 159.29804 -303.548828) (xy 159.29408 -303.499774) (xy 158.955232 -303.499774)
			(xy 158.954737 -303.524381) (xy 158.946842 -303.572958) (xy 158.931258 -303.619639) (xy 158.908387 -303.663216)
			(xy 158.878822 -303.70256) (xy 158.843329 -303.736652) (xy 158.802826 -303.764608) (xy 158.758364 -303.785706)
			(xy 158.711093 -303.799398) (xy 158.662238 -303.80533) (xy 158.613063 -303.803349) (xy 158.564844 -303.793505)
			(xy 158.518828 -303.776053) (xy 158.476207 -303.751446) (xy 158.438086 -303.720321) (xy 158.405451 -303.683484)
			(xy 158.379148 -303.641888) (xy 158.359857 -303.596612) (xy 158.34808 -303.548828) (xy 158.34412 -303.499774)
			(xy 158.005272 -303.499774) (xy 158.004777 -303.524381) (xy 157.996882 -303.572958) (xy 157.981298 -303.619639)
			(xy 157.958427 -303.663216) (xy 157.928862 -303.70256) (xy 157.893369 -303.736652) (xy 157.852866 -303.764608)
			(xy 157.808404 -303.785706) (xy 157.761133 -303.799398) (xy 157.712278 -303.80533) (xy 157.663103 -303.803349)
			(xy 157.614884 -303.793505) (xy 157.568868 -303.776053) (xy 157.526247 -303.751446) (xy 157.488126 -303.720321)
			(xy 157.455491 -303.683484) (xy 157.429188 -303.641888) (xy 157.409897 -303.596612) (xy 157.39812 -303.548828)
			(xy 157.39416 -303.499774) (xy 157.055312 -303.499774) (xy 157.054817 -303.524381) (xy 157.046922 -303.572958)
			(xy 157.031338 -303.619639) (xy 157.008467 -303.663216) (xy 156.978902 -303.70256) (xy 156.943409 -303.736652)
			(xy 156.902906 -303.764608) (xy 156.858444 -303.785706) (xy 156.811173 -303.799398) (xy 156.762318 -303.80533)
			(xy 156.713143 -303.803349) (xy 156.664924 -303.793505) (xy 156.618908 -303.776053) (xy 156.576287 -303.751446)
			(xy 156.538166 -303.720321) (xy 156.505531 -303.683484) (xy 156.479228 -303.641888) (xy 156.459937 -303.596612)
			(xy 156.44816 -303.548828) (xy 156.4442 -303.499774) (xy 156.105352 -303.499774) (xy 156.104857 -303.524381)
			(xy 156.096962 -303.572958) (xy 156.081378 -303.619639) (xy 156.058507 -303.663216) (xy 156.028942 -303.70256)
			(xy 155.993449 -303.736652) (xy 155.952946 -303.764608) (xy 155.908484 -303.785706) (xy 155.861213 -303.799398)
			(xy 155.812358 -303.80533) (xy 155.763183 -303.803349) (xy 155.714964 -303.793505) (xy 155.668948 -303.776053)
			(xy 155.626327 -303.751446) (xy 155.588206 -303.720321) (xy 155.555571 -303.683484) (xy 155.529268 -303.641888)
			(xy 155.509977 -303.596612) (xy 155.4982 -303.548828) (xy 155.49424 -303.499774) (xy 155.155392 -303.499774)
			(xy 155.154897 -303.524381) (xy 155.147002 -303.572958) (xy 155.131418 -303.619639) (xy 155.108547 -303.663216)
			(xy 155.078982 -303.70256) (xy 155.043489 -303.736652) (xy 155.002986 -303.764608) (xy 154.958524 -303.785706)
			(xy 154.911253 -303.799398) (xy 154.862398 -303.80533) (xy 154.813223 -303.803349) (xy 154.765004 -303.793505)
			(xy 154.718988 -303.776053) (xy 154.676367 -303.751446) (xy 154.638246 -303.720321) (xy 154.605611 -303.683484)
			(xy 154.579308 -303.641888) (xy 154.560017 -303.596612) (xy 154.54824 -303.548828) (xy 154.54428 -303.499774)
			(xy 154.205178 -303.499774) (xy 154.204683 -303.524381) (xy 154.196788 -303.572958) (xy 154.181204 -303.619639)
			(xy 154.158333 -303.663216) (xy 154.128768 -303.70256) (xy 154.093275 -303.736652) (xy 154.052772 -303.764608)
			(xy 154.00831 -303.785706) (xy 153.961039 -303.799398) (xy 153.912184 -303.80533) (xy 153.863009 -303.803349)
			(xy 153.81479 -303.793505) (xy 153.768774 -303.776053) (xy 153.726153 -303.751446) (xy 153.688032 -303.720321)
			(xy 153.655397 -303.683484) (xy 153.629094 -303.641888) (xy 153.609803 -303.596612) (xy 153.598026 -303.548828)
			(xy 153.594066 -303.499774) (xy 153.255218 -303.499774) (xy 153.254723 -303.524381) (xy 153.246828 -303.572958)
			(xy 153.231244 -303.619639) (xy 153.208373 -303.663216) (xy 153.178808 -303.70256) (xy 153.143315 -303.736652)
			(xy 153.102812 -303.764608) (xy 153.05835 -303.785706) (xy 153.011079 -303.799398) (xy 152.962224 -303.80533)
			(xy 152.913049 -303.803349) (xy 152.86483 -303.793505) (xy 152.818814 -303.776053) (xy 152.776193 -303.751446)
			(xy 152.738072 -303.720321) (xy 152.705437 -303.683484) (xy 152.679134 -303.641888) (xy 152.659843 -303.596612)
			(xy 152.648066 -303.548828) (xy 152.644106 -303.499774) (xy 145.562574 -303.499774) (xy 146.037554 -303.974754)
			(xy 162.619194 -303.974754) (xy 162.623154 -303.9257) (xy 162.634931 -303.877916) (xy 162.654222 -303.83264)
			(xy 162.680525 -303.791044) (xy 162.71316 -303.754207) (xy 162.751281 -303.723082) (xy 162.793902 -303.698475)
			(xy 162.839918 -303.681023) (xy 162.888137 -303.671179) (xy 162.937312 -303.669198) (xy 162.986167 -303.67513)
			(xy 163.033438 -303.688822) (xy 163.0779 -303.70992) (xy 163.118403 -303.737876) (xy 163.153896 -303.771968)
			(xy 163.183461 -303.811312) (xy 163.206332 -303.854889) (xy 163.221916 -303.90157) (xy 163.229811 -303.950147)
			(xy 163.230306 -303.974754) (xy 163.569154 -303.974754) (xy 163.573114 -303.9257) (xy 163.584891 -303.877916)
			(xy 163.604182 -303.83264) (xy 163.630485 -303.791044) (xy 163.66312 -303.754207) (xy 163.701241 -303.723082)
			(xy 163.743862 -303.698475) (xy 163.789878 -303.681023) (xy 163.838097 -303.671179) (xy 163.887272 -303.669198)
			(xy 163.936127 -303.67513) (xy 163.983398 -303.688822) (xy 164.02786 -303.70992) (xy 164.068363 -303.737876)
			(xy 164.103856 -303.771968) (xy 164.133421 -303.811312) (xy 164.156292 -303.854889) (xy 164.171876 -303.90157)
			(xy 164.179771 -303.950147) (xy 164.180266 -303.974754) (xy 164.179771 -303.999361) (xy 164.171876 -304.047938)
			(xy 164.156292 -304.094619) (xy 164.133421 -304.138196) (xy 164.103856 -304.17754) (xy 164.068363 -304.211632)
			(xy 164.02786 -304.239588) (xy 163.983398 -304.260686) (xy 163.936127 -304.274378) (xy 163.887272 -304.28031)
			(xy 163.838097 -304.278329) (xy 163.789878 -304.268485) (xy 163.743862 -304.251033) (xy 163.701241 -304.226426)
			(xy 163.66312 -304.195301) (xy 163.630485 -304.158464) (xy 163.604182 -304.116868) (xy 163.584891 -304.071592)
			(xy 163.573114 -304.023808) (xy 163.569154 -303.974754) (xy 163.230306 -303.974754) (xy 163.229811 -303.999361)
			(xy 163.221916 -304.047938) (xy 163.206332 -304.094619) (xy 163.183461 -304.138196) (xy 163.153896 -304.17754)
			(xy 163.118403 -304.211632) (xy 163.0779 -304.239588) (xy 163.033438 -304.260686) (xy 162.986167 -304.274378)
			(xy 162.937312 -304.28031) (xy 162.888137 -304.278329) (xy 162.839918 -304.268485) (xy 162.793902 -304.251033)
			(xy 162.751281 -304.226426) (xy 162.71316 -304.195301) (xy 162.680525 -304.158464) (xy 162.654222 -304.116868)
			(xy 162.634931 -304.071592) (xy 162.623154 -304.023808) (xy 162.619194 -303.974754) (xy 146.037554 -303.974754)
			(xy 146.543014 -304.480214) (xy 146.550409 -304.487068) (xy 146.569008 -304.49481) (xy 146.579082 -304.4952)
			(xy 151.66467 -304.4952)
		)
		(stroke
			(width 0)
			(type solid)
		)
		(fill yes)
		(layer "In5.Cu")
		(net "PCEPLL0_VDDA18_PEX1")
	)
	(gr_poly
		(pts
			(xy 2.770124 -64.707262) (xy 2.778883 -64.709305) (xy 2.796793 -64.707795) (xy 2.813079 -64.70019)
			(xy 2.819654 -64.694054) (xy 3.765042 -63.748666) (xy 3.772584 -63.740203) (xy 3.780085 -63.718842)
			(xy 3.77952 -63.707518) (xy 3.771646 -63.629032) (xy 3.769838 -63.617999) (xy 3.758237 -63.598914)
			(xy 3.749294 -63.592202) (xy 3.74904 -63.591948) (xy 3.726791 -63.57675) (xy 3.6864 -63.541088) (xy 3.651433 -63.500093)
			(xy 3.622587 -63.454584) (xy 3.600437 -63.405466) (xy 3.585423 -63.353719) (xy 3.577846 -63.300373)
			(xy 3.577336 -63.273432) (xy 3.577799 -63.246179) (xy 3.585556 -63.192228) (xy 3.600912 -63.13993)
			(xy 3.623554 -63.09035) (xy 3.653022 -63.044497) (xy 3.688716 -63.003305) (xy 3.729909 -62.967611)
			(xy 3.775762 -62.938143) (xy 3.825342 -62.915501) (xy 3.87764 -62.900146) (xy 3.931591 -62.892389)
			(xy 3.958844 -62.891924) (xy 3.985774 -62.89239) (xy 4.039098 -62.899968) (xy 4.090828 -62.914967)
			(xy 4.139934 -62.93709) (xy 4.185444 -62.965896) (xy 4.226451 -63.000815) (xy 4.262142 -63.041151)
			(xy 4.27736 -63.063374) (xy 4.27736 -63.063882) (xy 4.277614 -63.063882) (xy 4.284276 -63.072875)
			(xy 4.303392 -63.084463) (xy 4.314444 -63.086234) (xy 4.39293 -63.094108) (xy 4.404256 -63.0947)
			(xy 4.425624 -63.087189) (xy 4.434078 -63.07963) (xy 6.179566 -61.334142) (xy 6.186652 -61.326388)
			(xy 6.19436 -61.306874) (xy 6.193557 -61.285909) (xy 6.189472 -61.27623) (xy 6.140958 -61.174884)
			(xy 6.113018 -61.15939) (xy 6.097016 -61.161168) (xy 6.086888 -61.16221) (xy 6.066557 -61.163352)
			(xy 6.056376 -61.163454) (xy 6.029125 -61.162968) (xy 5.975178 -61.155211) (xy 5.922884 -61.139856)
			(xy 5.873308 -61.117214) (xy 5.827459 -61.087748) (xy 5.786269 -61.052057) (xy 5.750579 -61.010867)
			(xy 5.721113 -60.965017) (xy 5.698472 -60.915441) (xy 5.683118 -60.863146) (xy 5.675362 -60.8092)
			(xy 5.675362 -60.754698) (xy 5.683118 -60.700751) (xy 5.698473 -60.648457) (xy 5.721114 -60.598881)
			(xy 5.75058 -60.553031) (xy 5.786271 -60.511841) (xy 5.827461 -60.47615) (xy 5.873311 -60.446684)
			(xy 5.922887 -60.424043) (xy 5.975181 -60.408688) (xy 6.029128 -60.400932) (xy 6.08363 -60.400932)
			(xy 6.137576 -60.408688) (xy 6.189871 -60.424042) (xy 6.239447 -60.446683) (xy 6.285297 -60.476149)
			(xy 6.326487 -60.511839) (xy 6.362178 -60.553029) (xy 6.391644 -60.598878) (xy 6.414286 -60.648454)
			(xy 6.429641 -60.700748) (xy 6.437398 -60.754695) (xy 6.437884 -60.781946) (xy 6.437599 -60.802495)
			(xy 6.433147 -60.843353) (xy 6.428994 -60.86348) (xy 6.428994 -60.863734) (xy 6.42738 -60.87321)
			(xy 6.430529 -60.892158) (xy 6.44041 -60.90863) (xy 6.44779 -60.914788) (xy 6.533134 -60.979558)
			(xy 6.562598 -60.982098) (xy 6.575552 -60.97524) (xy 6.60719 -60.959159) (xy 6.67352 -60.933908)
			(xy 6.742413 -60.916851) (xy 6.812862 -60.908238) (xy 6.848348 -60.907676) (xy 7.72795 -60.907676)
			(xy 7.740373 -60.907068) (xy 7.762357 -60.895495) (xy 7.76986 -60.885578) (xy 7.824216 -60.80633)
			(xy 7.827264 -60.781438) (xy 7.822692 -60.769754) (xy 7.814732 -60.747949) (xy 7.803547 -60.702896)
			(xy 7.7979 -60.65682) (xy 7.797546 -60.63361) (xy 7.797546 -60.633356) (xy 7.798032 -60.606105) (xy 7.805788 -60.552157)
			(xy 7.821143 -60.499862) (xy 7.843785 -60.450285) (xy 7.873251 -60.404435) (xy 7.908942 -60.363244)
			(xy 7.950133 -60.327553) (xy 7.995983 -60.298087) (xy 8.04556 -60.275445) (xy 8.097855 -60.26009)
			(xy 8.151803 -60.252334) (xy 8.206305 -60.252334) (xy 8.260253 -60.26009) (xy 8.312548 -60.275445)
			(xy 8.362125 -60.298087) (xy 8.407975 -60.327553) (xy 8.449166 -60.363244) (xy 8.484857 -60.404435)
			(xy 8.514323 -60.450285) (xy 8.536965 -60.499862) (xy 8.55232 -60.552157) (xy 8.560076 -60.606105)
			(xy 8.560562 -60.633356) (xy 8.560562 -60.63361) (xy 8.560222 -60.656822) (xy 8.554589 -60.702901)
			(xy 8.543395 -60.747954) (xy 8.535416 -60.769754) (xy 8.530844 -60.781438) (xy 8.533892 -60.80633)
			(xy 8.588248 -60.885578) (xy 8.595768 -60.895485) (xy 8.617736 -60.907089) (xy 8.630158 -60.907676)
			(xy 8.824976 -60.907676) (xy 8.835755 -60.907188) (xy 8.855415 -60.898345) (xy 8.86971 -60.882209)
			(xy 8.876119 -60.861626) (xy 8.87351 -60.840227) (xy 8.86841 -60.830714) (xy 8.855424 -60.808337)
			(xy 8.834939 -60.760827) (xy 8.821049 -60.710989) (xy 8.814008 -60.659732) (xy 8.813546 -60.633864)
			(xy 8.813546 -60.633356) (xy 8.81408 -60.60449) (xy 8.822786 -60.547419) (xy 8.839993 -60.492312)
			(xy 8.865307 -60.440427) (xy 8.898151 -60.392949) (xy 8.937775 -60.350962) (xy 8.983273 -60.315426)
			(xy 9.033606 -60.287152) (xy 9.060434 -60.276486) (xy 9.06987 -60.2724) (xy 9.084681 -60.258163)
			(xy 9.092727 -60.23926) (xy 9.0932 -60.228988) (xy 9.0932 -58.85561) (xy 9.092703 -58.84521) (xy 9.084442 -58.826119)
			(xy 9.069277 -58.811882) (xy 9.059672 -58.807858) (xy 9.034134 -58.797991) (xy 8.985956 -58.77199)
			(xy 8.94199 -58.739367) (xy 8.903139 -58.700795) (xy 8.870202 -58.657064) (xy 8.843855 -58.609074)
			(xy 8.824639 -58.55781) (xy 8.812949 -58.504326) (xy 8.809026 -58.449719) (xy 8.812949 -58.395113)
			(xy 8.824639 -58.341629) (xy 8.843855 -58.290365) (xy 8.870203 -58.242375) (xy 8.90314 -58.198644)
			(xy 8.941991 -58.160072) (xy 8.985957 -58.12745) (xy 9.034135 -58.101448) (xy 9.059672 -58.091578)
			(xy 9.069286 -58.087574) (xy 9.084442 -58.073322) (xy 9.092702 -58.054228) (xy 9.0932 -58.043826)
			(xy 9.0932 -44.10456) (xy 9.093657 -44.071705) (xy 9.101007 -44.006408) (xy 9.115622 -43.942344)
			(xy 9.137318 -43.880319) (xy 9.165823 -43.821114) (xy 9.200776 -43.765472) (xy 9.24174 -43.714094)
			(xy 9.26465 -43.69054) (xy 10.595864 -42.359326) (xy 10.619429 -42.33643) (xy 10.670813 -42.295479)
			(xy 10.726457 -42.260535) (xy 10.78566 -42.232034) (xy 10.84768 -42.210337) (xy 10.911739 -42.195714)
			(xy 10.977031 -42.18835) (xy 11.009884 -42.187876) (xy 11.699494 -42.187876) (xy 11.709564 -42.187453)
			(xy 11.728168 -42.179738) (xy 11.735562 -42.17289) (xy 17.721072 -36.187126) (xy 17.744637 -36.16423)
			(xy 17.796022 -36.12328) (xy 17.851665 -36.088336) (xy 17.910868 -36.059837) (xy 17.972889 -36.03814)
			(xy 18.036947 -36.023519) (xy 18.102239 -36.016155) (xy 18.135092 -36.015676) (xy 18.617692 -36.015676)
			(xy 18.628143 -36.015121) (xy 18.647297 -36.006738) (xy 18.654776 -35.99942) (xy 18.712688 -35.936682)
			(xy 18.719546 -35.91687) (xy 18.718784 -35.906202) (xy 18.717768 -35.876738) (xy 18.718254 -35.849487)
			(xy 18.72601 -35.795539) (xy 18.741365 -35.743244) (xy 18.764007 -35.693667) (xy 18.793473 -35.647817)
			(xy 18.829164 -35.606626) (xy 18.870355 -35.570935) (xy 18.916205 -35.541469) (xy 18.965782 -35.518827)
			(xy 19.018077 -35.503472) (xy 19.072025 -35.495716) (xy 19.126527 -35.495716) (xy 19.180475 -35.503472)
			(xy 19.23277 -35.518827) (xy 19.282347 -35.541469) (xy 19.328197 -35.570935) (xy 19.369388 -35.606626)
			(xy 19.405079 -35.647817) (xy 19.434545 -35.693667) (xy 19.457187 -35.743244) (xy 19.472542 -35.795539)
			(xy 19.480298 -35.849487) (xy 19.480784 -35.876738) (xy 19.480784 -35.877246) (xy 19.480405 -35.900506)
			(xy 19.474686 -35.946674) (xy 19.4634 -35.991805) (xy 19.455384 -36.013644) (xy 19.452634 -36.021905)
			(xy 19.452258 -36.0393) (xy 19.454622 -36.04768) (xy 19.46402 -36.076128) (xy 19.467063 -36.0845)
			(xy 19.477986 -36.098558) (xy 19.485356 -36.10356) (xy 19.513823 -36.121721) (xy 19.566785 -36.163613)
			(xy 19.59102 -36.187126) (xy 19.79676 -36.392866) (xy 19.80416 -36.399707) (xy 19.822759 -36.407425)
			(xy 19.832828 -36.407852) (xy 20.591526 -36.407852) (xy 20.601797 -36.407378) (xy 20.620696 -36.399327)
			(xy 20.634936 -36.38452) (xy 20.639024 -36.375086) (xy 20.649722 -36.348285) (xy 20.678023 -36.297997)
			(xy 20.713574 -36.252545) (xy 20.755565 -36.212965) (xy 20.803037 -36.180159) (xy 20.854908 -36.154877)
			(xy 20.909995 -36.137694) (xy 20.967042 -36.129004) (xy 20.995894 -36.128452) (xy 21.021442 -36.12886)
			(xy 21.072081 -36.135675) (xy 21.121358 -36.149184) (xy 21.168393 -36.169145) (xy 21.212345 -36.195202)
			(xy 21.232622 -36.210748) (xy 21.237956 -36.205414) (xy 21.261521 -36.182518) (xy 21.312906 -36.141567)
			(xy 21.368549 -36.106623) (xy 21.427752 -36.078122) (xy 21.489772 -36.056424) (xy 21.553831 -36.041801)
			(xy 21.619123 -36.034437) (xy 21.651976 -36.033964) (xy 22.690836 -36.033964) (xy 22.701652 -36.033531)
			(xy 22.721398 -36.024714) (xy 22.728936 -36.016946) (xy 22.779482 -35.960304) (xy 22.786269 -35.951942)
			(xy 22.792731 -35.931418) (xy 22.791928 -35.92068) (xy 22.790738 -35.909734) (xy 22.78947 -35.887749)
			(xy 22.789388 -35.876738) (xy 22.789849 -35.849483) (xy 22.797601 -35.795528) (xy 22.812954 -35.743225)
			(xy 22.835594 -35.69364) (xy 22.865061 -35.647782) (xy 22.900755 -35.606585) (xy 22.941948 -35.570886)
			(xy 22.987803 -35.541414) (xy 23.037386 -35.518769) (xy 23.089687 -35.50341) (xy 23.143641 -35.495652)
			(xy 23.170896 -35.49523) (xy 23.2016 -35.495868) (xy 23.26221 -35.505747) (xy 23.320455 -35.525204)
			(xy 23.347934 -35.538918) (xy 23.34895 -35.539426) (xy 23.354284 -35.54222) (xy 23.36546 -35.54476)
			(xy 23.94077 -35.54476) (xy 23.950767 -35.544268) (xy 23.969248 -35.536635) (xy 23.983436 -35.522545)
			(xy 23.98776 -35.513518) (xy 23.993602 -35.499294) (xy 23.98776 -35.469322) (xy 22.911562 -34.393124)
			(xy 22.888665 -34.36956) (xy 22.847713 -34.318176) (xy 22.812767 -34.262533) (xy 22.784267 -34.203329)
			(xy 22.762569 -34.141309) (xy 22.747947 -34.07725) (xy 22.740584 -34.011957) (xy 22.740112 -33.979104)
			(xy 22.740112 -29.517848) (xy 22.73968 -29.507782) (xy 22.731954 -29.48919) (xy 22.725126 -29.48178)
			(xy 21.326856 -28.08351) (xy 21.319456 -28.076669) (xy 21.300857 -28.068949) (xy 21.290788 -28.068524)
			(xy 20.366482 -28.068524) (xy 20.357467 -28.0689) (xy 20.340557 -28.075165) (xy 20.326851 -28.086884)
			(xy 20.318034 -28.102614) (xy 20.31619 -28.11145) (xy 20.311583 -28.138099) (xy 20.295837 -28.189837)
			(xy 20.272944 -28.238833) (xy 20.243362 -28.284106) (xy 20.207685 -28.32475) (xy 20.166626 -28.359948)
			(xy 20.12101 -28.388998) (xy 20.071749 -28.411315) (xy 20.01983 -28.426454) (xy 19.966294 -28.434112)
			(xy 19.939254 -28.434538) (xy 19.938746 -28.434538) (xy 19.910841 -28.434005) (xy 19.855632 -28.425837)
			(xy 19.828764 -28.418282) (xy 19.819565 -28.415913) (xy 19.800641 -28.417419) (xy 19.783563 -28.425705)
			(xy 19.770669 -28.439637) (xy 19.763727 -28.457306) (xy 19.763232 -28.466796) (xy 19.763232 -29.114242)
			(xy 19.762742 -29.144226) (xy 19.754914 -29.203682) (xy 19.739393 -29.261607) (xy 19.716444 -29.317011)
			(xy 19.68646 -29.368945) (xy 19.649954 -29.416521) (xy 19.607549 -29.458926) (xy 19.559973 -29.495432)
			(xy 19.508039 -29.525416) (xy 19.452635 -29.548365) (xy 19.39471 -29.563886) (xy 19.335254 -29.571714)
			(xy 19.275286 -29.571714) (xy 19.21583 -29.563886) (xy 19.157905 -29.548365) (xy 19.102501 -29.525416)
			(xy 19.050567 -29.495432) (xy 19.002991 -29.458926) (xy 18.960586 -29.416521) (xy 18.92408 -29.368945)
			(xy 18.894096 -29.317011) (xy 18.871147 -29.261607) (xy 18.855626 -29.203682) (xy 18.847798 -29.144226)
			(xy 18.847308 -29.114242) (xy 18.847308 -28.466796) (xy 18.84693 -28.457277) (xy 18.840009 -28.439542)
			(xy 18.827088 -28.425562) (xy 18.809953 -28.417267) (xy 18.790972 -28.415806) (xy 18.781776 -28.418282)
			(xy 18.754918 -28.425883) (xy 18.699702 -28.434046) (xy 18.671794 -28.434538) (xy 18.671286 -28.434538)
			(xy 18.641731 -28.433983) (xy 18.583329 -28.424867) (xy 18.527031 -28.406856) (xy 18.474183 -28.38038)
			(xy 18.449798 -28.363672) (xy 18.442325 -28.358772) (xy 18.425106 -28.354028) (xy 18.407305 -28.355476)
			(xy 18.39108 -28.362939) (xy 18.38452 -28.369006) (xy 17.432782 -29.320998) (xy 17.409219 -29.343899)
			(xy 17.357838 -29.384858) (xy 17.302196 -29.419812) (xy 17.242993 -29.448321) (xy 17.180972 -29.470026)
			(xy 17.116912 -29.484656) (xy 17.051617 -29.492026) (xy 17.018762 -29.492448) (xy 16.20774 -29.492448)
			(xy 16.197676 -29.492884) (xy 16.179092 -29.500619) (xy 16.171672 -29.507434) (xy 14.758416 -30.92069)
			(xy 21.489416 -30.92069) (xy 21.489416 -30.05709) (xy 21.489906 -30.027106) (xy 21.497734 -29.96765)
			(xy 21.513255 -29.909725) (xy 21.536204 -29.854321) (xy 21.566188 -29.802387) (xy 21.602694 -29.754811)
			(xy 21.645099 -29.712406) (xy 21.692675 -29.6759) (xy 21.744609 -29.645916) (xy 21.800013 -29.622967)
			(xy 21.857938 -29.607446) (xy 21.917394 -29.599618) (xy 21.977362 -29.599618) (xy 22.036818 -29.607446)
			(xy 22.094743 -29.622967) (xy 22.150147 -29.645916) (xy 22.202081 -29.6759) (xy 22.249657 -29.712406)
			(xy 22.292062 -29.754811) (xy 22.328568 -29.802387) (xy 22.358552 -29.854321) (xy 22.381501 -29.909725)
			(xy 22.397022 -29.96765) (xy 22.40485 -30.027106) (xy 22.40534 -30.05709) (xy 22.40534 -30.92069)
			(xy 22.40485 -30.950674) (xy 22.397022 -31.01013) (xy 22.381501 -31.068055) (xy 22.358552 -31.123459)
			(xy 22.328568 -31.175393) (xy 22.292062 -31.222969) (xy 22.249657 -31.265374) (xy 22.202081 -31.30188)
			(xy 22.150147 -31.331864) (xy 22.094743 -31.354813) (xy 22.036818 -31.370334) (xy 21.977362 -31.378162)
			(xy 21.917394 -31.378162) (xy 21.857938 -31.370334) (xy 21.800013 -31.354813) (xy 21.744609 -31.331864)
			(xy 21.692675 -31.30188) (xy 21.645099 -31.265374) (xy 21.602694 -31.222969) (xy 21.566188 -31.175393)
			(xy 21.536204 -31.123459) (xy 21.513255 -31.068055) (xy 21.497734 -31.01013) (xy 21.489906 -30.950674)
			(xy 21.489416 -30.92069) (xy 14.758416 -30.92069) (xy 14.56944 -31.109666) (xy 14.561508 -31.118475)
			(xy 14.554014 -31.140932) (xy 14.557339 -31.164373) (xy 14.563598 -31.174436) (xy 14.579373 -31.198373)
			(xy 14.604333 -31.249979) (xy 14.621293 -31.304739) (xy 14.629871 -31.361419) (xy 14.6304 -31.390082)
			(xy 14.629938 -31.417335) (xy 14.622183 -31.471288) (xy 14.606828 -31.523587) (xy 14.584187 -31.573169)
			(xy 14.554719 -31.619024) (xy 14.519025 -31.660218) (xy 14.477832 -31.695913) (xy 14.431978 -31.725382)
			(xy 14.382397 -31.748025) (xy 14.330098 -31.763381) (xy 14.276145 -31.771137) (xy 14.248892 -31.77159)
			(xy 14.220229 -31.771073) (xy 14.163549 -31.762493) (xy 14.108791 -31.745525) (xy 14.05719 -31.720554)
			(xy 14.033246 -31.704788) (xy 14.023166 -31.698569) (xy 13.999745 -31.695237) (xy 13.977307 -31.702733)
			(xy 13.968476 -31.71063) (xy 13.285978 -32.393382) (xy 13.279136 -32.400781) (xy 13.271419 -32.41938)
			(xy 13.270992 -32.42945) (xy 13.270992 -32.714184) (xy 18.847308 -32.714184) (xy 18.847308 -31.850584)
			(xy 18.847798 -31.8206) (xy 18.855626 -31.761144) (xy 18.871147 -31.703219) (xy 18.894096 -31.647815)
			(xy 18.92408 -31.595881) (xy 18.960586 -31.548305) (xy 19.002991 -31.5059) (xy 19.050567 -31.469394)
			(xy 19.102501 -31.43941) (xy 19.157905 -31.416461) (xy 19.21583 -31.40094) (xy 19.275286 -31.393112)
			(xy 19.335254 -31.393112) (xy 19.39471 -31.40094) (xy 19.452635 -31.416461) (xy 19.508039 -31.43941)
			(xy 19.559973 -31.469394) (xy 19.607549 -31.5059) (xy 19.649954 -31.548305) (xy 19.68646 -31.595881)
			(xy 19.716444 -31.647815) (xy 19.739393 -31.703219) (xy 19.754914 -31.761144) (xy 19.762742 -31.8206)
			(xy 19.763232 -31.850584) (xy 19.763232 -32.714184) (xy 19.762742 -32.744168) (xy 19.754914 -32.803624)
			(xy 19.739393 -32.861549) (xy 19.716444 -32.916953) (xy 19.68646 -32.968887) (xy 19.649954 -33.016463)
			(xy 19.607549 -33.058868) (xy 19.559973 -33.095374) (xy 19.508039 -33.125358) (xy 19.452635 -33.148307)
			(xy 19.39471 -33.163828) (xy 19.335254 -33.171656) (xy 19.275286 -33.171656) (xy 19.21583 -33.163828)
			(xy 19.157905 -33.148307) (xy 19.102501 -33.125358) (xy 19.050567 -33.095374) (xy 19.002991 -33.058868)
			(xy 18.960586 -33.016463) (xy 18.92408 -32.968887) (xy 18.894096 -32.916953) (xy 18.871147 -32.861549)
			(xy 18.855626 -32.803624) (xy 18.847798 -32.744168) (xy 18.847308 -32.714184) (xy 13.270992 -32.714184)
			(xy 13.270992 -33.40735) (xy 13.270513 -33.440227) (xy 13.263119 -33.505565) (xy 13.248463 -33.569666)
			(xy 13.22673 -33.631726) (xy 13.198192 -33.690965) (xy 13.163206 -33.74664) (xy 13.122213 -33.798053)
			(xy 13.099288 -33.821624) (xy 12.400026 -34.520886) (xy 21.489416 -34.520886) (xy 21.489416 -33.657286)
			(xy 21.489906 -33.627302) (xy 21.497734 -33.567846) (xy 21.513255 -33.509921) (xy 21.536204 -33.454517)
			(xy 21.566188 -33.402583) (xy 21.602694 -33.355007) (xy 21.645099 -33.312602) (xy 21.692675 -33.276096)
			(xy 21.744609 -33.246112) (xy 21.800013 -33.223163) (xy 21.857938 -33.207642) (xy 21.917394 -33.199814)
			(xy 21.977362 -33.199814) (xy 22.036818 -33.207642) (xy 22.094743 -33.223163) (xy 22.150147 -33.246112)
			(xy 22.202081 -33.276096) (xy 22.249657 -33.312602) (xy 22.292062 -33.355007) (xy 22.328568 -33.402583)
			(xy 22.358552 -33.454517) (xy 22.381501 -33.509921) (xy 22.397022 -33.567846) (xy 22.40485 -33.627302)
			(xy 22.40534 -33.657286) (xy 22.40534 -34.520886) (xy 22.40485 -34.55087) (xy 22.397022 -34.610326)
			(xy 22.381501 -34.668251) (xy 22.358552 -34.723655) (xy 22.328568 -34.775589) (xy 22.292062 -34.823165)
			(xy 22.249657 -34.86557) (xy 22.202081 -34.902076) (xy 22.150147 -34.93206) (xy 22.094743 -34.955009)
			(xy 22.036818 -34.97053) (xy 21.977362 -34.978358) (xy 21.917394 -34.978358) (xy 21.857938 -34.97053)
			(xy 21.800013 -34.955009) (xy 21.744609 -34.93206) (xy 21.692675 -34.902076) (xy 21.645099 -34.86557)
			(xy 21.602694 -34.823165) (xy 21.566188 -34.775589) (xy 21.536204 -34.723655) (xy 21.513255 -34.668251)
			(xy 21.497734 -34.610326) (xy 21.489906 -34.55087) (xy 21.489416 -34.520886) (xy 12.400026 -34.520886)
			(xy 12.22883 -34.692082) (xy 12.222586 -34.698815) (xy 12.214947 -34.715498) (xy 12.213688 -34.733804)
			(xy 12.218974 -34.751375) (xy 12.224258 -34.758884) (xy 12.242589 -34.783961) (xy 12.27172 -34.83882)
			(xy 12.291578 -34.897674) (xy 12.301638 -34.958967) (xy 12.302236 -34.990024) (xy 12.301749 -35.017275)
			(xy 12.293989 -35.071221) (xy 12.278633 -35.123515) (xy 12.25599 -35.173091) (xy 12.226524 -35.21894)
			(xy 12.190833 -35.26013) (xy 12.149644 -35.295822) (xy 12.103794 -35.325289) (xy 12.054219 -35.347931)
			(xy 12.001925 -35.363289) (xy 11.947979 -35.371048) (xy 11.920728 -35.371532) (xy 11.889671 -35.370925)
			(xy 11.828376 -35.36087) (xy 11.769518 -35.341022) (xy 11.714651 -35.311904) (xy 11.689588 -35.293554)
			(xy 11.682057 -35.288317) (xy 11.664497 -35.283066) (xy 11.646211 -35.284316) (xy 11.629529 -35.291908)
			(xy 11.622786 -35.298126) (xy 10.57275 -36.348162) (xy 10.549185 -36.371059) (xy 10.497802 -36.412012)
			(xy 10.442159 -36.446959) (xy 10.382956 -36.475461) (xy 10.320935 -36.49716) (xy 10.256876 -36.511785)
			(xy 10.191583 -36.51915) (xy 10.15873 -36.519612) (xy 5.950204 -36.519612) (xy 5.91735 -36.519152)
			(xy 5.852056 -36.511796) (xy 5.787995 -36.497176) (xy 5.725975 -36.475476) (xy 5.666773 -36.446969)
			(xy 5.611136 -36.412012) (xy 5.559761 -36.371047) (xy 5.536184 -36.348162) (xy 5.3594 -36.171378)
			(xy 5.318506 -36.17087) (xy 5.30352 -36.18484) (xy 5.282214 -36.204031) (xy 5.234921 -36.236454)
			(xy 5.183307 -36.261432) (xy 5.128535 -36.278402) (xy 5.07184 -36.286981) (xy 5.04317 -36.287456)
			(xy 5.016216 -36.28699) (xy 4.962845 -36.2794) (xy 4.911074 -36.264375) (xy 4.861931 -36.242215)
			(xy 4.816396 -36.213361) (xy 4.775374 -36.178386) (xy 4.739682 -36.137986) (xy 4.71003 -36.092967)
			(xy 4.687008 -36.044222) (xy 4.671074 -35.992723) (xy 4.662545 -35.939494) (xy 4.661662 -35.912552)
			(xy 4.661662 -35.902646) (xy 4.653788 -35.884612) (xy 4.595622 -35.827462) (xy 4.58824 -35.820882)
			(xy 4.569941 -35.813438) (xy 4.560062 -35.812984) (xy 4.532884 -35.812984) (xy 4.523277 -35.813405)
			(xy 4.505404 -35.82046) (xy 4.498086 -35.8267) (xy 4.440428 -35.880548) (xy 4.432046 -35.898074)
			(xy 4.431538 -35.907472) (xy 4.429096 -35.936073) (xy 4.416708 -35.992122) (xy 4.396061 -36.045682)
			(xy 4.36762 -36.095542) (xy 4.332029 -36.140578) (xy 4.290091 -36.179771) (xy 4.242752 -36.212237)
			(xy 4.191084 -36.237242) (xy 4.136251 -36.254222) (xy 4.079493 -36.262793) (xy 4.050792 -36.263326)
			(xy 4.023541 -36.26284) (xy 3.969593 -36.255082) (xy 3.917298 -36.239727) (xy 3.867721 -36.217085)
			(xy 3.82187 -36.187619) (xy 3.780679 -36.151928) (xy 3.744987 -36.110738) (xy 3.715519 -36.064888)
			(xy 3.692877 -36.015311) (xy 3.67752 -35.963017) (xy 3.669761 -35.909069) (xy 3.669284 -35.881818)
			(xy 3.669813 -35.853007) (xy 3.67848 -35.796041) (xy 3.695611 -35.741025) (xy 3.720817 -35.689209)
			(xy 3.753525 -35.641771) (xy 3.792991 -35.599787) (xy 3.815334 -35.58159) (xy 3.82397 -35.574986)
			(xy 3.83413 -35.555682) (xy 3.83921 -35.468814) (xy 3.839379 -35.458039) (xy 3.831747 -35.437907)
			(xy 3.824478 -35.429952) (xy 3.212338 -34.817812) (xy 3.204936 -34.811138) (xy 3.186527 -34.803556)
			(xy 3.166618 -34.803567) (xy 3.15722 -34.80689) (xy 3.142742 -34.812732) (xy 3.125724 -34.838386)
			(xy 3.125724 -35.484562) (xy 3.125216 -35.503612) (xy 3.125189 -35.514883) (xy 3.133657 -35.53574)
			(xy 3.150211 -35.550995) (xy 3.160776 -35.55492) (xy 3.186358 -35.563357) (xy 3.235039 -35.586418)
			(xy 3.279996 -35.616091) (xy 3.320337 -35.651786) (xy 3.355262 -35.692797) (xy 3.384078 -35.738308)
			(xy 3.406212 -35.787417) (xy 3.421226 -35.839149) (xy 3.428822 -35.892477) (xy 3.429254 -35.91941)
			(xy 3.428791 -35.946663) (xy 3.421034 -36.000613) (xy 3.405678 -36.052911) (xy 3.383035 -36.102491)
			(xy 3.353567 -36.148344) (xy 3.317873 -36.189536) (xy 3.276681 -36.225229) (xy 3.230827 -36.254697)
			(xy 3.181247 -36.277339) (xy 3.12895 -36.292695) (xy 3.074999 -36.300451) (xy 3.047746 -36.300918)
			(xy 3.019209 -36.300382) (xy 2.962773 -36.291874) (xy 2.908234 -36.275056) (xy 2.856807 -36.250303)
			(xy 2.809641 -36.218167) (xy 2.767787 -36.179364) (xy 2.74955 -36.157408) (xy 2.742413 -36.149395)
			(xy 2.723384 -36.139531) (xy 2.71272 -36.138358) (xy 2.637028 -36.13404) (xy 2.626319 -36.133919)
			(xy 2.606325 -36.141546) (xy 2.59842 -36.148772) (xy 2.50571 -36.241228) (xy 2.498867 -36.248628)
			(xy 2.491141 -36.267226) (xy 2.490724 -36.277296) (xy 2.490724 -36.60013) (xy 11.998205 -36.60013)
			(xy 12.00221 -36.512222) (xy 12.014193 -36.425042) (xy 12.034053 -36.339313) (xy 12.061628 -36.255745)
			(xy 12.096687 -36.175031) (xy 12.13894 -36.097839) (xy 12.188038 -36.02481) (xy 12.243574 -35.956548)
			(xy 12.305086 -35.893618) (xy 12.372067 -35.836544) (xy 12.44396 -35.785796) (xy 12.520169 -35.741796)
			(xy 12.600064 -35.704909) (xy 12.682983 -35.67544) (xy 12.768238 -35.653633) (xy 12.855122 -35.639669)
			(xy 12.942916 -35.633663) (xy 13.030893 -35.635667) (xy 13.118323 -35.645662) (xy 13.204482 -35.663566)
			(xy 13.288656 -35.68923) (xy 13.370147 -35.722443) (xy 13.448281 -35.762929) (xy 13.522409 -35.810351)
			(xy 13.591917 -35.864318) (xy 13.656231 -35.924383) (xy 13.714815 -35.990047) (xy 13.767186 -36.060766)
			(xy 13.812909 -36.135954) (xy 13.851606 -36.214989) (xy 13.882955 -36.297215) (xy 13.906697 -36.381951)
			(xy 13.922635 -36.468495) (xy 13.930637 -36.55613) (xy 13.931138 -36.60013) (xy 13.930637 -36.64413)
			(xy 13.922635 -36.731765) (xy 13.906697 -36.818309) (xy 13.882955 -36.903045) (xy 13.851606 -36.985271)
			(xy 13.812909 -37.064306) (xy 13.767186 -37.139494) (xy 13.714815 -37.210213) (xy 13.656231 -37.275877)
			(xy 13.591917 -37.335942) (xy 13.522409 -37.389909) (xy 13.448281 -37.437331) (xy 13.370147 -37.477817)
			(xy 13.288656 -37.51103) (xy 13.204482 -37.536694) (xy 13.118323 -37.554598) (xy 13.030893 -37.564593)
			(xy 12.942916 -37.566597) (xy 12.855122 -37.560591) (xy 12.768238 -37.546627) (xy 12.682983 -37.52482)
			(xy 12.600064 -37.495351) (xy 12.520169 -37.458464) (xy 12.44396 -37.414464) (xy 12.372067 -37.363716)
			(xy 12.305086 -37.306642) (xy 12.243574 -37.243712) (xy 12.188038 -37.17545) (xy 12.13894 -37.102421)
			(xy 12.096687 -37.025229) (xy 12.061628 -36.944515) (xy 12.034053 -36.860947) (xy 12.014193 -36.775218)
			(xy 12.00221 -36.688038) (xy 11.998205 -36.60013) (xy 2.490724 -36.60013) (xy 2.490724 -38.928802)
			(xy 3.912868 -38.928802) (xy 3.916939 -38.87318) (xy 3.929065 -38.818743) (xy 3.948988 -38.766652)
			(xy 3.976284 -38.718017) (xy 4.01037 -38.673874) (xy 4.050519 -38.635165) (xy 4.095877 -38.602714)
			(xy 4.145477 -38.577213) (xy 4.198261 -38.559206) (xy 4.253104 -38.549076) (xy 4.308838 -38.547039)
			(xy 4.364275 -38.553139) (xy 4.418232 -38.567245) (xy 4.469561 -38.589057) (xy 4.517167 -38.618111)
			(xy 4.560035 -38.653786) (xy 4.597252 -38.695323) (xy 4.628025 -38.741836) (xy 4.651697 -38.792333)
			(xy 4.667765 -38.84574) (xy 4.675885 -38.900916) (xy 4.676394 -38.928802) (xy 5.182868 -38.928802)
			(xy 5.186939 -38.87318) (xy 5.199065 -38.818743) (xy 5.218988 -38.766652) (xy 5.246284 -38.718017)
			(xy 5.28037 -38.673874) (xy 5.320519 -38.635165) (xy 5.365877 -38.602714) (xy 5.415477 -38.577213)
			(xy 5.468261 -38.559206) (xy 5.523104 -38.549076) (xy 5.578838 -38.547039) (xy 5.634275 -38.553139)
			(xy 5.688232 -38.567245) (xy 5.739561 -38.589057) (xy 5.787167 -38.618111) (xy 5.830035 -38.653786)
			(xy 5.867252 -38.695323) (xy 5.898025 -38.741836) (xy 5.921697 -38.792333) (xy 5.937765 -38.84574)
			(xy 5.945885 -38.900916) (xy 5.946394 -38.928802) (xy 5.945885 -38.956688) (xy 5.937765 -39.011864)
			(xy 5.921697 -39.065271) (xy 5.898025 -39.115768) (xy 5.867252 -39.162281) (xy 5.830035 -39.203818)
			(xy 5.787167 -39.239493) (xy 5.739561 -39.268547) (xy 5.688232 -39.290359) (xy 5.634275 -39.304465)
			(xy 5.578838 -39.310565) (xy 5.523104 -39.308528) (xy 5.468261 -39.298398) (xy 5.415477 -39.280391)
			(xy 5.365877 -39.25489) (xy 5.320519 -39.222439) (xy 5.28037 -39.18373) (xy 5.246284 -39.139587)
			(xy 5.218988 -39.090952) (xy 5.199065 -39.038861) (xy 5.186939 -38.984424) (xy 5.182868 -38.928802)
			(xy 4.676394 -38.928802) (xy 4.675885 -38.956688) (xy 4.667765 -39.011864) (xy 4.651697 -39.065271)
			(xy 4.628025 -39.115768) (xy 4.597252 -39.162281) (xy 4.560035 -39.203818) (xy 4.517167 -39.239493)
			(xy 4.469561 -39.268547) (xy 4.418232 -39.290359) (xy 4.364275 -39.304465) (xy 4.308838 -39.310565)
			(xy 4.253104 -39.308528) (xy 4.198261 -39.298398) (xy 4.145477 -39.280391) (xy 4.095877 -39.25489)
			(xy 4.050519 -39.222439) (xy 4.01037 -39.18373) (xy 3.976284 -39.139587) (xy 3.948988 -39.090952)
			(xy 3.929065 -39.038861) (xy 3.916939 -38.984424) (xy 3.912868 -38.928802) (xy 2.490724 -38.928802)
			(xy 2.490724 -39.961566) (xy 2.491392 -39.974213) (xy 2.503381 -39.996484) (xy 2.513584 -40.003984)
			(xy 2.584958 -40.05072) (xy 2.595913 -40.057067) (xy 2.621109 -40.059222) (xy 2.632964 -40.054784)
			(xy 2.657103 -40.044747) (xy 2.707436 -40.030619) (xy 2.759225 -40.023486) (xy 2.785364 -40.023034)
			(xy 2.812615 -40.02352) (xy 2.866562 -40.031277) (xy 2.918856 -40.046633) (xy 2.968433 -40.069274)
			(xy 3.014283 -40.09874) (xy 3.055472 -40.134432) (xy 3.091163 -40.175622) (xy 3.120629 -40.221472)
			(xy 3.14327 -40.271049) (xy 3.158624 -40.323344) (xy 3.16638 -40.377291) (xy 3.166872 -40.404542)
			(xy 3.166337 -40.433458) (xy 3.157608 -40.490627) (xy 3.140352 -40.545825) (xy 3.114963 -40.597786)
			(xy 3.082025 -40.645321) (xy 3.04229 -40.687341) (xy 3.019806 -40.705532) (xy 3.010967 -40.713118)
			(xy 3.000764 -40.734029) (xy 3.000248 -40.745664) (xy 3.000248 -40.82542) (xy 3.00081 -40.837047)
			(xy 3.010988 -40.857955) (xy 3.019806 -40.865552) (xy 3.04229 -40.883742) (xy 3.082029 -40.92576)
			(xy 3.114969 -40.973294) (xy 3.140357 -41.025256) (xy 3.157611 -41.080455) (xy 3.166334 -41.137626)
			(xy 3.166872 -41.166542) (xy 5.443982 -41.166542) (xy 5.4445 -41.137625) (xy 5.453225 -41.080452)
			(xy 5.470481 -41.025252) (xy 5.495872 -40.97329) (xy 5.528818 -40.925756) (xy 5.568561 -40.883741)
			(xy 5.591048 -40.865552) (xy 5.599875 -40.857964) (xy 5.610046 -40.837048) (xy 5.610606 -40.82542)
			(xy 5.610606 -40.745664) (xy 5.610071 -40.734032) (xy 5.599879 -40.713122) (xy 5.591048 -40.705532)
			(xy 5.568569 -40.687336) (xy 5.528836 -40.645316) (xy 5.495898 -40.597781) (xy 5.470509 -40.545821)
			(xy 5.453251 -40.490625) (xy 5.444519 -40.433457) (xy 5.443982 -40.404542) (xy 5.444468 -40.377291)
			(xy 5.452224 -40.323343) (xy 5.467579 -40.271048) (xy 5.490221 -40.221471) (xy 5.519687 -40.175621)
			(xy 5.555378 -40.13443) (xy 5.596569 -40.098739) (xy 5.642419 -40.069273) (xy 5.691996 -40.046631)
			(xy 5.744291 -40.031276) (xy 5.798239 -40.02352) (xy 5.852741 -40.02352) (xy 5.906689 -40.031276)
			(xy 5.958984 -40.046631) (xy 6.008561 -40.069273) (xy 6.054411 -40.098739) (xy 6.095602 -40.13443)
			(xy 6.131293 -40.175621) (xy 6.160759 -40.221471) (xy 6.183401 -40.271048) (xy 6.198756 -40.323343)
			(xy 6.206512 -40.377291) (xy 6.206998 -40.404542) (xy 6.206439 -40.433457) (xy 6.197718 -40.490627)
			(xy 6.180469 -40.545825) (xy 6.155085 -40.597787) (xy 6.122148 -40.645322) (xy 6.082414 -40.687341)
			(xy 6.059932 -40.705532) (xy 6.051109 -40.713123) (xy 6.040937 -40.734036) (xy 6.040374 -40.745664)
			(xy 6.040374 -40.82542) (xy 6.04089 -40.837056) (xy 6.051092 -40.857967) (xy 6.059932 -40.865552)
			(xy 6.082412 -40.883747) (xy 6.122147 -40.925766) (xy 6.155087 -40.9733) (xy 6.180476 -41.025261)
			(xy 6.197733 -41.080457) (xy 6.206463 -41.137626) (xy 6.206998 -41.166542) (xy 6.206512 -41.193793)
			(xy 6.198756 -41.247741) (xy 6.183401 -41.300036) (xy 6.160759 -41.349613) (xy 6.131293 -41.395463)
			(xy 6.095602 -41.436654) (xy 6.054411 -41.472345) (xy 6.008561 -41.501811) (xy 5.958984 -41.524453)
			(xy 5.906689 -41.539808) (xy 5.852741 -41.547564) (xy 5.798239 -41.547564) (xy 5.744291 -41.539808)
			(xy 5.691996 -41.524453) (xy 5.642419 -41.501811) (xy 5.596569 -41.472345) (xy 5.555378 -41.436654)
			(xy 5.519687 -41.395463) (xy 5.490221 -41.349613) (xy 5.467579 -41.300036) (xy 5.452224 -41.247741)
			(xy 5.444468 -41.193793) (xy 5.443982 -41.166542) (xy 3.166872 -41.166542) (xy 3.166386 -41.193793)
			(xy 3.158629 -41.247741) (xy 3.143274 -41.300036) (xy 3.120633 -41.349613) (xy 3.091167 -41.395463)
			(xy 3.055475 -41.436654) (xy 3.014285 -41.472345) (xy 2.968435 -41.501812) (xy 2.918858 -41.524453)
			(xy 2.866563 -41.539809) (xy 2.812615 -41.547566) (xy 2.785364 -41.54805) (xy 2.759224 -41.547619)
			(xy 2.707434 -41.54048) (xy 2.657103 -41.52634) (xy 2.632964 -41.5163) (xy 2.621026 -41.51122) (xy 2.595626 -41.513252)
			(xy 2.513584 -41.5671) (xy 2.503396 -41.574616) (xy 2.491406 -41.596876) (xy 2.490724 -41.609518)
			(xy 2.490724 -42.600372) (xy 2.498344 -42.618914) (xy 2.499106 -42.619676) (xy 2.708148 -42.619676)
			(xy 2.717329 -42.619332) (xy 2.734541 -42.612943) (xy 2.748394 -42.600894) (xy 2.753106 -42.593006)
			(xy 2.795524 -42.513758) (xy 2.799472 -42.505499) (xy 2.801833 -42.487359) (xy 2.797692 -42.469541)
			(xy 2.792984 -42.461688) (xy 2.777902 -42.43812) (xy 2.754062 -42.387501) (xy 2.737877 -42.333941)
			(xy 2.729696 -42.27859) (xy 2.72923 -42.250614) (xy 2.729716 -42.223363) (xy 2.737472 -42.169415)
			(xy 2.752827 -42.11712) (xy 2.775469 -42.067543) (xy 2.804935 -42.021693) (xy 2.840626 -41.980502)
			(xy 2.881817 -41.944811) (xy 2.927667 -41.915345) (xy 2.977244 -41.892703) (xy 3.029539 -41.877348)
			(xy 3.083487 -41.869592) (xy 3.137989 -41.869592) (xy 3.191937 -41.877348) (xy 3.244232 -41.892703)
			(xy 3.293809 -41.915345) (xy 3.339659 -41.944811) (xy 3.38085 -41.980502) (xy 3.416541 -42.021693)
			(xy 3.446007 -42.067543) (xy 3.468649 -42.11712) (xy 3.484004 -42.169415) (xy 3.49176 -42.223363)
			(xy 3.492246 -42.250614) (xy 3.491753 -42.278589) (xy 3.483576 -42.333938) (xy 3.467399 -42.387498)
			(xy 3.44357 -42.438119) (xy 3.428492 -42.461688) (xy 3.423748 -42.46952) (xy 3.419623 -42.487346)
			(xy 3.422024 -42.505485) (xy 3.425952 -42.513758) (xy 3.46837 -42.593006) (xy 3.47307 -42.600906)
			(xy 3.486925 -42.612964) (xy 3.504143 -42.619363) (xy 3.513328 -42.619676) (xy 3.928364 -42.619676)
			(xy 3.939987 -42.619106) (xy 3.960884 -42.60892) (xy 3.968496 -42.600118) (xy 4.025138 -42.527728)
			(xy 4.029964 -42.504868) (xy 4.02717 -42.493692) (xy 4.021938 -42.471131) (xy 4.016336 -42.425156)
			(xy 4.015994 -42.401998) (xy 4.01648 -42.374747) (xy 4.024236 -42.320799) (xy 4.039591 -42.268504)
			(xy 4.062233 -42.218927) (xy 4.091699 -42.173077) (xy 4.12739 -42.131886) (xy 4.168581 -42.096195)
			(xy 4.214431 -42.066729) (xy 4.264008 -42.044087) (xy 4.316303 -42.028732) (xy 4.370251 -42.020976)
			(xy 4.424753 -42.020976) (xy 4.478701 -42.028732) (xy 4.530996 -42.044087) (xy 4.580573 -42.066729)
			(xy 4.626423 -42.096195) (xy 4.667614 -42.131886) (xy 4.703305 -42.173077) (xy 4.732771 -42.218927)
			(xy 4.755413 -42.268504) (xy 4.770768 -42.320799) (xy 4.778524 -42.374747) (xy 4.77901 -42.401998)
			(xy 4.77867 -42.425156) (xy 4.773066 -42.471131) (xy 4.767834 -42.493692) (xy 4.76504 -42.504868)
			(xy 4.769866 -42.527728) (xy 4.826508 -42.600118) (xy 4.834095 -42.608957) (xy 4.855004 -42.619166)
			(xy 4.86664 -42.619676) (xy 5.221224 -42.619676) (xy 5.233638 -42.619052) (xy 5.255594 -42.607461)
			(xy 5.263134 -42.597578) (xy 5.310632 -42.528744) (xy 5.316987 -42.518187) (xy 5.31992 -42.49376)
			(xy 5.31622 -42.482008) (xy 5.304718 -42.449483) (xy 5.292317 -42.381625) (xy 5.291582 -42.347134)
			(xy 5.292068 -42.319883) (xy 5.299824 -42.265935) (xy 5.315179 -42.21364) (xy 5.337821 -42.164063)
			(xy 5.367287 -42.118213) (xy 5.402978 -42.077022) (xy 5.444169 -42.041331) (xy 5.490019 -42.011865)
			(xy 5.539596 -41.989223) (xy 5.591891 -41.973868) (xy 5.645839 -41.966112) (xy 5.700341 -41.966112)
			(xy 5.754289 -41.973868) (xy 5.806584 -41.989223) (xy 5.856161 -42.011865) (xy 5.902011 -42.041331)
			(xy 5.943202 -42.077022) (xy 5.978893 -42.118213) (xy 6.008359 -42.164063) (xy 6.031001 -42.21364)
			(xy 6.046356 -42.265935) (xy 6.054112 -42.319883) (xy 6.054598 -42.347134) (xy 6.053853 -42.381624)
			(xy 6.041452 -42.44948) (xy 6.02996 -42.482008) (xy 6.026283 -42.493763) (xy 6.029218 -42.518176)
			(xy 6.035548 -42.528744) (xy 6.083046 -42.597578) (xy 6.090566 -42.607485) (xy 6.112534 -42.619091)
			(xy 6.124956 -42.619676) (xy 6.621018 -42.619676) (xy 6.647042 -42.620201) (xy 6.698448 -42.628364)
			(xy 6.747948 -42.644455) (xy 6.794327 -42.66808) (xy 6.836447 -42.698659) (xy 6.855206 -42.716704)
			(xy 6.982206 -42.843704) (xy 7.000321 -42.862484) (xy 7.03101 -42.90468) (xy 7.054715 -42.951161)
			(xy 7.07085 -43.000779) (xy 7.079019 -43.052312) (xy 7.079488 -43.0784) (xy 7.079488 -44.871132)
			(xy 7.079637 -44.877) (xy 7.082331 -44.888423) (xy 7.084822 -44.893738) (xy 7.085076 -44.894246)
			(xy 7.098908 -44.921775) (xy 7.11848 -44.980189) (xy 7.128403 -45.040989) (xy 7.129018 -45.071792)
			(xy 7.128532 -45.099043) (xy 7.120776 -45.152991) (xy 7.105421 -45.205286) (xy 7.082779 -45.254863)
			(xy 7.053313 -45.300713) (xy 7.017622 -45.341904) (xy 6.976431 -45.377595) (xy 6.930581 -45.407061)
			(xy 6.881004 -45.429703) (xy 6.828709 -45.445058) (xy 6.774761 -45.452814) (xy 6.720259 -45.452814)
			(xy 6.666311 -45.445058) (xy 6.614016 -45.429703) (xy 6.564439 -45.407061) (xy 6.518589 -45.377595)
			(xy 6.477398 -45.341904) (xy 6.441707 -45.300713) (xy 6.412241 -45.254863) (xy 6.389599 -45.205286)
			(xy 6.374244 -45.152991) (xy 6.366488 -45.099043) (xy 6.366002 -45.071792) (xy 6.366642 -45.041088)
			(xy 6.376525 -44.980481) (xy 6.395986 -44.922238) (xy 6.40969 -44.894754) (xy 6.410198 -44.893738)
			(xy 6.412992 -44.888404) (xy 6.415532 -44.877228) (xy 6.415532 -43.333924) (xy 6.415049 -43.323911)
			(xy 6.407394 -43.305405) (xy 6.393242 -43.291237) (xy 6.374745 -43.283562) (xy 6.364732 -43.283124)
			(xy 2.361692 -43.283124) (xy 2.347592 -43.283032) (xy 2.319487 -43.280743) (xy 2.305558 -43.278552)
			(xy 2.294382 -43.27652) (xy 2.272792 -43.282616) (xy 2.204974 -43.339766) (xy 2.196842 -43.347357)
			(xy 2.187495 -43.367516) (xy 2.18694 -43.378628) (xy 2.18694 -46.154848) (xy 2.187428 -46.164847)
			(xy 2.195056 -46.183336) (xy 2.209146 -46.19753) (xy 2.218182 -46.201838) (xy 2.232406 -46.20768)
			(xy 2.262378 -46.201838) (xy 3.867404 -44.596812) (xy 3.87157 -44.592458) (xy 3.877857 -44.58218)
			(xy 3.87985 -44.576492) (xy 3.87985 -44.576238) (xy 3.888285 -44.55068) (xy 3.911337 -44.502046)
			(xy 3.940995 -44.457134) (xy 3.976668 -44.416834) (xy 4.017651 -44.381948) (xy 4.063129 -44.353166)
			(xy 4.112201 -44.331061) (xy 4.163892 -44.31607) (xy 4.217176 -44.308491) (xy 4.244086 -44.308014)
			(xy 4.271339 -44.308476) (xy 4.32529 -44.316232) (xy 4.377588 -44.331587) (xy 4.427169 -44.354229)
			(xy 4.473022 -44.383697) (xy 4.514215 -44.419391) (xy 4.549908 -44.460584) (xy 4.579375 -44.506438)
			(xy 4.602016 -44.556019) (xy 4.61737 -44.608318) (xy 4.625124 -44.662269) (xy 4.625594 -44.689522)
			(xy 4.625131 -44.716421) (xy 4.61757 -44.769686) (xy 4.6026 -44.82136) (xy 4.580519 -44.870418) (xy 4.551765 -44.915888)
			(xy 4.516908 -44.956867) (xy 4.47664 -44.992543) (xy 4.431758 -45.022207) (xy 4.383155 -45.045271)
			(xy 4.357624 -45.053758) (xy 4.357116 -45.053758) (xy 4.351456 -45.055806) (xy 4.341197 -45.062097)
			(xy 4.336796 -45.066204) (xy 3.551575 -45.851318) (xy 7.87476 -45.851318) (xy 7.878831 -45.795696)
			(xy 7.890957 -45.741259) (xy 7.91088 -45.689168) (xy 7.938176 -45.640533) (xy 7.972262 -45.59639)
			(xy 8.012411 -45.557681) (xy 8.057769 -45.52523) (xy 8.107369 -45.499729) (xy 8.160153 -45.481722)
			(xy 8.214996 -45.471592) (xy 8.27073 -45.469555) (xy 8.326167 -45.475655) (xy 8.380124 -45.489761)
			(xy 8.431453 -45.511573) (xy 8.479059 -45.540627) (xy 8.521927 -45.576302) (xy 8.559144 -45.617839)
			(xy 8.589917 -45.664352) (xy 8.613589 -45.714849) (xy 8.629657 -45.768256) (xy 8.637777 -45.823432)
			(xy 8.638286 -45.851318) (xy 8.637777 -45.879204) (xy 8.629657 -45.93438) (xy 8.613589 -45.987787)
			(xy 8.589917 -46.038284) (xy 8.559144 -46.084797) (xy 8.521927 -46.126334) (xy 8.479059 -46.162009)
			(xy 8.431453 -46.191063) (xy 8.380124 -46.212875) (xy 8.326167 -46.226981) (xy 8.27073 -46.233081)
			(xy 8.214996 -46.231044) (xy 8.160153 -46.220914) (xy 8.107369 -46.202907) (xy 8.057769 -46.177406)
			(xy 8.012411 -46.144955) (xy 7.972262 -46.106246) (xy 7.938176 -46.062103) (xy 7.91088 -46.013468)
			(xy 7.890957 -45.961377) (xy 7.878831 -45.90694) (xy 7.87476 -45.851318) (xy 3.551575 -45.851318)
			(xy 2.468626 -46.93412) (xy 2.46178 -46.941518) (xy 2.454049 -46.960117) (xy 2.45364 -46.970188)
			(xy 2.45364 -49.601951) (xy 6.113002 -49.601951) (xy 6.113002 -49.547449) (xy 6.120758 -49.493502)
			(xy 6.136113 -49.441208) (xy 6.158754 -49.391632) (xy 6.18822 -49.345782) (xy 6.223911 -49.304592)
			(xy 6.2651 -49.268901) (xy 6.31095 -49.239435) (xy 6.360526 -49.216794) (xy 6.41282 -49.201439) (xy 6.466767 -49.193682)
			(xy 6.494018 -49.193196) (xy 6.521389 -49.193652) (xy 6.575568 -49.201473) (xy 6.628071 -49.216964)
			(xy 6.677818 -49.239808) (xy 6.723784 -49.269534) (xy 6.744716 -49.287176) (xy 6.74497 -49.28743)
			(xy 6.752059 -49.293013) (xy 6.768974 -49.299261) (xy 6.77799 -49.299622) (xy 6.845046 -49.299622)
			(xy 6.85406 -49.299235) (xy 6.870977 -49.293008) (xy 6.878066 -49.28743) (xy 6.878066 -49.287176)
			(xy 6.87832 -49.287176) (xy 6.899253 -49.269535) (xy 6.945221 -49.239811) (xy 6.994967 -49.216965)
			(xy 7.047469 -49.201469) (xy 7.101647 -49.19364) (xy 7.156389 -49.19364) (xy 7.210567 -49.201469)
			(xy 7.263069 -49.216965) (xy 7.312815 -49.239811) (xy 7.358783 -49.269535) (xy 7.379716 -49.287176)
			(xy 7.37997 -49.28743) (xy 7.387059 -49.293013) (xy 7.403974 -49.299261) (xy 7.41299 -49.299622)
			(xy 7.480046 -49.299622) (xy 7.48906 -49.299235) (xy 7.505977 -49.293008) (xy 7.513066 -49.28743)
			(xy 7.513066 -49.287176) (xy 7.51332 -49.287176) (xy 7.534253 -49.269535) (xy 7.580221 -49.239811)
			(xy 7.629967 -49.216965) (xy 7.682469 -49.201469) (xy 7.736647 -49.19364) (xy 7.791389 -49.19364)
			(xy 7.845567 -49.201469) (xy 7.898069 -49.216965) (xy 7.947815 -49.239811) (xy 7.993783 -49.269535)
			(xy 8.014716 -49.287176) (xy 8.01497 -49.28743) (xy 8.022059 -49.293013) (xy 8.038974 -49.299261)
			(xy 8.04799 -49.299622) (xy 8.115046 -49.299622) (xy 8.12406 -49.299235) (xy 8.140977 -49.293008)
			(xy 8.148066 -49.28743) (xy 8.148066 -49.287176) (xy 8.14832 -49.287176) (xy 8.169268 -49.269557)
			(xy 8.215237 -49.239843) (xy 8.26498 -49.217004) (xy 8.317477 -49.201508) (xy 8.37165 -49.193673)
			(xy 8.399018 -49.193196) (xy 8.426271 -49.193651) (xy 8.480223 -49.201408) (xy 8.532522 -49.216764)
			(xy 8.582102 -49.239407) (xy 8.627956 -49.268875) (xy 8.66915 -49.304569) (xy 8.704844 -49.345762)
			(xy 8.734312 -49.391616) (xy 8.756955 -49.441197) (xy 8.772312 -49.493495) (xy 8.780069 -49.547447)
			(xy 8.780069 -49.601953) (xy 8.772312 -49.655905) (xy 8.756955 -49.708203) (xy 8.734312 -49.757784)
			(xy 8.704844 -49.803638) (xy 8.66915 -49.844831) (xy 8.627956 -49.880525) (xy 8.582102 -49.909993)
			(xy 8.532522 -49.932636) (xy 8.480223 -49.947992) (xy 8.426271 -49.955749) (xy 8.399018 -49.956212)
			(xy 8.371648 -49.955732) (xy 8.31747 -49.947917) (xy 8.264967 -49.932431) (xy 8.21522 -49.909593)
			(xy 8.169252 -49.879872) (xy 8.14832 -49.862232) (xy 8.148066 -49.861978) (xy 8.140966 -49.85641)
			(xy 8.12406 -49.850153) (xy 8.115046 -49.849786) (xy 8.04799 -49.849786) (xy 8.038973 -49.850141)
			(xy 8.022056 -49.856391) (xy 8.01497 -49.861978) (xy 8.014716 -49.862232) (xy 7.993783 -49.879873)
			(xy 7.947815 -49.909597) (xy 7.898069 -49.932443) (xy 7.845567 -49.947939) (xy 7.791389 -49.955768)
			(xy 7.736647 -49.955768) (xy 7.682469 -49.947939) (xy 7.629967 -49.932443) (xy 7.580221 -49.909597)
			(xy 7.534253 -49.879873) (xy 7.51332 -49.862232) (xy 7.513066 -49.861978) (xy 7.505966 -49.85641)
			(xy 7.48906 -49.850153) (xy 7.480046 -49.849786) (xy 7.41299 -49.849786) (xy 7.403973 -49.850141)
			(xy 7.387056 -49.856391) (xy 7.37997 -49.861978) (xy 7.37997 -49.862232) (xy 7.379716 -49.862232)
			(xy 7.358783 -49.879873) (xy 7.312815 -49.909597) (xy 7.263069 -49.932443) (xy 7.210567 -49.947939)
			(xy 7.156389 -49.955768) (xy 7.101647 -49.955768) (xy 7.047469 -49.947939) (xy 6.994967 -49.932443)
			(xy 6.945221 -49.909597) (xy 6.899253 -49.879873) (xy 6.87832 -49.862232) (xy 6.878066 -49.861978)
			(xy 6.870966 -49.85641) (xy 6.85406 -49.850153) (xy 6.845046 -49.849786) (xy 6.77799 -49.849786)
			(xy 6.768973 -49.850141) (xy 6.752056 -49.856391) (xy 6.74497 -49.861978) (xy 6.74497 -49.862232)
			(xy 6.744716 -49.862232) (xy 6.723793 -49.879882) (xy 6.677817 -49.909591) (xy 6.628067 -49.932424)
			(xy 6.575565 -49.947913) (xy 6.521388 -49.955739) (xy 6.494018 -49.956212) (xy 6.466767 -49.955718)
			(xy 6.41282 -49.947961) (xy 6.360526 -49.932606) (xy 6.31095 -49.909965) (xy 6.2651 -49.880499) (xy 6.223911 -49.844808)
			(xy 6.18822 -49.803618) (xy 6.158754 -49.757768) (xy 6.136113 -49.708192) (xy 6.120758 -49.655898)
			(xy 6.113002 -49.601951) (xy 2.45364 -49.601951) (xy 2.45364 -51.243992) (xy 7.133082 -51.243992)
			(xy 7.133523 -51.216621) (xy 7.141344 -51.16244) (xy 7.156838 -51.109936) (xy 7.179686 -51.060189)
			(xy 7.209417 -51.014224) (xy 7.227062 -50.993294) (xy 7.227316 -50.99304) (xy 7.232894 -50.985947)
			(xy 7.239145 -50.969035) (xy 7.239508 -50.96002) (xy 7.239508 -50.892964) (xy 7.239167 -50.883946)
			(xy 7.232908 -50.867029) (xy 7.227316 -50.859944) (xy 7.227062 -50.859944) (xy 7.227062 -50.85969)
			(xy 7.209398 -50.838778) (xy 7.179691 -50.792799) (xy 7.156861 -50.743046) (xy 7.141375 -50.690541)
			(xy 7.133553 -50.636362) (xy 7.133082 -50.608992) (xy 7.13357 -50.581741) (xy 7.141328 -50.527794)
			(xy 7.156683 -50.4755) (xy 7.179325 -50.425923) (xy 7.208791 -50.380073) (xy 7.244482 -50.338883)
			(xy 7.285672 -50.303192) (xy 7.331521 -50.273726) (xy 7.381098 -50.251084) (xy 7.433392 -50.235728)
			(xy 7.487339 -50.22797) (xy 7.51459 -50.227484) (xy 7.543508 -50.227978) (xy 7.600682 -50.236707)
			(xy 7.655883 -50.253968) (xy 7.707845 -50.279364) (xy 7.755378 -50.312314) (xy 7.797392 -50.352061)
			(xy 7.81558 -50.37455) (xy 7.823197 -50.383347) (xy 7.844091 -50.393534) (xy 7.855712 -50.394108)
			(xy 7.935468 -50.394108) (xy 7.947095 -50.393533) (xy 7.968005 -50.383369) (xy 7.9756 -50.37455)
			(xy 7.993778 -50.352056) (xy 8.035802 -50.312324) (xy 8.08334 -50.279388) (xy 8.135304 -50.254001)
			(xy 8.190503 -50.236747) (xy 8.247673 -50.228019) (xy 8.27659 -50.227484) (xy 8.303842 -50.227965)
			(xy 8.357792 -50.23572) (xy 8.410089 -50.251074) (xy 8.459669 -50.273715) (xy 8.505522 -50.303181)
			(xy 8.546714 -50.338873) (xy 8.582408 -50.380064) (xy 8.611876 -50.425915) (xy 8.634519 -50.475494)
			(xy 8.649876 -50.52779) (xy 8.657634 -50.58174) (xy 8.658098 -50.608992) (xy 8.657626 -50.635306)
			(xy 8.650392 -50.687434) (xy 8.636074 -50.738077) (xy 8.614942 -50.786276) (xy 8.587397 -50.831119)
			(xy 8.553959 -50.871759) (xy 8.534908 -50.889916) (xy 8.527499 -50.897431) (xy 8.518978 -50.916716)
			(xy 8.518398 -50.927254) (xy 8.518398 -51.00193) (xy 8.518952 -51.012477) (xy 8.52747 -51.031772)
			(xy 8.534908 -51.039268) (xy 8.553991 -51.057396) (xy 8.587445 -51.098032) (xy 8.615001 -51.142878)
			(xy 8.636134 -51.191084) (xy 8.650446 -51.241736) (xy 8.657663 -51.293874) (xy 8.658098 -51.320192)
			(xy 8.657637 -51.347445) (xy 8.649881 -51.401397) (xy 8.634526 -51.453695) (xy 8.611883 -51.503276)
			(xy 8.582415 -51.54913) (xy 8.546721 -51.590323) (xy 8.505528 -51.626016) (xy 8.459674 -51.655484)
			(xy 8.410093 -51.678126) (xy 8.357795 -51.693481) (xy 8.303843 -51.701237) (xy 8.27659 -51.7017)
			(xy 8.248925 -51.701196) (xy 8.194175 -51.693195) (xy 8.141153 -51.677377) (xy 8.090969 -51.654073)
			(xy 8.044674 -51.62377) (xy 8.003236 -51.587104) (xy 7.967523 -51.544841) (xy 7.952486 -51.521614)
			(xy 7.945866 -51.511924) (xy 7.925992 -51.499488) (xy 7.914386 -51.497738) (xy 7.834376 -51.489864)
			(xy 7.822737 -51.489221) (xy 7.800899 -51.497308) (xy 7.792466 -51.505358) (xy 7.792212 -51.505612)
			(xy 7.77411 -51.524172) (xy 7.733782 -51.556752) (xy 7.689412 -51.583567) (xy 7.641818 -51.604124)
			(xy 7.591878 -51.618042) (xy 7.540512 -51.625065) (xy 7.51459 -51.6255) (xy 7.487338 -51.625031)
			(xy 7.433389 -51.617273) (xy 7.381094 -51.601917) (xy 7.331516 -51.579274) (xy 7.285665 -51.549806)
			(xy 7.244475 -51.514112) (xy 7.208784 -51.47292) (xy 7.179318 -51.427068) (xy 7.156677 -51.377489)
			(xy 7.141323 -51.325193) (xy 7.133567 -51.271244) (xy 7.133082 -51.243992) (xy 2.45364 -51.243992)
			(xy 2.45364 -52.555973) (xy 6.583889 -52.555973) (xy 6.583889 -52.501467) (xy 6.591646 -52.447517)
			(xy 6.607002 -52.395219) (xy 6.629645 -52.345639) (xy 6.659113 -52.299786) (xy 6.694807 -52.258594)
			(xy 6.735999 -52.222901) (xy 6.781853 -52.193433) (xy 6.831433 -52.170791) (xy 6.88373 -52.155435)
			(xy 6.937681 -52.147679) (xy 6.964934 -52.147216) (xy 6.992305 -52.147658) (xy 7.046485 -52.155481)
			(xy 7.098989 -52.170976) (xy 7.148735 -52.193823) (xy 7.194701 -52.223552) (xy 7.215632 -52.241196)
			(xy 7.215886 -52.24145) (xy 7.222968 -52.247043) (xy 7.239888 -52.253285) (xy 7.248906 -52.253642)
			(xy 7.315962 -52.253642) (xy 7.324979 -52.253279) (xy 7.341896 -52.247037) (xy 7.348982 -52.24145)
			(xy 7.348982 -52.241196) (xy 7.349236 -52.241196) (xy 7.370181 -52.223573) (xy 7.41615 -52.193859)
			(xy 7.465894 -52.17102) (xy 7.518392 -52.155525) (xy 7.572566 -52.147692) (xy 7.599934 -52.147216)
			(xy 7.627185 -52.147694) (xy 7.681133 -52.155451) (xy 7.733428 -52.170807) (xy 7.783005 -52.193448)
			(xy 7.828856 -52.222915) (xy 7.870046 -52.258607) (xy 7.905737 -52.299798) (xy 7.935204 -52.345648)
			(xy 7.957845 -52.395226) (xy 7.9732 -52.447521) (xy 7.980956 -52.501469) (xy 7.980956 -52.555971)
			(xy 7.9732 -52.609919) (xy 7.957845 -52.662214) (xy 7.935204 -52.711792) (xy 7.905737 -52.757642)
			(xy 7.870046 -52.798833) (xy 7.828856 -52.834525) (xy 7.783005 -52.863992) (xy 7.733428 -52.886633)
			(xy 7.681133 -52.901989) (xy 7.627185 -52.909746) (xy 7.599934 -52.910232) (xy 7.572564 -52.909763)
			(xy 7.518384 -52.901948) (xy 7.46588 -52.886461) (xy 7.416133 -52.863619) (xy 7.370167 -52.833894)
			(xy 7.349236 -52.816252) (xy 7.348982 -52.815998) (xy 7.341905 -52.810398) (xy 7.324981 -52.804159)
			(xy 7.315962 -52.803806) (xy 7.248906 -52.803806) (xy 7.239889 -52.804165) (xy 7.222972 -52.810411)
			(xy 7.215886 -52.815998) (xy 7.215886 -52.816252) (xy 7.215632 -52.816252) (xy 7.194693 -52.833882)
			(xy 7.148723 -52.863597) (xy 7.098977 -52.886435) (xy 7.046478 -52.901928) (xy 6.992303 -52.909758)
			(xy 6.964934 -52.910232) (xy 6.937681 -52.909761) (xy 6.88373 -52.902005) (xy 6.831433 -52.886649)
			(xy 6.781853 -52.864007) (xy 6.735999 -52.834539) (xy 6.694807 -52.798846) (xy 6.659113 -52.757654)
			(xy 6.629645 -52.711801) (xy 6.607002 -52.662221) (xy 6.591646 -52.609923) (xy 6.583889 -52.555973)
			(xy 2.45364 -52.555973) (xy 2.45364 -53.496543) (xy 6.133541 -53.496543) (xy 6.133541 -53.442037)
			(xy 6.141298 -53.388085) (xy 6.156655 -53.335787) (xy 6.179298 -53.286206) (xy 6.208766 -53.240352)
			(xy 6.24446 -53.199159) (xy 6.285654 -53.163465) (xy 6.331508 -53.133997) (xy 6.381088 -53.111354)
			(xy 6.433387 -53.095998) (xy 6.487339 -53.088241) (xy 6.514592 -53.087778) (xy 6.541963 -53.08823)
			(xy 6.596143 -53.096048) (xy 6.648647 -53.111539) (xy 6.698394 -53.134385) (xy 6.74436 -53.164114)
			(xy 6.76529 -53.181758) (xy 6.765544 -53.182012) (xy 6.772641 -53.187583) (xy 6.78955 -53.193839)
			(xy 6.798564 -53.194204) (xy 6.86562 -53.194204) (xy 6.874638 -53.193856) (xy 6.891555 -53.187602)
			(xy 6.89864 -53.182012) (xy 6.89864 -53.181758) (xy 6.898894 -53.181758) (xy 6.919812 -53.164101)
			(xy 6.965789 -53.134393) (xy 7.01554 -53.111561) (xy 7.068044 -53.096074) (xy 7.122222 -53.08825)
			(xy 7.149592 -53.087778) (xy 7.176843 -53.088272) (xy 7.23079 -53.096029) (xy 7.283084 -53.111384)
			(xy 7.33266 -53.134025) (xy 7.37851 -53.163491) (xy 7.419699 -53.199182) (xy 7.45539 -53.240372)
			(xy 7.484856 -53.286222) (xy 7.507497 -53.335798) (xy 7.522852 -53.388092) (xy 7.530608 -53.442039)
			(xy 7.530608 -53.496541) (xy 7.522852 -53.550488) (xy 7.507497 -53.602782) (xy 7.484856 -53.652358)
			(xy 7.45539 -53.698208) (xy 7.419699 -53.739398) (xy 7.37851 -53.775089) (xy 7.33266 -53.804555)
			(xy 7.283084 -53.827196) (xy 7.23079 -53.842551) (xy 7.176843 -53.850308) (xy 7.149592 -53.850794)
			(xy 7.122222 -53.850334) (xy 7.068042 -53.842515) (xy 7.015539 -53.827025) (xy 6.965792 -53.804181)
			(xy 6.919826 -53.774456) (xy 6.898894 -53.756814) (xy 6.89864 -53.75656) (xy 6.89155 -53.750979)
			(xy 6.874636 -53.74473) (xy 6.86562 -53.744368) (xy 6.798564 -53.744368) (xy 6.789546 -53.744715)
			(xy 6.77263 -53.75097) (xy 6.765544 -53.75656) (xy 6.765544 -53.756814) (xy 6.76529 -53.756814) (xy 6.744374 -53.774473)
			(xy 6.698397 -53.804182) (xy 6.648645 -53.827014) (xy 6.596141 -53.8425) (xy 6.541962 -53.850323)
			(xy 6.514592 -53.850794) (xy 6.487339 -53.850339) (xy 6.433387 -53.842582) (xy 6.381088 -53.827226)
			(xy 6.331508 -53.804583) (xy 6.285654 -53.775115) (xy 6.24446 -53.739421) (xy 6.208766 -53.698228)
			(xy 6.179298 -53.652374) (xy 6.156655 -53.602793) (xy 6.141298 -53.550495) (xy 6.133541 -53.496543)
			(xy 2.45364 -53.496543) (xy 2.45364 -54.913022) (xy 2.454204 -54.923713) (xy 2.462868 -54.943264)
			(xy 2.470404 -54.950868) (xy 2.513117 -54.989041) (xy 3.901168 -54.989041) (xy 3.901168 -54.934539)
			(xy 3.908924 -54.880592) (xy 3.924279 -54.828297) (xy 3.94692 -54.77872) (xy 3.976386 -54.73287)
			(xy 4.012077 -54.69168) (xy 4.053267 -54.655988) (xy 4.099117 -54.626522) (xy 4.148693 -54.603881)
			(xy 4.200988 -54.588525) (xy 4.254935 -54.580768) (xy 4.282186 -54.580282) (xy 4.310277 -54.580788)
			(xy 4.365854 -54.589013) (xy 4.419622 -54.605302) (xy 4.47042 -54.629303) (xy 4.517147 -54.660496)
			(xy 4.558792 -54.698207) (xy 4.594455 -54.741618) (xy 4.609338 -54.765448) (xy 4.614672 -54.774338)
			(xy 4.63169 -54.78653) (xy 4.724908 -54.80685) (xy 4.745482 -54.802532) (xy 4.754118 -54.79669) (xy 4.778175 -54.780679)
			(xy 4.830109 -54.755339) (xy 4.885269 -54.738117) (xy 4.942395 -54.729405) (xy 4.971288 -54.728872)
			(xy 4.998541 -54.729337) (xy 5.052492 -54.737094) (xy 5.104789 -54.75245) (xy 5.15437 -54.775092)
			(xy 5.200223 -54.80456) (xy 5.241415 -54.840253) (xy 5.277109 -54.881446) (xy 5.306577 -54.927299)
			(xy 5.32922 -54.976879) (xy 5.344576 -55.029176) (xy 5.352333 -55.083127) (xy 5.352796 -55.11038)
			(xy 5.352319 -55.13775) (xy 5.344504 -55.191929) (xy 5.329018 -55.244432) (xy 5.306178 -55.294179)
			(xy 5.276456 -55.340146) (xy 5.258816 -55.361078) (xy 5.258562 -55.361332) (xy 5.252994 -55.368431)
			(xy 5.246737 -55.385338) (xy 5.24637 -55.394352) (xy 5.24637 -55.461408) (xy 5.24673 -55.470424)
			(xy 5.252976 -55.487341) (xy 5.258562 -55.494428) (xy 5.258816 -55.494428) (xy 5.258816 -55.494682)
			(xy 5.276457 -55.515615) (xy 5.306181 -55.561583) (xy 5.329026 -55.611329) (xy 5.344522 -55.663831)
			(xy 5.352351 -55.718009) (xy 5.352351 -55.772751) (xy 5.344522 -55.826929) (xy 5.329026 -55.879431)
			(xy 5.306181 -55.929177) (xy 5.276457 -55.975145) (xy 5.258816 -55.996078) (xy 5.258562 -55.996332)
			(xy 5.252994 -56.003431) (xy 5.246737 -56.020338) (xy 5.24637 -56.029352) (xy 5.24637 -56.096408)
			(xy 5.24673 -56.105424) (xy 5.252976 -56.122341) (xy 5.258562 -56.129428) (xy 5.258816 -56.129428)
			(xy 5.258816 -56.129682) (xy 5.276463 -56.150608) (xy 5.306173 -56.196583) (xy 5.329007 -56.246332)
			(xy 5.344496 -56.298834) (xy 5.352323 -56.35301) (xy 5.352796 -56.38038) (xy 5.35231 -56.407631)
			(xy 5.344554 -56.461579) (xy 5.329199 -56.513874) (xy 5.306557 -56.563451) (xy 5.277091 -56.609301)
			(xy 5.2414 -56.650492) (xy 5.200209 -56.686183) (xy 5.154359 -56.715649) (xy 5.104782 -56.738291)
			(xy 5.052487 -56.753646) (xy 4.998539 -56.761402) (xy 4.944037 -56.761402) (xy 4.890089 -56.753646)
			(xy 4.837794 -56.738291) (xy 4.788217 -56.715649) (xy 4.742367 -56.686183) (xy 4.701176 -56.650492)
			(xy 4.665485 -56.609301) (xy 4.636019 -56.563451) (xy 4.613377 -56.513874) (xy 4.598022 -56.461579)
			(xy 4.590266 -56.407631) (xy 4.58978 -56.38038) (xy 4.590215 -56.353008) (xy 4.598037 -56.298827)
			(xy 4.613533 -56.246323) (xy 4.636382 -56.196577) (xy 4.666114 -56.150612) (xy 4.68376 -56.129682)
			(xy 4.684014 -56.129428) (xy 4.689597 -56.122339) (xy 4.695845 -56.105424) (xy 4.696206 -56.096408)
			(xy 4.696206 -56.029352) (xy 4.695823 -56.020338) (xy 4.689593 -56.003421) (xy 4.684014 -55.996332)
			(xy 4.68376 -55.996332) (xy 4.68376 -55.996078) (xy 4.666119 -55.975145) (xy 4.636394 -55.929178)
			(xy 4.613549 -55.879431) (xy 4.598052 -55.826929) (xy 4.590224 -55.772751) (xy 4.590224 -55.718009)
			(xy 4.598052 -55.663831) (xy 4.613549 -55.611329) (xy 4.636394 -55.561582) (xy 4.666119 -55.515615)
			(xy 4.68376 -55.494682) (xy 4.684014 -55.494428) (xy 4.689597 -55.487339) (xy 4.695845 -55.470424)
			(xy 4.696206 -55.461408) (xy 4.696206 -55.394352) (xy 4.695823 -55.385338) (xy 4.689593 -55.368421)
			(xy 4.684014 -55.361332) (xy 4.68376 -55.360824) (xy 4.672814 -55.348091) (xy 4.652974 -55.320999)
			(xy 4.644136 -55.306722) (xy 4.638802 -55.297832) (xy 4.621784 -55.28564) (xy 4.528566 -55.26532)
			(xy 4.507992 -55.269638) (xy 4.499356 -55.27548) (xy 4.475304 -55.291499) (xy 4.423368 -55.316838)
			(xy 4.368207 -55.334058) (xy 4.31108 -55.342767) (xy 4.282186 -55.343298) (xy 4.254935 -55.342812)
			(xy 4.200988 -55.335055) (xy 4.148693 -55.319699) (xy 4.099117 -55.297058) (xy 4.053267 -55.267592)
			(xy 4.012077 -55.2319) (xy 3.976386 -55.19071) (xy 3.94692 -55.14486) (xy 3.924279 -55.095283) (xy 3.908924 -55.042988)
			(xy 3.901168 -54.989041) (xy 2.513117 -54.989041) (xy 2.53492 -55.008526) (xy 2.55524 -55.01513)
			(xy 2.565908 -55.014114) (xy 2.575849 -55.013146) (xy 2.595798 -55.012128) (xy 2.605786 -55.012082)
			(xy 2.632102 -55.012522) (xy 2.684234 -55.019749) (xy 2.734881 -55.034068) (xy 2.78308 -55.055207)
			(xy 2.827919 -55.082766) (xy 2.868548 -55.116223) (xy 2.88671 -55.135272) (xy 2.894203 -55.142716)
			(xy 2.913499 -55.151246) (xy 2.924048 -55.151782) (xy 2.998724 -55.151782) (xy 3.009264 -55.151205)
			(xy 3.028553 -55.142688) (xy 3.036062 -55.135272) (xy 3.054219 -55.116221) (xy 3.094859 -55.082782)
			(xy 3.139702 -55.055236) (xy 3.187901 -55.034102) (xy 3.238544 -55.019782) (xy 3.290672 -55.012546)
			(xy 3.316986 -55.012082) (xy 3.344239 -55.012545) (xy 3.39819 -55.020302) (xy 3.450489 -55.035657)
			(xy 3.500069 -55.0583) (xy 3.545923 -55.087767) (xy 3.587116 -55.123461) (xy 3.62281 -55.164654)
			(xy 3.652279 -55.210507) (xy 3.674921 -55.260088) (xy 3.690278 -55.312386) (xy 3.698035 -55.366337)
			(xy 3.698035 -55.420843) (xy 3.690278 -55.474794) (xy 3.674921 -55.527092) (xy 3.652279 -55.576673)
			(xy 3.62281 -55.622526) (xy 3.587116 -55.663719) (xy 3.545923 -55.699413) (xy 3.500069 -55.72888)
			(xy 3.450489 -55.751523) (xy 3.39819 -55.766878) (xy 3.344239 -55.774635) (xy 3.316986 -55.775098)
			(xy 3.290668 -55.774663) (xy 3.238531 -55.767444) (xy 3.187879 -55.753132) (xy 3.139674 -55.731998)
			(xy 3.094828 -55.704443) (xy 3.054193 -55.670988) (xy 3.036062 -55.651908) (xy 3.028566 -55.644471)
			(xy 3.00927 -55.635955) (xy 2.998724 -55.635398) (xy 2.924048 -55.635398) (xy 2.913511 -55.63598)
			(xy 2.894227 -55.644501) (xy 2.88671 -55.651908) (xy 2.868553 -55.670959) (xy 2.827913 -55.704396)
			(xy 2.783069 -55.731941) (xy 2.73487 -55.753072) (xy 2.684228 -55.767389) (xy 2.6321 -55.774622)
			(xy 2.605786 -55.775098) (xy 2.595798 -55.775046) (xy 2.575849 -55.77403) (xy 2.565908 -55.773066)
			(xy 2.55524 -55.77205) (xy 2.53492 -55.778654) (xy 2.470404 -55.836312) (xy 2.46275 -55.843832) (xy 2.454078 -55.863436)
			(xy 2.45364 -55.874158) (xy 2.45364 -57.48528) (xy 4.606034 -57.48528) (xy 4.610105 -57.429658) (xy 4.622231 -57.375221)
			(xy 4.642154 -57.32313) (xy 4.66945 -57.274495) (xy 4.703536 -57.230352) (xy 4.743685 -57.191643)
			(xy 4.789043 -57.159192) (xy 4.838643 -57.133691) (xy 4.891427 -57.115684) (xy 4.94627 -57.105554)
			(xy 5.002004 -57.103517) (xy 5.057441 -57.109617) (xy 5.111398 -57.123723) (xy 5.162727 -57.145535)
			(xy 5.210333 -57.174589) (xy 5.253201 -57.210264) (xy 5.290418 -57.251801) (xy 5.321191 -57.298314)
			(xy 5.344863 -57.348811) (xy 5.360931 -57.402218) (xy 5.369051 -57.457394) (xy 5.36956 -57.48528)
			(xy 5.369051 -57.513166) (xy 5.360931 -57.568342) (xy 5.344863 -57.621749) (xy 5.321191 -57.672246)
			(xy 5.290418 -57.718759) (xy 5.253201 -57.760296) (xy 5.210333 -57.795971) (xy 5.162727 -57.825025)
			(xy 5.111398 -57.846837) (xy 5.057441 -57.860943) (xy 5.002004 -57.867043) (xy 4.94627 -57.865006)
			(xy 4.891427 -57.854876) (xy 4.838643 -57.836869) (xy 4.789043 -57.811368) (xy 4.743685 -57.778917)
			(xy 4.703536 -57.740208) (xy 4.66945 -57.696065) (xy 4.642154 -57.64743) (xy 4.622231 -57.595339)
			(xy 4.610105 -57.540902) (xy 4.606034 -57.48528) (xy 2.45364 -57.48528) (xy 2.45364 -58.184542) (xy 2.454072 -58.194608)
			(xy 2.461802 -58.213197) (xy 2.468626 -58.22061) (xy 2.607564 -58.359548) (xy 2.614989 -58.366326)
			(xy 2.633585 -58.373925) (xy 2.643632 -58.37428) (xy 4.951476 -58.37428) (xy 4.96154 -58.373843)
			(xy 4.980122 -58.366106) (xy 4.987544 -58.359294) (xy 5.363464 -57.983374) (xy 5.367638 -57.979024)
			(xy 5.373941 -57.968752) (xy 5.37591 -57.963054) (xy 5.37591 -57.9628) (xy 5.384347 -57.937242) (xy 5.407401 -57.88861)
			(xy 5.437059 -57.843698) (xy 5.472733 -57.8034) (xy 5.513716 -57.768513) (xy 5.559193 -57.73973)
			(xy 5.608263 -57.717622) (xy 5.659952 -57.702628) (xy 5.713236 -57.695045) (xy 5.740146 -57.694576)
			(xy 5.767396 -57.695065) (xy 5.821339 -57.702827) (xy 5.873629 -57.718186) (xy 5.923202 -57.740829)
			(xy 5.969048 -57.770296) (xy 6.010234 -57.805988) (xy 6.045922 -57.847177) (xy 6.058851 -57.867296)
			(xy 7.643112 -57.867296) (xy 7.647183 -57.811674) (xy 7.659309 -57.757237) (xy 7.679232 -57.705146)
			(xy 7.706528 -57.656511) (xy 7.740614 -57.612368) (xy 7.780763 -57.573659) (xy 7.826121 -57.541208)
			(xy 7.875721 -57.515707) (xy 7.928505 -57.4977) (xy 7.983348 -57.48757) (xy 8.039082 -57.485533)
			(xy 8.094519 -57.491633) (xy 8.148476 -57.505739) (xy 8.199805 -57.527551) (xy 8.247411 -57.556605)
			(xy 8.290279 -57.59228) (xy 8.327496 -57.633817) (xy 8.358269 -57.68033) (xy 8.381941 -57.730827)
			(xy 8.398009 -57.784234) (xy 8.406129 -57.83941) (xy 8.406638 -57.867296) (xy 8.406129 -57.895182)
			(xy 8.398009 -57.950358) (xy 8.381941 -58.003765) (xy 8.358269 -58.054262) (xy 8.327496 -58.100775)
			(xy 8.290279 -58.142312) (xy 8.247411 -58.177987) (xy 8.199805 -58.207041) (xy 8.148476 -58.228853)
			(xy 8.094519 -58.242959) (xy 8.039082 -58.249059) (xy 7.983348 -58.247022) (xy 7.928505 -58.236892)
			(xy 7.875721 -58.218885) (xy 7.826121 -58.193384) (xy 7.780763 -58.160933) (xy 7.740614 -58.122224)
			(xy 7.706528 -58.078081) (xy 7.679232 -58.029446) (xy 7.659309 -57.977355) (xy 7.647183 -57.922918)
			(xy 7.643112 -57.867296) (xy 6.058851 -57.867296) (xy 6.075385 -57.893025) (xy 6.098025 -57.942599)
			(xy 6.11338 -57.99489) (xy 6.121137 -58.048834) (xy 6.121654 -58.076084) (xy 6.121192 -58.102985)
			(xy 6.113632 -58.156252) (xy 6.098664 -58.207929) (xy 6.076585 -58.256991) (xy 6.047833 -58.302465)
			(xy 6.012978 -58.343448) (xy 5.972711 -58.379129) (xy 5.927831 -58.4088) (xy 5.879227 -58.431871)
			(xy 5.853684 -58.44032) (xy 5.853176 -58.44032) (xy 5.847511 -58.442362) (xy 5.837241 -58.448641)
			(xy 5.832856 -58.452766) (xy 5.724398 -58.561224) (xy 6.562342 -58.561224) (xy 6.566413 -58.505602)
			(xy 6.578539 -58.451165) (xy 6.598462 -58.399074) (xy 6.625758 -58.350439) (xy 6.659844 -58.306296)
			(xy 6.699993 -58.267587) (xy 6.745351 -58.235136) (xy 6.794951 -58.209635) (xy 6.847735 -58.191628)
			(xy 6.902578 -58.181498) (xy 6.958312 -58.179461) (xy 7.013749 -58.185561) (xy 7.067706 -58.199667)
			(xy 7.119035 -58.221479) (xy 7.166641 -58.250533) (xy 7.209509 -58.286208) (xy 7.246726 -58.327745)
			(xy 7.277499 -58.374258) (xy 7.301171 -58.424755) (xy 7.317239 -58.478162) (xy 7.325359 -58.533338)
			(xy 7.325868 -58.561224) (xy 7.325359 -58.58911) (xy 7.317239 -58.644286) (xy 7.301171 -58.697693)
			(xy 7.277499 -58.74819) (xy 7.246726 -58.794703) (xy 7.209509 -58.83624) (xy 7.166641 -58.871915)
			(xy 7.119035 -58.900969) (xy 7.067706 -58.922781) (xy 7.013749 -58.936887) (xy 6.958312 -58.942987)
			(xy 6.902578 -58.94095) (xy 6.847735 -58.93082) (xy 6.794951 -58.912813) (xy 6.745351 -58.887312)
			(xy 6.699993 -58.854861) (xy 6.659844 -58.816152) (xy 6.625758 -58.772009) (xy 6.598462 -58.723374)
			(xy 6.578539 -58.671283) (xy 6.566413 -58.616846) (xy 6.562342 -58.561224) (xy 5.724398 -58.561224)
			(xy 5.616448 -58.669174) (xy 5.608372 -58.678233) (xy 5.600946 -58.701302) (xy 5.602224 -58.71337)
			(xy 5.617718 -58.80735) (xy 5.63245 -58.826908) (xy 5.643372 -58.832242) (xy 5.667025 -58.844373)
			(xy 5.711021 -58.874203) (xy 5.750453 -58.909851) (xy 5.784556 -58.950625) (xy 5.812671 -58.995738)
			(xy 5.834253 -59.044315) (xy 5.848886 -59.095418) (xy 5.856285 -59.148056) (xy 5.856732 -59.174634)
			(xy 5.856246 -59.201885) (xy 5.84849 -59.255833) (xy 5.833135 -59.308128) (xy 5.810493 -59.357705)
			(xy 5.781027 -59.403555) (xy 5.745336 -59.444746) (xy 5.704145 -59.480437) (xy 5.658295 -59.509903)
			(xy 5.608718 -59.532545) (xy 5.556423 -59.5479) (xy 5.502475 -59.555656) (xy 5.447973 -59.555656)
			(xy 5.394025 -59.5479) (xy 5.34173 -59.532545) (xy 5.292153 -59.509903) (xy 5.246303 -59.480437)
			(xy 5.205112 -59.444746) (xy 5.169421 -59.403555) (xy 5.139955 -59.357705) (xy 5.117313 -59.308128)
			(xy 5.101958 -59.255833) (xy 5.094202 -59.201885) (xy 5.093716 -59.174634) (xy 5.094732 -59.146948)
			(xy 5.095494 -59.136534) (xy 5.088382 -59.116722) (xy 5.03047 -59.054492) (xy 5.022998 -59.047161)
			(xy 5.003842 -59.038775) (xy 4.993386 -59.038236) (xy 2.485136 -59.038236) (xy 2.459056 -59.037734)
			(xy 2.407546 -59.029529) (xy 2.35796 -59.013347) (xy 2.334514 -59.001914) (xy 2.322576 -58.995818)
			(xy 2.296414 -58.996834) (xy 2.21107 -59.049158) (xy 2.203875 -59.054018) (xy 2.193003 -59.067543)
			(xy 2.187255 -59.083915) (xy 2.18694 -59.092592) (xy 2.18694 -62.121034) (xy 4.242306 -62.121034)
			(xy 4.246377 -62.065412) (xy 4.258503 -62.010975) (xy 4.278426 -61.958884) (xy 4.305722 -61.910249)
			(xy 4.339808 -61.866106) (xy 4.379957 -61.827397) (xy 4.425315 -61.794946) (xy 4.474915 -61.769445)
			(xy 4.527699 -61.751438) (xy 4.582542 -61.741308) (xy 4.638276 -61.739271) (xy 4.693713 -61.745371)
			(xy 4.74767 -61.759477) (xy 4.798999 -61.781289) (xy 4.846605 -61.810343) (xy 4.889473 -61.846018)
			(xy 4.92669 -61.887555) (xy 4.957463 -61.934068) (xy 4.981135 -61.984565) (xy 4.997203 -62.037972)
			(xy 5.005323 -62.093148) (xy 5.005832 -62.121034) (xy 5.005323 -62.14892) (xy 4.997203 -62.204096)
			(xy 4.981135 -62.257503) (xy 4.957463 -62.308) (xy 4.92669 -62.354513) (xy 4.889473 -62.39605) (xy 4.846605 -62.431725)
			(xy 4.798999 -62.460779) (xy 4.74767 -62.482591) (xy 4.693713 -62.496697) (xy 4.638276 -62.502797)
			(xy 4.582542 -62.50076) (xy 4.527699 -62.49063) (xy 4.474915 -62.472623) (xy 4.425315 -62.447122)
			(xy 4.379957 -62.414671) (xy 4.339808 -62.375962) (xy 4.305722 -62.331819) (xy 4.278426 -62.283184)
			(xy 4.258503 -62.231093) (xy 4.246377 -62.176656) (xy 4.242306 -62.121034) (xy 2.18694 -62.121034)
			(xy 2.18694 -64.254126) (xy 2.1874 -64.264004) (xy 2.194839 -64.282305) (xy 2.201418 -64.289686)
			(xy 2.258314 -64.347852) (xy 2.276348 -64.355726) (xy 2.286254 -64.355726) (xy 2.314025 -64.356797)
			(xy 2.368834 -64.365987) (xy 2.421729 -64.383033) (xy 2.47159 -64.407575) (xy 2.517362 -64.439093)
			(xy 2.558075 -64.47692) (xy 2.592868 -64.520255) (xy 2.621004 -64.56818) (xy 2.641887 -64.619681)
			(xy 2.648966 -64.646556) (xy 2.651485 -64.655205) (xy 2.66159 -64.670106) (xy 2.676207 -64.680618)
			(xy 2.68478 -64.683386)
		)
		(stroke
			(width 0)
			(type solid)
		)
		(fill yes)
		(layer "In5.Cu")
		(net "GND")
	)
	(gr_poly
		(pts
			(xy 364.823756 -94.554294) (xy 365.079026 -94.299024) (xy 365.082328 -94.289118) (xy 365.090645 -94.263398)
			(xy 365.113525 -94.214425) (xy 365.143093 -94.169174) (xy 365.178755 -94.128553) (xy 365.219796 -94.093375)
			(xy 365.265395 -94.064346) (xy 365.314636 -94.042049) (xy 365.366533 -94.02693) (xy 365.420045 -94.019291)
			(xy 365.447072 -94.018862) (xy 365.474325 -94.019346) (xy 365.528278 -94.027099) (xy 365.580578 -94.042451)
			(xy 365.63016 -94.065091) (xy 365.676016 -94.094556) (xy 365.717212 -94.130247) (xy 365.75291 -94.171437)
			(xy 365.782382 -94.217289) (xy 365.805028 -94.266868) (xy 365.820389 -94.319166) (xy 365.82815 -94.373117)
			(xy 365.82858 -94.40037) (xy 365.82851 -94.410806) (xy 365.827366 -94.431645) (xy 365.826294 -94.442026)
			(xy 365.825024 -94.452948) (xy 365.828326 -94.463108) (xy 365.830067 -94.468121) (xy 365.835313 -94.477344)
			(xy 365.83874 -94.481396) (xy 365.88954 -94.537784) (xy 365.897106 -94.545402) (xy 365.916666 -94.554191)
			(xy 365.927386 -94.554802) (xy 365.954564 -94.554802) (xy 365.965806 -94.554224) (xy 365.986125 -94.544604)
			(xy 365.99368 -94.53626) (xy 366.043718 -94.475554) (xy 366.047121 -94.47119) (xy 366.05213 -94.461324)
			(xy 366.053624 -94.455996) (xy 366.056418 -94.445582) (xy 366.054132 -94.433898) (xy 366.050927 -94.416164)
			(xy 366.047489 -94.38029) (xy 366.047274 -94.36227) (xy 366.047274 -94.361508) (xy 366.04776 -94.334257)
			(xy 366.055516 -94.280309) (xy 366.070871 -94.228014) (xy 366.093513 -94.178437) (xy 366.122979 -94.132587)
			(xy 366.15867 -94.091396) (xy 366.199861 -94.055705) (xy 366.245711 -94.026239) (xy 366.295288 -94.003597)
			(xy 366.347583 -93.988242) (xy 366.401531 -93.980486) (xy 366.456033 -93.980486) (xy 366.509981 -93.988242)
			(xy 366.562276 -94.003597) (xy 366.611853 -94.026239) (xy 366.657703 -94.055705) (xy 366.698894 -94.091396)
			(xy 366.734585 -94.132587) (xy 366.764051 -94.178437) (xy 366.786693 -94.228014) (xy 366.802048 -94.280309)
			(xy 366.809804 -94.334257) (xy 366.81029 -94.361508) (xy 366.81029 -94.36227) (xy 366.810054 -94.380288)
			(xy 366.806616 -94.416161) (xy 366.803432 -94.433898) (xy 366.801146 -94.445582) (xy 366.80394 -94.455996)
			(xy 366.805469 -94.461311) (xy 366.81047 -94.471173) (xy 366.813846 -94.475554) (xy 366.863884 -94.53626)
			(xy 366.871487 -94.544539) (xy 366.891778 -94.55415) (xy 366.903 -94.554802) (xy 371.19814 -94.554802)
			(xy 371.205252 -94.554294) (xy 371.564154 -94.195646) (xy 371.570997 -94.188247) (xy 371.578719 -94.169648)
			(xy 371.57914 -94.159578) (xy 371.57914 -80.19923) (xy 371.579669 -80.173207) (xy 371.587838 -80.121805)
			(xy 371.603934 -80.072309) (xy 371.627562 -80.025934) (xy 371.658142 -79.983818) (xy 371.676168 -79.965042)
			(xy 374.917462 -76.724002) (xy 374.924313 -76.716605) (xy 374.932054 -76.698007) (xy 374.932448 -76.687934)
			(xy 374.932448 -65.542668) (xy 374.932018 -65.532602) (xy 374.924289 -65.51401) (xy 374.917462 -65.5066)
			(xy 374.42521 -65.014348) (xy 374.417814 -65.007495) (xy 374.399216 -64.999749) (xy 374.389142 -64.999362)
			(xy 373.816372 -64.999362) (xy 373.812054 -65.000124) (xy 373.79757 -65.002531) (xy 373.768316 -65.005071)
			(xy 373.753634 -65.005204) (xy 369.79606 -65.005204) (xy 369.785993 -65.005635) (xy 369.7674 -65.01336)
			(xy 369.759992 -65.02019) (xy 369.248944 -65.531238) (xy 369.241546 -65.538082) (xy 369.222947 -65.545806)
			(xy 369.212876 -65.546224) (xy 368.826034 -65.546224) (xy 368.815969 -65.54579) (xy 368.797379 -65.538061)
			(xy 368.789966 -65.531238) (xy 368.742214 -65.483486) (xy 368.731546 -65.475358) (xy 368.725958 -65.472056)
			(xy 368.7191 -65.470278) (xy 368.693863 -65.463304) (xy 368.645442 -65.443388) (xy 368.600196 -65.417041)
			(xy 368.558976 -65.384757) (xy 368.522554 -65.347143) (xy 368.491615 -65.304904) (xy 368.478816 -65.282064)
			(xy 368.47526 -65.27546) (xy 368.243104 -65.043304) (xy 368.235706 -65.036456) (xy 368.217108 -65.02872)
			(xy 368.207036 -65.028318) (xy 367.73612 -65.028318) (xy 367.726057 -65.028756) (xy 367.707475 -65.036493)
			(xy 367.700052 -65.043304) (xy 366.760506 -65.983104) (xy 366.742321 -66.000564) (xy 366.701525 -66.030175)
			(xy 366.656608 -66.053059) (xy 366.608671 -66.068654) (xy 366.558888 -66.076578) (xy 366.533684 -66.077084)
			(xy 366.511586 -66.077084) (xy 366.505744 -66.078354) (xy 366.486967 -66.082501) (xy 366.448771 -66.086957)
			(xy 366.429544 -66.087244) (xy 363.21746 -66.087244) (xy 363.209332 -66.091308) (xy 363.181406 -66.105643)
			(xy 363.122028 -66.125987) (xy 363.060121 -66.136335) (xy 363.028738 -66.137028) (xy 362.997356 -66.136345)
			(xy 362.935452 -66.125981) (xy 362.876079 -66.105624) (xy 362.848144 -66.091308) (xy 362.840016 -66.087244)
			(xy 362.361226 -66.087244) (xy 362.351163 -66.087682) (xy 362.332582 -66.09542) (xy 362.325158 -66.10223)
			(xy 361.456986 -66.970402) (xy 361.450131 -66.977797) (xy 361.442383 -66.996395) (xy 361.442 -67.00647)
			(xy 361.442 -67.128949) (xy 362.666798 -67.128949) (xy 362.666798 -67.074451) (xy 362.674554 -67.020507)
			(xy 362.689908 -66.968216) (xy 362.712547 -66.918642) (xy 362.74201 -66.872795) (xy 362.777699 -66.831607)
			(xy 362.818885 -66.795918) (xy 362.864732 -66.766452) (xy 362.914305 -66.743812) (xy 362.966595 -66.728457)
			(xy 363.020539 -66.720699) (xy 363.047788 -66.720212) (xy 363.075158 -66.720682) (xy 363.129337 -66.728499)
			(xy 363.18184 -66.743987) (xy 363.231587 -66.766827) (xy 363.277554 -66.796551) (xy 363.298486 -66.814192)
			(xy 363.29874 -66.814446) (xy 363.305836 -66.820019) (xy 363.322746 -66.826273) (xy 363.33176 -66.826638)
			(xy 363.398816 -66.826638) (xy 363.407833 -66.826281) (xy 363.424749 -66.820032) (xy 363.431836 -66.814446)
			(xy 363.431836 -66.814192) (xy 363.43209 -66.814192) (xy 363.453014 -66.796543) (xy 363.498989 -66.766833)
			(xy 363.548739 -66.743999) (xy 363.601241 -66.72851) (xy 363.655418 -66.720685) (xy 363.682788 -66.720212)
			(xy 363.710043 -66.720634) (xy 363.763998 -66.72839) (xy 363.8163 -66.743746) (xy 363.865884 -66.766389)
			(xy 363.911741 -66.795858) (xy 363.952938 -66.831554) (xy 363.988635 -66.872749) (xy 364.018105 -66.918605)
			(xy 364.04075 -66.968189) (xy 364.056107 -67.02049) (xy 364.063865 -67.074445) (xy 364.063865 -67.128955)
			(xy 364.056107 -67.18291) (xy 364.04075 -67.235211) (xy 364.018105 -67.284795) (xy 363.988635 -67.330651)
			(xy 363.952938 -67.371846) (xy 363.911741 -67.407542) (xy 363.865884 -67.437011) (xy 363.8163 -67.459654)
			(xy 363.763998 -67.47501) (xy 363.710043 -67.482766) (xy 363.682788 -67.483228) (xy 363.655417 -67.482787)
			(xy 363.601236 -67.474965) (xy 363.548732 -67.459472) (xy 363.498985 -67.436624) (xy 363.45302 -67.406893)
			(xy 363.43209 -67.389248) (xy 363.431836 -67.388994) (xy 363.424744 -67.383416) (xy 363.407831 -67.377164)
			(xy 363.398816 -67.376802) (xy 363.33176 -67.376802) (xy 363.322741 -67.37714) (xy 363.305824 -67.383401)
			(xy 363.29874 -67.388994) (xy 363.29874 -67.389248) (xy 363.298486 -67.389248) (xy 363.277526 -67.406852)
			(xy 363.231561 -67.436571) (xy 363.181821 -67.459415) (xy 363.129326 -67.474914) (xy 363.075155 -67.48275)
			(xy 363.047788 -67.483228) (xy 363.020539 -67.482701) (xy 362.966595 -67.474943) (xy 362.914305 -67.459588)
			(xy 362.864732 -67.436948) (xy 362.818885 -67.407482) (xy 362.777699 -67.371793) (xy 362.74201 -67.330605)
			(xy 362.712547 -67.284758) (xy 362.689908 -67.235184) (xy 362.674554 -67.182893) (xy 362.666798 -67.128949)
			(xy 361.442 -67.128949) (xy 361.442 -67.488054) (xy 367.079274 -67.488054) (xy 367.083345 -67.432432)
			(xy 367.095471 -67.377995) (xy 367.115394 -67.325904) (xy 367.14269 -67.277269) (xy 367.176776 -67.233126)
			(xy 367.216925 -67.194417) (xy 367.262283 -67.161966) (xy 367.311883 -67.136465) (xy 367.364667 -67.118458)
			(xy 367.41951 -67.108328) (xy 367.475244 -67.106291) (xy 367.530681 -67.112391) (xy 367.584638 -67.126497)
			(xy 367.635967 -67.148309) (xy 367.683573 -67.177363) (xy 367.726441 -67.213038) (xy 367.763658 -67.254575)
			(xy 367.794431 -67.301088) (xy 367.818103 -67.351585) (xy 367.834171 -67.404992) (xy 367.842291 -67.460168)
			(xy 367.8428 -67.488054) (xy 367.842291 -67.51594) (xy 367.839106 -67.537584) (xy 368.371372 -67.537584)
			(xy 368.375443 -67.481962) (xy 368.387569 -67.427525) (xy 368.407492 -67.375434) (xy 368.434788 -67.326799)
			(xy 368.468874 -67.282656) (xy 368.509023 -67.243947) (xy 368.554381 -67.211496) (xy 368.603981 -67.185995)
			(xy 368.656765 -67.167988) (xy 368.711608 -67.157858) (xy 368.767342 -67.155821) (xy 368.822779 -67.161921)
			(xy 368.876736 -67.176027) (xy 368.928065 -67.197839) (xy 368.975671 -67.226893) (xy 369.018539 -67.262568)
			(xy 369.055756 -67.304105) (xy 369.086529 -67.350618) (xy 369.110201 -67.401115) (xy 369.126269 -67.454522)
			(xy 369.134389 -67.509698) (xy 369.134898 -67.537584) (xy 369.134389 -67.56547) (xy 369.130344 -67.592956)
			(xy 369.645436 -67.592956) (xy 369.649507 -67.537334) (xy 369.661633 -67.482897) (xy 369.681556 -67.430806)
			(xy 369.708852 -67.382171) (xy 369.742938 -67.338028) (xy 369.783087 -67.299319) (xy 369.828445 -67.266868)
			(xy 369.878045 -67.241367) (xy 369.930829 -67.22336) (xy 369.985672 -67.21323) (xy 370.041406 -67.211193)
			(xy 370.096843 -67.217293) (xy 370.1508 -67.231399) (xy 370.202129 -67.253211) (xy 370.249735 -67.282265)
			(xy 370.292603 -67.31794) (xy 370.32982 -67.359477) (xy 370.360593 -67.40599) (xy 370.384265 -67.456487)
			(xy 370.400333 -67.509894) (xy 370.40845 -67.565048) (xy 372.746816 -67.565048) (xy 372.746816 -67.510553)
			(xy 372.754571 -67.456612) (xy 372.769924 -67.404324) (xy 372.792561 -67.354754) (xy 372.822022 -67.308909)
			(xy 372.857708 -67.267723) (xy 372.898891 -67.232035) (xy 372.944734 -67.202572) (xy 372.994304 -67.179931)
			(xy 373.046591 -67.164576) (xy 373.100531 -67.156818) (xy 373.127778 -67.15633) (xy 373.155148 -67.156802)
			(xy 373.209327 -67.164617) (xy 373.261831 -67.180104) (xy 373.311578 -67.202945) (xy 373.357544 -67.232669)
			(xy 373.378476 -67.25031) (xy 373.37873 -67.250564) (xy 373.385827 -67.256135) (xy 373.402736 -67.262389)
			(xy 373.41175 -67.262756) (xy 373.478806 -67.262756) (xy 373.487824 -67.262411) (xy 373.504742 -67.256156)
			(xy 373.511826 -67.250564) (xy 373.511826 -67.25031) (xy 373.51208 -67.25031) (xy 373.53301 -67.232668)
			(xy 373.578983 -67.202957) (xy 373.628731 -67.180121) (xy 373.681232 -67.164631) (xy 373.735409 -67.156803)
			(xy 373.762778 -67.15633) (xy 373.790035 -67.156715) (xy 373.843993 -67.164471) (xy 373.896299 -67.179826)
			(xy 373.945887 -67.20247) (xy 373.991748 -67.23194) (xy 374.032947 -67.267637) (xy 374.068647 -67.308835)
			(xy 374.09812 -67.354694) (xy 374.120766 -67.40428) (xy 374.136125 -67.456585) (xy 374.143883 -67.510543)
			(xy 374.143883 -67.565057) (xy 374.136125 -67.619015) (xy 374.120766 -67.67132) (xy 374.09812 -67.720906)
			(xy 374.068647 -67.766765) (xy 374.032947 -67.807963) (xy 373.991748 -67.84366) (xy 373.945887 -67.87313)
			(xy 373.896299 -67.895774) (xy 373.843993 -67.911129) (xy 373.790035 -67.918885) (xy 373.762778 -67.919346)
			(xy 373.735407 -67.918906) (xy 373.681226 -67.911084) (xy 373.628722 -67.895589) (xy 373.578976 -67.872742)
			(xy 373.53301 -67.843011) (xy 373.51208 -67.825366) (xy 373.511826 -67.825112) (xy 373.504735 -67.819532)
			(xy 373.487822 -67.813281) (xy 373.478806 -67.81292) (xy 373.41175 -67.81292) (xy 373.402735 -67.813297)
			(xy 373.385818 -67.81953) (xy 373.37873 -67.825112) (xy 373.37873 -67.825366) (xy 373.378476 -67.825366)
			(xy 373.357522 -67.842978) (xy 373.311556 -67.872695) (xy 373.261814 -67.895537) (xy 373.209318 -67.911034)
			(xy 373.155146 -67.918869) (xy 373.127778 -67.919346) (xy 373.100531 -67.918782) (xy 373.046591 -67.911024)
			(xy 372.994304 -67.895669) (xy 372.944734 -67.873028) (xy 372.898891 -67.843565) (xy 372.857708 -67.807877)
			(xy 372.822022 -67.766691) (xy 372.792561 -67.720846) (xy 372.769924 -67.671276) (xy 372.754571 -67.618988)
			(xy 372.746816 -67.565048) (xy 370.40845 -67.565048) (xy 370.408453 -67.56507) (xy 370.408962 -67.592956)
			(xy 370.408453 -67.620842) (xy 370.400333 -67.676018) (xy 370.384265 -67.729425) (xy 370.360593 -67.779922)
			(xy 370.32982 -67.826435) (xy 370.292603 -67.867972) (xy 370.249735 -67.903647) (xy 370.202129 -67.932701)
			(xy 370.1508 -67.954513) (xy 370.096843 -67.968619) (xy 370.041406 -67.974719) (xy 369.985672 -67.972682)
			(xy 369.930829 -67.962552) (xy 369.878045 -67.944545) (xy 369.828445 -67.919044) (xy 369.783087 -67.886593)
			(xy 369.742938 -67.847884) (xy 369.708852 -67.803741) (xy 369.681556 -67.755106) (xy 369.661633 -67.703015)
			(xy 369.649507 -67.648578) (xy 369.645436 -67.592956) (xy 369.130344 -67.592956) (xy 369.126269 -67.620646)
			(xy 369.110201 -67.674053) (xy 369.086529 -67.72455) (xy 369.055756 -67.771063) (xy 369.018539 -67.8126)
			(xy 368.975671 -67.848275) (xy 368.928065 -67.877329) (xy 368.876736 -67.899141) (xy 368.822779 -67.913247)
			(xy 368.767342 -67.919347) (xy 368.711608 -67.91731) (xy 368.656765 -67.90718) (xy 368.603981 -67.889173)
			(xy 368.554381 -67.863672) (xy 368.509023 -67.831221) (xy 368.468874 -67.792512) (xy 368.434788 -67.748369)
			(xy 368.407492 -67.699734) (xy 368.387569 -67.647643) (xy 368.375443 -67.593206) (xy 368.371372 -67.537584)
			(xy 367.839106 -67.537584) (xy 367.834171 -67.571116) (xy 367.818103 -67.624523) (xy 367.794431 -67.67502)
			(xy 367.763658 -67.721533) (xy 367.726441 -67.76307) (xy 367.683573 -67.798745) (xy 367.635967 -67.827799)
			(xy 367.584638 -67.849611) (xy 367.530681 -67.863717) (xy 367.475244 -67.869817) (xy 367.41951 -67.86778)
			(xy 367.364667 -67.85765) (xy 367.311883 -67.839643) (xy 367.262283 -67.814142) (xy 367.216925 -67.781691)
			(xy 367.176776 -67.742982) (xy 367.14269 -67.698839) (xy 367.115394 -67.650204) (xy 367.095471 -67.598113)
			(xy 367.083345 -67.543676) (xy 367.079274 -67.488054) (xy 361.442 -67.488054) (xy 361.442 -68.586604)
			(xy 364.925356 -68.586604) (xy 364.925811 -68.559233) (xy 364.933629 -68.505053) (xy 364.94912 -68.452549)
			(xy 364.971965 -68.402803) (xy 365.001693 -68.356837) (xy 365.019336 -68.335906) (xy 365.01959 -68.335652)
			(xy 365.02516 -68.328554) (xy 365.031417 -68.311646) (xy 365.031782 -68.302632) (xy 365.031782 -68.235576)
			(xy 365.03144 -68.226557) (xy 365.025183 -68.20964) (xy 365.01959 -68.202556) (xy 365.019336 -68.202556)
			(xy 365.019336 -68.202302) (xy 365.00169 -68.181375) (xy 364.971978 -68.135402) (xy 364.949143 -68.085653)
			(xy 364.933653 -68.033151) (xy 364.925828 -67.978974) (xy 364.925356 -67.951604) (xy 364.925881 -67.924354)
			(xy 364.933636 -67.87041) (xy 364.948989 -67.818118) (xy 364.971627 -67.768543) (xy 365.00109 -67.722695)
			(xy 365.036777 -67.681505) (xy 365.077963 -67.645814) (xy 365.123808 -67.616346) (xy 365.173381 -67.593703)
			(xy 365.225671 -67.578345) (xy 365.279615 -67.570584) (xy 365.306864 -67.570096) (xy 365.333179 -67.570522)
			(xy 365.38531 -67.577766) (xy 365.435953 -67.592093) (xy 365.484152 -67.613233) (xy 365.528994 -67.640786)
			(xy 365.569632 -67.674231) (xy 365.587788 -67.693286) (xy 365.595314 -67.700682) (xy 365.614591 -67.70921)
			(xy 365.625126 -67.709796) (xy 365.699802 -67.709796) (xy 365.710354 -67.709282) (xy 365.729649 -67.700736)
			(xy 365.73714 -67.693286) (xy 365.75528 -67.674215) (xy 365.795914 -67.64076) (xy 365.840757 -67.613203)
			(xy 365.888961 -67.592068) (xy 365.939611 -67.577754) (xy 365.991747 -67.570533) (xy 366.018064 -67.570096)
			(xy 366.045433 -67.570584) (xy 366.099612 -67.578397) (xy 366.152114 -67.593881) (xy 366.201862 -67.616718)
			(xy 366.247829 -67.646437) (xy 366.268762 -67.664076) (xy 366.269016 -67.66433) (xy 366.276091 -67.669933)
			(xy 366.293017 -67.676169) (xy 366.302036 -67.676522) (xy 366.369092 -67.676522) (xy 366.378108 -67.676156)
			(xy 366.395025 -67.669914) (xy 366.402112 -67.66433) (xy 366.402112 -67.664076) (xy 366.402366 -67.664076)
			(xy 366.423297 -67.646436) (xy 366.46927 -67.616725) (xy 366.519018 -67.59389) (xy 366.571519 -67.578399)
			(xy 366.625695 -67.57057) (xy 366.653064 -67.570096) (xy 366.680316 -67.570589) (xy 366.734266 -67.578341)
			(xy 366.786564 -67.593693) (xy 366.836144 -67.616331) (xy 366.881998 -67.645796) (xy 366.923191 -67.681487)
			(xy 366.958885 -67.722677) (xy 366.988353 -67.768528) (xy 367.010996 -67.818106) (xy 367.026352 -67.870402)
			(xy 367.034109 -67.924352) (xy 367.034572 -67.951604) (xy 367.034115 -67.978975) (xy 367.026296 -68.033154)
			(xy 367.010805 -68.085658) (xy 366.987961 -68.135405) (xy 366.958234 -68.181371) (xy 366.940592 -68.202302)
			(xy 366.940338 -68.202556) (xy 366.934756 -68.209646) (xy 366.928508 -68.22656) (xy 366.928146 -68.235576)
			(xy 366.928146 -68.302632) (xy 366.928478 -68.311652) (xy 366.934742 -68.328569) (xy 366.940338 -68.335652)
			(xy 366.940592 -68.335652) (xy 366.940592 -68.335906) (xy 366.958246 -68.356826) (xy 366.987956 -68.402802)
			(xy 367.010789 -68.452553) (xy 367.026277 -68.505056) (xy 367.0341 -68.559234) (xy 367.034572 -68.586604)
			(xy 367.034148 -68.613859) (xy 367.02639 -68.667813) (xy 367.011031 -68.720114) (xy 366.994399 -68.75653)
			(xy 370.47043 -68.75653) (xy 370.470906 -68.72916) (xy 370.478721 -68.674981) (xy 370.494207 -68.622478)
			(xy 370.517046 -68.572731) (xy 370.546769 -68.526764) (xy 370.56441 -68.505832) (xy 370.564664 -68.505578)
			(xy 370.570273 -68.498507) (xy 370.576505 -68.481578) (xy 370.576856 -68.472558) (xy 370.576856 -68.405502)
			(xy 370.576507 -68.396484) (xy 370.570255 -68.379567) (xy 370.564664 -68.372482) (xy 370.56441 -68.372482)
			(xy 370.56441 -68.372228) (xy 370.546772 -68.351295) (xy 370.51706 -68.305323) (xy 370.494223 -68.255575)
			(xy 370.478732 -68.203075) (xy 370.470904 -68.148899) (xy 370.47043 -68.12153) (xy 370.470883 -68.094276)
			(xy 370.478637 -68.040323) (xy 370.493991 -67.988023) (xy 370.516633 -67.93844) (xy 370.546102 -67.892585)
			(xy 370.581797 -67.851391) (xy 370.622991 -67.815697) (xy 370.668847 -67.786229) (xy 370.71843 -67.763589)
			(xy 370.770731 -67.748236) (xy 370.824684 -67.740483) (xy 370.851938 -67.740022) (xy 370.879307 -67.740519)
			(xy 370.933485 -67.748329) (xy 370.985988 -67.76381) (xy 371.035736 -67.786645) (xy 371.081704 -67.816364)
			(xy 371.102636 -67.834002) (xy 371.10289 -67.834256) (xy 371.10997 -67.839851) (xy 371.126892 -67.846091)
			(xy 371.13591 -67.846448) (xy 371.202966 -67.846448) (xy 371.211983 -67.846086) (xy 371.2289 -67.839843)
			(xy 371.235986 -67.834256) (xy 371.235986 -67.834002) (xy 371.23624 -67.834002) (xy 371.257184 -67.816378)
			(xy 371.303154 -67.786664) (xy 371.352898 -67.763825) (xy 371.405396 -67.74833) (xy 371.45957 -67.740498)
			(xy 371.486938 -67.740022) (xy 371.513253 -67.740457) (xy 371.565383 -67.747698) (xy 371.616027 -67.762023)
			(xy 371.664226 -67.783161) (xy 371.709069 -67.810713) (xy 371.749707 -67.844158) (xy 371.767862 -67.863212)
			(xy 371.775394 -67.870601) (xy 371.794666 -67.879132) (xy 371.8052 -67.879722) (xy 371.879876 -67.879722)
			(xy 371.890425 -67.879187) (xy 371.90972 -67.870655) (xy 371.917214 -67.863212) (xy 371.935372 -67.844159)
			(xy 371.976001 -67.810701) (xy 372.020841 -67.783141) (xy 372.069041 -67.762002) (xy 372.119688 -67.747685)
			(xy 372.171822 -67.74046) (xy 372.198138 -67.740022) (xy 372.225392 -67.740443) (xy 372.279343 -67.748205)
			(xy 372.331641 -67.763566) (xy 372.38122 -67.786214) (xy 372.427072 -67.815687) (xy 372.468263 -67.851386)
			(xy 372.503954 -67.892583) (xy 372.533418 -67.938439) (xy 372.556057 -67.988023) (xy 372.571409 -68.040323)
			(xy 372.579162 -68.094276) (xy 372.579646 -68.12153) (xy 372.579211 -68.148901) (xy 372.571387 -68.203082)
			(xy 372.555892 -68.255586) (xy 372.533043 -68.305333) (xy 372.503311 -68.351298) (xy 372.485666 -68.372228)
			(xy 372.485412 -68.372482) (xy 372.479828 -68.379571) (xy 372.473579 -68.396486) (xy 372.47322 -68.405502)
			(xy 372.47322 -68.472558) (xy 372.473593 -68.481573) (xy 372.479829 -68.498491) (xy 372.485412 -68.505578)
			(xy 372.485666 -68.505578) (xy 372.485666 -68.505832) (xy 372.503281 -68.526783) (xy 372.532998 -68.57275)
			(xy 372.555839 -68.622493) (xy 372.571336 -68.674989) (xy 372.579169 -68.729162) (xy 372.579646 -68.75653)
			(xy 372.57915 -68.78378) (xy 372.571391 -68.837726) (xy 372.556034 -68.890018) (xy 372.533392 -68.939593)
			(xy 372.503926 -68.985441) (xy 372.468236 -69.02663) (xy 372.427048 -69.062321) (xy 372.3812 -69.091788)
			(xy 372.331625 -69.114431) (xy 372.279333 -69.129789) (xy 372.225388 -69.13755) (xy 372.198138 -69.138038)
			(xy 372.171822 -69.137632) (xy 372.11969 -69.130387) (xy 372.069045 -69.116057) (xy 372.020846 -69.094914)
			(xy 371.976004 -69.067356) (xy 371.935368 -69.033905) (xy 371.917214 -69.014848) (xy 371.909683 -69.007458)
			(xy 371.89041 -68.998925) (xy 371.879876 -68.998338) (xy 371.8052 -68.998338) (xy 371.794647 -68.998842)
			(xy 371.775351 -69.007394) (xy 371.767862 -69.014848) (xy 371.749727 -69.033924) (xy 371.709092 -69.067378)
			(xy 371.664247 -69.094933) (xy 371.616042 -69.116067) (xy 371.565392 -69.130381) (xy 371.513255 -69.137601)
			(xy 371.486938 -69.138038) (xy 371.459568 -69.137565) (xy 371.405388 -69.129751) (xy 371.352885 -69.114264)
			(xy 371.303138 -69.091424) (xy 371.257171 -69.061699) (xy 371.23624 -69.044058) (xy 371.235986 -69.043804)
			(xy 371.228907 -69.038206) (xy 371.211985 -69.031966) (xy 371.202966 -69.031612) (xy 371.13591 -69.031612)
			(xy 371.126893 -69.031971) (xy 371.109976 -69.038217) (xy 371.10289 -69.043804) (xy 371.10289 -69.044058)
			(xy 371.102636 -69.044058) (xy 371.081696 -69.061687) (xy 371.035726 -69.091402) (xy 370.985981 -69.11424)
			(xy 370.933481 -69.129734) (xy 370.879307 -69.137563) (xy 370.851938 -69.138038) (xy 370.824687 -69.137509)
			(xy 370.77074 -69.129758) (xy 370.718446 -69.114409) (xy 370.668868 -69.091773) (xy 370.623016 -69.062312)
			(xy 370.581823 -69.026625) (xy 370.546129 -68.985439) (xy 370.51666 -68.939592) (xy 370.494015 -68.890018)
			(xy 370.478656 -68.837726) (xy 370.470895 -68.78378) (xy 370.47043 -68.75653) (xy 366.994399 -68.75653)
			(xy 366.988386 -68.769696) (xy 366.958914 -68.815551) (xy 366.923216 -68.856745) (xy 366.882019 -68.892438)
			(xy 366.836161 -68.921905) (xy 366.786576 -68.944545) (xy 366.734274 -68.959898) (xy 366.680319 -68.967651)
			(xy 366.653064 -68.968112) (xy 366.625693 -68.967664) (xy 366.571513 -68.959841) (xy 366.51901 -68.944348)
			(xy 366.469264 -68.921502) (xy 366.423297 -68.891775) (xy 366.402366 -68.874132) (xy 366.402112 -68.873878)
			(xy 366.395028 -68.868288) (xy 366.378109 -68.862044) (xy 366.369092 -68.861686) (xy 366.302036 -68.861686)
			(xy 366.293021 -68.862063) (xy 366.276104 -68.868297) (xy 366.269016 -68.873878) (xy 366.269016 -68.874132)
			(xy 366.268762 -68.874132) (xy 366.247821 -68.89176) (xy 366.20185 -68.921473) (xy 366.152105 -68.94431)
			(xy 366.099606 -68.959804) (xy 366.045433 -68.967636) (xy 366.018064 -68.968112) (xy 365.991749 -68.967665)
			(xy 365.93962 -68.960425) (xy 365.888977 -68.946102) (xy 365.840778 -68.924966) (xy 365.795935 -68.897416)
			(xy 365.755296 -68.863975) (xy 365.73714 -68.844922) (xy 365.729603 -68.837539) (xy 365.710335 -68.829003)
			(xy 365.699802 -68.828412) (xy 365.625126 -68.828412) (xy 365.614576 -68.828938) (xy 365.59528 -68.837475)
			(xy 365.587788 -68.844922) (xy 365.569636 -68.863981) (xy 365.529005 -68.897437) (xy 365.484164 -68.924995)
			(xy 365.435962 -68.946132) (xy 365.385314 -68.960449) (xy 365.33318 -68.967674) (xy 365.306864 -68.968112)
			(xy 365.279612 -68.967656) (xy 365.225663 -68.959894) (xy 365.173368 -68.944535) (xy 365.123791 -68.92189)
			(xy 365.077941 -68.89242) (xy 365.036752 -68.856726) (xy 365.001061 -68.815533) (xy 364.971595 -68.769681)
			(xy 364.948954 -68.720102) (xy 364.933599 -68.667805) (xy 364.925842 -68.613856) (xy 364.925356 -68.586604)
			(xy 361.442 -68.586604) (xy 361.442 -71.555864) (xy 367.494564 -71.555864) (xy 367.498635 -71.500242)
			(xy 367.510761 -71.445805) (xy 367.530684 -71.393714) (xy 367.55798 -71.345079) (xy 367.592066 -71.300936)
			(xy 367.632215 -71.262227) (xy 367.677573 -71.229776) (xy 367.727173 -71.204275) (xy 367.779957 -71.186268)
			(xy 367.8348 -71.176138) (xy 367.890534 -71.174101) (xy 367.945971 -71.180201) (xy 367.999928 -71.194307)
			(xy 368.051257 -71.216119) (xy 368.098863 -71.245173) (xy 368.141731 -71.280848) (xy 368.178948 -71.322385)
			(xy 368.209721 -71.368898) (xy 368.233393 -71.419395) (xy 368.249461 -71.472802) (xy 368.257581 -71.527978)
			(xy 368.25809 -71.555864) (xy 368.257581 -71.58375) (xy 368.251742 -71.623428) (xy 369.003578 -71.623428)
			(xy 369.007649 -71.567806) (xy 369.019775 -71.513369) (xy 369.039698 -71.461278) (xy 369.066994 -71.412643)
			(xy 369.10108 -71.3685) (xy 369.141229 -71.329791) (xy 369.186587 -71.29734) (xy 369.236187 -71.271839)
			(xy 369.288971 -71.253832) (xy 369.343814 -71.243702) (xy 369.399548 -71.241665) (xy 369.454985 -71.247765)
			(xy 369.508942 -71.261871) (xy 369.560271 -71.283683) (xy 369.607877 -71.312737) (xy 369.650745 -71.348412)
			(xy 369.687962 -71.389949) (xy 369.718735 -71.436462) (xy 369.742407 -71.486959) (xy 369.758475 -71.540366)
			(xy 369.766595 -71.595542) (xy 369.767104 -71.623428) (xy 369.766595 -71.651314) (xy 369.758475 -71.70649)
			(xy 369.742407 -71.759897) (xy 369.718735 -71.810394) (xy 369.687962 -71.856907) (xy 369.650745 -71.898444)
			(xy 369.607877 -71.934119) (xy 369.560271 -71.963173) (xy 369.508942 -71.984985) (xy 369.454985 -71.999091)
			(xy 369.399548 -72.005191) (xy 369.343814 -72.003154) (xy 369.288971 -71.993024) (xy 369.236187 -71.975017)
			(xy 369.186587 -71.949516) (xy 369.141229 -71.917065) (xy 369.10108 -71.878356) (xy 369.066994 -71.834213)
			(xy 369.039698 -71.785578) (xy 369.019775 -71.733487) (xy 369.007649 -71.67905) (xy 369.003578 -71.623428)
			(xy 368.251742 -71.623428) (xy 368.249461 -71.638926) (xy 368.233393 -71.692333) (xy 368.209721 -71.74283)
			(xy 368.178948 -71.789343) (xy 368.141731 -71.83088) (xy 368.098863 -71.866555) (xy 368.051257 -71.895609)
			(xy 367.999928 -71.917421) (xy 367.945971 -71.931527) (xy 367.890534 -71.937627) (xy 367.8348 -71.93559)
			(xy 367.779957 -71.92546) (xy 367.727173 -71.907453) (xy 367.677573 -71.881952) (xy 367.632215 -71.849501)
			(xy 367.592066 -71.810792) (xy 367.55798 -71.766649) (xy 367.530684 -71.718014) (xy 367.510761 -71.665923)
			(xy 367.498635 -71.611486) (xy 367.494564 -71.555864) (xy 361.442 -71.555864) (xy 361.442 -74.663808)
			(xy 361.441736 -74.683037) (xy 361.437281 -74.721235) (xy 361.43311 -74.740008) (xy 361.43184 -74.74585)
			(xy 361.43184 -75.376532) (xy 361.43131 -75.401734) (xy 361.423375 -75.451512) (xy 361.40778 -75.499445)
			(xy 361.384909 -75.544364) (xy 361.355318 -75.58517) (xy 361.33786 -75.603354) (xy 355.95687 -80.98409)
			(xy 355.952044 -80.989678) (xy 355.948404 -80.994795) (xy 355.943524 -81.006361) (xy 355.942392 -81.012538)
			(xy 355.941884 -81.020158) (xy 355.941884 -81.498694) (xy 364.632238 -81.498694) (xy 364.636309 -81.443072)
			(xy 364.648435 -81.388635) (xy 364.668358 -81.336544) (xy 364.695654 -81.287909) (xy 364.72974 -81.243766)
			(xy 364.769889 -81.205057) (xy 364.815247 -81.172606) (xy 364.864847 -81.147105) (xy 364.917631 -81.129098)
			(xy 364.972474 -81.118968) (xy 365.028208 -81.116931) (xy 365.083645 -81.123031) (xy 365.137602 -81.137137)
			(xy 365.188931 -81.158949) (xy 365.236537 -81.188003) (xy 365.279405 -81.223678) (xy 365.316622 -81.265215)
			(xy 365.347395 -81.311728) (xy 365.371067 -81.362225) (xy 365.387135 -81.415632) (xy 365.395255 -81.470808)
			(xy 365.395764 -81.498694) (xy 367.679222 -81.498694) (xy 367.683293 -81.443072) (xy 367.695419 -81.388635)
			(xy 367.715342 -81.336544) (xy 367.742638 -81.287909) (xy 367.776724 -81.243766) (xy 367.816873 -81.205057)
			(xy 367.862231 -81.172606) (xy 367.911831 -81.147105) (xy 367.964615 -81.129098) (xy 368.019458 -81.118968)
			(xy 368.075192 -81.116931) (xy 368.130629 -81.123031) (xy 368.184586 -81.137137) (xy 368.235915 -81.158949)
			(xy 368.283521 -81.188003) (xy 368.326389 -81.223678) (xy 368.363606 -81.265215) (xy 368.394379 -81.311728)
			(xy 368.418051 -81.362225) (xy 368.434119 -81.415632) (xy 368.442239 -81.470808) (xy 368.442748 -81.498694)
			(xy 370.219222 -81.498694) (xy 370.223293 -81.443072) (xy 370.235419 -81.388635) (xy 370.255342 -81.336544)
			(xy 370.282638 -81.287909) (xy 370.316724 -81.243766) (xy 370.356873 -81.205057) (xy 370.402231 -81.172606)
			(xy 370.451831 -81.147105) (xy 370.504615 -81.129098) (xy 370.559458 -81.118968) (xy 370.615192 -81.116931)
			(xy 370.670629 -81.123031) (xy 370.724586 -81.137137) (xy 370.775915 -81.158949) (xy 370.823521 -81.188003)
			(xy 370.866389 -81.223678) (xy 370.903606 -81.265215) (xy 370.934379 -81.311728) (xy 370.958051 -81.362225)
			(xy 370.974119 -81.415632) (xy 370.982239 -81.470808) (xy 370.982748 -81.498694) (xy 370.982239 -81.52658)
			(xy 370.974119 -81.581756) (xy 370.958051 -81.635163) (xy 370.934379 -81.68566) (xy 370.903606 -81.732173)
			(xy 370.866389 -81.77371) (xy 370.823521 -81.809385) (xy 370.775915 -81.838439) (xy 370.724586 -81.860251)
			(xy 370.670629 -81.874357) (xy 370.615192 -81.880457) (xy 370.559458 -81.87842) (xy 370.504615 -81.86829)
			(xy 370.451831 -81.850283) (xy 370.402231 -81.824782) (xy 370.356873 -81.792331) (xy 370.316724 -81.753622)
			(xy 370.282638 -81.709479) (xy 370.255342 -81.660844) (xy 370.235419 -81.608753) (xy 370.223293 -81.554316)
			(xy 370.219222 -81.498694) (xy 368.442748 -81.498694) (xy 368.442239 -81.52658) (xy 368.434119 -81.581756)
			(xy 368.418051 -81.635163) (xy 368.394379 -81.68566) (xy 368.363606 -81.732173) (xy 368.326389 -81.77371)
			(xy 368.283521 -81.809385) (xy 368.235915 -81.838439) (xy 368.184586 -81.860251) (xy 368.130629 -81.874357)
			(xy 368.075192 -81.880457) (xy 368.019458 -81.87842) (xy 367.964615 -81.86829) (xy 367.911831 -81.850283)
			(xy 367.862231 -81.824782) (xy 367.816873 -81.792331) (xy 367.776724 -81.753622) (xy 367.742638 -81.709479)
			(xy 367.715342 -81.660844) (xy 367.695419 -81.608753) (xy 367.683293 -81.554316) (xy 367.679222 -81.498694)
			(xy 365.395764 -81.498694) (xy 365.395255 -81.52658) (xy 365.387135 -81.581756) (xy 365.371067 -81.635163)
			(xy 365.347395 -81.68566) (xy 365.316622 -81.732173) (xy 365.279405 -81.77371) (xy 365.236537 -81.809385)
			(xy 365.188931 -81.838439) (xy 365.137602 -81.860251) (xy 365.083645 -81.874357) (xy 365.028208 -81.880457)
			(xy 364.972474 -81.87842) (xy 364.917631 -81.86829) (xy 364.864847 -81.850283) (xy 364.815247 -81.824782)
			(xy 364.769889 -81.792331) (xy 364.72974 -81.753622) (xy 364.695654 -81.709479) (xy 364.668358 -81.660844)
			(xy 364.648435 -81.608753) (xy 364.636309 -81.554316) (xy 364.632238 -81.498694) (xy 355.941884 -81.498694)
			(xy 355.941884 -81.510378) (xy 355.941884 -81.51114) (xy 355.942488 -81.521276) (xy 355.950618 -81.539865)
			(xy 355.957632 -81.547208) (xy 355.959918 -81.548986) (xy 355.970586 -81.556098) (xy 356.017322 -81.578958)
			(xy 356.052882 -81.59623) (xy 356.059394 -81.599156) (xy 356.073451 -81.601613) (xy 356.080568 -81.601056)
			(xy 356.087172 -81.600294) (xy 356.10038 -81.59496) (xy 356.106222 -81.590388) (xy 356.126467 -81.575011)
			(xy 356.170256 -81.549184) (xy 356.217086 -81.5294) (xy 356.266129 -81.51601) (xy 356.316515 -81.50925)
			(xy 356.341934 -81.508854) (xy 356.369186 -81.509342) (xy 356.423136 -81.517103) (xy 356.475432 -81.532463)
			(xy 356.52501 -81.555108) (xy 356.57086 -81.584578) (xy 356.612051 -81.620274) (xy 356.647742 -81.661467)
			(xy 356.677208 -81.70732) (xy 356.699849 -81.7569) (xy 356.715204 -81.809197) (xy 356.72296 -81.863148)
			(xy 356.72296 -81.917652) (xy 356.715204 -81.971603) (xy 356.699849 -82.0239) (xy 356.677208 -82.07348)
			(xy 356.647742 -82.119333) (xy 356.612051 -82.160526) (xy 356.57086 -82.196222) (xy 356.52501 -82.225692)
			(xy 356.475432 -82.248337) (xy 356.423136 -82.263697) (xy 356.369186 -82.271458) (xy 356.341934 -82.27187)
			(xy 356.316515 -82.271452) (xy 356.266127 -82.264704) (xy 356.217082 -82.251324) (xy 356.170249 -82.231547)
			(xy 356.126457 -82.205725) (xy 356.106222 -82.190336) (xy 356.105968 -82.190082) (xy 356.100235 -82.18591)
			(xy 356.087086 -82.18062) (xy 356.08006 -82.179668) (xy 356.073456 -82.178906) (xy 356.059486 -82.181446)
			(xy 356.017322 -82.201766) (xy 355.970586 -82.224626) (xy 355.959918 -82.231738) (xy 355.957632 -82.233516)
			(xy 355.950586 -82.240835) (xy 355.942467 -82.259441) (xy 355.941884 -82.269584) (xy 355.941884 -82.641694)
			(xy 363.896146 -82.641694) (xy 363.900217 -82.586072) (xy 363.912343 -82.531635) (xy 363.932266 -82.479544)
			(xy 363.959562 -82.430909) (xy 363.993648 -82.386766) (xy 364.033797 -82.348057) (xy 364.079155 -82.315606)
			(xy 364.128755 -82.290105) (xy 364.181539 -82.272098) (xy 364.236382 -82.261968) (xy 364.292116 -82.259931)
			(xy 364.347553 -82.266031) (xy 364.40151 -82.280137) (xy 364.452839 -82.301949) (xy 364.500445 -82.331003)
			(xy 364.543313 -82.366678) (xy 364.58053 -82.408215) (xy 364.611303 -82.454728) (xy 364.634975 -82.505225)
			(xy 364.651043 -82.558632) (xy 364.659163 -82.613808) (xy 364.659672 -82.641694) (xy 364.659163 -82.66958)
			(xy 364.651043 -82.724756) (xy 364.634975 -82.778163) (xy 364.611303 -82.82866) (xy 364.58053 -82.875173)
			(xy 364.543313 -82.91671) (xy 364.542013 -82.917792) (xy 367.650774 -82.917792) (xy 367.654845 -82.86217)
			(xy 367.666971 -82.807733) (xy 367.686894 -82.755642) (xy 367.71419 -82.707007) (xy 367.748276 -82.662864)
			(xy 367.788425 -82.624155) (xy 367.833783 -82.591704) (xy 367.883383 -82.566203) (xy 367.936167 -82.548196)
			(xy 367.99101 -82.538066) (xy 368.046744 -82.536029) (xy 368.102181 -82.542129) (xy 368.156138 -82.556235)
			(xy 368.207467 -82.578047) (xy 368.255073 -82.607101) (xy 368.296641 -82.641694) (xy 370.219222 -82.641694)
			(xy 370.223293 -82.586072) (xy 370.235419 -82.531635) (xy 370.255342 -82.479544) (xy 370.282638 -82.430909)
			(xy 370.316724 -82.386766) (xy 370.356873 -82.348057) (xy 370.402231 -82.315606) (xy 370.451831 -82.290105)
			(xy 370.504615 -82.272098) (xy 370.559458 -82.261968) (xy 370.615192 -82.259931) (xy 370.670629 -82.266031)
			(xy 370.724586 -82.280137) (xy 370.775915 -82.301949) (xy 370.823521 -82.331003) (xy 370.866389 -82.366678)
			(xy 370.903606 -82.408215) (xy 370.934379 -82.454728) (xy 370.958051 -82.505225) (xy 370.974119 -82.558632)
			(xy 370.982239 -82.613808) (xy 370.982748 -82.641694) (xy 370.982239 -82.66958) (xy 370.974119 -82.724756)
			(xy 370.958051 -82.778163) (xy 370.934379 -82.82866) (xy 370.903606 -82.875173) (xy 370.866389 -82.91671)
			(xy 370.823521 -82.952385) (xy 370.775915 -82.981439) (xy 370.724586 -83.003251) (xy 370.670629 -83.017357)
			(xy 370.615192 -83.023457) (xy 370.559458 -83.02142) (xy 370.504615 -83.01129) (xy 370.451831 -82.993283)
			(xy 370.402231 -82.967782) (xy 370.356873 -82.935331) (xy 370.316724 -82.896622) (xy 370.282638 -82.852479)
			(xy 370.255342 -82.803844) (xy 370.235419 -82.751753) (xy 370.223293 -82.697316) (xy 370.219222 -82.641694)
			(xy 368.296641 -82.641694) (xy 368.297941 -82.642776) (xy 368.335158 -82.684313) (xy 368.365931 -82.730826)
			(xy 368.389603 -82.781323) (xy 368.405671 -82.83473) (xy 368.413791 -82.889906) (xy 368.4143 -82.917792)
			(xy 368.413791 -82.945678) (xy 368.405671 -83.000854) (xy 368.389603 -83.054261) (xy 368.365931 -83.104758)
			(xy 368.335158 -83.151271) (xy 368.297941 -83.192808) (xy 368.255073 -83.228483) (xy 368.207467 -83.257537)
			(xy 368.156138 -83.279349) (xy 368.102181 -83.293455) (xy 368.046744 -83.299555) (xy 367.99101 -83.297518)
			(xy 367.936167 -83.287388) (xy 367.883383 -83.269381) (xy 367.833783 -83.24388) (xy 367.788425 -83.211429)
			(xy 367.748276 -83.17272) (xy 367.71419 -83.128577) (xy 367.686894 -83.079942) (xy 367.666971 -83.027851)
			(xy 367.654845 -82.973414) (xy 367.650774 -82.917792) (xy 364.542013 -82.917792) (xy 364.500445 -82.952385)
			(xy 364.452839 -82.981439) (xy 364.40151 -83.003251) (xy 364.347553 -83.017357) (xy 364.292116 -83.023457)
			(xy 364.236382 -83.02142) (xy 364.181539 -83.01129) (xy 364.128755 -82.993283) (xy 364.079155 -82.967782)
			(xy 364.033797 -82.935331) (xy 363.993648 -82.896622) (xy 363.959562 -82.852479) (xy 363.932266 -82.803844)
			(xy 363.912343 -82.751753) (xy 363.900217 -82.697316) (xy 363.896146 -82.641694) (xy 355.941884 -82.641694)
			(xy 355.941884 -83.784694) (xy 365.080548 -83.784694) (xy 365.084619 -83.729072) (xy 365.096745 -83.674635)
			(xy 365.116668 -83.622544) (xy 365.143964 -83.573909) (xy 365.17805 -83.529766) (xy 365.218199 -83.491057)
			(xy 365.263557 -83.458606) (xy 365.313157 -83.433105) (xy 365.365941 -83.415098) (xy 365.420784 -83.404968)
			(xy 365.476518 -83.402931) (xy 365.531955 -83.409031) (xy 365.585912 -83.423137) (xy 365.637241 -83.444949)
			(xy 365.684847 -83.474003) (xy 365.727715 -83.509678) (xy 365.764932 -83.551215) (xy 365.795705 -83.597728)
			(xy 365.819377 -83.648225) (xy 365.835445 -83.701632) (xy 365.843565 -83.756808) (xy 365.844074 -83.784694)
			(xy 365.843565 -83.81258) (xy 365.835445 -83.867756) (xy 365.819377 -83.921163) (xy 365.795705 -83.97166)
			(xy 365.764932 -84.018173) (xy 365.727715 -84.05971) (xy 365.684847 -84.095385) (xy 365.637241 -84.124439)
			(xy 365.585912 -84.146251) (xy 365.531955 -84.160357) (xy 365.476518 -84.166457) (xy 365.420784 -84.16442)
			(xy 365.365941 -84.15429) (xy 365.313157 -84.136283) (xy 365.263557 -84.110782) (xy 365.218199 -84.078331)
			(xy 365.17805 -84.039622) (xy 365.143964 -83.995479) (xy 365.116668 -83.946844) (xy 365.096745 -83.894753)
			(xy 365.084619 -83.840316) (xy 365.080548 -83.784694) (xy 355.941884 -83.784694) (xy 355.941884 -84.864956)
			(xy 363.863634 -84.864956) (xy 363.867705 -84.809334) (xy 363.879831 -84.754897) (xy 363.899754 -84.702806)
			(xy 363.92705 -84.654171) (xy 363.961136 -84.610028) (xy 364.001285 -84.571319) (xy 364.046643 -84.538868)
			(xy 364.096243 -84.513367) (xy 364.149027 -84.49536) (xy 364.20387 -84.48523) (xy 364.259604 -84.483193)
			(xy 364.315041 -84.489293) (xy 364.368998 -84.503399) (xy 364.420327 -84.525211) (xy 364.467933 -84.554265)
			(xy 364.473791 -84.55914) (xy 367.596928 -84.55914) (xy 367.59742 -84.530678) (xy 367.605878 -84.474387)
			(xy 367.622614 -84.419979) (xy 367.647253 -84.368664) (xy 367.67925 -84.321584) (xy 367.717891 -84.279786)
			(xy 367.762318 -84.244198) (xy 367.786666 -84.229448) (xy 367.798256 -84.22222) (xy 367.817381 -84.202733)
			(xy 367.830658 -84.178874) (xy 367.837138 -84.152349) (xy 367.836356 -84.125056) (xy 367.828369 -84.098945)
			(xy 367.813747 -84.075885) (xy 367.803938 -84.06638) (xy 367.784723 -84.048244) (xy 367.751006 -84.007563)
			(xy 367.723225 -83.962618) (xy 367.70191 -83.914271) (xy 367.68747 -83.863445) (xy 367.68018 -83.811113)
			(xy 367.679732 -83.784694) (xy 367.680218 -83.757443) (xy 367.687974 -83.703495) (xy 367.703329 -83.6512)
			(xy 367.725971 -83.601623) (xy 367.755437 -83.555773) (xy 367.791128 -83.514582) (xy 367.832319 -83.478891)
			(xy 367.878169 -83.449425) (xy 367.927746 -83.426783) (xy 367.980041 -83.411428) (xy 368.033989 -83.403672)
			(xy 368.088491 -83.403672) (xy 368.142439 -83.411428) (xy 368.194734 -83.426783) (xy 368.244311 -83.449425)
			(xy 368.290161 -83.478891) (xy 368.331352 -83.514582) (xy 368.367043 -83.555773) (xy 368.396509 -83.601623)
			(xy 368.419151 -83.6512) (xy 368.434506 -83.703495) (xy 368.442262 -83.757443) (xy 368.442748 -83.784694)
			(xy 370.219222 -83.784694) (xy 370.223293 -83.729072) (xy 370.235419 -83.674635) (xy 370.255342 -83.622544)
			(xy 370.282638 -83.573909) (xy 370.316724 -83.529766) (xy 370.356873 -83.491057) (xy 370.402231 -83.458606)
			(xy 370.451831 -83.433105) (xy 370.504615 -83.415098) (xy 370.559458 -83.404968) (xy 370.615192 -83.402931)
			(xy 370.670629 -83.409031) (xy 370.724586 -83.423137) (xy 370.775915 -83.444949) (xy 370.823521 -83.474003)
			(xy 370.866389 -83.509678) (xy 370.903606 -83.551215) (xy 370.934379 -83.597728) (xy 370.958051 -83.648225)
			(xy 370.974119 -83.701632) (xy 370.982239 -83.756808) (xy 370.982748 -83.784694) (xy 370.982239 -83.81258)
			(xy 370.974119 -83.867756) (xy 370.958051 -83.921163) (xy 370.934379 -83.97166) (xy 370.903606 -84.018173)
			(xy 370.866389 -84.05971) (xy 370.823521 -84.095385) (xy 370.775915 -84.124439) (xy 370.724586 -84.146251)
			(xy 370.670629 -84.160357) (xy 370.615192 -84.166457) (xy 370.559458 -84.16442) (xy 370.504615 -84.15429)
			(xy 370.451831 -84.136283) (xy 370.402231 -84.110782) (xy 370.356873 -84.078331) (xy 370.316724 -84.039622)
			(xy 370.282638 -83.995479) (xy 370.255342 -83.946844) (xy 370.235419 -83.894753) (xy 370.223293 -83.840316)
			(xy 370.219222 -83.784694) (xy 368.442748 -83.784694) (xy 368.442216 -83.813155) (xy 368.433766 -83.869445)
			(xy 368.417039 -83.923852) (xy 368.392406 -83.975167) (xy 368.360416 -84.022248) (xy 368.321779 -84.064048)
			(xy 368.277356 -84.099636) (xy 368.25301 -84.114386) (xy 368.24139 -84.121569) (xy 368.222267 -84.141067)
			(xy 368.208993 -84.164935) (xy 368.202519 -84.191468) (xy 368.203306 -84.218768) (xy 368.211299 -84.244883)
			(xy 368.225925 -84.267947) (xy 368.235738 -84.277454) (xy 368.254965 -84.295578) (xy 368.288682 -84.336262)
			(xy 368.316462 -84.381208) (xy 368.337775 -84.429558) (xy 368.352213 -84.480386) (xy 368.359498 -84.53272)
			(xy 368.359944 -84.55914) (xy 368.359458 -84.586391) (xy 368.351702 -84.640339) (xy 368.336347 -84.692634)
			(xy 368.313705 -84.742211) (xy 368.284239 -84.788061) (xy 368.248548 -84.829252) (xy 368.207357 -84.864943)
			(xy 368.161507 -84.894409) (xy 368.11193 -84.917051) (xy 368.075683 -84.927694) (xy 370.219222 -84.927694)
			(xy 370.223293 -84.872072) (xy 370.235419 -84.817635) (xy 370.255342 -84.765544) (xy 370.282638 -84.716909)
			(xy 370.316724 -84.672766) (xy 370.356873 -84.634057) (xy 370.402231 -84.601606) (xy 370.451831 -84.576105)
			(xy 370.504615 -84.558098) (xy 370.559458 -84.547968) (xy 370.615192 -84.545931) (xy 370.670629 -84.552031)
			(xy 370.724586 -84.566137) (xy 370.775915 -84.587949) (xy 370.823521 -84.617003) (xy 370.866389 -84.652678)
			(xy 370.903606 -84.694215) (xy 370.934379 -84.740728) (xy 370.958051 -84.791225) (xy 370.974119 -84.844632)
			(xy 370.982239 -84.899808) (xy 370.982748 -84.927694) (xy 370.982239 -84.95558) (xy 370.974119 -85.010756)
			(xy 370.958051 -85.064163) (xy 370.934379 -85.11466) (xy 370.903606 -85.161173) (xy 370.866389 -85.20271)
			(xy 370.823521 -85.238385) (xy 370.775915 -85.267439) (xy 370.724586 -85.289251) (xy 370.670629 -85.303357)
			(xy 370.615192 -85.309457) (xy 370.559458 -85.30742) (xy 370.504615 -85.29729) (xy 370.451831 -85.279283)
			(xy 370.402231 -85.253782) (xy 370.356873 -85.221331) (xy 370.316724 -85.182622) (xy 370.282638 -85.138479)
			(xy 370.255342 -85.089844) (xy 370.235419 -85.037753) (xy 370.223293 -84.983316) (xy 370.219222 -84.927694)
			(xy 368.075683 -84.927694) (xy 368.059635 -84.932406) (xy 368.005687 -84.940162) (xy 367.951185 -84.940162)
			(xy 367.897237 -84.932406) (xy 367.844942 -84.917051) (xy 367.795365 -84.894409) (xy 367.749515 -84.864943)
			(xy 367.708324 -84.829252) (xy 367.672633 -84.788061) (xy 367.643167 -84.742211) (xy 367.620525 -84.692634)
			(xy 367.60517 -84.640339) (xy 367.597414 -84.586391) (xy 367.596928 -84.55914) (xy 364.473791 -84.55914)
			(xy 364.510801 -84.58994) (xy 364.548018 -84.631477) (xy 364.578791 -84.67799) (xy 364.602463 -84.728487)
			(xy 364.618531 -84.781894) (xy 364.626651 -84.83707) (xy 364.62716 -84.864956) (xy 364.626651 -84.892842)
			(xy 364.618531 -84.948018) (xy 364.602463 -85.001425) (xy 364.578791 -85.051922) (xy 364.548018 -85.098435)
			(xy 364.510801 -85.139972) (xy 364.467933 -85.175647) (xy 364.420327 -85.204701) (xy 364.368998 -85.226513)
			(xy 364.315041 -85.240619) (xy 364.259604 -85.246719) (xy 364.20387 -85.244682) (xy 364.149027 -85.234552)
			(xy 364.096243 -85.216545) (xy 364.046643 -85.191044) (xy 364.001285 -85.158593) (xy 363.961136 -85.119884)
			(xy 363.92705 -85.075741) (xy 363.899754 -85.027106) (xy 363.879831 -84.975015) (xy 363.867705 -84.920578)
			(xy 363.863634 -84.864956) (xy 355.941884 -84.864956) (xy 355.941884 -85.514942) (xy 365.30483 -85.514942)
			(xy 365.308901 -85.45932) (xy 365.321027 -85.404883) (xy 365.34095 -85.352792) (xy 365.368246 -85.304157)
			(xy 365.402332 -85.260014) (xy 365.442481 -85.221305) (xy 365.487839 -85.188854) (xy 365.537439 -85.163353)
			(xy 365.590223 -85.145346) (xy 365.645066 -85.135216) (xy 365.7008 -85.133179) (xy 365.756237 -85.139279)
			(xy 365.810194 -85.153385) (xy 365.861523 -85.175197) (xy 365.909129 -85.204251) (xy 365.951997 -85.239926)
			(xy 365.989214 -85.281463) (xy 366.019987 -85.327976) (xy 366.043659 -85.378473) (xy 366.059727 -85.43188)
			(xy 366.067847 -85.487056) (xy 366.068356 -85.514942) (xy 366.067847 -85.542828) (xy 366.059727 -85.598004)
			(xy 366.043659 -85.651411) (xy 366.019987 -85.701908) (xy 365.989214 -85.748421) (xy 365.951997 -85.789958)
			(xy 365.909129 -85.825633) (xy 365.861523 -85.854687) (xy 365.810194 -85.876499) (xy 365.756237 -85.890605)
			(xy 365.7008 -85.896705) (xy 365.645066 -85.894668) (xy 365.590223 -85.884538) (xy 365.537439 -85.866531)
			(xy 365.487839 -85.84103) (xy 365.442481 -85.808579) (xy 365.402332 -85.76987) (xy 365.368246 -85.725727)
			(xy 365.34095 -85.677092) (xy 365.321027 -85.625001) (xy 365.308901 -85.570564) (xy 365.30483 -85.514942)
			(xy 355.941884 -85.514942) (xy 355.941884 -86.164928) (xy 363.895638 -86.164928) (xy 363.899709 -86.109306)
			(xy 363.911835 -86.054869) (xy 363.931758 -86.002778) (xy 363.959054 -85.954143) (xy 363.99314 -85.91)
			(xy 364.033289 -85.871291) (xy 364.078647 -85.83884) (xy 364.128247 -85.813339) (xy 364.181031 -85.795332)
			(xy 364.235874 -85.785202) (xy 364.291608 -85.783165) (xy 364.347045 -85.789265) (xy 364.401002 -85.803371)
			(xy 364.452331 -85.825183) (xy 364.499937 -85.854237) (xy 364.542805 -85.889912) (xy 364.580022 -85.931449)
			(xy 364.610795 -85.977962) (xy 364.634467 -86.028459) (xy 364.647174 -86.070694) (xy 370.219222 -86.070694)
			(xy 370.223293 -86.015072) (xy 370.235419 -85.960635) (xy 370.255342 -85.908544) (xy 370.282638 -85.859909)
			(xy 370.316724 -85.815766) (xy 370.356873 -85.777057) (xy 370.402231 -85.744606) (xy 370.451831 -85.719105)
			(xy 370.504615 -85.701098) (xy 370.559458 -85.690968) (xy 370.615192 -85.688931) (xy 370.670629 -85.695031)
			(xy 370.724586 -85.709137) (xy 370.775915 -85.730949) (xy 370.823521 -85.760003) (xy 370.866389 -85.795678)
			(xy 370.903606 -85.837215) (xy 370.934379 -85.883728) (xy 370.958051 -85.934225) (xy 370.974119 -85.987632)
			(xy 370.982239 -86.042808) (xy 370.982748 -86.070694) (xy 370.982239 -86.09858) (xy 370.974119 -86.153756)
			(xy 370.958051 -86.207163) (xy 370.934379 -86.25766) (xy 370.903606 -86.304173) (xy 370.866389 -86.34571)
			(xy 370.823521 -86.381385) (xy 370.775915 -86.410439) (xy 370.724586 -86.432251) (xy 370.670629 -86.446357)
			(xy 370.615192 -86.452457) (xy 370.559458 -86.45042) (xy 370.504615 -86.44029) (xy 370.451831 -86.422283)
			(xy 370.402231 -86.396782) (xy 370.356873 -86.364331) (xy 370.316724 -86.325622) (xy 370.282638 -86.281479)
			(xy 370.255342 -86.232844) (xy 370.235419 -86.180753) (xy 370.223293 -86.126316) (xy 370.219222 -86.070694)
			(xy 364.647174 -86.070694) (xy 364.650535 -86.081866) (xy 364.658655 -86.137042) (xy 364.659164 -86.164928)
			(xy 364.658655 -86.192814) (xy 364.650535 -86.24799) (xy 364.634467 -86.301397) (xy 364.610795 -86.351894)
			(xy 364.580022 -86.398407) (xy 364.542805 -86.439944) (xy 364.499937 -86.475619) (xy 364.452331 -86.504673)
			(xy 364.449091 -86.50605) (xy 367.536982 -86.50605) (xy 367.541053 -86.450428) (xy 367.553179 -86.395991)
			(xy 367.573102 -86.3439) (xy 367.600398 -86.295265) (xy 367.634484 -86.251122) (xy 367.674633 -86.212413)
			(xy 367.719991 -86.179962) (xy 367.769591 -86.154461) (xy 367.822375 -86.136454) (xy 367.877218 -86.126324)
			(xy 367.932952 -86.124287) (xy 367.988389 -86.130387) (xy 368.042346 -86.144493) (xy 368.093675 -86.166305)
			(xy 368.141281 -86.195359) (xy 368.184149 -86.231034) (xy 368.221366 -86.272571) (xy 368.252139 -86.319084)
			(xy 368.275811 -86.369581) (xy 368.291879 -86.422988) (xy 368.299999 -86.478164) (xy 368.300508 -86.50605)
			(xy 368.299999 -86.533936) (xy 368.291879 -86.589112) (xy 368.275811 -86.642519) (xy 368.252139 -86.693016)
			(xy 368.221366 -86.739529) (xy 368.184149 -86.781066) (xy 368.141281 -86.816741) (xy 368.093675 -86.845795)
			(xy 368.042346 -86.867607) (xy 367.988389 -86.881713) (xy 367.932952 -86.887813) (xy 367.877218 -86.885776)
			(xy 367.822375 -86.875646) (xy 367.769591 -86.857639) (xy 367.719991 -86.832138) (xy 367.674633 -86.799687)
			(xy 367.634484 -86.760978) (xy 367.600398 -86.716835) (xy 367.573102 -86.6682) (xy 367.553179 -86.616109)
			(xy 367.541053 -86.561672) (xy 367.536982 -86.50605) (xy 364.449091 -86.50605) (xy 364.401002 -86.526485)
			(xy 364.347045 -86.540591) (xy 364.291608 -86.546691) (xy 364.235874 -86.544654) (xy 364.181031 -86.534524)
			(xy 364.128247 -86.516517) (xy 364.078647 -86.491016) (xy 364.033289 -86.458565) (xy 363.99314 -86.419856)
			(xy 363.959054 -86.375713) (xy 363.931758 -86.327078) (xy 363.911835 -86.274987) (xy 363.899709 -86.22055)
			(xy 363.895638 -86.164928) (xy 355.941884 -86.164928) (xy 355.941884 -87.213694) (xy 370.219222 -87.213694)
			(xy 370.223293 -87.158072) (xy 370.235419 -87.103635) (xy 370.255342 -87.051544) (xy 370.282638 -87.002909)
			(xy 370.316724 -86.958766) (xy 370.356873 -86.920057) (xy 370.402231 -86.887606) (xy 370.451831 -86.862105)
			(xy 370.504615 -86.844098) (xy 370.559458 -86.833968) (xy 370.615192 -86.831931) (xy 370.670629 -86.838031)
			(xy 370.724586 -86.852137) (xy 370.775915 -86.873949) (xy 370.823521 -86.903003) (xy 370.866389 -86.938678)
			(xy 370.903606 -86.980215) (xy 370.934379 -87.026728) (xy 370.958051 -87.077225) (xy 370.974119 -87.130632)
			(xy 370.982239 -87.185808) (xy 370.982748 -87.213694) (xy 370.982239 -87.24158) (xy 370.974119 -87.296756)
			(xy 370.958051 -87.350163) (xy 370.934379 -87.40066) (xy 370.903606 -87.447173) (xy 370.866389 -87.48871)
			(xy 370.823521 -87.524385) (xy 370.775915 -87.553439) (xy 370.724586 -87.575251) (xy 370.670629 -87.589357)
			(xy 370.615192 -87.595457) (xy 370.559458 -87.59342) (xy 370.504615 -87.58329) (xy 370.451831 -87.565283)
			(xy 370.402231 -87.539782) (xy 370.356873 -87.507331) (xy 370.316724 -87.468622) (xy 370.282638 -87.424479)
			(xy 370.255342 -87.375844) (xy 370.235419 -87.323753) (xy 370.223293 -87.269316) (xy 370.219222 -87.213694)
			(xy 355.941884 -87.213694) (xy 355.941884 -87.712296) (xy 367.61877 -87.712296) (xy 367.622841 -87.656674)
			(xy 367.634967 -87.602237) (xy 367.65489 -87.550146) (xy 367.682186 -87.501511) (xy 367.716272 -87.457368)
			(xy 367.756421 -87.418659) (xy 367.801779 -87.386208) (xy 367.851379 -87.360707) (xy 367.904163 -87.3427)
			(xy 367.959006 -87.33257) (xy 368.01474 -87.330533) (xy 368.070177 -87.336633) (xy 368.124134 -87.350739)
			(xy 368.175463 -87.372551) (xy 368.223069 -87.401605) (xy 368.265937 -87.43728) (xy 368.303154 -87.478817)
			(xy 368.333927 -87.52533) (xy 368.357599 -87.575827) (xy 368.373667 -87.629234) (xy 368.381787 -87.68441)
			(xy 368.382296 -87.712296) (xy 368.381787 -87.740182) (xy 368.373667 -87.795358) (xy 368.357599 -87.848765)
			(xy 368.333927 -87.899262) (xy 368.303154 -87.945775) (xy 368.265937 -87.987312) (xy 368.223069 -88.022987)
			(xy 368.175463 -88.052041) (xy 368.124134 -88.073853) (xy 368.070177 -88.087959) (xy 368.01474 -88.094059)
			(xy 367.959006 -88.092022) (xy 367.904163 -88.081892) (xy 367.851379 -88.063885) (xy 367.801779 -88.038384)
			(xy 367.756421 -88.005933) (xy 367.716272 -87.967224) (xy 367.682186 -87.923081) (xy 367.65489 -87.874446)
			(xy 367.634967 -87.822355) (xy 367.622841 -87.767918) (xy 367.61877 -87.712296) (xy 355.941884 -87.712296)
			(xy 355.941884 -88.302846) (xy 357.714802 -88.302846) (xy 357.718873 -88.247224) (xy 357.730999 -88.192787)
			(xy 357.750922 -88.140696) (xy 357.778218 -88.092061) (xy 357.812304 -88.047918) (xy 357.852453 -88.009209)
			(xy 357.897811 -87.976758) (xy 357.947411 -87.951257) (xy 358.000195 -87.93325) (xy 358.055038 -87.92312)
			(xy 358.110772 -87.921083) (xy 358.166209 -87.927183) (xy 358.220166 -87.941289) (xy 358.271495 -87.963101)
			(xy 358.319101 -87.992155) (xy 358.361969 -88.02783) (xy 358.399186 -88.069367) (xy 358.429959 -88.11588)
			(xy 358.453631 -88.166377) (xy 358.469699 -88.219784) (xy 358.477819 -88.27496) (xy 358.478328 -88.302846)
			(xy 358.477819 -88.330732) (xy 358.469699 -88.385908) (xy 358.453631 -88.439315) (xy 358.429959 -88.489812)
			(xy 358.399186 -88.536325) (xy 358.361969 -88.577862) (xy 358.319101 -88.613537) (xy 358.271495 -88.642591)
			(xy 358.220166 -88.664403) (xy 358.166209 -88.678509) (xy 358.110772 -88.684609) (xy 358.055038 -88.682572)
			(xy 358.000195 -88.672442) (xy 357.947411 -88.654435) (xy 357.897811 -88.628934) (xy 357.852453 -88.596483)
			(xy 357.812304 -88.557774) (xy 357.778218 -88.513631) (xy 357.750922 -88.464996) (xy 357.730999 -88.412905)
			(xy 357.718873 -88.358468) (xy 357.714802 -88.302846) (xy 355.941884 -88.302846) (xy 355.941884 -90.458036)
			(xy 355.942313 -90.468104) (xy 355.950035 -90.4867) (xy 355.95687 -90.494104) (xy 356.480618 -91.017852)
			(xy 356.488015 -91.024701) (xy 356.506614 -91.032436) (xy 356.516686 -91.032838) (xy 362.225082 -91.032838)
			(xy 362.235144 -91.032398) (xy 362.253721 -91.024656) (xy 362.26115 -91.017852) (xy 363.494828 -89.784174)
			(xy 363.501678 -89.776778) (xy 363.509414 -89.758179) (xy 363.509814 -89.748106) (xy 363.509814 -88.639142)
			(xy 363.510248 -88.629077) (xy 363.517979 -88.610489) (xy 363.5248 -88.603074) (xy 363.625892 -88.501982)
			(xy 363.633258 -88.492584) (xy 363.643663 -88.47615) (xy 363.667725 -88.445589) (xy 363.681264 -88.431624)
			(xy 364.045246 -88.067896) (xy 364.047532 -88.060276) (xy 364.055776 -88.034417) (xy 364.078561 -87.985157)
			(xy 364.108098 -87.939624) (xy 364.143793 -87.898738) (xy 364.184923 -87.863325) (xy 364.230657 -87.834101)
			(xy 364.280073 -87.811655) (xy 364.332171 -87.796441) (xy 364.385901 -87.788767) (xy 364.413038 -87.788242)
			(xy 364.440288 -87.788708) (xy 364.494232 -87.79647) (xy 364.546522 -87.811829) (xy 364.596095 -87.834475)
			(xy 364.641939 -87.863945) (xy 364.683123 -87.899639) (xy 364.718808 -87.940831) (xy 364.748267 -87.986683)
			(xy 364.770901 -88.03626) (xy 364.786249 -88.088554) (xy 364.787259 -88.095582) (xy 365.484662 -88.095582)
			(xy 365.488733 -88.03996) (xy 365.500859 -87.985523) (xy 365.520782 -87.933432) (xy 365.548078 -87.884797)
			(xy 365.582164 -87.840654) (xy 365.622313 -87.801945) (xy 365.667671 -87.769494) (xy 365.717271 -87.743993)
			(xy 365.770055 -87.725986) (xy 365.824898 -87.715856) (xy 365.880632 -87.713819) (xy 365.936069 -87.719919)
			(xy 365.990026 -87.734025) (xy 366.041355 -87.755837) (xy 366.088961 -87.784891) (xy 366.131829 -87.820566)
			(xy 366.169046 -87.862103) (xy 366.199819 -87.908616) (xy 366.223491 -87.959113) (xy 366.239559 -88.01252)
			(xy 366.247679 -88.067696) (xy 366.248188 -88.095582) (xy 366.247679 -88.123468) (xy 366.239559 -88.178644)
			(xy 366.223491 -88.232051) (xy 366.199819 -88.282548) (xy 366.169046 -88.329061) (xy 366.144287 -88.356694)
			(xy 370.219222 -88.356694) (xy 370.223293 -88.301072) (xy 370.235419 -88.246635) (xy 370.255342 -88.194544)
			(xy 370.282638 -88.145909) (xy 370.316724 -88.101766) (xy 370.356873 -88.063057) (xy 370.402231 -88.030606)
			(xy 370.451831 -88.005105) (xy 370.504615 -87.987098) (xy 370.559458 -87.976968) (xy 370.615192 -87.974931)
			(xy 370.670629 -87.981031) (xy 370.724586 -87.995137) (xy 370.775915 -88.016949) (xy 370.823521 -88.046003)
			(xy 370.866389 -88.081678) (xy 370.903606 -88.123215) (xy 370.934379 -88.169728) (xy 370.958051 -88.220225)
			(xy 370.974119 -88.273632) (xy 370.982239 -88.328808) (xy 370.982748 -88.356694) (xy 370.982239 -88.38458)
			(xy 370.974119 -88.439756) (xy 370.958051 -88.493163) (xy 370.934379 -88.54366) (xy 370.903606 -88.590173)
			(xy 370.866389 -88.63171) (xy 370.823521 -88.667385) (xy 370.775915 -88.696439) (xy 370.724586 -88.718251)
			(xy 370.670629 -88.732357) (xy 370.615192 -88.738457) (xy 370.559458 -88.73642) (xy 370.504615 -88.72629)
			(xy 370.451831 -88.708283) (xy 370.402231 -88.682782) (xy 370.356873 -88.650331) (xy 370.316724 -88.611622)
			(xy 370.282638 -88.567479) (xy 370.255342 -88.518844) (xy 370.235419 -88.466753) (xy 370.223293 -88.412316)
			(xy 370.219222 -88.356694) (xy 366.144287 -88.356694) (xy 366.131829 -88.370598) (xy 366.088961 -88.406273)
			(xy 366.041355 -88.435327) (xy 365.990026 -88.457139) (xy 365.936069 -88.471245) (xy 365.880632 -88.477345)
			(xy 365.824898 -88.475308) (xy 365.770055 -88.465178) (xy 365.717271 -88.447171) (xy 365.667671 -88.42167)
			(xy 365.622313 -88.389219) (xy 365.582164 -88.35051) (xy 365.548078 -88.306367) (xy 365.520782 -88.257732)
			(xy 365.500859 -88.205641) (xy 365.488733 -88.151204) (xy 365.484662 -88.095582) (xy 364.787259 -88.095582)
			(xy 364.793998 -88.1425) (xy 364.794546 -88.16975) (xy 364.79411 -88.196026) (xy 364.786903 -88.248081)
			(xy 364.772618 -88.298654) (xy 364.751526 -88.346787) (xy 364.724026 -88.391569) (xy 364.690639 -88.432152)
			(xy 364.651997 -88.467767) (xy 364.608832 -88.497741) (xy 364.561961 -88.521506) (xy 364.537244 -88.53043)
			(xy 364.536228 -88.530938) (xy 364.513622 -88.539066) (xy 364.508542 -88.544146) (xy 364.508542 -88.907874)
			(xy 364.50898 -88.917937) (xy 364.516718 -88.936518) (xy 364.523528 -88.943942) (xy 364.690152 -89.110566)
			(xy 364.70717 -89.118186) (xy 364.712504 -89.11844) (xy 364.739079 -89.119934) (xy 364.791463 -89.129369)
			(xy 364.842027 -89.145992) (xy 364.889791 -89.169479) (xy 364.933827 -89.199376) (xy 364.973283 -89.235102)
			(xy 365.00739 -89.275964) (xy 365.035489 -89.32117) (xy 365.057034 -89.369841) (xy 365.064802 -89.3953)
			(xy 365.064802 -89.395808) (xy 365.06682 -89.401951) (xy 365.073504 -89.413014) (xy 365.07801 -89.417652)
			(xy 365.082864 -89.422264) (xy 365.094449 -89.428966) (xy 365.10087 -89.43086) (xy 365.18596 -89.452958)
			(xy 365.190769 -89.454065) (xy 365.200621 -89.45458) (xy 365.205518 -89.453974) (xy 365.341662 -89.31783)
			(xy 365.348502 -89.31043) (xy 365.356216 -89.291831) (xy 365.356648 -89.281762) (xy 365.356648 -89.192862)
			(xy 365.354108 -89.181686) (xy 365.351568 -89.17686) (xy 365.337572 -89.149199) (xy 365.317756 -89.090463)
			(xy 365.307716 -89.029292) (xy 365.307118 -88.998298) (xy 365.307604 -88.971047) (xy 365.31536 -88.917099)
			(xy 365.330715 -88.864804) (xy 365.353357 -88.815227) (xy 365.382823 -88.769377) (xy 365.418514 -88.728186)
			(xy 365.459705 -88.692495) (xy 365.505555 -88.663029) (xy 365.555132 -88.640387) (xy 365.607427 -88.625032)
			(xy 365.661375 -88.617276) (xy 365.715877 -88.617276) (xy 365.769825 -88.625032) (xy 365.82212 -88.640387)
			(xy 365.871697 -88.663029) (xy 365.917547 -88.692495) (xy 365.958738 -88.728186) (xy 365.984583 -88.758014)
			(xy 367.55578 -88.758014) (xy 367.556266 -88.730763) (xy 367.564022 -88.676815) (xy 367.579377 -88.62452)
			(xy 367.602019 -88.574943) (xy 367.631485 -88.529093) (xy 367.667176 -88.487902) (xy 367.708367 -88.452211)
			(xy 367.754217 -88.422745) (xy 367.803794 -88.400103) (xy 367.856089 -88.384748) (xy 367.910037 -88.376992)
			(xy 367.964539 -88.376992) (xy 368.018487 -88.384748) (xy 368.070782 -88.400103) (xy 368.120359 -88.422745)
			(xy 368.166209 -88.452211) (xy 368.2074 -88.487902) (xy 368.243091 -88.529093) (xy 368.272557 -88.574943)
			(xy 368.295199 -88.62452) (xy 368.310554 -88.676815) (xy 368.31831 -88.730763) (xy 368.318796 -88.758014)
			(xy 368.318796 -88.758268) (xy 368.318301 -88.785979) (xy 368.310288 -88.840817) (xy 368.294412 -88.893916)
			(xy 368.271008 -88.944153) (xy 368.240571 -88.990467) (xy 368.22253 -89.011506) (xy 368.214656 -89.020142)
			(xy 368.208306 -89.041986) (xy 368.223292 -89.131394) (xy 368.225638 -89.142656) (xy 368.238891 -89.161436)
			(xy 368.248692 -89.167462) (xy 368.273516 -89.182113) (xy 368.318894 -89.217652) (xy 368.358408 -89.259615)
			(xy 368.391156 -89.307046) (xy 368.416393 -89.358866) (xy 368.433545 -89.413893) (xy 368.44222 -89.470875)
			(xy 368.442748 -89.499694) (xy 370.219222 -89.499694) (xy 370.223293 -89.444072) (xy 370.235419 -89.389635)
			(xy 370.255342 -89.337544) (xy 370.282638 -89.288909) (xy 370.316724 -89.244766) (xy 370.356873 -89.206057)
			(xy 370.402231 -89.173606) (xy 370.451831 -89.148105) (xy 370.504615 -89.130098) (xy 370.559458 -89.119968)
			(xy 370.615192 -89.117931) (xy 370.670629 -89.124031) (xy 370.724586 -89.138137) (xy 370.775915 -89.159949)
			(xy 370.823521 -89.189003) (xy 370.866389 -89.224678) (xy 370.903606 -89.266215) (xy 370.934379 -89.312728)
			(xy 370.958051 -89.363225) (xy 370.974119 -89.416632) (xy 370.982239 -89.471808) (xy 370.982748 -89.499694)
			(xy 370.982239 -89.52758) (xy 370.974119 -89.582756) (xy 370.958051 -89.636163) (xy 370.934379 -89.68666)
			(xy 370.903606 -89.733173) (xy 370.866389 -89.77471) (xy 370.823521 -89.810385) (xy 370.775915 -89.839439)
			(xy 370.724586 -89.861251) (xy 370.670629 -89.875357) (xy 370.615192 -89.881457) (xy 370.559458 -89.87942)
			(xy 370.504615 -89.86929) (xy 370.451831 -89.851283) (xy 370.402231 -89.825782) (xy 370.356873 -89.793331)
			(xy 370.316724 -89.754622) (xy 370.282638 -89.710479) (xy 370.255342 -89.661844) (xy 370.235419 -89.609753)
			(xy 370.223293 -89.555316) (xy 370.219222 -89.499694) (xy 368.442748 -89.499694) (xy 368.442262 -89.526945)
			(xy 368.434506 -89.580893) (xy 368.419151 -89.633188) (xy 368.396509 -89.682765) (xy 368.367043 -89.728615)
			(xy 368.331352 -89.769806) (xy 368.290161 -89.805497) (xy 368.244311 -89.834963) (xy 368.194734 -89.857605)
			(xy 368.142439 -89.87296) (xy 368.088491 -89.880716) (xy 368.033989 -89.880716) (xy 367.980041 -89.87296)
			(xy 367.927746 -89.857605) (xy 367.878169 -89.834963) (xy 367.832319 -89.805497) (xy 367.791128 -89.769806)
			(xy 367.755437 -89.728615) (xy 367.725971 -89.682765) (xy 367.703329 -89.633188) (xy 367.687974 -89.580893)
			(xy 367.680218 -89.526945) (xy 367.679732 -89.499694) (xy 367.679732 -89.49944) (xy 367.680225 -89.471729)
			(xy 367.688237 -89.41689) (xy 367.704113 -89.363792) (xy 367.727518 -89.313555) (xy 367.757956 -89.26724)
			(xy 367.775998 -89.246202) (xy 367.783872 -89.237566) (xy 367.790222 -89.215722) (xy 367.775236 -89.126314)
			(xy 367.772874 -89.115057) (xy 367.759632 -89.096276) (xy 367.749836 -89.090246) (xy 367.724978 -89.075649)
			(xy 367.679598 -89.040103) (xy 367.640085 -88.998132) (xy 367.60734 -88.950691) (xy 367.582108 -88.898862)
			(xy 367.564965 -88.843826) (xy 367.556302 -88.786836) (xy 367.55578 -88.758014) (xy 365.984583 -88.758014)
			(xy 365.994429 -88.769377) (xy 366.023895 -88.815227) (xy 366.046537 -88.864804) (xy 366.061892 -88.917099)
			(xy 366.069648 -88.971047) (xy 366.070134 -88.998298) (xy 366.069515 -89.029195) (xy 366.059522 -89.090176)
			(xy 366.039844 -89.148754) (xy 366.025938 -89.176352) (xy 366.02543 -89.177368) (xy 366.020604 -89.18702)
			(xy 366.020604 -89.440258) (xy 366.020121 -89.466347) (xy 366.011961 -89.517883) (xy 365.995836 -89.567506)
			(xy 365.972142 -89.613994) (xy 365.941464 -89.656201) (xy 365.923322 -89.674954) (xy 365.866426 -89.73185)
			(xy 365.866426 -89.732358) (xy 365.901986 -89.767918) (xy 365.908636 -89.774105) (xy 365.925112 -89.781717)
			(xy 365.943212 -89.783071) (xy 365.952024 -89.780872) (xy 365.952278 -89.780872) (xy 365.978544 -89.773621)
			(xy 366.032475 -89.765838) (xy 366.05972 -89.765378) (xy 366.086971 -89.765865) (xy 366.140919 -89.773624)
			(xy 366.193213 -89.788982) (xy 366.24279 -89.811625) (xy 366.288639 -89.841093) (xy 366.329829 -89.876786)
			(xy 366.365519 -89.917977) (xy 366.394985 -89.963828) (xy 366.417625 -90.013406) (xy 366.43298 -90.065701)
			(xy 366.440736 -90.119649) (xy 366.440736 -90.174151) (xy 366.43298 -90.228099) (xy 366.417625 -90.280394)
			(xy 366.394985 -90.329972) (xy 366.365519 -90.375823) (xy 366.329829 -90.417014) (xy 366.288639 -90.452707)
			(xy 366.24279 -90.482175) (xy 366.193213 -90.504818) (xy 366.140919 -90.520176) (xy 366.086971 -90.527935)
			(xy 366.05972 -90.528394) (xy 366.032607 -90.527919) (xy 365.978926 -90.520243) (xy 365.926873 -90.505043)
			(xy 365.877497 -90.482625) (xy 365.831793 -90.453442) (xy 365.790682 -90.41808) (xy 365.754993 -90.377254)
			(xy 365.725444 -90.331785) (xy 365.702632 -90.28259) (xy 365.687016 -90.23066) (xy 365.67891 -90.177043)
			(xy 365.678212 -90.149934) (xy 365.678212 -90.142314) (xy 365.67364 -90.127582) (xy 365.669576 -90.12174)
			(xy 365.665177 -90.115851) (xy 365.653684 -90.1067) (xy 365.64697 -90.103706) (xy 365.559848 -90.067892)
			(xy 365.553528 -90.065526) (xy 365.540141 -90.06386) (xy 365.533432 -90.06459) (xy 364.9554 -90.642694)
			(xy 367.679222 -90.642694) (xy 367.683293 -90.587072) (xy 367.695419 -90.532635) (xy 367.715342 -90.480544)
			(xy 367.742638 -90.431909) (xy 367.776724 -90.387766) (xy 367.816873 -90.349057) (xy 367.862231 -90.316606)
			(xy 367.911831 -90.291105) (xy 367.964615 -90.273098) (xy 368.019458 -90.262968) (xy 368.075192 -90.260931)
			(xy 368.130629 -90.267031) (xy 368.184586 -90.281137) (xy 368.235915 -90.302949) (xy 368.283521 -90.332003)
			(xy 368.326389 -90.367678) (xy 368.363606 -90.409215) (xy 368.394379 -90.455728) (xy 368.418051 -90.506225)
			(xy 368.434119 -90.559632) (xy 368.442239 -90.614808) (xy 368.442748 -90.642694) (xy 368.442239 -90.67058)
			(xy 368.434119 -90.725756) (xy 368.418051 -90.779163) (xy 368.394379 -90.82966) (xy 368.363606 -90.876173)
			(xy 368.326389 -90.91771) (xy 368.283521 -90.953385) (xy 368.235915 -90.982439) (xy 368.184586 -91.004251)
			(xy 368.130629 -91.018357) (xy 368.075192 -91.024457) (xy 368.019458 -91.02242) (xy 367.964615 -91.01229)
			(xy 367.911831 -90.994283) (xy 367.862231 -90.968782) (xy 367.816873 -90.936331) (xy 367.776724 -90.897622)
			(xy 367.742638 -90.853479) (xy 367.715342 -90.804844) (xy 367.695419 -90.752753) (xy 367.683293 -90.698316)
			(xy 367.679222 -90.642694) (xy 364.9554 -90.642694) (xy 363.958829 -91.63939) (xy 367.28349 -91.63939)
			(xy 367.287561 -91.583768) (xy 367.299687 -91.529331) (xy 367.31961 -91.47724) (xy 367.346906 -91.428605)
			(xy 367.380992 -91.384462) (xy 367.421141 -91.345753) (xy 367.466499 -91.313302) (xy 367.516099 -91.287801)
			(xy 367.568883 -91.269794) (xy 367.623726 -91.259664) (xy 367.67946 -91.257627) (xy 367.734897 -91.263727)
			(xy 367.788854 -91.277833) (xy 367.840183 -91.299645) (xy 367.887789 -91.328699) (xy 367.930657 -91.364374)
			(xy 367.967874 -91.405911) (xy 367.998647 -91.452424) (xy 368.022319 -91.502921) (xy 368.038387 -91.556328)
			(xy 368.046507 -91.611504) (xy 368.047016 -91.63939) (xy 368.046507 -91.667276) (xy 368.038387 -91.722452)
			(xy 368.022319 -91.775859) (xy 367.998647 -91.826356) (xy 367.967874 -91.872869) (xy 367.930657 -91.914406)
			(xy 367.887789 -91.950081) (xy 367.840183 -91.979135) (xy 367.788854 -92.000947) (xy 367.734897 -92.015053)
			(xy 367.67946 -92.021153) (xy 367.623726 -92.019116) (xy 367.568883 -92.008986) (xy 367.516099 -91.990979)
			(xy 367.466499 -91.965478) (xy 367.421141 -91.933027) (xy 367.380992 -91.894318) (xy 367.346906 -91.850175)
			(xy 367.31961 -91.80154) (xy 367.299687 -91.749449) (xy 367.287561 -91.695012) (xy 367.28349 -91.63939)
			(xy 363.958829 -91.63939) (xy 363.505242 -92.093034) (xy 363.502187 -92.096336) (xy 364.008414 -92.096336)
			(xy 364.012485 -92.040714) (xy 364.024611 -91.986277) (xy 364.044534 -91.934186) (xy 364.07183 -91.885551)
			(xy 364.105916 -91.841408) (xy 364.146065 -91.802699) (xy 364.191423 -91.770248) (xy 364.241023 -91.744747)
			(xy 364.293807 -91.72674) (xy 364.34865 -91.71661) (xy 364.404384 -91.714573) (xy 364.459821 -91.720673)
			(xy 364.513778 -91.734779) (xy 364.565107 -91.756591) (xy 364.612713 -91.785645) (xy 364.655581 -91.82132)
			(xy 364.692798 -91.862857) (xy 364.723571 -91.90937) (xy 364.747243 -91.959867) (xy 364.763311 -92.013274)
			(xy 364.771431 -92.06845) (xy 364.77194 -92.096336) (xy 364.771431 -92.124222) (xy 364.763311 -92.179398)
			(xy 364.747243 -92.232805) (xy 364.723571 -92.283302) (xy 364.692798 -92.329815) (xy 364.659846 -92.366592)
			(xy 366.150396 -92.366592) (xy 366.154467 -92.31097) (xy 366.166593 -92.256533) (xy 366.186516 -92.204442)
			(xy 366.213812 -92.155807) (xy 366.247898 -92.111664) (xy 366.288047 -92.072955) (xy 366.333405 -92.040504)
			(xy 366.383005 -92.015003) (xy 366.435789 -91.996996) (xy 366.490632 -91.986866) (xy 366.546366 -91.984829)
			(xy 366.601803 -91.990929) (xy 366.65576 -92.005035) (xy 366.707089 -92.026847) (xy 366.754695 -92.055901)
			(xy 366.797563 -92.091576) (xy 366.83478 -92.133113) (xy 366.865553 -92.179626) (xy 366.889225 -92.230123)
			(xy 366.905293 -92.28353) (xy 366.913413 -92.338706) (xy 366.913922 -92.366592) (xy 366.913413 -92.394478)
			(xy 366.905293 -92.449654) (xy 366.889225 -92.503061) (xy 366.865553 -92.553558) (xy 366.83478 -92.600071)
			(xy 366.797563 -92.641608) (xy 366.754695 -92.677283) (xy 366.707089 -92.706337) (xy 366.65576 -92.728149)
			(xy 366.601803 -92.742255) (xy 366.546366 -92.748355) (xy 366.490632 -92.746318) (xy 366.435789 -92.736188)
			(xy 366.383005 -92.718181) (xy 366.333405 -92.69268) (xy 366.288047 -92.660229) (xy 366.247898 -92.62152)
			(xy 366.213812 -92.577377) (xy 366.186516 -92.528742) (xy 366.166593 -92.476651) (xy 366.154467 -92.422214)
			(xy 366.150396 -92.366592) (xy 364.659846 -92.366592) (xy 364.655581 -92.371352) (xy 364.612713 -92.407027)
			(xy 364.565107 -92.436081) (xy 364.513778 -92.457893) (xy 364.459821 -92.471999) (xy 364.404384 -92.478099)
			(xy 364.34865 -92.476062) (xy 364.293807 -92.465932) (xy 364.241023 -92.447925) (xy 364.191423 -92.422424)
			(xy 364.146065 -92.389973) (xy 364.105916 -92.351264) (xy 364.07183 -92.307121) (xy 364.044534 -92.258486)
			(xy 364.024611 -92.206395) (xy 364.012485 -92.151958) (xy 364.008414 -92.096336) (xy 363.502187 -92.096336)
			(xy 363.498397 -92.100432) (xy 363.490668 -92.119031) (xy 363.490256 -92.129102) (xy 363.490256 -92.97162)
			(xy 366.878106 -92.97162) (xy 366.882177 -92.915998) (xy 366.894303 -92.861561) (xy 366.914226 -92.80947)
			(xy 366.941522 -92.760835) (xy 366.975608 -92.716692) (xy 367.015757 -92.677983) (xy 367.061115 -92.645532)
			(xy 367.110715 -92.620031) (xy 367.163499 -92.602024) (xy 367.218342 -92.591894) (xy 367.274076 -92.589857)
			(xy 367.329513 -92.595957) (xy 367.38347 -92.610063) (xy 367.434799 -92.631875) (xy 367.482405 -92.660929)
			(xy 367.525273 -92.696604) (xy 367.56249 -92.738141) (xy 367.593263 -92.784654) (xy 367.616935 -92.835151)
			(xy 367.633003 -92.888558) (xy 367.641123 -92.943734) (xy 367.641632 -92.97162) (xy 367.641123 -92.999506)
			(xy 367.633003 -93.054682) (xy 367.616935 -93.108089) (xy 367.593263 -93.158586) (xy 367.56249 -93.205099)
			(xy 367.525273 -93.246636) (xy 367.482405 -93.282311) (xy 367.434799 -93.311365) (xy 367.38347 -93.333177)
			(xy 367.329513 -93.347283) (xy 367.274076 -93.353383) (xy 367.218342 -93.351346) (xy 367.163499 -93.341216)
			(xy 367.110715 -93.323209) (xy 367.061115 -93.297708) (xy 367.015757 -93.265257) (xy 366.975608 -93.226548)
			(xy 366.941522 -93.182405) (xy 366.914226 -93.13377) (xy 366.894303 -93.081679) (xy 366.882177 -93.027242)
			(xy 366.878106 -92.97162) (xy 363.490256 -92.97162) (xy 363.490256 -94.328742) (xy 363.490688 -94.338808)
			(xy 363.49842 -94.357396) (xy 363.505242 -94.36481) (xy 363.680248 -94.539816) (xy 363.687645 -94.546664)
			(xy 363.706244 -94.554394) (xy 363.716316 -94.554802) (xy 364.816644 -94.554802)
		)
		(stroke
			(width 0)
			(type solid)
		)
		(fill yes)
		(layer "In5.Cu")
		(net "GND")
	)
	(gr_poly
		(pts
			(xy 93.556582 -335.815178) (xy 93.563741 -335.813473) (xy 93.576765 -335.806638) (xy 93.582236 -335.801716)
			(xy 94.52229 -334.861662) (xy 94.527277 -334.856163) (xy 94.534119 -334.842996) (xy 94.535752 -334.835754)
			(xy 94.536768 -334.826102) (xy 94.536768 -334.337152) (xy 94.53634 -334.327072) (xy 94.528568 -334.308472)
			(xy 94.51421 -334.294321) (xy 94.505018 -334.290162) (xy 94.417388 -334.254856) (xy 94.407909 -334.251486)
			(xy 94.387808 -334.251703) (xy 94.36934 -334.259641) (xy 94.362016 -334.26654) (xy 94.361762 -334.266794)
			(xy 94.340104 -334.28867) (xy 94.291937 -334.327004) (xy 94.239064 -334.358533) (xy 94.182442 -334.382689)
			(xy 94.123093 -334.399035) (xy 94.062088 -334.407276) (xy 94.031308 -334.407764) (xy 94.00134 -334.407295)
			(xy 93.941916 -334.399473) (xy 93.884021 -334.38396) (xy 93.828648 -334.361022) (xy 93.776741 -334.331053)
			(xy 93.729192 -334.294565) (xy 93.686812 -334.252181) (xy 93.650327 -334.204629) (xy 93.620362 -334.15272)
			(xy 93.597429 -334.097344) (xy 93.58192 -334.039449) (xy 93.574102 -333.980024) (xy 93.5736 -333.950056)
			(xy 93.5736 -333.086456) (xy 93.574093 -333.05649) (xy 93.581921 -332.997073) (xy 93.597437 -332.939185)
			(xy 93.620376 -332.883817) (xy 93.650345 -332.831917) (xy 93.686832 -332.784373) (xy 93.729212 -332.741998)
			(xy 93.776761 -332.705516) (xy 93.828664 -332.675553) (xy 93.884034 -332.65262) (xy 93.941924 -332.637111)
			(xy 94.001342 -332.629289) (xy 94.031308 -332.628748) (xy 94.062087 -332.629248) (xy 94.123089 -332.637497)
			(xy 94.182436 -332.653845) (xy 94.239057 -332.677998) (xy 94.291932 -332.709519) (xy 94.340106 -332.747841)
			(xy 94.361762 -332.769718) (xy 94.362016 -332.769972) (xy 94.36939 -332.776785) (xy 94.387836 -332.784654)
			(xy 94.407889 -332.784906) (xy 94.417388 -332.781656) (xy 94.505018 -332.74635) (xy 94.51419 -332.742163)
			(xy 94.528521 -332.728002) (xy 94.536333 -332.709431) (xy 94.536768 -332.69936) (xy 94.536768 -308.437026)
			(xy 94.537272 -308.426975) (xy 94.544992 -308.408412) (xy 94.551754 -308.400958) (xy 95.956374 -306.996338)
			(xy 95.961352 -306.990834) (xy 95.968177 -306.977664) (xy 95.969836 -306.97043) (xy 95.970852 -306.960778)
			(xy 95.970852 -298.360338) (xy 95.970512 -298.351644) (xy 95.964676 -298.335267) (xy 95.959422 -298.328334)
			(xy 95.95612 -298.324524) (xy 94.43593 -296.804334) (xy 94.429091 -296.796933) (xy 94.421376 -296.778335)
			(xy 94.420944 -296.768266) (xy 94.420944 -293.981124) (xy 94.420601 -293.972431) (xy 94.414762 -293.956058)
			(xy 94.409514 -293.94912) (xy 94.406212 -293.94531) (xy 91.335352 -290.87445) (xy 91.331619 -290.870933)
			(xy 91.323041 -290.865312) (xy 91.318334 -290.863274) (xy 91.309698 -290.859718) (xy 84.055458 -290.859718)
			(xy 84.045391 -290.859288) (xy 84.026796 -290.851565) (xy 84.01939 -290.844732) (xy 83.99272 -290.818062)
			(xy 83.985308 -290.811378) (xy 83.966875 -290.803781) (xy 83.946937 -290.803781) (xy 83.928504 -290.811378)
			(xy 83.921092 -290.818062) (xy 83.700366 -291.038788) (xy 83.696844 -291.042518) (xy 83.691212 -291.051091)
			(xy 83.68919 -291.055806) (xy 83.685634 -291.064442) (xy 83.685634 -291.465) (xy 86.104982 -291.465)
			(xy 86.109053 -291.409378) (xy 86.121179 -291.354941) (xy 86.141102 -291.30285) (xy 86.168398 -291.254215)
			(xy 86.202484 -291.210072) (xy 86.242633 -291.171363) (xy 86.287991 -291.138912) (xy 86.337591 -291.113411)
			(xy 86.390375 -291.095404) (xy 86.445218 -291.085274) (xy 86.500952 -291.083237) (xy 86.556389 -291.089337)
			(xy 86.610346 -291.103443) (xy 86.661675 -291.125255) (xy 86.709281 -291.154309) (xy 86.752149 -291.189984)
			(xy 86.789366 -291.231521) (xy 86.820139 -291.278034) (xy 86.843811 -291.328531) (xy 86.859879 -291.381938)
			(xy 86.867999 -291.437114) (xy 86.868508 -291.465) (xy 86.867999 -291.492886) (xy 86.859879 -291.548062)
			(xy 86.843811 -291.601469) (xy 86.820139 -291.651966) (xy 86.789366 -291.698479) (xy 86.752149 -291.740016)
			(xy 86.709281 -291.775691) (xy 86.661675 -291.804745) (xy 86.610346 -291.826557) (xy 86.556389 -291.840663)
			(xy 86.500952 -291.846763) (xy 86.445218 -291.844726) (xy 86.390375 -291.834596) (xy 86.337591 -291.816589)
			(xy 86.287991 -291.791088) (xy 86.242633 -291.758637) (xy 86.202484 -291.719928) (xy 86.168398 -291.675785)
			(xy 86.141102 -291.62715) (xy 86.121179 -291.575059) (xy 86.109053 -291.520622) (xy 86.104982 -291.465)
			(xy 83.685634 -291.465) (xy 83.685634 -294.016176) (xy 89.640662 -294.016176) (xy 89.644733 -293.960554)
			(xy 89.656859 -293.906117) (xy 89.676782 -293.854026) (xy 89.704078 -293.805391) (xy 89.738164 -293.761248)
			(xy 89.778313 -293.722539) (xy 89.823671 -293.690088) (xy 89.873271 -293.664587) (xy 89.926055 -293.64658)
			(xy 89.980898 -293.63645) (xy 90.036632 -293.634413) (xy 90.092069 -293.640513) (xy 90.146026 -293.654619)
			(xy 90.197355 -293.676431) (xy 90.244961 -293.705485) (xy 90.287829 -293.74116) (xy 90.325046 -293.782697)
			(xy 90.355819 -293.82921) (xy 90.379491 -293.879707) (xy 90.395559 -293.933114) (xy 90.40255 -293.980616)
			(xy 91.28074 -293.980616) (xy 91.284811 -293.924994) (xy 91.296937 -293.870557) (xy 91.31686 -293.818466)
			(xy 91.344156 -293.769831) (xy 91.378242 -293.725688) (xy 91.418391 -293.686979) (xy 91.463749 -293.654528)
			(xy 91.513349 -293.629027) (xy 91.566133 -293.61102) (xy 91.620976 -293.60089) (xy 91.67671 -293.598853)
			(xy 91.732147 -293.604953) (xy 91.786104 -293.619059) (xy 91.837433 -293.640871) (xy 91.885039 -293.669925)
			(xy 91.927907 -293.7056) (xy 91.965124 -293.747137) (xy 91.995897 -293.79365) (xy 92.019569 -293.844147)
			(xy 92.035637 -293.897554) (xy 92.043757 -293.95273) (xy 92.044266 -293.980616) (xy 92.043757 -294.008502)
			(xy 92.035637 -294.063678) (xy 92.019569 -294.117085) (xy 91.995897 -294.167582) (xy 91.965124 -294.214095)
			(xy 91.927907 -294.255632) (xy 91.885039 -294.291307) (xy 91.837433 -294.320361) (xy 91.786104 -294.342173)
			(xy 91.732147 -294.356279) (xy 91.67671 -294.362379) (xy 91.620976 -294.360342) (xy 91.566133 -294.350212)
			(xy 91.513349 -294.332205) (xy 91.463749 -294.306704) (xy 91.418391 -294.274253) (xy 91.378242 -294.235544)
			(xy 91.344156 -294.191401) (xy 91.31686 -294.142766) (xy 91.296937 -294.090675) (xy 91.284811 -294.036238)
			(xy 91.28074 -293.980616) (xy 90.40255 -293.980616) (xy 90.403679 -293.98829) (xy 90.404188 -294.016176)
			(xy 90.403679 -294.044062) (xy 90.395559 -294.099238) (xy 90.379491 -294.152645) (xy 90.355819 -294.203142)
			(xy 90.325046 -294.249655) (xy 90.287829 -294.291192) (xy 90.244961 -294.326867) (xy 90.197355 -294.355921)
			(xy 90.146026 -294.377733) (xy 90.092069 -294.391839) (xy 90.036632 -294.397939) (xy 89.980898 -294.395902)
			(xy 89.926055 -294.385772) (xy 89.873271 -294.367765) (xy 89.823671 -294.342264) (xy 89.778313 -294.309813)
			(xy 89.738164 -294.271104) (xy 89.704078 -294.226961) (xy 89.676782 -294.178326) (xy 89.656859 -294.126235)
			(xy 89.644733 -294.071798) (xy 89.640662 -294.016176) (xy 83.685634 -294.016176) (xy 83.685634 -295.915588)
			(xy 83.68665 -295.925494) (xy 83.688354 -295.932654) (xy 83.695184 -295.945682) (xy 83.700112 -295.951148)
			(xy 84.679028 -296.930064) (xy 84.68453 -296.935046) (xy 84.697698 -296.941881) (xy 84.704936 -296.943526)
			(xy 84.714588 -296.944542) (xy 89.219532 -296.944542) (xy 89.224358 -296.944288) (xy 89.23472 -296.942861)
			(xy 89.253091 -296.932906) (xy 89.259918 -296.924984) (xy 89.26322 -296.91965) (xy 89.307924 -296.844974)
			(xy 89.309448 -296.84218) (xy 89.314091 -296.831887) (xy 89.314864 -296.809348) (xy 89.310972 -296.798746)
			(xy 89.30894 -296.794936) (xy 89.294518 -296.766901) (xy 89.27405 -296.707276) (xy 89.263652 -296.6451)
			(xy 89.262966 -296.61358) (xy 89.262966 -296.613072) (xy 89.263452 -296.585821) (xy 89.271208 -296.531873)
			(xy 89.286563 -296.479578) (xy 89.309205 -296.430001) (xy 89.338671 -296.384151) (xy 89.374362 -296.34296)
			(xy 89.415553 -296.307269) (xy 89.461403 -296.277803) (xy 89.51098 -296.255161) (xy 89.563275 -296.239806)
			(xy 89.617223 -296.23205) (xy 89.671725 -296.23205) (xy 89.725673 -296.239806) (xy 89.777968 -296.255161)
			(xy 89.827545 -296.277803) (xy 89.873395 -296.307269) (xy 89.914586 -296.34296) (xy 89.950277 -296.384151)
			(xy 89.979743 -296.430001) (xy 90.002385 -296.479578) (xy 90.01774 -296.531873) (xy 90.025496 -296.585821)
			(xy 90.025982 -296.613072) (xy 90.026236 -296.613072) (xy 90.025595 -296.644691) (xy 90.015135 -296.707058)
			(xy 89.994545 -296.76685) (xy 89.980008 -296.794936) (xy 89.978484 -296.797984) (xy 89.974209 -296.80868)
			(xy 89.974751 -296.831684) (xy 89.9795 -296.84218) (xy 89.981024 -296.844974) (xy 90.025728 -296.91965)
			(xy 90.02903 -296.924984) (xy 90.035875 -296.932886) (xy 90.054236 -296.942838) (xy 90.06459 -296.944288)
			(xy 90.069416 -296.944542) (xy 90.494358 -296.944542) (xy 90.499184 -296.944288) (xy 90.509543 -296.942856)
			(xy 90.527907 -296.932896) (xy 90.534744 -296.924984) (xy 90.538046 -296.91965) (xy 90.58275 -296.844974)
			(xy 90.584274 -296.84218) (xy 90.588915 -296.831886) (xy 90.589688 -296.809349) (xy 90.585798 -296.798746)
			(xy 90.583766 -296.794936) (xy 90.569343 -296.766902) (xy 90.548874 -296.707277) (xy 90.538475 -296.6451)
			(xy 90.537792 -296.61358) (xy 90.537792 -296.613072) (xy 90.538278 -296.585821) (xy 90.546034 -296.531873)
			(xy 90.561389 -296.479578) (xy 90.584031 -296.430001) (xy 90.613497 -296.384151) (xy 90.649188 -296.34296)
			(xy 90.690379 -296.307269) (xy 90.736229 -296.277803) (xy 90.785806 -296.255161) (xy 90.838101 -296.239806)
			(xy 90.892049 -296.23205) (xy 90.946551 -296.23205) (xy 91.000499 -296.239806) (xy 91.052794 -296.255161)
			(xy 91.102371 -296.277803) (xy 91.148221 -296.307269) (xy 91.189412 -296.34296) (xy 91.225103 -296.384151)
			(xy 91.254569 -296.430001) (xy 91.277211 -296.479578) (xy 91.292566 -296.531873) (xy 91.300322 -296.585821)
			(xy 91.300808 -296.613072) (xy 91.300278 -296.641964) (xy 91.29157 -296.699089) (xy 91.274349 -296.754247)
			(xy 91.249009 -296.806179) (xy 91.216129 -296.853697) (xy 91.17646 -296.895714) (xy 91.13091 -296.93127)
			(xy 91.08052 -296.959552) (xy 91.026442 -296.979914) (xy 90.998294 -296.986452) (xy 90.992673 -296.988221)
			(xy 90.982404 -296.993997) (xy 90.977974 -296.997882) (xy 90.97772 -296.997882) (xy 90.973043 -297.002415)
			(xy 90.965973 -297.013349) (xy 90.96375 -297.019472) (xy 90.948764 -297.07078) (xy 90.93835 -297.10634)
			(xy 90.937842 -297.108118) (xy 90.937842 -297.108626) (xy 90.935937 -297.117922) (xy 90.938412 -297.136721)
			(xy 90.942668 -297.145202) (xy 90.944469 -297.148313) (xy 90.94881 -297.154043) (xy 90.951304 -297.156632)
			(xy 91.16949 -297.374818) (xy 92.615764 -297.374818) (xy 92.619835 -297.319196) (xy 92.631961 -297.264759)
			(xy 92.651884 -297.212668) (xy 92.67918 -297.164033) (xy 92.713266 -297.11989) (xy 92.753415 -297.081181)
			(xy 92.798773 -297.04873) (xy 92.848373 -297.023229) (xy 92.901157 -297.005222) (xy 92.956 -296.995092)
			(xy 93.011734 -296.993055) (xy 93.067171 -296.999155) (xy 93.121128 -297.013261) (xy 93.172457 -297.035073)
			(xy 93.220063 -297.064127) (xy 93.262931 -297.099802) (xy 93.300148 -297.141339) (xy 93.330921 -297.187852)
			(xy 93.354593 -297.238349) (xy 93.370661 -297.291756) (xy 93.378781 -297.346932) (xy 93.37929 -297.374818)
			(xy 93.378781 -297.402704) (xy 93.370661 -297.45788) (xy 93.354593 -297.511287) (xy 93.330921 -297.561784)
			(xy 93.300148 -297.608297) (xy 93.262931 -297.649834) (xy 93.220063 -297.685509) (xy 93.172457 -297.714563)
			(xy 93.121128 -297.736375) (xy 93.067171 -297.750481) (xy 93.011734 -297.756581) (xy 92.956 -297.754544)
			(xy 92.901157 -297.744414) (xy 92.848373 -297.726407) (xy 92.798773 -297.700906) (xy 92.753415 -297.668455)
			(xy 92.713266 -297.629746) (xy 92.67918 -297.585603) (xy 92.651884 -297.536968) (xy 92.631961 -297.484877)
			(xy 92.619835 -297.43044) (xy 92.615764 -297.374818) (xy 91.16949 -297.374818) (xy 93.609922 -299.81525)
			(xy 93.615991 -299.82096) (xy 93.630912 -299.82836) (xy 93.639132 -299.829728) (xy 93.660631 -299.832952)
			(xy 93.702771 -299.843647) (xy 93.723206 -299.851064) (xy 93.724222 -299.851572) (xy 93.724984 -299.851826)
			(xy 93.73235 -299.85462) (xy 93.980254 -299.85462) (xy 93.99032 -299.854188) (xy 94.008912 -299.846462)
			(xy 94.016322 -299.839634) (xy 94.04985 -299.806106) (xy 94.056703 -299.79871) (xy 94.064447 -299.780112)
			(xy 94.064836 -299.770038) (xy 94.064836 -299.099224) (xy 94.064304 -299.089234) (xy 94.056601 -299.070792)
			(xy 94.04985 -299.06341) (xy 93.733366 -298.746672) (xy 93.726553 -298.739328) (xy 93.71882 -298.720865)
			(xy 93.71838 -298.710858) (xy 93.71838 -298.27601) (xy 93.718915 -298.266021) (xy 93.726624 -298.247585)
			(xy 93.733366 -298.240196) (xy 94.040706 -297.932856) (xy 94.048049 -297.92604) (xy 94.066512 -297.918301)
			(xy 94.07652 -297.91787) (xy 94.511368 -297.91787) (xy 94.521359 -297.918401) (xy 94.539802 -297.926103)
			(xy 94.547182 -297.932856) (xy 95.200978 -298.586652) (xy 95.207783 -298.593999) (xy 95.2155 -298.612462)
			(xy 95.215964 -298.622466) (xy 95.215964 -304.708814) (xy 95.215423 -304.718799) (xy 95.207702 -304.737224)
			(xy 95.200978 -304.744628) (xy 93.601032 -306.344574) (xy 93.593684 -306.351377) (xy 93.575221 -306.359089)
			(xy 93.565218 -306.35956) (xy 91.28379 -306.35956) (xy 91.281758 -306.35956) (xy 91.262454 -306.360068)
			(xy 86.424262 -306.360068) (xy 86.416947 -306.361211) (xy 86.403394 -306.367153) (xy 86.397592 -306.371752)
			(xy 85.978492 -306.790852) (xy 85.970872 -306.798218) (xy 85.969856 -306.799234) (xy 85.684797 -307.084222)
			(xy 92.714316 -307.084222) (xy 92.718387 -307.0286) (xy 92.730513 -306.974163) (xy 92.750436 -306.922072)
			(xy 92.777732 -306.873437) (xy 92.811818 -306.829294) (xy 92.851967 -306.790585) (xy 92.897325 -306.758134)
			(xy 92.946925 -306.732633) (xy 92.999709 -306.714626) (xy 93.054552 -306.704496) (xy 93.110286 -306.702459)
			(xy 93.165723 -306.708559) (xy 93.21968 -306.722665) (xy 93.271009 -306.744477) (xy 93.318615 -306.773531)
			(xy 93.361483 -306.809206) (xy 93.3987 -306.850743) (xy 93.429473 -306.897256) (xy 93.453145 -306.947753)
			(xy 93.469213 -307.00116) (xy 93.477333 -307.056336) (xy 93.477842 -307.084222) (xy 93.477333 -307.112108)
			(xy 93.469213 -307.167284) (xy 93.453145 -307.220691) (xy 93.429473 -307.271188) (xy 93.3987 -307.317701)
			(xy 93.361483 -307.359238) (xy 93.318615 -307.394913) (xy 93.271009 -307.423967) (xy 93.21968 -307.445779)
			(xy 93.165723 -307.459885) (xy 93.110286 -307.465985) (xy 93.054552 -307.463948) (xy 92.999709 -307.453818)
			(xy 92.946925 -307.435811) (xy 92.897325 -307.41031) (xy 92.851967 -307.377859) (xy 92.811818 -307.33915)
			(xy 92.777732 -307.295007) (xy 92.750436 -307.246372) (xy 92.730513 -307.194281) (xy 92.718387 -307.139844)
			(xy 92.714316 -307.084222) (xy 85.684797 -307.084222) (xy 84.954364 -307.814472) (xy 84.678266 -308.09057)
			(xy 84.670867 -308.097414) (xy 84.652269 -308.105141) (xy 84.642198 -308.105556) (xy 82.854546 -308.105556)
			(xy 82.843858 -308.106127) (xy 82.824318 -308.1148) (xy 82.8167 -308.12232) (xy 82.766154 -308.178454)
			(xy 82.759369 -308.186675) (xy 82.752792 -308.206931) (xy 82.753454 -308.21757) (xy 82.753454 -308.217824)
			(xy 82.755232 -308.249828) (xy 82.754759 -308.273818) (xy 82.74725 -308.321208) (xy 82.73242 -308.36684)
			(xy 82.710636 -308.409591) (xy 82.682432 -308.448407) (xy 82.648504 -308.482335) (xy 82.609687 -308.510538)
			(xy 82.566936 -308.532322) (xy 82.521304 -308.547151) (xy 82.473914 -308.55466) (xy 82.449924 -308.555136)
			(xy 82.420206 -308.553612) (xy 82.419698 -308.553612) (xy 82.40903 -308.552596) (xy 82.389218 -308.5592)
			(xy 82.32521 -308.617112) (xy 82.317669 -308.624711) (xy 82.309016 -308.644266) (xy 82.308446 -308.654958)
			(xy 82.308446 -309.175912) (xy 88.334086 -309.175912) (xy 88.338157 -309.12029) (xy 88.350283 -309.065853)
			(xy 88.370206 -309.013762) (xy 88.397502 -308.965127) (xy 88.431588 -308.920984) (xy 88.471737 -308.882275)
			(xy 88.517095 -308.849824) (xy 88.566695 -308.824323) (xy 88.619479 -308.806316) (xy 88.674322 -308.796186)
			(xy 88.730056 -308.794149) (xy 88.785493 -308.800249) (xy 88.83945 -308.814355) (xy 88.890779 -308.836167)
			(xy 88.938385 -308.865221) (xy 88.981253 -308.900896) (xy 89.01847 -308.942433) (xy 89.049243 -308.988946)
			(xy 89.072915 -309.039443) (xy 89.088983 -309.09285) (xy 89.097103 -309.148026) (xy 89.097612 -309.175912)
			(xy 89.097103 -309.203798) (xy 89.088983 -309.258974) (xy 89.072915 -309.312381) (xy 89.049243 -309.362878)
			(xy 89.01847 -309.409391) (xy 88.981253 -309.450928) (xy 88.938385 -309.486603) (xy 88.890779 -309.515657)
			(xy 88.83945 -309.537469) (xy 88.785493 -309.551575) (xy 88.730056 -309.557675) (xy 88.674322 -309.555638)
			(xy 88.619479 -309.545508) (xy 88.566695 -309.527501) (xy 88.517095 -309.502) (xy 88.471737 -309.469549)
			(xy 88.431588 -309.43084) (xy 88.397502 -309.386697) (xy 88.370206 -309.338062) (xy 88.350283 -309.285971)
			(xy 88.338157 -309.231534) (xy 88.334086 -309.175912) (xy 82.308446 -309.175912) (xy 82.308446 -309.241698)
			(xy 82.30887 -309.251767) (xy 82.316589 -309.270368) (xy 82.323432 -309.277766) (xy 82.37474 -309.329074)
			(xy 82.382139 -309.335917) (xy 82.400738 -309.343641) (xy 82.410808 -309.34406) (xy 82.924904 -309.34406)
			(xy 82.950893 -309.34457) (xy 83.002232 -309.352702) (xy 83.051667 -309.368765) (xy 83.097981 -309.392363)
			(xy 83.140032 -309.422916) (xy 83.176787 -309.459671) (xy 83.207339 -309.501723) (xy 83.230937 -309.548036)
			(xy 83.246999 -309.597471) (xy 83.25513 -309.648811) (xy 83.25513 -309.700789) (xy 83.246999 -309.752129)
			(xy 83.230937 -309.801564) (xy 83.207339 -309.847877) (xy 83.203377 -309.85333) (xy 89.010742 -309.85333)
			(xy 89.014813 -309.797708) (xy 89.026939 -309.743271) (xy 89.046862 -309.69118) (xy 89.074158 -309.642545)
			(xy 89.108244 -309.598402) (xy 89.148393 -309.559693) (xy 89.193751 -309.527242) (xy 89.243351 -309.501741)
			(xy 89.296135 -309.483734) (xy 89.350978 -309.473604) (xy 89.406712 -309.471567) (xy 89.462149 -309.477667)
			(xy 89.516106 -309.491773) (xy 89.567435 -309.513585) (xy 89.615041 -309.542639) (xy 89.657909 -309.578314)
			(xy 89.695126 -309.619851) (xy 89.725899 -309.666364) (xy 89.749571 -309.716861) (xy 89.765639 -309.770268)
			(xy 89.773759 -309.825444) (xy 89.774268 -309.85333) (xy 89.773759 -309.881216) (xy 89.765639 -309.936392)
			(xy 89.749571 -309.989799) (xy 89.725899 -310.040296) (xy 89.695126 -310.086809) (xy 89.657909 -310.128346)
			(xy 89.615041 -310.164021) (xy 89.567435 -310.193075) (xy 89.516106 -310.214887) (xy 89.462149 -310.228993)
			(xy 89.406712 -310.235093) (xy 89.350978 -310.233056) (xy 89.296135 -310.222926) (xy 89.243351 -310.204919)
			(xy 89.193751 -310.179418) (xy 89.148393 -310.146967) (xy 89.108244 -310.108258) (xy 89.074158 -310.064115)
			(xy 89.046862 -310.01548) (xy 89.026939 -309.963389) (xy 89.014813 -309.908952) (xy 89.010742 -309.85333)
			(xy 83.203377 -309.85333) (xy 83.176787 -309.889929) (xy 83.140032 -309.926684) (xy 83.097981 -309.957237)
			(xy 83.051667 -309.980835) (xy 83.002232 -309.996898) (xy 82.950893 -310.00503) (xy 82.924904 -310.005476)
			(xy 82.854546 -310.005476) (xy 82.843856 -310.006044) (xy 82.824307 -310.014708) (xy 82.8167 -310.02224)
			(xy 82.766154 -310.078374) (xy 82.759372 -310.086596) (xy 82.752803 -310.106851) (xy 82.753454 -310.11749)
			(xy 82.753454 -310.117744) (xy 82.755232 -310.149748) (xy 82.754758 -310.173737) (xy 82.747246 -310.221125)
			(xy 82.732415 -310.266754) (xy 82.710629 -310.309502) (xy 82.682425 -310.348316) (xy 82.648497 -310.382241)
			(xy 82.609681 -310.410441) (xy 82.566932 -310.432224) (xy 82.521301 -310.447052) (xy 82.473913 -310.45456)
			(xy 82.449924 -310.455056) (xy 82.420714 -310.453786) (xy 82.410046 -310.45277) (xy 82.389726 -310.459374)
			(xy 82.326226 -310.517032) (xy 82.318686 -310.524631) (xy 82.310039 -310.544187) (xy 82.309462 -310.554878)
			(xy 82.309462 -310.68518) (xy 89.842592 -310.68518) (xy 89.846663 -310.629558) (xy 89.858789 -310.575121)
			(xy 89.878712 -310.52303) (xy 89.906008 -310.474395) (xy 89.940094 -310.430252) (xy 89.980243 -310.391543)
			(xy 90.025601 -310.359092) (xy 90.075201 -310.333591) (xy 90.127985 -310.315584) (xy 90.182828 -310.305454)
			(xy 90.238562 -310.303417) (xy 90.293999 -310.309517) (xy 90.347956 -310.323623) (xy 90.399285 -310.345435)
			(xy 90.446891 -310.374489) (xy 90.489759 -310.410164) (xy 90.526976 -310.451701) (xy 90.557749 -310.498214)
			(xy 90.581421 -310.548711) (xy 90.597489 -310.602118) (xy 90.605609 -310.657294) (xy 90.606118 -310.68518)
			(xy 90.605609 -310.713066) (xy 90.597489 -310.768242) (xy 90.581421 -310.821649) (xy 90.557749 -310.872146)
			(xy 90.526976 -310.918659) (xy 90.489759 -310.960196) (xy 90.446891 -310.995871) (xy 90.399285 -311.024925)
			(xy 90.347956 -311.046737) (xy 90.293999 -311.060843) (xy 90.238562 -311.066943) (xy 90.182828 -311.064906)
			(xy 90.127985 -311.054776) (xy 90.075201 -311.036769) (xy 90.025601 -311.011268) (xy 89.980243 -310.978817)
			(xy 89.940094 -310.940108) (xy 89.906008 -310.895965) (xy 89.878712 -310.84733) (xy 89.858789 -310.795239)
			(xy 89.846663 -310.740802) (xy 89.842592 -310.68518) (xy 82.309462 -310.68518) (xy 82.309462 -311.150254)
			(xy 82.309897 -311.160318) (xy 82.317632 -311.178903) (xy 82.324448 -311.186322) (xy 82.36712 -311.228994)
			(xy 82.374519 -311.235838) (xy 82.393117 -311.243566) (xy 82.403188 -311.24398) (xy 82.924904 -311.24398)
			(xy 82.950908 -311.24449) (xy 83.002274 -311.252627) (xy 83.051736 -311.268698) (xy 83.098075 -311.29231)
			(xy 83.140149 -311.322879) (xy 83.176924 -311.359654) (xy 83.192351 -311.380887) (xy 90.566604 -311.380887)
			(xy 90.574356 -311.326928) (xy 90.589708 -311.274622) (xy 90.612348 -311.225033) (xy 90.641815 -311.17917)
			(xy 90.677508 -311.137968) (xy 90.718703 -311.102265) (xy 90.764559 -311.072788) (xy 90.814143 -311.050137)
			(xy 90.866446 -311.034774) (xy 90.920404 -311.02701) (xy 90.974917 -311.027004) (xy 91.028875 -311.034757)
			(xy 91.081182 -311.050109) (xy 91.130771 -311.07275) (xy 91.176633 -311.102217) (xy 91.217835 -311.137911)
			(xy 91.253537 -311.179106) (xy 91.283014 -311.224962) (xy 91.305664 -311.274547) (xy 91.321027 -311.32685)
			(xy 91.32879 -311.380808) (xy 91.329256 -311.408064) (xy 91.329059 -311.425112) (xy 91.326005 -311.459072)
			(xy 91.32316 -311.475882) (xy 91.320874 -311.488328) (xy 91.32824 -311.51195) (xy 91.405202 -311.588912)
			(xy 91.428824 -311.596278) (xy 91.44127 -311.593992) (xy 91.458079 -311.591134) (xy 91.492039 -311.588079)
			(xy 91.509088 -311.587896) (xy 91.509342 -311.587896) (xy 91.536594 -311.588339) (xy 91.590544 -311.596101)
			(xy 91.64284 -311.611462) (xy 91.692417 -311.634108) (xy 91.738268 -311.663579) (xy 91.779458 -311.699275)
			(xy 91.815149 -311.740469) (xy 91.844614 -311.786323) (xy 91.867254 -311.835903) (xy 91.882609 -311.888201)
			(xy 91.890365 -311.942151) (xy 91.89085 -311.969404) (xy 91.889834 -311.99836) (xy 91.889072 -312.009536)
			(xy 91.896692 -312.030364) (xy 91.967812 -312.100468) (xy 91.98864 -312.108088) (xy 91.999816 -312.107072)
			(xy 92.032328 -312.105802) (xy 92.059577 -312.106308) (xy 92.113519 -312.114068) (xy 92.165807 -312.129425)
			(xy 92.215378 -312.152067) (xy 92.261223 -312.181533) (xy 92.302407 -312.217224) (xy 92.338093 -312.258412)
			(xy 92.367554 -312.30426) (xy 92.39019 -312.353833) (xy 92.405541 -312.406124) (xy 92.413295 -312.460067)
			(xy 92.413293 -312.514564) (xy 92.405535 -312.568506) (xy 92.39018 -312.620795) (xy 92.367539 -312.670367)
			(xy 92.338074 -312.716212) (xy 92.302385 -312.757398) (xy 92.261198 -312.793085) (xy 92.215351 -312.822548)
			(xy 92.165779 -312.845186) (xy 92.113489 -312.860539) (xy 92.059546 -312.868294) (xy 92.005049 -312.868294)
			(xy 91.951106 -312.860538) (xy 91.898816 -312.845184) (xy 91.849244 -312.822545) (xy 91.803398 -312.793082)
			(xy 91.762211 -312.757394) (xy 91.726523 -312.716208) (xy 91.697058 -312.670363) (xy 91.674419 -312.62079)
			(xy 91.659064 -312.568501) (xy 91.651307 -312.514559) (xy 91.65082 -312.48731) (xy 91.651836 -312.458354)
			(xy 91.652598 -312.447178) (xy 91.644978 -312.42635) (xy 91.573858 -312.356246) (xy 91.55303 -312.348626)
			(xy 91.541854 -312.349642) (xy 91.509342 -312.350912) (xy 91.48209 -312.350406) (xy 91.428141 -312.342654)
			(xy 91.375844 -312.327304) (xy 91.326265 -312.304667) (xy 91.280412 -312.275203) (xy 91.239218 -312.239514)
			(xy 91.203524 -312.198325) (xy 91.174055 -312.152476) (xy 91.151412 -312.102899) (xy 91.136055 -312.050604)
			(xy 91.128298 -311.996656) (xy 91.127834 -311.969404) (xy 91.12804 -311.952356) (xy 91.131088 -311.918397)
			(xy 91.13393 -311.901586) (xy 91.136216 -311.88914) (xy 91.12885 -311.865518) (xy 91.051888 -311.788556)
			(xy 91.028266 -311.78119) (xy 91.01582 -311.783476) (xy 90.999012 -311.786335) (xy 90.965051 -311.789389)
			(xy 90.948002 -311.789572) (xy 90.947748 -311.789572) (xy 90.920491 -311.789196) (xy 90.866532 -311.781445)
			(xy 90.814226 -311.766094) (xy 90.764636 -311.743454) (xy 90.718773 -311.713988) (xy 90.677571 -311.678294)
			(xy 90.641867 -311.637101) (xy 90.61239 -311.591245) (xy 90.589739 -311.541661) (xy 90.574374 -311.489358)
			(xy 90.56661 -311.4354) (xy 90.566604 -311.380887) (xy 83.192351 -311.380887) (xy 83.207493 -311.401729)
			(xy 83.231103 -311.448068) (xy 83.247174 -311.497529) (xy 83.25531 -311.548896) (xy 83.25531 -311.600904)
			(xy 83.247174 -311.652271) (xy 83.231103 -311.701732) (xy 83.207493 -311.748071) (xy 83.176924 -311.790146)
			(xy 83.140149 -311.826921) (xy 83.098075 -311.85749) (xy 83.051736 -311.881102) (xy 83.002274 -311.897173)
			(xy 82.950908 -311.90531) (xy 82.924904 -311.905904) (xy 82.854546 -311.905904) (xy 82.843857 -311.906473)
			(xy 82.824311 -311.91514) (xy 82.8167 -311.922668) (xy 82.766154 -311.978802) (xy 82.759377 -311.987025)
			(xy 82.752819 -312.00728) (xy 82.753454 -312.017918) (xy 82.753454 -312.018172) (xy 82.755232 -312.049922)
			(xy 82.75476 -312.073913) (xy 82.747251 -312.121303) (xy 82.732422 -312.166936) (xy 82.710638 -312.209687)
			(xy 82.682434 -312.248505) (xy 82.648506 -312.282433) (xy 82.609689 -312.310637) (xy 82.566938 -312.332421)
			(xy 82.521305 -312.347251) (xy 82.473915 -312.35476) (xy 82.449924 -312.35523) (xy 82.423954 -312.354702)
			(xy 82.372764 -312.345899) (xy 82.323803 -312.328561) (xy 82.278482 -312.303186) (xy 82.238109 -312.270508)
			(xy 82.203849 -312.231469) (xy 82.176689 -312.187195) (xy 82.157413 -312.138964) (xy 82.151474 -312.113676)
			(xy 82.14868 -312.10504) (xy 82.14468 -312.096361) (xy 82.131454 -312.082588) (xy 82.1141 -312.074621)
			(xy 82.095034 -312.073571) (xy 82.07691 -312.079582) (xy 82.06225 -312.091818) (xy 82.05724 -312.09996)
			(xy 82.055394 -312.10315) (xy 82.050928 -312.109011) (xy 82.04835 -312.111644) (xy 82.048096 -312.111898)
			(xy 81.31302 -312.846974) (xy 81.305618 -312.853811) (xy 81.28702 -312.86152) (xy 81.276952 -312.86196)
			(xy 81.12887 -312.86196) (xy 81.118804 -312.86239) (xy 81.100213 -312.870119) (xy 81.092802 -312.876946)
			(xy 81.059274 -312.910474) (xy 81.032671 -312.936277) (xy 80.974075 -312.981659) (xy 80.91022 -313.019283)
			(xy 80.876394 -313.034426) (xy 80.865665 -313.039718) (xy 80.850276 -313.057995) (xy 80.84693 -313.069478)
			(xy 80.840584 -313.094279) (xy 80.820758 -313.141472) (xy 80.793341 -313.1847) (xy 80.7591 -313.222751)
			(xy 80.718995 -313.254561) (xy 80.674147 -313.279238) (xy 80.625812 -313.296093) (xy 80.575344 -313.304652)
			(xy 80.54975 -313.30519) (xy 80.52383 -313.304637) (xy 80.472736 -313.295874) (xy 80.423856 -313.278607)
			(xy 80.378594 -313.253332) (xy 80.338251 -313.220777) (xy 80.303986 -313.181875) (xy 80.276784 -313.137746)
			(xy 80.26654 -313.113928) (xy 80.26654 -313.113674) (xy 80.262327 -313.104469) (xy 80.248083 -313.090107)
			(xy 80.22941 -313.082329) (xy 80.219296 -313.081924) (xy 79.957422 -313.081924) (xy 79.94707 -313.082351)
			(xy 79.928014 -313.090434) (xy 79.913723 -313.105408) (xy 79.90967 -313.114944) (xy 79.900487 -313.13833)
			(xy 79.876074 -313.182238) (xy 79.845297 -313.221946) (xy 79.808866 -313.25654) (xy 79.76762 -313.285223)
			(xy 79.722508 -313.307334) (xy 79.67457 -313.322363) (xy 79.62491 -313.329966) (xy 79.57467 -313.329966)
			(xy 79.52501 -313.322363) (xy 79.477072 -313.307334) (xy 79.43196 -313.285223) (xy 79.390714 -313.25654)
			(xy 79.354283 -313.221946) (xy 79.323506 -313.182238) (xy 79.299093 -313.13833) (xy 79.28991 -313.114944)
			(xy 79.285821 -313.105436) (xy 79.271518 -313.090503) (xy 79.252497 -313.082392) (xy 79.242158 -313.081924)
			(xy 78.980284 -313.081924) (xy 78.970155 -313.082297) (xy 78.951439 -313.09003) (xy 78.937202 -313.104433)
			(xy 78.93304 -313.113674) (xy 78.93304 -313.113928) (xy 78.923574 -313.136198) (xy 78.898645 -313.17767)
			(xy 78.867487 -313.214691) (xy 78.830879 -313.246334) (xy 78.789738 -313.271807) (xy 78.745095 -313.290471)
			(xy 78.698066 -313.30186) (xy 78.64983 -313.305688) (xy 78.601594 -313.30186) (xy 78.554565 -313.290471)
			(xy 78.509922 -313.271807) (xy 78.468781 -313.246334) (xy 78.432173 -313.214691) (xy 78.401015 -313.17767)
			(xy 78.376086 -313.136198) (xy 78.36662 -313.113928) (xy 78.36662 -313.113674) (xy 78.362406 -313.104471)
			(xy 78.348161 -313.090115) (xy 78.329489 -313.082343) (xy 78.319376 -313.081924) (xy 78.057502 -313.081924)
			(xy 78.047152 -313.082355) (xy 78.028103 -313.090442) (xy 78.013818 -313.105416) (xy 78.00975 -313.114944)
			(xy 78.000567 -313.13833) (xy 77.976154 -313.182238) (xy 77.945377 -313.221946) (xy 77.908946 -313.25654)
			(xy 77.8677 -313.285223) (xy 77.822588 -313.307334) (xy 77.77465 -313.322363) (xy 77.72499 -313.329966)
			(xy 77.67475 -313.329966) (xy 77.62509 -313.322363) (xy 77.577152 -313.307334) (xy 77.53204 -313.285223)
			(xy 77.490794 -313.25654) (xy 77.454363 -313.221946) (xy 77.423586 -313.182238) (xy 77.399173 -313.13833)
			(xy 77.38999 -313.114944) (xy 77.3859 -313.105438) (xy 77.371596 -313.090511) (xy 77.352576 -313.082408)
			(xy 77.342238 -313.081924) (xy 77.080364 -313.081924) (xy 77.070238 -313.082301) (xy 77.051527 -313.090038)
			(xy 77.037297 -313.104441) (xy 77.03312 -313.113674) (xy 77.03312 -313.113928) (xy 77.023654 -313.136198)
			(xy 76.998725 -313.17767) (xy 76.967567 -313.214691) (xy 76.930959 -313.246334) (xy 76.889818 -313.271807)
			(xy 76.845175 -313.290471) (xy 76.798146 -313.30186) (xy 76.74991 -313.305688) (xy 76.701674 -313.30186)
			(xy 76.654645 -313.290471) (xy 76.610002 -313.271807) (xy 76.568861 -313.246334) (xy 76.532253 -313.214691)
			(xy 76.501095 -313.17767) (xy 76.476166 -313.136198) (xy 76.4667 -313.113928) (xy 76.4667 -313.113674)
			(xy 76.462486 -313.104473) (xy 76.448239 -313.090122) (xy 76.429567 -313.082358) (xy 76.419456 -313.081924)
			(xy 76.157582 -313.081924) (xy 76.147234 -313.082359) (xy 76.128192 -313.09045) (xy 76.113914 -313.105424)
			(xy 76.10983 -313.114944) (xy 76.100647 -313.13833) (xy 76.076234 -313.182238) (xy 76.045457 -313.221946)
			(xy 76.009026 -313.25654) (xy 75.96778 -313.285223) (xy 75.922668 -313.307334) (xy 75.87473 -313.322363)
			(xy 75.82507 -313.329966) (xy 75.77483 -313.329966) (xy 75.72517 -313.322363) (xy 75.677232 -313.307334)
			(xy 75.63212 -313.285223) (xy 75.590874 -313.25654) (xy 75.554443 -313.221946) (xy 75.523666 -313.182238)
			(xy 75.499253 -313.13833) (xy 75.49007 -313.114944) (xy 75.485979 -313.105441) (xy 75.471674 -313.090519)
			(xy 75.452654 -313.082422) (xy 75.442318 -313.081924) (xy 75.180444 -313.081924) (xy 75.17032 -313.082305)
			(xy 75.151616 -313.090046) (xy 75.137392 -313.104449) (xy 75.1332 -313.113674) (xy 75.1332 -313.113928)
			(xy 75.123734 -313.136198) (xy 75.098805 -313.17767) (xy 75.067647 -313.214691) (xy 75.031039 -313.246334)
			(xy 74.989898 -313.271807) (xy 74.945255 -313.290471) (xy 74.898226 -313.30186) (xy 74.84999 -313.305688)
			(xy 74.801754 -313.30186) (xy 74.754725 -313.290471) (xy 74.710082 -313.271807) (xy 74.668941 -313.246334)
			(xy 74.632333 -313.214691) (xy 74.601175 -313.17767) (xy 74.576246 -313.136198) (xy 74.56678 -313.113928)
			(xy 74.56678 -313.113674) (xy 74.562564 -313.104476) (xy 74.548317 -313.09013) (xy 74.529646 -313.082373)
			(xy 74.519536 -313.081924) (xy 74.257408 -313.081924) (xy 74.247057 -313.082354) (xy 74.228006 -313.09044)
			(xy 74.21372 -313.105414) (xy 74.209656 -313.114944) (xy 74.200473 -313.13833) (xy 74.17606 -313.182238)
			(xy 74.145283 -313.221946) (xy 74.108852 -313.25654) (xy 74.067606 -313.285223) (xy 74.022494 -313.307334)
			(xy 73.974556 -313.322363) (xy 73.924896 -313.329966) (xy 73.874656 -313.329966) (xy 73.824996 -313.322363)
			(xy 73.777058 -313.307334) (xy 73.731946 -313.285223) (xy 73.6907 -313.25654) (xy 73.654269 -313.221946)
			(xy 73.623492 -313.182238) (xy 73.599079 -313.13833) (xy 73.589896 -313.114944) (xy 73.585806 -313.105438)
			(xy 73.571503 -313.090508) (xy 73.552482 -313.082403) (xy 73.542144 -313.081924) (xy 73.28027 -313.081924)
			(xy 73.270143 -313.0823) (xy 73.251431 -313.090036) (xy 73.237199 -313.104439) (xy 73.233026 -313.113674)
			(xy 73.233026 -313.113928) (xy 73.22356 -313.136198) (xy 73.198631 -313.17767) (xy 73.167473 -313.214691)
			(xy 73.130865 -313.246334) (xy 73.089724 -313.271807) (xy 73.045081 -313.290471) (xy 72.998052 -313.30186)
			(xy 72.949816 -313.305688) (xy 72.90158 -313.30186) (xy 72.854551 -313.290471) (xy 72.809908 -313.271807)
			(xy 72.768767 -313.246334) (xy 72.732159 -313.214691) (xy 72.701001 -313.17767) (xy 72.676072 -313.136198)
			(xy 72.666606 -313.113928) (xy 72.666606 -313.113674) (xy 72.662392 -313.104473) (xy 72.648145 -313.09012)
			(xy 72.629474 -313.082354) (xy 72.619362 -313.081924) (xy 72.357488 -313.081924) (xy 72.34714 -313.082357)
			(xy 72.328095 -313.090448) (xy 72.313815 -313.105422) (xy 72.309736 -313.114944) (xy 72.300553 -313.13833)
			(xy 72.27614 -313.182238) (xy 72.245363 -313.221946) (xy 72.208932 -313.25654) (xy 72.167686 -313.285223)
			(xy 72.122574 -313.307334) (xy 72.074636 -313.322363) (xy 72.024976 -313.329966) (xy 71.974736 -313.329966)
			(xy 71.925076 -313.322363) (xy 71.877138 -313.307334) (xy 71.832026 -313.285223) (xy 71.79078 -313.25654)
			(xy 71.754349 -313.221946) (xy 71.723572 -313.182238) (xy 71.699159 -313.13833) (xy 71.689976 -313.114944)
			(xy 71.685885 -313.10544) (xy 71.671581 -313.090516) (xy 71.652561 -313.082418) (xy 71.642224 -313.081924)
			(xy 71.38035 -313.081924) (xy 71.370225 -313.082304) (xy 71.351519 -313.090044) (xy 71.337294 -313.104447)
			(xy 71.333106 -313.113674) (xy 71.333106 -313.113928) (xy 71.322915 -313.13777) (xy 71.295705 -313.181903)
			(xy 71.261432 -313.220806) (xy 71.22108 -313.253361) (xy 71.17581 -313.278633) (xy 71.126921 -313.295895)
			(xy 71.075819 -313.304652) (xy 71.049896 -313.30519) (xy 71.026492 -313.304734) (xy 70.980235 -313.297573)
			(xy 70.935614 -313.283435) (xy 70.893673 -313.262651) (xy 70.855397 -313.235709) (xy 70.821681 -313.20324)
			(xy 70.793318 -313.166004) (xy 70.77097 -313.124875) (xy 70.762622 -313.103006) (xy 70.759328 -313.094922)
			(xy 70.748241 -313.081454) (xy 70.73327 -313.072499) (xy 70.724776 -313.070494) (xy 70.691188 -313.063215)
			(xy 70.62587 -313.041834) (xy 70.563501 -313.012959) (xy 70.504938 -312.976989) (xy 70.450984 -312.934415)
			(xy 70.426326 -312.910474) (xy 70.197726 -312.681874) (xy 70.173397 -312.656835) (xy 70.130245 -312.601951)
			(xy 70.093927 -312.542323) (xy 70.064961 -312.478799) (xy 70.043756 -312.41228) (xy 70.03669 -312.37809)
			(xy 70.034641 -312.369329) (xy 70.02535 -312.353934) (xy 70.011313 -312.342696) (xy 70.002908 -312.339482)
			(xy 69.980464 -312.331485) (xy 69.938186 -312.309521) (xy 69.899834 -312.281254) (xy 69.866342 -312.24737)
			(xy 69.838521 -312.208693) (xy 69.81705 -312.166163) (xy 69.802448 -312.120812) (xy 69.795072 -312.073744)
			(xy 69.794628 -312.049922) (xy 69.795199 -312.023454) (xy 69.804337 -311.971314) (xy 69.822325 -311.921528)
			(xy 69.848626 -311.875589) (xy 69.882451 -311.83487) (xy 69.922789 -311.800591) (xy 69.968432 -311.773779)
			(xy 69.993002 -311.763918) (xy 69.993256 -311.763918) (xy 70.002765 -311.759829) (xy 70.0177 -311.745527)
			(xy 70.025813 -311.726506) (xy 70.026276 -311.716166) (xy 70.026276 -311.433718) (xy 70.025848 -311.423366)
			(xy 70.017764 -311.404312) (xy 70.00279 -311.390022) (xy 69.993256 -311.385966) (xy 69.993002 -311.385966)
			(xy 69.970027 -311.376869) (xy 69.927135 -311.35234) (xy 69.888752 -311.321223) (xy 69.855881 -311.284332)
			(xy 69.829381 -311.242628) (xy 69.809943 -311.197201) (xy 69.798074 -311.149237) (xy 69.794084 -311.099987)
			(xy 69.798078 -311.050737) (xy 69.809951 -311.002774) (xy 69.829393 -310.957348) (xy 69.855897 -310.915647)
			(xy 69.888771 -310.878758) (xy 69.927156 -310.847645) (xy 69.970051 -310.82312) (xy 69.993002 -310.813958)
			(xy 69.993256 -310.813958) (xy 70.002758 -310.809866) (xy 70.017677 -310.795561) (xy 70.025769 -310.776542)
			(xy 70.026276 -310.766206) (xy 70.026276 -310.510428) (xy 70.025806 -310.499844) (xy 70.017381 -310.480432)
			(xy 70.001831 -310.46608) (xy 69.991986 -310.462168) (xy 69.967943 -310.453369) (xy 69.922696 -310.429413)
			(xy 69.881686 -310.398765) (xy 69.845893 -310.362159) (xy 69.816176 -310.32047) (xy 69.793244 -310.274695)
			(xy 69.777647 -310.225932) (xy 69.769758 -310.175347) (xy 69.769228 -310.149748) (xy 69.769228 -310.14924)
			(xy 69.769398 -310.135199) (xy 69.771811 -310.107221) (xy 69.774054 -310.09336) (xy 69.775387 -310.082609)
			(xy 69.769945 -310.061659) (xy 69.756381 -310.044792) (xy 69.737086 -310.034982) (xy 69.726302 -310.033924)
			(xy 69.212206 -310.033924) (xy 69.202135 -310.033503) (xy 69.183526 -310.025793) (xy 69.176138 -310.018938)
			(xy 68.851272 -309.694072) (xy 68.839334 -309.687214) (xy 68.834 -309.685944) (xy 68.826786 -309.684175)
			(xy 68.813747 -309.677073) (xy 68.808346 -309.671974) (xy 68.732146 -309.595774) (xy 68.72859 -309.593234)
			(xy 68.706962 -309.57798) (xy 68.66626 -309.544145) (xy 68.64731 -309.52567) (xy 68.410582 -309.288942)
			(xy 68.403724 -309.288434) (xy 63.689484 -309.288434) (xy 63.680793 -309.288783) (xy 63.664427 -309.29463)
			(xy 63.65748 -309.299864) (xy 63.65367 -309.303166) (xy 63.50889 -309.447946) (xy 63.50537 -309.451678)
			(xy 63.499745 -309.460253) (xy 63.497714 -309.464964) (xy 63.494158 -309.4736) (xy 63.494158 -309.780178)
			(xy 63.494751 -309.791399) (xy 63.504293 -309.811713) (xy 63.521544 -309.826069) (xy 63.532258 -309.829454)
			(xy 63.557006 -309.836312) (xy 63.604169 -309.856623) (xy 63.647626 -309.883982) (xy 63.68633 -309.91773)
			(xy 63.719352 -309.957056) (xy 63.745897 -310.001015) (xy 63.765326 -310.048549) (xy 63.777173 -310.098515)
			(xy 63.781153 -310.149712) (xy 63.777169 -310.200909) (xy 63.765319 -310.250874) (xy 63.745886 -310.298406)
			(xy 63.719338 -310.342363) (xy 63.686314 -310.381687) (xy 63.647607 -310.415432) (xy 63.604148 -310.442788)
			(xy 63.556983 -310.463095) (xy 63.532258 -310.470042) (xy 63.521523 -310.4734) (xy 63.504224 -310.487732)
			(xy 63.49471 -310.508083) (xy 63.494158 -310.519318) (xy 63.494158 -310.730392) (xy 63.494754 -310.741611)
			(xy 63.504299 -310.76192) (xy 63.521549 -310.776272) (xy 63.532258 -310.779668) (xy 63.557012 -310.786526)
			(xy 63.604189 -310.806839) (xy 63.647659 -310.834202) (xy 63.686375 -310.867956) (xy 63.719408 -310.90729)
			(xy 63.745962 -310.951258) (xy 63.765399 -310.998803) (xy 63.777252 -311.048781) (xy 63.781234 -311.099962)
			(xy 64.094118 -311.099962) (xy 64.098078 -311.050908) (xy 64.109855 -311.003124) (xy 64.129146 -310.957848)
			(xy 64.155449 -310.916252) (xy 64.188084 -310.879415) (xy 64.226205 -310.84829) (xy 64.268826 -310.823683)
			(xy 64.314842 -310.806231) (xy 64.363061 -310.796387) (xy 64.412236 -310.794406) (xy 64.461091 -310.800338)
			(xy 64.508362 -310.81403) (xy 64.552824 -310.835128) (xy 64.593327 -310.863084) (xy 64.62882 -310.897176)
			(xy 64.658385 -310.93652) (xy 64.681256 -310.980097) (xy 64.69684 -311.026778) (xy 64.704735 -311.075355)
			(xy 64.70523 -311.099962) (xy 65.994038 -311.099962) (xy 65.997998 -311.050908) (xy 66.009775 -311.003124)
			(xy 66.029066 -310.957848) (xy 66.055369 -310.916252) (xy 66.088004 -310.879415) (xy 66.126125 -310.84829)
			(xy 66.168746 -310.823683) (xy 66.214762 -310.806231) (xy 66.262981 -310.796387) (xy 66.312156 -310.794406)
			(xy 66.361011 -310.800338) (xy 66.408282 -310.81403) (xy 66.452744 -310.835128) (xy 66.493247 -310.863084)
			(xy 66.52874 -310.897176) (xy 66.558305 -310.93652) (xy 66.581176 -310.980097) (xy 66.59676 -311.026778)
			(xy 66.604655 -311.075355) (xy 66.60515 -311.099962) (xy 67.893958 -311.099962) (xy 67.897918 -311.050908)
			(xy 67.909695 -311.003124) (xy 67.928986 -310.957848) (xy 67.955289 -310.916252) (xy 67.987924 -310.879415)
			(xy 68.026045 -310.84829) (xy 68.068666 -310.823683) (xy 68.114682 -310.806231) (xy 68.162901 -310.796387)
			(xy 68.212076 -310.794406) (xy 68.260931 -310.800338) (xy 68.308202 -310.81403) (xy 68.352664 -310.835128)
			(xy 68.393167 -310.863084) (xy 68.42866 -310.897176) (xy 68.458225 -310.93652) (xy 68.481096 -310.980097)
			(xy 68.49668 -311.026778) (xy 68.504575 -311.075355) (xy 68.50507 -311.099962) (xy 68.504575 -311.124569)
			(xy 68.49668 -311.173146) (xy 68.481096 -311.219827) (xy 68.458225 -311.263404) (xy 68.42866 -311.302748)
			(xy 68.393167 -311.33684) (xy 68.352664 -311.364796) (xy 68.308202 -311.385894) (xy 68.260931 -311.399586)
			(xy 68.212076 -311.405518) (xy 68.162901 -311.403537) (xy 68.114682 -311.393693) (xy 68.068666 -311.376241)
			(xy 68.026045 -311.351634) (xy 67.987924 -311.320509) (xy 67.955289 -311.283672) (xy 67.928986 -311.242076)
			(xy 67.909695 -311.1968) (xy 67.897918 -311.149016) (xy 67.893958 -311.099962) (xy 66.60515 -311.099962)
			(xy 66.604655 -311.124569) (xy 66.59676 -311.173146) (xy 66.581176 -311.219827) (xy 66.558305 -311.263404)
			(xy 66.52874 -311.302748) (xy 66.493247 -311.33684) (xy 66.452744 -311.364796) (xy 66.408282 -311.385894)
			(xy 66.361011 -311.399586) (xy 66.312156 -311.405518) (xy 66.262981 -311.403537) (xy 66.214762 -311.393693)
			(xy 66.168746 -311.376241) (xy 66.126125 -311.351634) (xy 66.088004 -311.320509) (xy 66.055369 -311.283672)
			(xy 66.029066 -311.242076) (xy 66.009775 -311.1968) (xy 65.997998 -311.149016) (xy 65.994038 -311.099962)
			(xy 64.70523 -311.099962) (xy 64.704735 -311.124569) (xy 64.69684 -311.173146) (xy 64.681256 -311.219827)
			(xy 64.658385 -311.263404) (xy 64.62882 -311.302748) (xy 64.593327 -311.33684) (xy 64.552824 -311.364796)
			(xy 64.508362 -311.385894) (xy 64.461091 -311.399586) (xy 64.412236 -311.405518) (xy 64.363061 -311.403537)
			(xy 64.314842 -311.393693) (xy 64.268826 -311.376241) (xy 64.226205 -311.351634) (xy 64.188084 -311.320509)
			(xy 64.155449 -311.283672) (xy 64.129146 -311.242076) (xy 64.109855 -311.1968) (xy 64.098078 -311.149016)
			(xy 64.094118 -311.099962) (xy 63.781234 -311.099962) (xy 63.781236 -311.099991) (xy 63.777255 -311.1512)
			(xy 63.765405 -311.201179) (xy 63.74597 -311.248725) (xy 63.719419 -311.292694) (xy 63.686388 -311.33203)
			(xy 63.647674 -311.365787) (xy 63.604206 -311.393152) (xy 63.55703 -311.413468) (xy 63.532258 -311.420256)
			(xy 63.521513 -311.42361) (xy 63.504191 -311.437938) (xy 63.494644 -311.458291) (xy 63.494158 -311.469532)
			(xy 63.494158 -311.680352) (xy 63.494746 -311.691576) (xy 63.504283 -311.7119) (xy 63.521536 -311.726265)
			(xy 63.532258 -311.729628) (xy 63.557008 -311.736486) (xy 63.604175 -311.756798) (xy 63.647636 -311.784158)
			(xy 63.686344 -311.817908) (xy 63.719369 -311.857236) (xy 63.745916 -311.901198) (xy 63.765348 -311.948735)
			(xy 63.777197 -311.998705) (xy 63.781178 -312.049905) (xy 63.781177 -312.049922) (xy 64.094118 -312.049922)
			(xy 64.098078 -312.000868) (xy 64.109855 -311.953084) (xy 64.129146 -311.907808) (xy 64.155449 -311.866212)
			(xy 64.188084 -311.829375) (xy 64.226205 -311.79825) (xy 64.268826 -311.773643) (xy 64.314842 -311.756191)
			(xy 64.363061 -311.746347) (xy 64.412236 -311.744366) (xy 64.461091 -311.750298) (xy 64.508362 -311.76399)
			(xy 64.552824 -311.785088) (xy 64.593327 -311.813044) (xy 64.62882 -311.847136) (xy 64.658385 -311.88648)
			(xy 64.681256 -311.930057) (xy 64.69684 -311.976738) (xy 64.704735 -312.025315) (xy 64.70523 -312.049922)
			(xy 65.994038 -312.049922) (xy 65.997998 -312.000868) (xy 66.009775 -311.953084) (xy 66.029066 -311.907808)
			(xy 66.055369 -311.866212) (xy 66.088004 -311.829375) (xy 66.126125 -311.79825) (xy 66.168746 -311.773643)
			(xy 66.214762 -311.756191) (xy 66.262981 -311.746347) (xy 66.312156 -311.744366) (xy 66.361011 -311.750298)
			(xy 66.408282 -311.76399) (xy 66.452744 -311.785088) (xy 66.493247 -311.813044) (xy 66.52874 -311.847136)
			(xy 66.558305 -311.88648) (xy 66.581176 -311.930057) (xy 66.59676 -311.976738) (xy 66.604655 -312.025315)
			(xy 66.60515 -312.049922) (xy 67.893958 -312.049922) (xy 67.897918 -312.000868) (xy 67.909695 -311.953084)
			(xy 67.928986 -311.907808) (xy 67.955289 -311.866212) (xy 67.987924 -311.829375) (xy 68.026045 -311.79825)
			(xy 68.068666 -311.773643) (xy 68.114682 -311.756191) (xy 68.162901 -311.746347) (xy 68.212076 -311.744366)
			(xy 68.260931 -311.750298) (xy 68.308202 -311.76399) (xy 68.352664 -311.785088) (xy 68.393167 -311.813044)
			(xy 68.42866 -311.847136) (xy 68.458225 -311.88648) (xy 68.481096 -311.930057) (xy 68.49668 -311.976738)
			(xy 68.504575 -312.025315) (xy 68.50507 -312.049922) (xy 68.504575 -312.074529) (xy 68.49668 -312.123106)
			(xy 68.481096 -312.169787) (xy 68.458225 -312.213364) (xy 68.42866 -312.252708) (xy 68.393167 -312.2868)
			(xy 68.352664 -312.314756) (xy 68.308202 -312.335854) (xy 68.260931 -312.349546) (xy 68.212076 -312.355478)
			(xy 68.162901 -312.353497) (xy 68.114682 -312.343653) (xy 68.068666 -312.326201) (xy 68.026045 -312.301594)
			(xy 67.987924 -312.270469) (xy 67.955289 -312.233632) (xy 67.928986 -312.192036) (xy 67.909695 -312.14676)
			(xy 67.897918 -312.098976) (xy 67.893958 -312.049922) (xy 66.60515 -312.049922) (xy 66.604655 -312.074529)
			(xy 66.59676 -312.123106) (xy 66.581176 -312.169787) (xy 66.558305 -312.213364) (xy 66.52874 -312.252708)
			(xy 66.493247 -312.2868) (xy 66.452744 -312.314756) (xy 66.408282 -312.335854) (xy 66.361011 -312.349546)
			(xy 66.312156 -312.355478) (xy 66.262981 -312.353497) (xy 66.214762 -312.343653) (xy 66.168746 -312.326201)
			(xy 66.126125 -312.301594) (xy 66.088004 -312.270469) (xy 66.055369 -312.233632) (xy 66.029066 -312.192036)
			(xy 66.009775 -312.14676) (xy 65.997998 -312.098976) (xy 65.994038 -312.049922) (xy 64.70523 -312.049922)
			(xy 64.704735 -312.074529) (xy 64.69684 -312.123106) (xy 64.681256 -312.169787) (xy 64.658385 -312.213364)
			(xy 64.62882 -312.252708) (xy 64.593327 -312.2868) (xy 64.552824 -312.314756) (xy 64.508362 -312.335854)
			(xy 64.461091 -312.349546) (xy 64.412236 -312.355478) (xy 64.363061 -312.353497) (xy 64.314842 -312.343653)
			(xy 64.268826 -312.326201) (xy 64.226205 -312.301594) (xy 64.188084 -312.270469) (xy 64.155449 -312.233632)
			(xy 64.129146 -312.192036) (xy 64.109855 -312.14676) (xy 64.098078 -312.098976) (xy 64.094118 -312.049922)
			(xy 63.781177 -312.049922) (xy 63.777195 -312.101106) (xy 63.765345 -312.151076) (xy 63.745911 -312.198612)
			(xy 63.719362 -312.242572) (xy 63.686336 -312.2819) (xy 63.647627 -312.315649) (xy 63.604166 -312.343007)
			(xy 63.556997 -312.363317) (xy 63.532258 -312.370216) (xy 63.52152 -312.373572) (xy 63.504214 -312.387904)
			(xy 63.49469 -312.408255) (xy 63.494158 -312.419492) (xy 63.494158 -312.656728) (xy 63.494722 -312.66777)
			(xy 63.50399 -312.687817) (xy 63.52078 -312.702167) (xy 63.531242 -312.70575) (xy 63.531496 -312.70575)
			(xy 63.555285 -312.712856) (xy 63.600346 -312.733694) (xy 63.641444 -312.761544) (xy 63.677497 -312.795673)
			(xy 63.707558 -312.835184) (xy 63.730833 -312.879035) (xy 63.746711 -312.926073) (xy 63.754774 -312.97506)
			(xy 63.75527 -312.999882) (xy 65.044078 -312.999882) (xy 65.048038 -312.950828) (xy 65.059815 -312.903044)
			(xy 65.079106 -312.857768) (xy 65.105409 -312.816172) (xy 65.138044 -312.779335) (xy 65.176165 -312.74821)
			(xy 65.218786 -312.723603) (xy 65.264802 -312.706151) (xy 65.313021 -312.696307) (xy 65.362196 -312.694326)
			(xy 65.411051 -312.700258) (xy 65.458322 -312.71395) (xy 65.502784 -312.735048) (xy 65.543287 -312.763004)
			(xy 65.57878 -312.797096) (xy 65.608345 -312.83644) (xy 65.631216 -312.880017) (xy 65.6468 -312.926698)
			(xy 65.654695 -312.975275) (xy 65.65519 -312.999882) (xy 66.943998 -312.999882) (xy 66.947958 -312.950828)
			(xy 66.959735 -312.903044) (xy 66.979026 -312.857768) (xy 67.005329 -312.816172) (xy 67.037964 -312.779335)
			(xy 67.076085 -312.74821) (xy 67.118706 -312.723603) (xy 67.164722 -312.706151) (xy 67.212941 -312.696307)
			(xy 67.262116 -312.694326) (xy 67.310971 -312.700258) (xy 67.358242 -312.71395) (xy 67.402704 -312.735048)
			(xy 67.443207 -312.763004) (xy 67.4787 -312.797096) (xy 67.508265 -312.83644) (xy 67.531136 -312.880017)
			(xy 67.54672 -312.926698) (xy 67.554615 -312.975275) (xy 67.55511 -312.999882) (xy 68.844172 -312.999882)
			(xy 68.848132 -312.950828) (xy 68.859909 -312.903044) (xy 68.8792 -312.857768) (xy 68.905503 -312.816172)
			(xy 68.938138 -312.779335) (xy 68.976259 -312.74821) (xy 69.01888 -312.723603) (xy 69.064896 -312.706151)
			(xy 69.113115 -312.696307) (xy 69.16229 -312.694326) (xy 69.211145 -312.700258) (xy 69.258416 -312.71395)
			(xy 69.302878 -312.735048) (xy 69.343381 -312.763004) (xy 69.378874 -312.797096) (xy 69.408439 -312.83644)
			(xy 69.43131 -312.880017) (xy 69.446894 -312.926698) (xy 69.454789 -312.975275) (xy 69.455284 -312.999882)
			(xy 69.454789 -313.024489) (xy 69.446894 -313.073066) (xy 69.43131 -313.119747) (xy 69.408439 -313.163324)
			(xy 69.378874 -313.202668) (xy 69.343381 -313.23676) (xy 69.302878 -313.264716) (xy 69.258416 -313.285814)
			(xy 69.211145 -313.299506) (xy 69.16229 -313.305438) (xy 69.113115 -313.303457) (xy 69.064896 -313.293613)
			(xy 69.01888 -313.276161) (xy 68.976259 -313.251554) (xy 68.938138 -313.220429) (xy 68.905503 -313.183592)
			(xy 68.8792 -313.141996) (xy 68.859909 -313.09672) (xy 68.848132 -313.048936) (xy 68.844172 -312.999882)
			(xy 67.55511 -312.999882) (xy 67.554615 -313.024489) (xy 67.54672 -313.073066) (xy 67.531136 -313.119747)
			(xy 67.508265 -313.163324) (xy 67.4787 -313.202668) (xy 67.443207 -313.23676) (xy 67.402704 -313.264716)
			(xy 67.358242 -313.285814) (xy 67.310971 -313.299506) (xy 67.262116 -313.305438) (xy 67.212941 -313.303457)
			(xy 67.164722 -313.293613) (xy 67.118706 -313.276161) (xy 67.076085 -313.251554) (xy 67.037964 -313.220429)
			(xy 67.005329 -313.183592) (xy 66.979026 -313.141996) (xy 66.959735 -313.09672) (xy 66.947958 -313.048936)
			(xy 66.943998 -312.999882) (xy 65.65519 -312.999882) (xy 65.654695 -313.024489) (xy 65.6468 -313.073066)
			(xy 65.631216 -313.119747) (xy 65.608345 -313.163324) (xy 65.57878 -313.202668) (xy 65.543287 -313.23676)
			(xy 65.502784 -313.264716) (xy 65.458322 -313.285814) (xy 65.411051 -313.299506) (xy 65.362196 -313.305438)
			(xy 65.313021 -313.303457) (xy 65.264802 -313.293613) (xy 65.218786 -313.276161) (xy 65.176165 -313.251554)
			(xy 65.138044 -313.220429) (xy 65.105409 -313.183592) (xy 65.079106 -313.141996) (xy 65.059815 -313.09672)
			(xy 65.048038 -313.048936) (xy 65.044078 -312.999882) (xy 63.75527 -312.999882) (xy 63.755166 -313.008923)
			(xy 63.754022 -313.026969) (xy 63.752984 -313.03595) (xy 63.752984 -313.036458) (xy 63.751714 -313.048142)
			(xy 63.759842 -313.070494) (xy 63.836042 -313.143392) (xy 63.858648 -313.150504) (xy 63.866268 -313.149234)
			(xy 63.880873 -313.146749) (xy 63.910382 -313.144081) (xy 63.925196 -313.1439) (xy 63.95117 -313.144408)
			(xy 64.002481 -313.15253) (xy 64.051889 -313.168576) (xy 64.098182 -313.192149) (xy 64.140219 -313.222671)
			(xy 64.176966 -313.259391) (xy 64.20752 -313.301405) (xy 64.231128 -313.347679) (xy 64.247211 -313.397076)
			(xy 64.255372 -313.44838) (xy 64.255904 -313.474354) (xy 64.255904 -313.949842) (xy 65.044078 -313.949842)
			(xy 65.048038 -313.900788) (xy 65.059815 -313.853004) (xy 65.079106 -313.807728) (xy 65.105409 -313.766132)
			(xy 65.138044 -313.729295) (xy 65.176165 -313.69817) (xy 65.218786 -313.673563) (xy 65.264802 -313.656111)
			(xy 65.313021 -313.646267) (xy 65.362196 -313.644286) (xy 65.411051 -313.650218) (xy 65.458322 -313.66391)
			(xy 65.502784 -313.685008) (xy 65.543287 -313.712964) (xy 65.57878 -313.747056) (xy 65.608345 -313.7864)
			(xy 65.631216 -313.829977) (xy 65.6468 -313.876658) (xy 65.654695 -313.925235) (xy 65.65519 -313.949842)
			(xy 66.943998 -313.949842) (xy 66.947958 -313.900788) (xy 66.959735 -313.853004) (xy 66.979026 -313.807728)
			(xy 67.005329 -313.766132) (xy 67.037964 -313.729295) (xy 67.076085 -313.69817) (xy 67.118706 -313.673563)
			(xy 67.164722 -313.656111) (xy 67.212941 -313.646267) (xy 67.262116 -313.644286) (xy 67.310971 -313.650218)
			(xy 67.358242 -313.66391) (xy 67.402704 -313.685008) (xy 67.443207 -313.712964) (xy 67.4787 -313.747056)
			(xy 67.508265 -313.7864) (xy 67.531136 -313.829977) (xy 67.54672 -313.876658) (xy 67.554615 -313.925235)
			(xy 67.55511 -313.949842) (xy 68.844172 -313.949842) (xy 68.848132 -313.900788) (xy 68.859909 -313.853004)
			(xy 68.8792 -313.807728) (xy 68.905503 -313.766132) (xy 68.938138 -313.729295) (xy 68.976259 -313.69817)
			(xy 69.01888 -313.673563) (xy 69.064896 -313.656111) (xy 69.113115 -313.646267) (xy 69.16229 -313.644286)
			(xy 69.211145 -313.650218) (xy 69.258416 -313.66391) (xy 69.302878 -313.685008) (xy 69.343381 -313.712964)
			(xy 69.378874 -313.747056) (xy 69.408439 -313.7864) (xy 69.43131 -313.829977) (xy 69.446894 -313.876658)
			(xy 69.454789 -313.925235) (xy 69.455284 -313.949842) (xy 70.744092 -313.949842) (xy 70.748052 -313.900788)
			(xy 70.759829 -313.853004) (xy 70.77912 -313.807728) (xy 70.805423 -313.766132) (xy 70.838058 -313.729295)
			(xy 70.876179 -313.69817) (xy 70.9188 -313.673563) (xy 70.964816 -313.656111) (xy 71.013035 -313.646267)
			(xy 71.06221 -313.644286) (xy 71.111065 -313.650218) (xy 71.158336 -313.66391) (xy 71.202798 -313.685008)
			(xy 71.243301 -313.712964) (xy 71.278794 -313.747056) (xy 71.308359 -313.7864) (xy 71.33123 -313.829977)
			(xy 71.346814 -313.876658) (xy 71.354709 -313.925235) (xy 71.355204 -313.949842) (xy 72.644012 -313.949842)
			(xy 72.647972 -313.900788) (xy 72.659749 -313.853004) (xy 72.67904 -313.807728) (xy 72.705343 -313.766132)
			(xy 72.737978 -313.729295) (xy 72.776099 -313.69817) (xy 72.81872 -313.673563) (xy 72.864736 -313.656111)
			(xy 72.912955 -313.646267) (xy 72.96213 -313.644286) (xy 73.010985 -313.650218) (xy 73.058256 -313.66391)
			(xy 73.102718 -313.685008) (xy 73.143221 -313.712964) (xy 73.178714 -313.747056) (xy 73.208279 -313.7864)
			(xy 73.23115 -313.829977) (xy 73.246734 -313.876658) (xy 73.254629 -313.925235) (xy 73.255124 -313.949842)
			(xy 74.544186 -313.949842) (xy 74.548146 -313.900788) (xy 74.559923 -313.853004) (xy 74.579214 -313.807728)
			(xy 74.605517 -313.766132) (xy 74.638152 -313.729295) (xy 74.676273 -313.69817) (xy 74.718894 -313.673563)
			(xy 74.76491 -313.656111) (xy 74.813129 -313.646267) (xy 74.862304 -313.644286) (xy 74.911159 -313.650218)
			(xy 74.95843 -313.66391) (xy 75.002892 -313.685008) (xy 75.043395 -313.712964) (xy 75.078888 -313.747056)
			(xy 75.108453 -313.7864) (xy 75.131324 -313.829977) (xy 75.146908 -313.876658) (xy 75.154803 -313.925235)
			(xy 75.155298 -313.949842) (xy 76.444106 -313.949842) (xy 76.448066 -313.900788) (xy 76.459843 -313.853004)
			(xy 76.479134 -313.807728) (xy 76.505437 -313.766132) (xy 76.538072 -313.729295) (xy 76.576193 -313.69817)
			(xy 76.618814 -313.673563) (xy 76.66483 -313.656111) (xy 76.713049 -313.646267) (xy 76.762224 -313.644286)
			(xy 76.811079 -313.650218) (xy 76.85835 -313.66391) (xy 76.902812 -313.685008) (xy 76.943315 -313.712964)
			(xy 76.978808 -313.747056) (xy 77.008373 -313.7864) (xy 77.031244 -313.829977) (xy 77.046828 -313.876658)
			(xy 77.054723 -313.925235) (xy 77.055218 -313.949842) (xy 78.344026 -313.949842) (xy 78.347986 -313.900788)
			(xy 78.359763 -313.853004) (xy 78.379054 -313.807728) (xy 78.405357 -313.766132) (xy 78.437992 -313.729295)
			(xy 78.476113 -313.69817) (xy 78.518734 -313.673563) (xy 78.56475 -313.656111) (xy 78.612969 -313.646267)
			(xy 78.662144 -313.644286) (xy 78.710999 -313.650218) (xy 78.75827 -313.66391) (xy 78.802732 -313.685008)
			(xy 78.843235 -313.712964) (xy 78.878728 -313.747056) (xy 78.908293 -313.7864) (xy 78.931164 -313.829977)
			(xy 78.946748 -313.876658) (xy 78.954643 -313.925235) (xy 78.955138 -313.949842) (xy 80.243946 -313.949842)
			(xy 80.247906 -313.900788) (xy 80.259683 -313.853004) (xy 80.278974 -313.807728) (xy 80.305277 -313.766132)
			(xy 80.337912 -313.729295) (xy 80.376033 -313.69817) (xy 80.418654 -313.673563) (xy 80.46467 -313.656111)
			(xy 80.512889 -313.646267) (xy 80.562064 -313.644286) (xy 80.610919 -313.650218) (xy 80.65819 -313.66391)
			(xy 80.702652 -313.685008) (xy 80.743155 -313.712964) (xy 80.778648 -313.747056) (xy 80.808213 -313.7864)
			(xy 80.831084 -313.829977) (xy 80.846668 -313.876658) (xy 80.854563 -313.925235) (xy 80.855058 -313.949842)
			(xy 80.854563 -313.974449) (xy 80.846668 -314.023026) (xy 80.831084 -314.069707) (xy 80.808213 -314.113284)
			(xy 80.778648 -314.152628) (xy 80.743155 -314.18672) (xy 80.702652 -314.214676) (xy 80.65819 -314.235774)
			(xy 80.610919 -314.249466) (xy 80.562064 -314.255398) (xy 80.512889 -314.253417) (xy 80.46467 -314.243573)
			(xy 80.418654 -314.226121) (xy 80.376033 -314.201514) (xy 80.337912 -314.170389) (xy 80.305277 -314.133552)
			(xy 80.278974 -314.091956) (xy 80.259683 -314.04668) (xy 80.247906 -313.998896) (xy 80.243946 -313.949842)
			(xy 78.955138 -313.949842) (xy 78.954643 -313.974449) (xy 78.946748 -314.023026) (xy 78.931164 -314.069707)
			(xy 78.908293 -314.113284) (xy 78.878728 -314.152628) (xy 78.843235 -314.18672) (xy 78.802732 -314.214676)
			(xy 78.75827 -314.235774) (xy 78.710999 -314.249466) (xy 78.662144 -314.255398) (xy 78.612969 -314.253417)
			(xy 78.56475 -314.243573) (xy 78.518734 -314.226121) (xy 78.476113 -314.201514) (xy 78.437992 -314.170389)
			(xy 78.405357 -314.133552) (xy 78.379054 -314.091956) (xy 78.359763 -314.04668) (xy 78.347986 -313.998896)
			(xy 78.344026 -313.949842) (xy 77.055218 -313.949842) (xy 77.054723 -313.974449) (xy 77.046828 -314.023026)
			(xy 77.031244 -314.069707) (xy 77.008373 -314.113284) (xy 76.978808 -314.152628) (xy 76.943315 -314.18672)
			(xy 76.902812 -314.214676) (xy 76.85835 -314.235774) (xy 76.811079 -314.249466) (xy 76.762224 -314.255398)
			(xy 76.713049 -314.253417) (xy 76.66483 -314.243573) (xy 76.618814 -314.226121) (xy 76.576193 -314.201514)
			(xy 76.538072 -314.170389) (xy 76.505437 -314.133552) (xy 76.479134 -314.091956) (xy 76.459843 -314.04668)
			(xy 76.448066 -313.998896) (xy 76.444106 -313.949842) (xy 75.155298 -313.949842) (xy 75.154803 -313.974449)
			(xy 75.146908 -314.023026) (xy 75.131324 -314.069707) (xy 75.108453 -314.113284) (xy 75.078888 -314.152628)
			(xy 75.043395 -314.18672) (xy 75.002892 -314.214676) (xy 74.95843 -314.235774) (xy 74.911159 -314.249466)
			(xy 74.862304 -314.255398) (xy 74.813129 -314.253417) (xy 74.76491 -314.243573) (xy 74.718894 -314.226121)
			(xy 74.676273 -314.201514) (xy 74.638152 -314.170389) (xy 74.605517 -314.133552) (xy 74.579214 -314.091956)
			(xy 74.559923 -314.04668) (xy 74.548146 -313.998896) (xy 74.544186 -313.949842) (xy 73.255124 -313.949842)
			(xy 73.254629 -313.974449) (xy 73.246734 -314.023026) (xy 73.23115 -314.069707) (xy 73.208279 -314.113284)
			(xy 73.178714 -314.152628) (xy 73.143221 -314.18672) (xy 73.102718 -314.214676) (xy 73.058256 -314.235774)
			(xy 73.010985 -314.249466) (xy 72.96213 -314.255398) (xy 72.912955 -314.253417) (xy 72.864736 -314.243573)
			(xy 72.81872 -314.226121) (xy 72.776099 -314.201514) (xy 72.737978 -314.170389) (xy 72.705343 -314.133552)
			(xy 72.67904 -314.091956) (xy 72.659749 -314.04668) (xy 72.647972 -313.998896) (xy 72.644012 -313.949842)
			(xy 71.355204 -313.949842) (xy 71.354709 -313.974449) (xy 71.346814 -314.023026) (xy 71.33123 -314.069707)
			(xy 71.308359 -314.113284) (xy 71.278794 -314.152628) (xy 71.243301 -314.18672) (xy 71.202798 -314.214676)
			(xy 71.158336 -314.235774) (xy 71.111065 -314.249466) (xy 71.06221 -314.255398) (xy 71.013035 -314.253417)
			(xy 70.964816 -314.243573) (xy 70.9188 -314.226121) (xy 70.876179 -314.201514) (xy 70.838058 -314.170389)
			(xy 70.805423 -314.133552) (xy 70.77912 -314.091956) (xy 70.759829 -314.04668) (xy 70.748052 -313.998896)
			(xy 70.744092 -313.949842) (xy 69.455284 -313.949842) (xy 69.454789 -313.974449) (xy 69.446894 -314.023026)
			(xy 69.43131 -314.069707) (xy 69.408439 -314.113284) (xy 69.378874 -314.152628) (xy 69.343381 -314.18672)
			(xy 69.302878 -314.214676) (xy 69.258416 -314.235774) (xy 69.211145 -314.249466) (xy 69.16229 -314.255398)
			(xy 69.113115 -314.253417) (xy 69.064896 -314.243573) (xy 69.01888 -314.226121) (xy 68.976259 -314.201514)
			(xy 68.938138 -314.170389) (xy 68.905503 -314.133552) (xy 68.8792 -314.091956) (xy 68.859909 -314.04668)
			(xy 68.848132 -313.998896) (xy 68.844172 -313.949842) (xy 67.55511 -313.949842) (xy 67.554615 -313.974449)
			(xy 67.54672 -314.023026) (xy 67.531136 -314.069707) (xy 67.508265 -314.113284) (xy 67.4787 -314.152628)
			(xy 67.443207 -314.18672) (xy 67.402704 -314.214676) (xy 67.358242 -314.235774) (xy 67.310971 -314.249466)
			(xy 67.262116 -314.255398) (xy 67.212941 -314.253417) (xy 67.164722 -314.243573) (xy 67.118706 -314.226121)
			(xy 67.076085 -314.201514) (xy 67.037964 -314.170389) (xy 67.005329 -314.133552) (xy 66.979026 -314.091956)
			(xy 66.959735 -314.04668) (xy 66.947958 -313.998896) (xy 66.943998 -313.949842) (xy 65.65519 -313.949842)
			(xy 65.654695 -313.974449) (xy 65.6468 -314.023026) (xy 65.631216 -314.069707) (xy 65.608345 -314.113284)
			(xy 65.57878 -314.152628) (xy 65.543287 -314.18672) (xy 65.502784 -314.214676) (xy 65.458322 -314.235774)
			(xy 65.411051 -314.249466) (xy 65.362196 -314.255398) (xy 65.313021 -314.253417) (xy 65.264802 -314.243573)
			(xy 65.218786 -314.226121) (xy 65.176165 -314.201514) (xy 65.138044 -314.170389) (xy 65.105409 -314.133552)
			(xy 65.079106 -314.091956) (xy 65.059815 -314.04668) (xy 65.048038 -313.998896) (xy 65.044078 -313.949842)
			(xy 64.255904 -313.949842) (xy 64.255904 -314.424822) (xy 64.255394 -314.450817) (xy 64.247262 -314.502166)
			(xy 64.231203 -314.551612) (xy 64.207611 -314.59794) (xy 64.177066 -314.64001) (xy 64.140319 -314.676787)
			(xy 64.098274 -314.707367) (xy 64.051966 -314.730998) (xy 64.002533 -314.747098) (xy 63.95119 -314.755272)
			(xy 63.925196 -314.755784) (xy 63.924688 -314.755784) (xy 63.890652 -314.754006) (xy 63.879326 -314.753417)
			(xy 63.857956 -314.760923) (xy 63.849504 -314.768484) (xy 63.785242 -314.832492) (xy 63.777622 -314.854082)
			(xy 63.778892 -314.865512) (xy 63.78067 -314.899802) (xy 63.780111 -314.927086) (xy 63.771152 -314.980913)
			(xy 63.753477 -315.032538) (xy 63.727566 -315.080562) (xy 63.694122 -315.123679) (xy 63.654053 -315.160721)
			(xy 63.608447 -315.190682) (xy 63.55854 -315.212748) (xy 63.532258 -315.220096) (xy 63.521518 -315.223452)
			(xy 63.504206 -315.237782) (xy 63.494675 -315.258134) (xy 63.494158 -315.269372) (xy 63.494158 -315.410088)
			(xy 63.495174 -315.419994) (xy 63.496879 -315.427153) (xy 63.503711 -315.44018) (xy 63.508636 -315.445648)
			(xy 63.647574 -315.584586) (xy 63.650114 -315.586618) (xy 63.667677 -315.600442) (xy 63.69928 -315.632048)
			(xy 63.713106 -315.64961) (xy 63.715138 -315.65215) (xy 63.92545 -315.862462) (xy 63.932395 -315.868756)
			(xy 63.949537 -315.876297) (xy 63.968243 -315.87719) (xy 63.977266 -315.874654) (xy 64.063626 -315.846206)
			(xy 64.072412 -315.842851) (xy 64.086927 -315.830917) (xy 64.09616 -315.814551) (xy 64.097916 -315.805312)
			(xy 64.101894 -315.781462) (xy 64.116389 -315.735335) (xy 64.137973 -315.692069) (xy 64.166106 -315.652745)
			(xy 64.200084 -315.618346) (xy 64.239059 -315.589732) (xy 64.282057 -315.567618) (xy 64.328002 -315.552557)
			(xy 64.375747 -315.544924) (xy 64.399922 -315.544454) (xy 64.423913 -315.544926) (xy 64.471304 -315.552435)
			(xy 64.516938 -315.567264) (xy 64.55969 -315.589048) (xy 64.598509 -315.617251) (xy 64.632439 -315.651179)
			(xy 64.660644 -315.689996) (xy 64.68243 -315.732747) (xy 64.697261 -315.77838) (xy 64.704773 -315.825771)
			(xy 64.70523 -315.849762) (xy 64.70523 -315.85027) (xy 64.704748 -315.874437) (xy 64.697089 -315.92216)
			(xy 64.68999 -315.945266) (xy 64.68745 -315.952886) (xy 64.68745 -315.961014) (xy 64.68794 -315.971023)
			(xy 64.6956 -315.989519) (xy 64.709751 -316.00368) (xy 64.728241 -316.011353) (xy 64.73825 -316.011814)
			(xy 64.756538 -316.011814) (xy 64.763396 -316.011306) (xy 64.773556 -316.009782) (xy 64.775842 -316.009274)
			(xy 64.799367 -316.002274) (xy 64.847828 -315.994494) (xy 64.872362 -315.99378) (xy 64.87414 -315.99378)
			(xy 64.893885 -315.958066) (xy 64.938523 -315.889741) (xy 64.988728 -315.825397) (xy 65.016126 -315.795152)
			(xy 65.020414 -315.790261) (xy 65.026593 -315.778818) (xy 65.028318 -315.772546) (xy 65.034883 -315.7474)
			(xy 65.054775 -315.69939) (xy 65.081932 -315.655082) (xy 65.115685 -315.615567) (xy 65.155202 -315.581818)
			(xy 65.199512 -315.554664) (xy 65.247523 -315.534775) (xy 65.272666 -315.528198) (xy 65.278938 -315.526472)
			(xy 65.290379 -315.520293) (xy 65.295272 -315.516006) (xy 65.325115 -315.488968) (xy 65.388569 -315.439371)
			(xy 65.422018 -315.416946) (xy 65.427318 -315.413253) (xy 65.436053 -315.403741) (xy 65.43929 -315.39815)
			(xy 65.459615 -315.360415) (xy 65.505962 -315.28831) (xy 65.558476 -315.220564) (xy 65.616749 -315.157703)
			(xy 65.680329 -315.100215) (xy 65.748723 -315.048547) (xy 65.821398 -315.003099) (xy 65.897792 -314.964224)
			(xy 65.937384 -314.947808) (xy 65.946556 -314.943622) (xy 65.960884 -314.929461) (xy 65.968688 -314.910889)
			(xy 65.969134 -314.900818) (xy 65.969134 -314.899802) (xy 65.969644 -314.873815) (xy 65.977774 -314.82248)
			(xy 65.993835 -314.77305) (xy 66.017431 -314.72674) (xy 66.047981 -314.684692) (xy 66.084732 -314.647941)
			(xy 66.12678 -314.617391) (xy 66.17309 -314.593795) (xy 66.22252 -314.577734) (xy 66.273855 -314.569604)
			(xy 66.325829 -314.569604) (xy 66.377164 -314.577734) (xy 66.426594 -314.593795) (xy 66.472904 -314.617391)
			(xy 66.514952 -314.647941) (xy 66.551703 -314.684692) (xy 66.582253 -314.72674) (xy 66.605849 -314.77305)
			(xy 66.62191 -314.82248) (xy 66.63004 -314.873815) (xy 66.63055 -314.899802) (xy 66.63055 -314.900818)
			(xy 66.630973 -314.9109) (xy 66.638741 -314.929508) (xy 66.6531 -314.943663) (xy 66.6623 -314.947808)
			(xy 66.712249 -314.968694) (xy 66.807594 -315.019996) (xy 66.852546 -315.05017) (xy 66.855971 -315.052392)
			(xy 66.863374 -315.055832) (xy 66.867278 -315.057028) (xy 66.893736 -315.065313) (xy 66.94364 -315.089457)
			(xy 66.988825 -315.121578) (xy 67.028025 -315.160779) (xy 67.060146 -315.205964) (xy 67.084288 -315.255869)
			(xy 67.092576 -315.282326) (xy 67.093756 -315.286236) (xy 67.097202 -315.293638) (xy 67.099434 -315.297058)
			(xy 67.11517 -315.320186) (xy 67.144273 -315.367967) (xy 67.1576 -315.392562) (xy 67.16268 -315.402214)
			(xy 67.179698 -315.415422) (xy 67.274694 -315.438536) (xy 67.295776 -315.434726) (xy 67.304666 -315.42863)
			(xy 67.321938 -315.416946) (xy 67.327244 -315.413258) (xy 67.335991 -315.403752) (xy 67.33921 -315.39815)
			(xy 67.359535 -315.360415) (xy 67.405883 -315.288311) (xy 67.458398 -315.220566) (xy 67.516671 -315.157706)
			(xy 67.580252 -315.100219) (xy 67.648645 -315.048552) (xy 67.721321 -315.003106) (xy 67.797716 -314.964233)
			(xy 67.837304 -314.947808) (xy 67.846473 -314.94362) (xy 67.860796 -314.929458) (xy 67.868597 -314.910887)
			(xy 67.869054 -314.900818) (xy 67.869054 -314.899802) (xy 67.869564 -314.873815) (xy 67.877694 -314.82248)
			(xy 67.893755 -314.77305) (xy 67.917351 -314.72674) (xy 67.947901 -314.684692) (xy 67.984652 -314.647941)
			(xy 68.0267 -314.617391) (xy 68.07301 -314.593795) (xy 68.12244 -314.577734) (xy 68.173775 -314.569604)
			(xy 68.225749 -314.569604) (xy 68.277084 -314.577734) (xy 68.326514 -314.593795) (xy 68.372824 -314.617391)
			(xy 68.414872 -314.647941) (xy 68.451623 -314.684692) (xy 68.482173 -314.72674) (xy 68.505769 -314.77305)
			(xy 68.52183 -314.82248) (xy 68.52996 -314.873815) (xy 68.53047 -314.899802) (xy 68.53047 -314.900818)
			(xy 68.530893 -314.9109) (xy 68.538663 -314.929504) (xy 68.553024 -314.943655) (xy 68.56222 -314.947808)
			(xy 68.612042 -314.968708) (xy 68.707135 -315.020004) (xy 68.751958 -315.05017) (xy 68.755367 -315.052468)
			(xy 68.762768 -315.056048) (xy 68.76669 -315.057282) (xy 68.793262 -315.065513) (xy 68.843395 -315.089611)
			(xy 68.888782 -315.121767) (xy 68.928141 -315.161072) (xy 68.960359 -315.206415) (xy 68.984525 -315.256515)
			(xy 68.99275 -315.283088) (xy 68.993929 -315.286998) (xy 68.997375 -315.294401) (xy 68.999608 -315.29782)
			(xy 69.015263 -315.320832) (xy 69.044237 -315.368358) (xy 69.05752 -315.392816) (xy 69.0626 -315.402468)
			(xy 69.079618 -315.415676) (xy 69.163946 -315.43625) (xy 69.17453 -315.43831) (xy 69.195711 -315.434368)
			(xy 69.20484 -315.42863) (xy 69.222112 -315.416946) (xy 69.227413 -315.413253) (xy 69.236148 -315.403742)
			(xy 69.239384 -315.39815) (xy 69.259709 -315.360415) (xy 69.306056 -315.288309) (xy 69.35857 -315.220563)
			(xy 69.416843 -315.157702) (xy 69.480423 -315.100214) (xy 69.548816 -315.048545) (xy 69.621491 -315.003096)
			(xy 69.697885 -314.964221) (xy 69.737478 -314.947808) (xy 69.746637 -314.943612) (xy 69.760939 -314.929445)
			(xy 69.768727 -314.910881) (xy 69.769228 -314.900818) (xy 69.769228 -314.899802) (xy 69.769738 -314.873815)
			(xy 69.777868 -314.82248) (xy 69.793929 -314.77305) (xy 69.817525 -314.72674) (xy 69.848075 -314.684692)
			(xy 69.884826 -314.647941) (xy 69.926874 -314.617391) (xy 69.973184 -314.593795) (xy 70.022614 -314.577734)
			(xy 70.073949 -314.569604) (xy 70.125923 -314.569604) (xy 70.177258 -314.577734) (xy 70.226688 -314.593795)
			(xy 70.272998 -314.617391) (xy 70.315046 -314.647941) (xy 70.351797 -314.684692) (xy 70.382347 -314.72674)
			(xy 70.405943 -314.77305) (xy 70.422004 -314.82248) (xy 70.430134 -314.873815) (xy 70.430644 -314.899802)
			(xy 70.430644 -314.900818) (xy 70.431067 -314.910901) (xy 70.438834 -314.929509) (xy 70.453193 -314.943666)
			(xy 70.462394 -314.947808) (xy 70.512343 -314.968694) (xy 70.607689 -315.019995) (xy 70.65264 -315.05017)
			(xy 70.656065 -315.052392) (xy 70.663468 -315.055833) (xy 70.667372 -315.057028) (xy 70.69383 -315.065313)
			(xy 70.743735 -315.089456) (xy 70.78892 -315.121577) (xy 70.828121 -315.160778) (xy 70.860243 -315.205962)
			(xy 70.884386 -315.255868) (xy 70.89267 -315.282326) (xy 70.893852 -315.286234) (xy 70.897304 -315.293634)
			(xy 70.899528 -315.297058) (xy 70.915265 -315.320186) (xy 70.944367 -315.367967) (xy 70.957694 -315.392562)
			(xy 70.962774 -315.402214) (xy 70.979792 -315.415422) (xy 71.074788 -315.438536) (xy 71.09587 -315.434726)
			(xy 71.10476 -315.42863) (xy 71.122032 -315.416946) (xy 71.127339 -315.413259) (xy 71.136086 -315.403753)
			(xy 71.139304 -315.39815) (xy 71.159629 -315.360415) (xy 71.205977 -315.28831) (xy 71.258491 -315.220565)
			(xy 71.316765 -315.157705) (xy 71.380345 -315.100218) (xy 71.448739 -315.048551) (xy 71.521414 -315.003104)
			(xy 71.597809 -314.96423) (xy 71.637398 -314.947808) (xy 71.646568 -314.943621) (xy 71.660893 -314.929459)
			(xy 71.668694 -314.910888) (xy 71.669148 -314.900818) (xy 71.669148 -314.899802) (xy 71.669658 -314.873815)
			(xy 71.677788 -314.82248) (xy 71.693849 -314.77305) (xy 71.717445 -314.72674) (xy 71.747995 -314.684692)
			(xy 71.784746 -314.647941) (xy 71.826794 -314.617391) (xy 71.873104 -314.593795) (xy 71.922534 -314.577734)
			(xy 71.973869 -314.569604) (xy 72.025843 -314.569604) (xy 72.077178 -314.577734) (xy 72.126608 -314.593795)
			(xy 72.172918 -314.617391) (xy 72.214966 -314.647941) (xy 72.251717 -314.684692) (xy 72.282267 -314.72674)
			(xy 72.305863 -314.77305) (xy 72.321924 -314.82248) (xy 72.330054 -314.873815) (xy 72.330564 -314.899802)
			(xy 81.19416 -314.899802) (xy 81.19812 -314.850748) (xy 81.209897 -314.802964) (xy 81.229188 -314.757688)
			(xy 81.255491 -314.716092) (xy 81.288126 -314.679255) (xy 81.326247 -314.64813) (xy 81.368868 -314.623523)
			(xy 81.414884 -314.606071) (xy 81.463103 -314.596227) (xy 81.512278 -314.594246) (xy 81.561133 -314.600178)
			(xy 81.608404 -314.61387) (xy 81.652866 -314.634968) (xy 81.693369 -314.662924) (xy 81.728862 -314.697016)
			(xy 81.758427 -314.73636) (xy 81.781298 -314.779937) (xy 81.796882 -314.826618) (xy 81.804777 -314.875195)
			(xy 81.805272 -314.899802) (xy 82.14412 -314.899802) (xy 82.14808 -314.850748) (xy 82.159857 -314.802964)
			(xy 82.179148 -314.757688) (xy 82.205451 -314.716092) (xy 82.238086 -314.679255) (xy 82.276207 -314.64813)
			(xy 82.318828 -314.623523) (xy 82.364844 -314.606071) (xy 82.413063 -314.596227) (xy 82.462238 -314.594246)
			(xy 82.511093 -314.600178) (xy 82.558364 -314.61387) (xy 82.602826 -314.634968) (xy 82.643329 -314.662924)
			(xy 82.678822 -314.697016) (xy 82.708387 -314.73636) (xy 82.731258 -314.779937) (xy 82.746842 -314.826618)
			(xy 82.754737 -314.875195) (xy 82.755232 -314.899802) (xy 82.754737 -314.924409) (xy 82.746842 -314.972986)
			(xy 82.731258 -315.019667) (xy 82.708387 -315.063244) (xy 82.678822 -315.102588) (xy 82.643329 -315.13668)
			(xy 82.602826 -315.164636) (xy 82.558364 -315.185734) (xy 82.511093 -315.199426) (xy 82.462238 -315.205358)
			(xy 82.413063 -315.203377) (xy 82.364844 -315.193533) (xy 82.318828 -315.176081) (xy 82.276207 -315.151474)
			(xy 82.238086 -315.120349) (xy 82.205451 -315.083512) (xy 82.179148 -315.041916) (xy 82.159857 -314.99664)
			(xy 82.14808 -314.948856) (xy 82.14412 -314.899802) (xy 81.805272 -314.899802) (xy 81.804777 -314.924409)
			(xy 81.796882 -314.972986) (xy 81.781298 -315.019667) (xy 81.758427 -315.063244) (xy 81.728862 -315.102588)
			(xy 81.693369 -315.13668) (xy 81.652866 -315.164636) (xy 81.608404 -315.185734) (xy 81.561133 -315.199426)
			(xy 81.512278 -315.205358) (xy 81.463103 -315.203377) (xy 81.414884 -315.193533) (xy 81.368868 -315.176081)
			(xy 81.326247 -315.151474) (xy 81.288126 -315.120349) (xy 81.255491 -315.083512) (xy 81.229188 -315.041916)
			(xy 81.209897 -314.99664) (xy 81.19812 -314.948856) (xy 81.19416 -314.899802) (xy 72.330564 -314.899802)
			(xy 72.330564 -314.900818) (xy 72.330987 -314.9109) (xy 72.338756 -314.929505) (xy 72.353117 -314.943657)
			(xy 72.362314 -314.947808) (xy 72.412263 -314.968695) (xy 72.507607 -315.019997) (xy 72.55256 -315.05017)
			(xy 72.555985 -315.052391) (xy 72.563389 -315.055829) (xy 72.567292 -315.057028) (xy 72.593725 -315.065336)
			(xy 72.643576 -315.08951) (xy 72.68871 -315.121642) (xy 72.727867 -315.160837) (xy 72.759955 -315.206002)
			(xy 72.78408 -315.255878) (xy 72.792336 -315.282326) (xy 72.793584 -315.286243) (xy 72.797154 -315.293647)
			(xy 72.799448 -315.297058) (xy 72.823107 -315.332117) (xy 72.86495 -315.405627) (xy 72.883014 -315.44387)
			(xy 72.886904 -315.451534) (xy 72.898839 -315.463885) (xy 72.906382 -315.468) (xy 72.928654 -315.479384)
			(xy 72.972109 -315.504162) (xy 72.99325 -315.51753) (xy 72.997404 -315.520144) (xy 73.006487 -315.523859)
			(xy 73.011284 -315.524896) (xy 73.03551 -315.529951) (xy 73.082218 -315.546295) (xy 73.12597 -315.569418)
			(xy 73.165787 -315.598803) (xy 73.20078 -315.633794) (xy 73.230168 -315.673608) (xy 73.253294 -315.717358)
			(xy 73.269643 -315.764066) (xy 73.274682 -315.788294) (xy 73.275763 -315.793077) (xy 73.279477 -315.802152)
			(xy 73.282048 -315.806328) (xy 73.305257 -315.843451) (xy 73.345581 -315.92117) (xy 73.362566 -315.961522)
			(xy 73.363074 -315.962792) (xy 73.36536 -315.967618) (xy 73.370185 -315.975741) (xy 73.384564 -315.987977)
			(xy 73.402393 -315.994191) (xy 73.411842 -315.994288) (xy 73.412096 -315.994288) (xy 73.424796 -315.994034)
			(xy 73.450097 -315.994559) (xy 73.500098 -316.002347) (xy 73.524364 -316.009528) (xy 73.53173 -316.011814)
			(xy 73.561448 -316.011814) (xy 73.57145 -316.011318) (xy 73.589928 -316.00365) (xy 73.60407 -315.9895)
			(xy 73.611725 -315.971017) (xy 73.612248 -315.961014) (xy 73.612248 -315.952886) (xy 73.609708 -315.945266)
			(xy 73.602605 -315.922162) (xy 73.594947 -315.874437) (xy 73.594468 -315.85027) (xy 73.594468 -315.849762)
			(xy 73.59499 -315.824507) (xy 73.603303 -315.774685) (xy 73.619704 -315.726911) (xy 73.643745 -315.682488)
			(xy 73.674769 -315.642628) (xy 73.711931 -315.608418) (xy 73.754217 -315.580792) (xy 73.800473 -315.560502)
			(xy 73.849438 -315.548102) (xy 73.899776 -315.543931) (xy 73.950114 -315.548102) (xy 73.999079 -315.560502)
			(xy 74.045335 -315.580792) (xy 74.087621 -315.608418) (xy 74.124783 -315.642628) (xy 74.155807 -315.682488)
			(xy 74.179848 -315.726911) (xy 74.196249 -315.774685) (xy 74.204562 -315.824507) (xy 74.205084 -315.849762)
			(xy 75.494146 -315.849762) (xy 75.498106 -315.800708) (xy 75.509883 -315.752924) (xy 75.529174 -315.707648)
			(xy 75.555477 -315.666052) (xy 75.588112 -315.629215) (xy 75.626233 -315.59809) (xy 75.668854 -315.573483)
			(xy 75.71487 -315.556031) (xy 75.763089 -315.546187) (xy 75.812264 -315.544206) (xy 75.861119 -315.550138)
			(xy 75.90839 -315.56383) (xy 75.952852 -315.584928) (xy 75.993355 -315.612884) (xy 76.028848 -315.646976)
			(xy 76.058413 -315.68632) (xy 76.081284 -315.729897) (xy 76.096868 -315.776578) (xy 76.104763 -315.825155)
			(xy 76.105258 -315.849762) (xy 77.394066 -315.849762) (xy 77.398026 -315.800708) (xy 77.409803 -315.752924)
			(xy 77.429094 -315.707648) (xy 77.455397 -315.666052) (xy 77.488032 -315.629215) (xy 77.526153 -315.59809)
			(xy 77.568774 -315.573483) (xy 77.61479 -315.556031) (xy 77.663009 -315.546187) (xy 77.712184 -315.544206)
			(xy 77.761039 -315.550138) (xy 77.80831 -315.56383) (xy 77.852772 -315.584928) (xy 77.893275 -315.612884)
			(xy 77.928768 -315.646976) (xy 77.958333 -315.68632) (xy 77.981204 -315.729897) (xy 77.996788 -315.776578)
			(xy 78.004683 -315.825155) (xy 78.005178 -315.849762) (xy 79.293986 -315.849762) (xy 79.297946 -315.800708)
			(xy 79.309723 -315.752924) (xy 79.329014 -315.707648) (xy 79.355317 -315.666052) (xy 79.387952 -315.629215)
			(xy 79.426073 -315.59809) (xy 79.468694 -315.573483) (xy 79.51471 -315.556031) (xy 79.562929 -315.546187)
			(xy 79.612104 -315.544206) (xy 79.660959 -315.550138) (xy 79.70823 -315.56383) (xy 79.752692 -315.584928)
			(xy 79.793195 -315.612884) (xy 79.828688 -315.646976) (xy 79.858253 -315.68632) (xy 79.881124 -315.729897)
			(xy 79.896708 -315.776578) (xy 79.904603 -315.825155) (xy 79.905098 -315.849762) (xy 79.904603 -315.874369)
			(xy 79.896708 -315.922946) (xy 79.881124 -315.969627) (xy 79.858253 -316.013204) (xy 79.828688 -316.052548)
			(xy 79.793195 -316.08664) (xy 79.752692 -316.114596) (xy 79.70823 -316.135694) (xy 79.660959 -316.149386)
			(xy 79.612104 -316.155318) (xy 79.562929 -316.153337) (xy 79.51471 -316.143493) (xy 79.468694 -316.126041)
			(xy 79.426073 -316.101434) (xy 79.387952 -316.070309) (xy 79.355317 -316.033472) (xy 79.329014 -315.991876)
			(xy 79.309723 -315.9466) (xy 79.297946 -315.898816) (xy 79.293986 -315.849762) (xy 78.005178 -315.849762)
			(xy 78.004683 -315.874369) (xy 77.996788 -315.922946) (xy 77.981204 -315.969627) (xy 77.958333 -316.013204)
			(xy 77.928768 -316.052548) (xy 77.893275 -316.08664) (xy 77.852772 -316.114596) (xy 77.80831 -316.135694)
			(xy 77.761039 -316.149386) (xy 77.712184 -316.155318) (xy 77.663009 -316.153337) (xy 77.61479 -316.143493)
			(xy 77.568774 -316.126041) (xy 77.526153 -316.101434) (xy 77.488032 -316.070309) (xy 77.455397 -316.033472)
			(xy 77.429094 -315.991876) (xy 77.409803 -315.9466) (xy 77.398026 -315.898816) (xy 77.394066 -315.849762)
			(xy 76.105258 -315.849762) (xy 76.104763 -315.874369) (xy 76.096868 -315.922946) (xy 76.081284 -315.969627)
			(xy 76.058413 -316.013204) (xy 76.028848 -316.052548) (xy 75.993355 -316.08664) (xy 75.952852 -316.114596)
			(xy 75.90839 -316.135694) (xy 75.861119 -316.149386) (xy 75.812264 -316.155318) (xy 75.763089 -316.153337)
			(xy 75.71487 -316.143493) (xy 75.668854 -316.126041) (xy 75.626233 -316.101434) (xy 75.588112 -316.070309)
			(xy 75.555477 -316.033472) (xy 75.529174 -315.991876) (xy 75.509883 -315.9466) (xy 75.498106 -315.898816)
			(xy 75.494146 -315.849762) (xy 74.205084 -315.849762) (xy 74.20498 -315.858803) (xy 74.203838 -315.876849)
			(xy 74.202798 -315.88583) (xy 74.202798 -315.886338) (xy 74.201528 -315.898022) (xy 74.209656 -315.920374)
			(xy 74.285856 -315.993272) (xy 74.308462 -316.000384) (xy 74.317352 -315.99886) (xy 74.331649 -315.99649)
			(xy 74.360519 -315.993942) (xy 74.37501 -315.99378) (xy 74.401018 -315.994264) (xy 74.452392 -316.002403)
			(xy 74.50186 -316.018479) (xy 74.548205 -316.042096) (xy 74.590284 -316.072673) (xy 74.627061 -316.109456)
			(xy 74.657631 -316.15154) (xy 74.681241 -316.197888) (xy 74.697309 -316.247359) (xy 74.70544 -316.298734)
			(xy 74.705972 -316.324742) (xy 74.705972 -316.799722) (xy 75.494146 -316.799722) (xy 75.498106 -316.750668)
			(xy 75.509883 -316.702884) (xy 75.529174 -316.657608) (xy 75.555477 -316.616012) (xy 75.588112 -316.579175)
			(xy 75.626233 -316.54805) (xy 75.668854 -316.523443) (xy 75.71487 -316.505991) (xy 75.763089 -316.496147)
			(xy 75.812264 -316.494166) (xy 75.861119 -316.500098) (xy 75.90839 -316.51379) (xy 75.952852 -316.534888)
			(xy 75.993355 -316.562844) (xy 76.028848 -316.596936) (xy 76.058413 -316.63628) (xy 76.081284 -316.679857)
			(xy 76.096868 -316.726538) (xy 76.104763 -316.775115) (xy 76.105258 -316.799722) (xy 77.394066 -316.799722)
			(xy 77.398026 -316.750668) (xy 77.409803 -316.702884) (xy 77.429094 -316.657608) (xy 77.455397 -316.616012)
			(xy 77.488032 -316.579175) (xy 77.526153 -316.54805) (xy 77.568774 -316.523443) (xy 77.61479 -316.505991)
			(xy 77.663009 -316.496147) (xy 77.712184 -316.494166) (xy 77.761039 -316.500098) (xy 77.80831 -316.51379)
			(xy 77.852772 -316.534888) (xy 77.893275 -316.562844) (xy 77.928768 -316.596936) (xy 77.958333 -316.63628)
			(xy 77.981204 -316.679857) (xy 77.996788 -316.726538) (xy 78.004683 -316.775115) (xy 78.005178 -316.799722)
			(xy 79.293986 -316.799722) (xy 79.297946 -316.750668) (xy 79.309723 -316.702884) (xy 79.329014 -316.657608)
			(xy 79.355317 -316.616012) (xy 79.387952 -316.579175) (xy 79.426073 -316.54805) (xy 79.468694 -316.523443)
			(xy 79.51471 -316.505991) (xy 79.562929 -316.496147) (xy 79.612104 -316.494166) (xy 79.660959 -316.500098)
			(xy 79.70823 -316.51379) (xy 79.752692 -316.534888) (xy 79.793195 -316.562844) (xy 79.828688 -316.596936)
			(xy 79.858253 -316.63628) (xy 79.881124 -316.679857) (xy 79.896708 -316.726538) (xy 79.904603 -316.775115)
			(xy 79.905098 -316.799722) (xy 81.19416 -316.799722) (xy 81.19812 -316.750668) (xy 81.209897 -316.702884)
			(xy 81.229188 -316.657608) (xy 81.255491 -316.616012) (xy 81.288126 -316.579175) (xy 81.326247 -316.54805)
			(xy 81.368868 -316.523443) (xy 81.414884 -316.505991) (xy 81.463103 -316.496147) (xy 81.512278 -316.494166)
			(xy 81.561133 -316.500098) (xy 81.608404 -316.51379) (xy 81.652866 -316.534888) (xy 81.693369 -316.562844)
			(xy 81.728862 -316.596936) (xy 81.758427 -316.63628) (xy 81.781298 -316.679857) (xy 81.796882 -316.726538)
			(xy 81.804777 -316.775115) (xy 81.805272 -316.799722) (xy 82.14412 -316.799722) (xy 82.14808 -316.750668)
			(xy 82.159857 -316.702884) (xy 82.179148 -316.657608) (xy 82.205451 -316.616012) (xy 82.238086 -316.579175)
			(xy 82.276207 -316.54805) (xy 82.318828 -316.523443) (xy 82.364844 -316.505991) (xy 82.413063 -316.496147)
			(xy 82.462238 -316.494166) (xy 82.511093 -316.500098) (xy 82.558364 -316.51379) (xy 82.602826 -316.534888)
			(xy 82.643329 -316.562844) (xy 82.678822 -316.596936) (xy 82.708387 -316.63628) (xy 82.731258 -316.679857)
			(xy 82.746842 -316.726538) (xy 82.754737 -316.775115) (xy 82.755232 -316.799722) (xy 82.754737 -316.824329)
			(xy 82.746842 -316.872906) (xy 82.731258 -316.919587) (xy 82.708387 -316.963164) (xy 82.678822 -317.002508)
			(xy 82.643329 -317.0366) (xy 82.602826 -317.064556) (xy 82.558364 -317.085654) (xy 82.511093 -317.099346)
			(xy 82.462238 -317.105278) (xy 82.413063 -317.103297) (xy 82.364844 -317.093453) (xy 82.318828 -317.076001)
			(xy 82.276207 -317.051394) (xy 82.238086 -317.020269) (xy 82.205451 -316.983432) (xy 82.179148 -316.941836)
			(xy 82.159857 -316.89656) (xy 82.14808 -316.848776) (xy 82.14412 -316.799722) (xy 81.805272 -316.799722)
			(xy 81.804777 -316.824329) (xy 81.796882 -316.872906) (xy 81.781298 -316.919587) (xy 81.758427 -316.963164)
			(xy 81.728862 -317.002508) (xy 81.693369 -317.0366) (xy 81.652866 -317.064556) (xy 81.608404 -317.085654)
			(xy 81.561133 -317.099346) (xy 81.512278 -317.105278) (xy 81.463103 -317.103297) (xy 81.414884 -317.093453)
			(xy 81.368868 -317.076001) (xy 81.326247 -317.051394) (xy 81.288126 -317.020269) (xy 81.255491 -316.983432)
			(xy 81.229188 -316.941836) (xy 81.209897 -316.89656) (xy 81.19812 -316.848776) (xy 81.19416 -316.799722)
			(xy 79.905098 -316.799722) (xy 79.904603 -316.824329) (xy 79.896708 -316.872906) (xy 79.881124 -316.919587)
			(xy 79.858253 -316.963164) (xy 79.828688 -317.002508) (xy 79.793195 -317.0366) (xy 79.752692 -317.064556)
			(xy 79.70823 -317.085654) (xy 79.660959 -317.099346) (xy 79.612104 -317.105278) (xy 79.562929 -317.103297)
			(xy 79.51471 -317.093453) (xy 79.468694 -317.076001) (xy 79.426073 -317.051394) (xy 79.387952 -317.020269)
			(xy 79.355317 -316.983432) (xy 79.329014 -316.941836) (xy 79.309723 -316.89656) (xy 79.297946 -316.848776)
			(xy 79.293986 -316.799722) (xy 78.005178 -316.799722) (xy 78.004683 -316.824329) (xy 77.996788 -316.872906)
			(xy 77.981204 -316.919587) (xy 77.958333 -316.963164) (xy 77.928768 -317.002508) (xy 77.893275 -317.0366)
			(xy 77.852772 -317.064556) (xy 77.80831 -317.085654) (xy 77.761039 -317.099346) (xy 77.712184 -317.105278)
			(xy 77.663009 -317.103297) (xy 77.61479 -317.093453) (xy 77.568774 -317.076001) (xy 77.526153 -317.051394)
			(xy 77.488032 -317.020269) (xy 77.455397 -316.983432) (xy 77.429094 -316.941836) (xy 77.409803 -316.89656)
			(xy 77.398026 -316.848776) (xy 77.394066 -316.799722) (xy 76.105258 -316.799722) (xy 76.104763 -316.824329)
			(xy 76.096868 -316.872906) (xy 76.081284 -316.919587) (xy 76.058413 -316.963164) (xy 76.028848 -317.002508)
			(xy 75.993355 -317.0366) (xy 75.952852 -317.064556) (xy 75.90839 -317.085654) (xy 75.861119 -317.099346)
			(xy 75.812264 -317.105278) (xy 75.763089 -317.103297) (xy 75.71487 -317.093453) (xy 75.668854 -317.076001)
			(xy 75.626233 -317.051394) (xy 75.588112 -317.020269) (xy 75.555477 -316.983432) (xy 75.529174 -316.941836)
			(xy 75.509883 -316.89656) (xy 75.498106 -316.848776) (xy 75.494146 -316.799722) (xy 74.705972 -316.799722)
			(xy 74.705972 -317.275464) (xy 74.705803 -317.289829) (xy 74.703262 -317.318445) (xy 74.700892 -317.332614)
			(xy 74.700892 -317.333122) (xy 74.699622 -317.34125) (xy 74.70648 -317.363856) (xy 74.77125 -317.43142)
			(xy 74.779745 -317.439485) (xy 74.801715 -317.447538) (xy 74.813414 -317.446914) (xy 74.813668 -317.446914)
			(xy 74.822712 -317.445865) (xy 74.840886 -317.444721) (xy 74.84999 -317.444628) (xy 74.875245 -317.44512)
			(xy 74.925067 -317.453432) (xy 74.972841 -317.469832) (xy 75.017265 -317.493871) (xy 75.057125 -317.524894)
			(xy 75.091336 -317.562056) (xy 75.118963 -317.604341) (xy 75.139253 -317.650597) (xy 75.151653 -317.699562)
			(xy 75.155824 -317.7499) (xy 75.155821 -317.749936) (xy 76.444106 -317.749936) (xy 76.448066 -317.700882)
			(xy 76.459843 -317.653098) (xy 76.479134 -317.607822) (xy 76.505437 -317.566226) (xy 76.538072 -317.529389)
			(xy 76.576193 -317.498264) (xy 76.618814 -317.473657) (xy 76.66483 -317.456205) (xy 76.713049 -317.446361)
			(xy 76.762224 -317.44438) (xy 76.811079 -317.450312) (xy 76.85835 -317.464004) (xy 76.902812 -317.485102)
			(xy 76.943315 -317.513058) (xy 76.978808 -317.54715) (xy 77.008373 -317.586494) (xy 77.031244 -317.630071)
			(xy 77.046828 -317.676752) (xy 77.054723 -317.725329) (xy 77.055218 -317.749936) (xy 78.344026 -317.749936)
			(xy 78.347986 -317.700882) (xy 78.359763 -317.653098) (xy 78.379054 -317.607822) (xy 78.405357 -317.566226)
			(xy 78.437992 -317.529389) (xy 78.476113 -317.498264) (xy 78.518734 -317.473657) (xy 78.56475 -317.456205)
			(xy 78.612969 -317.446361) (xy 78.662144 -317.44438) (xy 78.710999 -317.450312) (xy 78.75827 -317.464004)
			(xy 78.802732 -317.485102) (xy 78.843235 -317.513058) (xy 78.878728 -317.54715) (xy 78.908293 -317.586494)
			(xy 78.931164 -317.630071) (xy 78.946748 -317.676752) (xy 78.954643 -317.725329) (xy 78.955138 -317.749936)
			(xy 80.243946 -317.749936) (xy 80.247906 -317.700882) (xy 80.259683 -317.653098) (xy 80.278974 -317.607822)
			(xy 80.305277 -317.566226) (xy 80.337912 -317.529389) (xy 80.376033 -317.498264) (xy 80.418654 -317.473657)
			(xy 80.46467 -317.456205) (xy 80.512889 -317.446361) (xy 80.562064 -317.44438) (xy 80.610919 -317.450312)
			(xy 80.65819 -317.464004) (xy 80.702652 -317.485102) (xy 80.743155 -317.513058) (xy 80.778648 -317.54715)
			(xy 80.808213 -317.586494) (xy 80.831084 -317.630071) (xy 80.846668 -317.676752) (xy 80.854563 -317.725329)
			(xy 80.855058 -317.749936) (xy 80.854563 -317.774543) (xy 80.846668 -317.82312) (xy 80.831084 -317.869801)
			(xy 80.808213 -317.913378) (xy 80.778648 -317.952722) (xy 80.743155 -317.986814) (xy 80.702652 -318.01477)
			(xy 80.65819 -318.035868) (xy 80.610919 -318.04956) (xy 80.562064 -318.055492) (xy 80.512889 -318.053511)
			(xy 80.46467 -318.043667) (xy 80.418654 -318.026215) (xy 80.376033 -318.001608) (xy 80.337912 -317.970483)
			(xy 80.305277 -317.933646) (xy 80.278974 -317.89205) (xy 80.259683 -317.846774) (xy 80.247906 -317.79899)
			(xy 80.243946 -317.749936) (xy 78.955138 -317.749936) (xy 78.954643 -317.774543) (xy 78.946748 -317.82312)
			(xy 78.931164 -317.869801) (xy 78.908293 -317.913378) (xy 78.878728 -317.952722) (xy 78.843235 -317.986814)
			(xy 78.802732 -318.01477) (xy 78.75827 -318.035868) (xy 78.710999 -318.04956) (xy 78.662144 -318.055492)
			(xy 78.612969 -318.053511) (xy 78.56475 -318.043667) (xy 78.518734 -318.026215) (xy 78.476113 -318.001608)
			(xy 78.437992 -317.970483) (xy 78.405357 -317.933646) (xy 78.379054 -317.89205) (xy 78.359763 -317.846774)
			(xy 78.347986 -317.79899) (xy 78.344026 -317.749936) (xy 77.055218 -317.749936) (xy 77.054723 -317.774543)
			(xy 77.046828 -317.82312) (xy 77.031244 -317.869801) (xy 77.008373 -317.913378) (xy 76.978808 -317.952722)
			(xy 76.943315 -317.986814) (xy 76.902812 -318.01477) (xy 76.85835 -318.035868) (xy 76.811079 -318.04956)
			(xy 76.762224 -318.055492) (xy 76.713049 -318.053511) (xy 76.66483 -318.043667) (xy 76.618814 -318.026215)
			(xy 76.576193 -318.001608) (xy 76.538072 -317.970483) (xy 76.505437 -317.933646) (xy 76.479134 -317.89205)
			(xy 76.459843 -317.846774) (xy 76.448066 -317.79899) (xy 76.444106 -317.749936) (xy 75.155821 -317.749936)
			(xy 75.151653 -317.800238) (xy 75.139253 -317.849203) (xy 75.118963 -317.895459) (xy 75.091336 -317.937744)
			(xy 75.057125 -317.974906) (xy 75.017265 -318.005929) (xy 74.972841 -318.029968) (xy 74.925067 -318.046368)
			(xy 74.875245 -318.05468) (xy 74.84999 -318.055244) (xy 74.840822 -318.055151) (xy 74.822522 -318.054007)
			(xy 74.813414 -318.052958) (xy 74.81316 -318.052958) (xy 74.801356 -318.052137) (xy 74.779098 -318.060081)
			(xy 74.770488 -318.068198) (xy 74.705972 -318.135762) (xy 74.699114 -318.158368) (xy 74.70013 -318.165226)
			(xy 74.702648 -318.180019) (xy 74.705316 -318.209911) (xy 74.705464 -318.224916) (xy 74.705242 -318.239799)
			(xy 74.70244 -318.269435) (xy 74.699876 -318.284098) (xy 74.699876 -318.285622) (xy 74.69886 -318.291464)
			(xy 74.705972 -318.31407) (xy 74.770488 -318.381634) (xy 74.779126 -318.389707) (xy 74.801364 -318.39766)
			(xy 74.81316 -318.396874) (xy 74.813414 -318.396874) (xy 74.822522 -318.39582) (xy 74.840822 -318.394678)
			(xy 74.84999 -318.394588) (xy 74.875249 -318.39508) (xy 74.925077 -318.403393) (xy 74.972857 -318.419795)
			(xy 75.017286 -318.443837) (xy 75.057152 -318.474865) (xy 75.091367 -318.512031) (xy 75.118998 -318.554322)
			(xy 75.139291 -318.600584) (xy 75.151692 -318.649555) (xy 75.155864 -318.699896) (xy 76.444106 -318.699896)
			(xy 76.448066 -318.650842) (xy 76.459843 -318.603058) (xy 76.479134 -318.557782) (xy 76.505437 -318.516186)
			(xy 76.538072 -318.479349) (xy 76.576193 -318.448224) (xy 76.618814 -318.423617) (xy 76.66483 -318.406165)
			(xy 76.713049 -318.396321) (xy 76.762224 -318.39434) (xy 76.811079 -318.400272) (xy 76.85835 -318.413964)
			(xy 76.902812 -318.435062) (xy 76.943315 -318.463018) (xy 76.978808 -318.49711) (xy 77.008373 -318.536454)
			(xy 77.031244 -318.580031) (xy 77.046828 -318.626712) (xy 77.054723 -318.675289) (xy 77.055218 -318.699896)
			(xy 78.344026 -318.699896) (xy 78.347986 -318.650842) (xy 78.359763 -318.603058) (xy 78.379054 -318.557782)
			(xy 78.405357 -318.516186) (xy 78.437992 -318.479349) (xy 78.476113 -318.448224) (xy 78.518734 -318.423617)
			(xy 78.56475 -318.406165) (xy 78.612969 -318.396321) (xy 78.662144 -318.39434) (xy 78.710999 -318.400272)
			(xy 78.75827 -318.413964) (xy 78.802732 -318.435062) (xy 78.843235 -318.463018) (xy 78.878728 -318.49711)
			(xy 78.908293 -318.536454) (xy 78.931164 -318.580031) (xy 78.946748 -318.626712) (xy 78.954643 -318.675289)
			(xy 78.955138 -318.699896) (xy 80.243946 -318.699896) (xy 80.247906 -318.650842) (xy 80.259683 -318.603058)
			(xy 80.278974 -318.557782) (xy 80.305277 -318.516186) (xy 80.337912 -318.479349) (xy 80.376033 -318.448224)
			(xy 80.418654 -318.423617) (xy 80.46467 -318.406165) (xy 80.512889 -318.396321) (xy 80.562064 -318.39434)
			(xy 80.610919 -318.400272) (xy 80.65819 -318.413964) (xy 80.702652 -318.435062) (xy 80.743155 -318.463018)
			(xy 80.778648 -318.49711) (xy 80.808213 -318.536454) (xy 80.831084 -318.580031) (xy 80.846668 -318.626712)
			(xy 80.854563 -318.675289) (xy 80.855058 -318.699896) (xy 80.854563 -318.724503) (xy 80.846668 -318.77308)
			(xy 80.831084 -318.819761) (xy 80.808213 -318.863338) (xy 80.778648 -318.902682) (xy 80.743155 -318.936774)
			(xy 80.702652 -318.96473) (xy 80.65819 -318.985828) (xy 80.610919 -318.99952) (xy 80.562064 -319.005452)
			(xy 80.512889 -319.003471) (xy 80.46467 -318.993627) (xy 80.418654 -318.976175) (xy 80.376033 -318.951568)
			(xy 80.337912 -318.920443) (xy 80.305277 -318.883606) (xy 80.278974 -318.84201) (xy 80.259683 -318.796734)
			(xy 80.247906 -318.74895) (xy 80.243946 -318.699896) (xy 78.955138 -318.699896) (xy 78.954643 -318.724503)
			(xy 78.946748 -318.77308) (xy 78.931164 -318.819761) (xy 78.908293 -318.863338) (xy 78.878728 -318.902682)
			(xy 78.843235 -318.936774) (xy 78.802732 -318.96473) (xy 78.75827 -318.985828) (xy 78.710999 -318.99952)
			(xy 78.662144 -319.005452) (xy 78.612969 -319.003471) (xy 78.56475 -318.993627) (xy 78.518734 -318.976175)
			(xy 78.476113 -318.951568) (xy 78.437992 -318.920443) (xy 78.405357 -318.883606) (xy 78.379054 -318.84201)
			(xy 78.359763 -318.796734) (xy 78.347986 -318.74895) (xy 78.344026 -318.699896) (xy 77.055218 -318.699896)
			(xy 77.054723 -318.724503) (xy 77.046828 -318.77308) (xy 77.031244 -318.819761) (xy 77.008373 -318.863338)
			(xy 76.978808 -318.902682) (xy 76.943315 -318.936774) (xy 76.902812 -318.96473) (xy 76.85835 -318.985828)
			(xy 76.811079 -318.99952) (xy 76.762224 -319.005452) (xy 76.713049 -319.003471) (xy 76.66483 -318.993627)
			(xy 76.618814 -318.976175) (xy 76.576193 -318.951568) (xy 76.538072 -318.920443) (xy 76.505437 -318.883606)
			(xy 76.479134 -318.84201) (xy 76.459843 -318.796734) (xy 76.448066 -318.74895) (xy 76.444106 -318.699896)
			(xy 75.155864 -318.699896) (xy 75.155864 -318.6999) (xy 75.151692 -318.750245) (xy 75.139291 -318.799216)
			(xy 75.118998 -318.845478) (xy 75.091367 -318.887769) (xy 75.057152 -318.924935) (xy 75.017286 -318.955963)
			(xy 74.972857 -318.980005) (xy 74.925077 -318.996407) (xy 74.875249 -319.00472) (xy 74.84999 -319.005204)
			(xy 74.840822 -319.005111) (xy 74.822522 -319.003967) (xy 74.813414 -319.002918) (xy 74.81316 -319.002918)
			(xy 74.801355 -319.002096) (xy 74.779093 -319.010036) (xy 74.770488 -319.018158) (xy 74.705972 -319.085722)
			(xy 74.69886 -319.108328) (xy 74.699876 -319.114932) (xy 74.702463 -319.129784) (xy 74.705266 -319.159802)
			(xy 74.705464 -319.174876) (xy 74.704983 -319.200865) (xy 74.696854 -319.252204) (xy 74.680793 -319.301639)
			(xy 74.657196 -319.347952) (xy 74.626644 -319.390004) (xy 74.589888 -319.426757) (xy 74.547835 -319.457307)
			(xy 74.501521 -319.480901) (xy 74.452085 -319.496959) (xy 74.400745 -319.505084) (xy 74.374756 -319.505584)
			(xy 74.361802 -319.50533) (xy 74.353378 -319.50533) (xy 74.33728 -319.510258) (xy 74.330306 -319.514982)
			(xy 74.325872 -319.518375) (xy 74.318429 -319.526694) (xy 74.315574 -319.531492) (xy 74.31405 -319.53454)
			(xy 74.296193 -319.577214) (xy 74.253407 -319.659236) (xy 74.202917 -319.736755) (xy 74.145192 -319.809048)
			(xy 74.11339 -319.842642) (xy 74.106176 -319.851574) (xy 74.099915 -319.873641) (xy 74.103865 -319.896237)
			(xy 74.110088 -319.905888) (xy 74.885905 -320.900044) (xy 86.882487 -320.900044) (xy 86.886476 -320.751504)
			(xy 86.898433 -320.603391) (xy 86.918323 -320.456134) (xy 86.946088 -320.310158) (xy 86.981649 -320.165881)
			(xy 87.024903 -320.023722) (xy 87.075725 -319.884089) (xy 87.133969 -319.747386) (xy 87.199467 -319.614006)
			(xy 87.27203 -319.484334) (xy 87.351448 -319.358744) (xy 87.437493 -319.237597) (xy 87.529917 -319.121244)
			(xy 87.628453 -319.01002) (xy 87.732817 -318.904245) (xy 87.842709 -318.804225) (xy 87.95781 -318.710247)
			(xy 88.07779 -318.622583) (xy 88.202303 -318.541486) (xy 88.330989 -318.467189) (xy 88.463478 -318.399907)
			(xy 88.599387 -318.339833) (xy 88.738325 -318.287141) (xy 88.879891 -318.241982) (xy 89.023677 -318.204487)
			(xy 89.169268 -318.174765) (xy 89.316244 -318.1529) (xy 89.464183 -318.138956) (xy 89.612656 -318.132972)
			(xy 89.761237 -318.134967) (xy 89.909496 -318.144935) (xy 90.057007 -318.162846) (xy 90.203343 -318.188649)
			(xy 90.348084 -318.222269) (xy 90.490811 -318.263611) (xy 90.631114 -318.312554) (xy 90.768587 -318.368957)
			(xy 90.902834 -318.432658) (xy 91.033469 -318.503474) (xy 91.160114 -318.581199) (xy 91.282404 -318.66561)
			(xy 91.399987 -318.756463) (xy 91.512524 -318.853497) (xy 91.619691 -318.956432) (xy 91.721178 -319.064971)
			(xy 91.816692 -319.1788) (xy 91.905959 -319.297593) (xy 91.98872 -319.421005) (xy 92.064738 -319.548683)
			(xy 92.133793 -319.680256) (xy 92.195686 -319.815347) (xy 92.250239 -319.953564) (xy 92.297294 -320.094511)
			(xy 92.336716 -320.237781) (xy 92.36839 -320.38296) (xy 92.392226 -320.529629) (xy 92.408155 -320.677367)
			(xy 92.416131 -320.825747) (xy 92.41663 -320.900044) (xy 92.416131 -320.974341) (xy 92.408155 -321.122721)
			(xy 92.392226 -321.270459) (xy 92.36839 -321.417128) (xy 92.336716 -321.562307) (xy 92.297294 -321.705577)
			(xy 92.250239 -321.846524) (xy 92.195686 -321.984741) (xy 92.133793 -322.119832) (xy 92.064738 -322.251405)
			(xy 91.98872 -322.379083) (xy 91.905959 -322.502495) (xy 91.816692 -322.621288) (xy 91.721178 -322.735117)
			(xy 91.619691 -322.843656) (xy 91.512524 -322.946591) (xy 91.399987 -323.043625) (xy 91.282404 -323.134478)
			(xy 91.160114 -323.218889) (xy 91.033469 -323.296614) (xy 90.902834 -323.36743) (xy 90.768587 -323.431131)
			(xy 90.631114 -323.487534) (xy 90.490811 -323.536477) (xy 90.348084 -323.577819) (xy 90.203343 -323.611439)
			(xy 90.057007 -323.637242) (xy 89.909496 -323.655153) (xy 89.761237 -323.665121) (xy 89.612656 -323.667116)
			(xy 89.464183 -323.661132) (xy 89.316244 -323.647188) (xy 89.169268 -323.625323) (xy 89.023677 -323.595601)
			(xy 88.879891 -323.558106) (xy 88.738325 -323.512947) (xy 88.599387 -323.460255) (xy 88.463478 -323.400181)
			(xy 88.330989 -323.332899) (xy 88.202303 -323.258602) (xy 88.07779 -323.177505) (xy 87.95781 -323.089841)
			(xy 87.842709 -322.995863) (xy 87.732817 -322.895843) (xy 87.628453 -322.790068) (xy 87.529917 -322.678844)
			(xy 87.437493 -322.562491) (xy 87.351448 -322.441344) (xy 87.27203 -322.315754) (xy 87.199467 -322.186082)
			(xy 87.133969 -322.052702) (xy 87.075725 -321.915999) (xy 87.024903 -321.776366) (xy 86.981649 -321.634207)
			(xy 86.946088 -321.48993) (xy 86.918323 -321.343954) (xy 86.898433 -321.196697) (xy 86.886476 -321.048584)
			(xy 86.882487 -320.900044) (xy 74.885905 -320.900044) (xy 76.956666 -323.553582) (xy 76.957936 -323.555106)
			(xy 77.829918 -324.535546) (xy 77.831442 -324.536816) (xy 87.589614 -334.294988) (xy 87.592408 -334.297528)
			(xy 89.338658 -335.803748) (xy 89.345728 -335.809388) (xy 89.362644 -335.81575) (xy 89.371678 -335.816194)
			(xy 93.546676 -335.816194)
		)
		(stroke
			(width 0)
			(type solid)
		)
		(fill yes)
		(layer "In5.Cu")
		(net "GND")
	)
	(gr_poly
		(pts
			(xy 261.36727 -300.668944) (xy 261.372289 -300.66885) (xy 261.38214 -300.666928) (xy 261.386828 -300.665134)
			(xy 262.841232 -300.062392) (xy 262.886572 -300.044299) (xy 262.980008 -300.016004) (xy 263.075759 -299.99696)
			(xy 263.172911 -299.987349) (xy 263.221724 -299.9867) (xy 263.488932 -299.9867) (xy 263.498935 -299.986206)
			(xy 263.517416 -299.978541) (xy 263.531559 -299.964389) (xy 263.539213 -299.945904) (xy 263.539732 -299.9359)
			(xy 263.539732 -299.93336) (xy 263.539478 -299.931074) (xy 263.537954 -299.89653) (xy 263.537954 -299.895514)
			(xy 263.538493 -299.866143) (xy 263.547494 -299.808094) (xy 263.565286 -299.752111) (xy 263.591448 -299.699516)
			(xy 263.625361 -299.651553) (xy 263.666225 -299.609353) (xy 263.689338 -299.591222) (xy 263.695688 -299.586396)
			(xy 263.69899 -299.58411) (xy 263.704324 -299.573696) (xy 263.706733 -299.568486) (xy 263.709429 -299.557333)
			(xy 263.709658 -299.551598) (xy 263.710166 -299.513498) (xy 263.710674 -299.47108) (xy 263.710605 -299.465305)
			(xy 263.708164 -299.454019) (xy 263.705848 -299.448728) (xy 263.703562 -299.443648) (xy 263.69645 -299.434758)
			(xy 263.691878 -299.430948) (xy 263.670054 -299.412717) (xy 263.631527 -299.370894) (xy 263.599627 -299.32382)
			(xy 263.575059 -299.272538) (xy 263.558366 -299.218179) (xy 263.549918 -299.161946) (xy 263.549384 -299.133514)
			(xy 263.54987 -299.106263) (xy 263.557626 -299.052315) (xy 263.572981 -299.00002) (xy 263.595623 -298.950443)
			(xy 263.625089 -298.904593) (xy 263.66078 -298.863402) (xy 263.701971 -298.827711) (xy 263.747821 -298.798245)
			(xy 263.797398 -298.775603) (xy 263.849693 -298.760248) (xy 263.903641 -298.752492) (xy 263.958143 -298.752492)
			(xy 264.012091 -298.760248) (xy 264.064386 -298.775603) (xy 264.113963 -298.798245) (xy 264.159813 -298.827711)
			(xy 264.201004 -298.863402) (xy 264.236695 -298.904593) (xy 264.266161 -298.950443) (xy 264.288803 -299.00002)
			(xy 264.304158 -299.052315) (xy 264.311914 -299.106263) (xy 264.3124 -299.133514) (xy 264.311858 -299.162884)
			(xy 264.302853 -299.220929) (xy 264.285057 -299.276907) (xy 264.258891 -299.329497) (xy 264.224973 -299.377454)
			(xy 264.184105 -299.419646) (xy 264.161016 -299.437806) (xy 264.154666 -299.442632) (xy 264.151364 -299.444918)
			(xy 264.14603 -299.455332) (xy 264.143626 -299.460543) (xy 264.140938 -299.471696) (xy 264.140696 -299.47743)
			(xy 264.140188 -299.51553) (xy 264.13968 -299.557948) (xy 264.139752 -299.563723) (xy 264.142196 -299.575006)
			(xy 264.144506 -299.5803) (xy 264.146792 -299.58538) (xy 264.153904 -299.59427) (xy 264.158476 -299.59808)
			(xy 264.181566 -299.617366) (xy 264.221961 -299.661945) (xy 264.254867 -299.712307) (xy 264.27947 -299.767205)
			(xy 264.295161 -299.825281) (xy 264.298938 -299.855128) (xy 264.299954 -299.86605) (xy 264.305288 -299.875194)
			(xy 264.308053 -299.879667) (xy 264.315094 -299.887477) (xy 264.319258 -299.890688) (xy 264.34923 -299.912786)
			(xy 264.349738 -299.912786) (xy 264.38098 -299.936154) (xy 264.389286 -299.941307) (xy 264.408363 -299.94548)
			(xy 264.418064 -299.944282) (xy 264.681462 -299.891958) (xy 264.905236 -299.847508) (xy 264.912334 -299.845898)
			(xy 264.925244 -299.839189) (xy 264.930636 -299.8343) (xy 264.941558 -299.823886) (xy 264.943082 -299.816774)
			(xy 264.94486 -299.809154) (xy 264.951816 -299.781544) (xy 264.972799 -299.728616) (xy 265.001415 -299.679393)
			(xy 265.037028 -299.63497) (xy 265.078847 -299.596332) (xy 265.125943 -299.564337) (xy 265.177271 -299.539697)
			(xy 265.231691 -299.522958) (xy 265.287994 -299.514491) (xy 265.316462 -299.514006) (xy 265.3292 -299.514083)
			(xy 265.354622 -299.515734) (xy 265.367262 -299.517308) (xy 265.367262 -299.517054) (xy 265.389092 -299.520271)
			(xy 265.431872 -299.531094) (xy 265.452606 -299.538644) (xy 265.46286 -299.542644) (xy 265.482938 -299.551668)
			(xy 265.492738 -299.556678) (xy 265.519041 -299.571051) (xy 265.567212 -299.606715) (xy 265.609231 -299.649456)
			(xy 265.627104 -299.673518) (xy 265.631422 -299.679614) (xy 265.642852 -299.688504) (xy 265.649456 -299.691044)
			(xy 265.656337 -299.693568) (xy 265.670918 -299.694982) (xy 265.678158 -299.693838) (xy 265.896852 -299.650404)
			(xy 265.904669 -299.648436) (xy 265.918638 -299.64041) (xy 265.924284 -299.634656) (xy 265.924538 -299.634656)
			(xy 265.943679 -299.614937) (xy 265.986621 -299.580646) (xy 266.034035 -299.552862) (xy 266.084941 -299.532161)
			(xy 266.138288 -299.518968) (xy 266.165584 -299.515784) (xy 266.174474 -299.515022) (xy 266.200636 -299.502576)
			(xy 266.211304 -299.494956) (xy 266.22883 -299.476922) (xy 266.234986 -299.469719) (xy 266.241917 -299.452099)
			(xy 266.242292 -299.442632) (xy 266.242292 -279.138888) (xy 266.242717 -279.128819) (xy 266.250433 -279.110216)
			(xy 266.257278 -279.10282) (xy 268.488414 -276.871684) (xy 268.496446 -276.86268) (xy 268.503849 -276.83975)
			(xy 268.502638 -276.827742) (xy 268.502638 -276.82698) (xy 268.486128 -276.742906) (xy 268.484763 -276.736971)
			(xy 268.479626 -276.725931) (xy 268.475968 -276.721062) (xy 268.472412 -276.716236) (xy 268.462506 -276.70887)
			(xy 268.456156 -276.70633) (xy 268.4328 -276.6959) (xy 268.389655 -276.668429) (xy 268.351686 -276.634159)
			(xy 268.319952 -276.594046) (xy 268.295338 -276.549211) (xy 268.278531 -276.500903) (xy 268.27 -276.450472)
			(xy 268.269466 -276.424898) (xy 268.269988 -276.399643) (xy 268.278301 -276.349821) (xy 268.294702 -276.302047)
			(xy 268.318743 -276.257624) (xy 268.349767 -276.217764) (xy 268.386929 -276.183554) (xy 268.429215 -276.155928)
			(xy 268.475471 -276.135638) (xy 268.524436 -276.123238) (xy 268.574774 -276.119067) (xy 268.625112 -276.123238)
			(xy 268.674077 -276.135638) (xy 268.720333 -276.155928) (xy 268.762619 -276.183554) (xy 268.799781 -276.217764)
			(xy 268.830805 -276.257624) (xy 268.854846 -276.302047) (xy 268.871247 -276.349821) (xy 268.87956 -276.399643)
			(xy 268.880082 -276.424898) (xy 268.879479 -276.452228) (xy 268.869771 -276.506018) (xy 268.860778 -276.531832)
			(xy 268.859508 -276.535388) (xy 268.856206 -276.553676) (xy 268.856465 -276.560565) (xy 268.860188 -276.573833)
			(xy 268.863572 -276.579838) (xy 268.888972 -276.616922) (xy 268.91234 -276.651212) (xy 268.919863 -276.661115)
			(xy 268.94183 -276.672715) (xy 268.95425 -276.67331) (xy 269.145258 -276.67331) (xy 269.157681 -276.672702)
			(xy 269.179668 -276.661131) (xy 269.187168 -276.651212) (xy 269.210536 -276.616922) (xy 269.235936 -276.579838)
			(xy 269.239323 -276.573832) (xy 269.243059 -276.560567) (xy 269.243302 -276.553676) (xy 269.24 -276.535388)
			(xy 269.23873 -276.531832) (xy 269.229738 -276.506017) (xy 269.220026 -276.452228) (xy 269.219426 -276.424898)
			(xy 269.219948 -276.399643) (xy 269.228261 -276.349821) (xy 269.244662 -276.302047) (xy 269.268703 -276.257624)
			(xy 269.299727 -276.217764) (xy 269.336889 -276.183554) (xy 269.379175 -276.155928) (xy 269.425431 -276.135638)
			(xy 269.474396 -276.123238) (xy 269.524734 -276.119067) (xy 269.575072 -276.123238) (xy 269.624037 -276.135638)
			(xy 269.670293 -276.155928) (xy 269.712579 -276.183554) (xy 269.749741 -276.217764) (xy 269.780765 -276.257624)
			(xy 269.804806 -276.302047) (xy 269.821207 -276.349821) (xy 269.82952 -276.399643) (xy 269.830042 -276.424898)
			(xy 269.829439 -276.452227) (xy 269.81973 -276.506017) (xy 269.810738 -276.531832) (xy 269.809468 -276.535388)
			(xy 269.806166 -276.553676) (xy 269.806424 -276.560565) (xy 269.810145 -276.573835) (xy 269.813532 -276.579838)
			(xy 269.838932 -276.616922) (xy 269.8623 -276.651212) (xy 269.869827 -276.661105) (xy 269.891795 -276.672679)
			(xy 269.90421 -276.67331) (xy 276.387814 -276.67331) (xy 276.397447 -276.672844) (xy 276.415331 -276.665665)
			(xy 276.422612 -276.65934) (xy 276.441132 -276.642474) (xy 276.48231 -276.613956) (xy 276.527318 -276.591976)
			(xy 276.575128 -276.577037) (xy 276.624644 -276.569481) (xy 276.674732 -276.569481) (xy 276.724248 -276.577037)
			(xy 276.772058 -276.591976) (xy 276.817066 -276.613956) (xy 276.858244 -276.642474) (xy 276.876764 -276.65934)
			(xy 276.884033 -276.665683) (xy 276.901925 -276.672853) (xy 276.911562 -276.67331) (xy 277.338028 -276.67331)
			(xy 277.34766 -276.672841) (xy 277.365541 -276.665659) (xy 277.372826 -276.65934) (xy 277.391346 -276.642474)
			(xy 277.432524 -276.613956) (xy 277.477532 -276.591976) (xy 277.525342 -276.577037) (xy 277.574858 -276.569481)
			(xy 277.624946 -276.569481) (xy 277.674462 -276.577037) (xy 277.722272 -276.591976) (xy 277.76728 -276.613956)
			(xy 277.808458 -276.642474) (xy 277.826978 -276.65934) (xy 277.834242 -276.665696) (xy 277.852134 -276.672896)
			(xy 277.861776 -276.67331) (xy 278.287988 -276.67331) (xy 278.297623 -276.672848) (xy 278.315513 -276.665676)
			(xy 278.322786 -276.65934) (xy 278.341306 -276.642474) (xy 278.382484 -276.613956) (xy 278.427492 -276.591976)
			(xy 278.475302 -276.577037) (xy 278.524818 -276.569481) (xy 278.574906 -276.569481) (xy 278.624422 -276.577037)
			(xy 278.672232 -276.591976) (xy 278.71724 -276.613956) (xy 278.758418 -276.642474) (xy 278.776938 -276.65934)
			(xy 278.784205 -276.665687) (xy 278.802097 -276.672866) (xy 278.811736 -276.67331) (xy 279.237948 -276.67331)
			(xy 279.247578 -276.672838) (xy 279.265454 -276.66565) (xy 279.272746 -276.65934) (xy 279.291266 -276.642474)
			(xy 279.332444 -276.613956) (xy 279.377452 -276.591976) (xy 279.425262 -276.577037) (xy 279.474778 -276.569481)
			(xy 279.524866 -276.569481) (xy 279.574382 -276.577037) (xy 279.622192 -276.591976) (xy 279.6672 -276.613956)
			(xy 279.708378 -276.642474) (xy 279.726898 -276.65934) (xy 279.734163 -276.665693) (xy 279.752055 -276.672886)
			(xy 279.761696 -276.67331) (xy 280.187908 -276.67331) (xy 280.197541 -276.672845) (xy 280.215427 -276.665667)
			(xy 280.222706 -276.65934) (xy 280.241226 -276.642474) (xy 280.282404 -276.613956) (xy 280.327412 -276.591976)
			(xy 280.375222 -276.577037) (xy 280.424738 -276.569481) (xy 280.474826 -276.569481) (xy 280.524342 -276.577037)
			(xy 280.572152 -276.591976) (xy 280.61716 -276.613956) (xy 280.658338 -276.642474) (xy 280.676858 -276.65934)
			(xy 280.684126 -276.665684) (xy 280.702018 -276.672856) (xy 280.711656 -276.67331) (xy 281.137868 -276.67331)
			(xy 281.147504 -276.672852) (xy 281.1654 -276.665684) (xy 281.172666 -276.65934) (xy 281.191186 -276.642474)
			(xy 281.232364 -276.613956) (xy 281.277372 -276.591976) (xy 281.325182 -276.577037) (xy 281.374698 -276.569481)
			(xy 281.424786 -276.569481) (xy 281.474302 -276.577037) (xy 281.522112 -276.591976) (xy 281.56712 -276.613956)
			(xy 281.608298 -276.642474) (xy 281.626818 -276.65934) (xy 281.634084 -276.66569) (xy 281.651976 -276.672876)
			(xy 281.661616 -276.67331) (xy 282.087828 -276.67331) (xy 282.09746 -276.672841) (xy 282.115341 -276.665659)
			(xy 282.122626 -276.65934) (xy 282.141146 -276.642474) (xy 282.182324 -276.613956) (xy 282.227332 -276.591976)
			(xy 282.275142 -276.577037) (xy 282.324658 -276.569481) (xy 282.374746 -276.569481) (xy 282.424262 -276.577037)
			(xy 282.472072 -276.591976) (xy 282.51708 -276.613956) (xy 282.558258 -276.642474) (xy 282.576778 -276.65934)
			(xy 282.584042 -276.665696) (xy 282.601934 -276.672896) (xy 282.611576 -276.67331) (xy 283.038042 -276.67331)
			(xy 283.047673 -276.672839) (xy 283.06555 -276.665653) (xy 283.07284 -276.65934) (xy 283.09136 -276.642474)
			(xy 283.132538 -276.613956) (xy 283.177546 -276.591976) (xy 283.225356 -276.577037) (xy 283.274872 -276.569481)
			(xy 283.32496 -276.569481) (xy 283.374476 -276.577037) (xy 283.422286 -276.591976) (xy 283.467294 -276.613956)
			(xy 283.508472 -276.642474) (xy 283.526992 -276.65934) (xy 283.534257 -276.665694) (xy 283.552149 -276.672889)
			(xy 283.56179 -276.67331) (xy 283.988002 -276.67331) (xy 283.997636 -276.672846) (xy 284.015523 -276.66567)
			(xy 284.0228 -276.65934) (xy 284.04132 -276.642474) (xy 284.082498 -276.613956) (xy 284.127506 -276.591976)
			(xy 284.175316 -276.577037) (xy 284.224832 -276.569481) (xy 284.27492 -276.569481) (xy 284.324436 -276.577037)
			(xy 284.372246 -276.591976) (xy 284.417254 -276.613956) (xy 284.458432 -276.642474) (xy 284.476952 -276.65934)
			(xy 284.48422 -276.665685) (xy 284.502112 -276.672859) (xy 284.51175 -276.67331) (xy 284.937962 -276.67331)
			(xy 284.947591 -276.672835) (xy 284.965464 -276.665644) (xy 284.97276 -276.65934) (xy 284.99128 -276.642474)
			(xy 285.032458 -276.613956) (xy 285.077466 -276.591976) (xy 285.125276 -276.577037) (xy 285.174792 -276.569481)
			(xy 285.22488 -276.569481) (xy 285.274396 -276.577037) (xy 285.322206 -276.591976) (xy 285.367214 -276.613956)
			(xy 285.408392 -276.642474) (xy 285.426912 -276.65934) (xy 285.434178 -276.665691) (xy 285.45207 -276.672879)
			(xy 285.46171 -276.67331) (xy 285.887922 -276.67331) (xy 285.897554 -276.672842) (xy 285.915437 -276.665661)
			(xy 285.92272 -276.65934) (xy 285.94124 -276.642474) (xy 285.982418 -276.613956) (xy 286.027426 -276.591976)
			(xy 286.075236 -276.577037) (xy 286.124752 -276.569481) (xy 286.17484 -276.569481) (xy 286.224356 -276.577037)
			(xy 286.272166 -276.591976) (xy 286.317174 -276.613956) (xy 286.358352 -276.642474) (xy 286.376872 -276.65934)
			(xy 286.384136 -276.665697) (xy 286.402028 -276.672899) (xy 286.41167 -276.67331) (xy 286.837882 -276.67331)
			(xy 286.847517 -276.672849) (xy 286.865409 -276.665678) (xy 286.87268 -276.65934) (xy 286.8912 -276.642474)
			(xy 286.932378 -276.613956) (xy 286.977386 -276.591976) (xy 287.025196 -276.577037) (xy 287.074712 -276.569481)
			(xy 287.1248 -276.569481) (xy 287.174316 -276.577037) (xy 287.222126 -276.591976) (xy 287.267134 -276.613956)
			(xy 287.308312 -276.642474) (xy 287.326832 -276.65934) (xy 287.334099 -276.665688) (xy 287.351991 -276.672869)
			(xy 287.36163 -276.67331) (xy 287.787842 -276.67331) (xy 287.797473 -276.672839) (xy 287.81535 -276.665653)
			(xy 287.82264 -276.65934) (xy 287.84116 -276.642474) (xy 287.882338 -276.613956) (xy 287.927346 -276.591976)
			(xy 287.975156 -276.577037) (xy 288.024672 -276.569481) (xy 288.07476 -276.569481) (xy 288.124276 -276.577037)
			(xy 288.172086 -276.591976) (xy 288.217094 -276.613956) (xy 288.258272 -276.642474) (xy 288.276792 -276.65934)
			(xy 288.284057 -276.665694) (xy 288.301949 -276.672889) (xy 288.31159 -276.67331) (xy 288.738056 -276.67331)
			(xy 288.747686 -276.672837) (xy 288.76556 -276.665647) (xy 288.772854 -276.65934) (xy 288.791374 -276.642474)
			(xy 288.832552 -276.613956) (xy 288.87756 -276.591976) (xy 288.92537 -276.577037) (xy 288.974886 -276.569481)
			(xy 289.024974 -276.569481) (xy 289.07449 -276.577037) (xy 289.1223 -276.591976) (xy 289.167308 -276.613956)
			(xy 289.208486 -276.642474) (xy 289.227006 -276.65934) (xy 289.234272 -276.665692) (xy 289.252163 -276.672882)
			(xy 289.261804 -276.67331) (xy 289.688016 -276.67331) (xy 289.697649 -276.672844) (xy 289.715533 -276.665664)
			(xy 289.722814 -276.65934) (xy 289.741334 -276.642474) (xy 289.782512 -276.613956) (xy 289.82752 -276.591976)
			(xy 289.87533 -276.577037) (xy 289.924846 -276.569481) (xy 289.974934 -276.569481) (xy 290.02445 -276.577037)
			(xy 290.07226 -276.591976) (xy 290.117268 -276.613956) (xy 290.158446 -276.642474) (xy 290.176966 -276.65934)
			(xy 290.18423 -276.665698) (xy 290.202121 -276.672902) (xy 290.211764 -276.67331) (xy 290.645596 -276.67331)
			(xy 290.649604 -276.67324) (xy 290.657517 -276.671963) (xy 290.661344 -276.67077) (xy 290.672452 -276.659426)
			(xy 290.696496 -276.638688) (xy 290.70935 -276.629368) (xy 290.712906 -276.627082) (xy 290.964874 -276.375114)
			(xy 290.970068 -276.369363) (xy 290.977037 -276.355529) (xy 290.97859 -276.347936) (xy 290.979352 -276.339554)
			(xy 290.979352 -276.327108) (xy 290.978825 -276.316597) (xy 290.970424 -276.297325) (xy 290.963096 -276.28977)
			(xy 290.940236 -276.268688) (xy 290.932813 -276.262402) (xy 290.914654 -276.255477) (xy 290.90493 -276.255226)
			(xy 290.89985 -276.255226) (xy 290.875861 -276.254752) (xy 290.828474 -276.247239) (xy 290.782846 -276.232408)
			(xy 290.740099 -276.210622) (xy 290.701285 -276.182418) (xy 290.667361 -276.14849) (xy 290.639161 -276.109674)
			(xy 290.61738 -276.066925) (xy 290.602553 -276.021295) (xy 290.595046 -275.973907) (xy 290.594542 -275.949918)
			(xy 290.595073 -275.924191) (xy 290.603696 -275.873465) (xy 290.620702 -275.824904) (xy 290.645609 -275.77988)
			(xy 290.677712 -275.73967) (xy 290.716102 -275.705411) (xy 290.759693 -275.678073) (xy 290.807249 -275.658431)
			(xy 290.857426 -275.64704) (xy 290.883086 -275.645118) (xy 290.883594 -275.645118) (xy 290.893246 -275.64461)
			(xy 290.910518 -275.636482) (xy 290.965382 -275.57857) (xy 290.97176 -275.571247) (xy 290.978938 -275.553221)
			(xy 290.979352 -275.543518) (xy 290.979352 -275.406358) (xy 290.978926 -275.396658) (xy 290.971754 -275.378631)
			(xy 290.965382 -275.371306) (xy 290.917122 -275.320506) (xy 290.910247 -275.313928) (xy 290.893046 -275.305837)
			(xy 290.883594 -275.304758) (xy 290.88334 -275.304758) (xy 290.859034 -275.30296) (xy 290.811409 -275.292616)
			(xy 290.766033 -275.274835) (xy 290.724059 -275.25007) (xy 290.686554 -275.218948) (xy 290.654471 -275.182263)
			(xy 290.628626 -275.140945) (xy 290.609675 -275.096045) (xy 290.5981 -275.048704) (xy 290.594196 -275.000125)
			(xy 290.598061 -274.951543) (xy 290.609597 -274.904192) (xy 290.628511 -274.859277) (xy 290.654323 -274.817938)
			(xy 290.686375 -274.781226) (xy 290.723855 -274.750074) (xy 290.765809 -274.725274) (xy 290.81117 -274.707456)
			(xy 290.858787 -274.697073) (xy 290.883086 -274.695158) (xy 290.883594 -274.695158) (xy 290.893246 -274.69465)
			(xy 290.910518 -274.686522) (xy 290.965382 -274.62861) (xy 290.971767 -274.621289) (xy 290.978958 -274.603263)
			(xy 290.979352 -274.593558) (xy 290.979352 -274.521422) (xy 290.978671 -274.508975) (xy 290.966965 -274.486999)
			(xy 290.957 -274.479512) (xy 290.956746 -274.479258) (xy 290.923417 -274.456693) (xy 290.860217 -274.406844)
			(xy 290.830508 -274.37969) (xy 290.825964 -274.375716) (xy 290.815443 -274.369802) (xy 290.80968 -274.368006)
			(xy 290.786633 -274.361023) (xy 290.742694 -274.341312) (xy 290.702078 -274.31544) (xy 290.665642 -274.283953)
			(xy 290.634155 -274.247516) (xy 290.608284 -274.206899) (xy 290.588575 -274.16296) (xy 290.581588 -274.139914)
			(xy 290.579796 -274.134148) (xy 290.573885 -274.123625) (xy 290.569904 -274.119086) (xy 290.539077 -274.085376)
			(xy 290.483197 -274.013105) (xy 290.434349 -273.935907) (xy 290.392963 -273.854465) (xy 290.359406 -273.769497)
			(xy 290.333973 -273.681754) (xy 290.316889 -273.592011) (xy 290.308305 -273.501061) (xy 290.307776 -273.455384)
			(xy 290.307776 -273.41576) (xy 290.307325 -273.406217) (xy 290.300275 -273.388475) (xy 290.287265 -273.374503)
			(xy 290.27882 -273.37004) (xy 290.182554 -273.324066) (xy 290.153598 -273.327622) (xy 290.142168 -273.33702)
			(xy 290.121622 -273.352985) (xy 290.076227 -273.378408) (xy 290.027182 -273.395775) (xy 289.975904 -273.404585)
			(xy 289.94989 -273.405092) (xy 289.924637 -273.40457) (xy 289.874819 -273.396255) (xy 289.827049 -273.379854)
			(xy 289.78263 -273.355815) (xy 289.742773 -273.324792) (xy 289.708566 -273.287632) (xy 289.680942 -273.245349)
			(xy 289.660654 -273.199096) (xy 289.648256 -273.150134) (xy 289.644085 -273.0998) (xy 289.648256 -273.049466)
			(xy 289.660654 -273.000504) (xy 289.680942 -272.954251) (xy 289.708566 -272.911968) (xy 289.742773 -272.874808)
			(xy 289.78263 -272.843785) (xy 289.827049 -272.819746) (xy 289.874819 -272.803345) (xy 289.924637 -272.79503)
			(xy 289.94989 -272.794476) (xy 289.975904 -272.794999) (xy 290.027181 -272.803805) (xy 290.076227 -272.821165)
			(xy 290.121626 -272.846579) (xy 290.142168 -272.862548) (xy 290.153598 -272.871946) (xy 290.182554 -272.875502)
			(xy 290.27882 -272.829528) (xy 290.287284 -272.825077) (xy 290.300348 -272.811132) (xy 290.307374 -272.793362)
			(xy 290.307776 -272.783808) (xy 290.307776 -271.905222) (xy 290.307659 -271.900532) (xy 290.305878 -271.891322)
			(xy 290.30422 -271.886934) (xy 290.287999 -271.843668) (xy 290.262691 -271.754795) (xy 290.245702 -271.663963)
			(xy 290.237179 -271.57195) (xy 290.236656 -271.525746) (xy 290.236656 -270.248888) (xy 290.234878 -270.235426)
			(xy 281.68346 -239.653064) (xy 281.681519 -239.646872) (xy 281.674967 -239.635677) (xy 281.670506 -239.630966)
			(xy 281.449272 -239.409732) (xy 281.44642 -239.407028) (xy 281.44004 -239.402438) (xy 281.436572 -239.400588)
			(xy 281.431145 -239.398004) (xy 281.419466 -239.395177) (xy 281.413458 -239.395) (xy 278.163274 -239.395)
			(xy 278.153206 -239.395428) (xy 278.134608 -239.403149) (xy 278.127206 -239.409986) (xy 277.400766 -240.136172)
			(xy 277.393924 -240.143571) (xy 277.386205 -240.16217) (xy 277.38578 -240.17224) (xy 277.38578 -266.942824)
			(xy 277.385317 -266.968255) (xy 277.377529 -267.018517) (xy 277.370286 -267.0429) (xy 277.368 -267.05052)
			(xy 277.368 -267.133832) (xy 277.367571 -267.1439) (xy 277.359848 -267.162496) (xy 277.353014 -267.1699)
			(xy 273.172682 -271.350232) (xy 273.16586 -271.357707) (xy 273.158244 -271.37644) (xy 273.15795 -271.386554)
			(xy 273.162522 -271.465294) (xy 273.162956 -271.470652) (xy 273.165781 -271.481023) (xy 273.16811 -271.485868)
			(xy 273.172936 -271.495012) (xy 273.177762 -271.498822) (xy 273.199043 -271.515806) (xy 273.236687 -271.555139)
			(xy 273.267913 -271.599739) (xy 273.291995 -271.648569) (xy 273.308371 -271.700492) (xy 273.316661 -271.754302)
			(xy 273.317208 -271.781524) (xy 273.316657 -271.809506) (xy 273.307899 -271.86478) (xy 273.290603 -271.918004)
			(xy 273.265193 -271.967867) (xy 273.232297 -272.013141) (xy 273.192723 -272.052712) (xy 273.147446 -272.085606)
			(xy 273.097582 -272.111012) (xy 273.044357 -272.128305) (xy 272.989082 -272.137059) (xy 272.9611 -272.137632)
			(xy 272.933876 -272.137116) (xy 272.880062 -272.12883) (xy 272.828136 -272.112452) (xy 272.779307 -272.088363)
			(xy 272.734712 -272.057124) (xy 272.695391 -272.019462) (xy 272.678398 -271.998186) (xy 272.674588 -271.99336)
			(xy 272.665444 -271.988534) (xy 272.660607 -271.986183) (xy 272.650232 -271.983362) (xy 272.64487 -271.982946)
			(xy 272.56613 -271.978374) (xy 272.556026 -271.97872) (xy 272.537315 -271.986332) (xy 272.529808 -271.993106)
			(xy 272.461736 -272.061178) (xy 272.454335 -272.068017) (xy 272.435737 -272.075731) (xy 272.425668 -272.076164)
			(xy 270.902938 -272.076164) (xy 270.892874 -272.075729) (xy 270.874289 -272.067995) (xy 270.86687 -272.061178)
			(xy 270.735552 -271.92986) (xy 270.732758 -271.92732) (xy 270.731488 -271.926304) (xy 270.727319 -271.923128)
			(xy 270.717973 -271.918388) (xy 270.712946 -271.916906) (xy 270.699738 -271.915128) (xy 270.153892 -271.915128)
			(xy 270.143823 -271.915553) (xy 270.125223 -271.923273) (xy 270.117824 -271.930114) (xy 269.423134 -272.624804)
			(xy 270.169144 -272.624804) (xy 270.173104 -272.57575) (xy 270.184881 -272.527966) (xy 270.204172 -272.48269)
			(xy 270.230475 -272.441094) (xy 270.26311 -272.404257) (xy 270.301231 -272.373132) (xy 270.343852 -272.348525)
			(xy 270.389868 -272.331073) (xy 270.438087 -272.321229) (xy 270.487262 -272.319248) (xy 270.536117 -272.32518)
			(xy 270.583388 -272.338872) (xy 270.62785 -272.35997) (xy 270.668353 -272.387926) (xy 270.703846 -272.422018)
			(xy 270.733411 -272.461362) (xy 270.756282 -272.504939) (xy 270.771866 -272.55162) (xy 270.779761 -272.600197)
			(xy 270.780256 -272.624804) (xy 272.069064 -272.624804) (xy 272.073024 -272.57575) (xy 272.084801 -272.527966)
			(xy 272.104092 -272.48269) (xy 272.130395 -272.441094) (xy 272.16303 -272.404257) (xy 272.201151 -272.373132)
			(xy 272.243772 -272.348525) (xy 272.289788 -272.331073) (xy 272.338007 -272.321229) (xy 272.387182 -272.319248)
			(xy 272.436037 -272.32518) (xy 272.483308 -272.338872) (xy 272.52777 -272.35997) (xy 272.568273 -272.387926)
			(xy 272.603766 -272.422018) (xy 272.633331 -272.461362) (xy 272.656202 -272.504939) (xy 272.671786 -272.55162)
			(xy 272.679681 -272.600197) (xy 272.680176 -272.624804) (xy 273.968984 -272.624804) (xy 273.972944 -272.57575)
			(xy 273.984721 -272.527966) (xy 274.004012 -272.48269) (xy 274.030315 -272.441094) (xy 274.06295 -272.404257)
			(xy 274.101071 -272.373132) (xy 274.143692 -272.348525) (xy 274.189708 -272.331073) (xy 274.237927 -272.321229)
			(xy 274.287102 -272.319248) (xy 274.335957 -272.32518) (xy 274.383228 -272.338872) (xy 274.42769 -272.35997)
			(xy 274.468193 -272.387926) (xy 274.503686 -272.422018) (xy 274.533251 -272.461362) (xy 274.556122 -272.504939)
			(xy 274.571706 -272.55162) (xy 274.579601 -272.600197) (xy 274.580096 -272.624804) (xy 274.579601 -272.649411)
			(xy 274.571706 -272.697988) (xy 274.556122 -272.744669) (xy 274.533251 -272.788246) (xy 274.503686 -272.82759)
			(xy 274.468193 -272.861682) (xy 274.42769 -272.889638) (xy 274.383228 -272.910736) (xy 274.335957 -272.924428)
			(xy 274.287102 -272.93036) (xy 274.237927 -272.928379) (xy 274.189708 -272.918535) (xy 274.143692 -272.901083)
			(xy 274.101071 -272.876476) (xy 274.06295 -272.845351) (xy 274.030315 -272.808514) (xy 274.004012 -272.766918)
			(xy 273.984721 -272.721642) (xy 273.972944 -272.673858) (xy 273.968984 -272.624804) (xy 272.680176 -272.624804)
			(xy 272.679681 -272.649411) (xy 272.671786 -272.697988) (xy 272.656202 -272.744669) (xy 272.633331 -272.788246)
			(xy 272.603766 -272.82759) (xy 272.568273 -272.861682) (xy 272.52777 -272.889638) (xy 272.483308 -272.910736)
			(xy 272.436037 -272.924428) (xy 272.387182 -272.93036) (xy 272.338007 -272.928379) (xy 272.289788 -272.918535)
			(xy 272.243772 -272.901083) (xy 272.201151 -272.876476) (xy 272.16303 -272.845351) (xy 272.130395 -272.808514)
			(xy 272.104092 -272.766918) (xy 272.084801 -272.721642) (xy 272.073024 -272.673858) (xy 272.069064 -272.624804)
			(xy 270.780256 -272.624804) (xy 270.779761 -272.649411) (xy 270.771866 -272.697988) (xy 270.756282 -272.744669)
			(xy 270.733411 -272.788246) (xy 270.703846 -272.82759) (xy 270.668353 -272.861682) (xy 270.62785 -272.889638)
			(xy 270.583388 -272.910736) (xy 270.536117 -272.924428) (xy 270.487262 -272.93036) (xy 270.438087 -272.928379)
			(xy 270.389868 -272.918535) (xy 270.343852 -272.901083) (xy 270.301231 -272.876476) (xy 270.26311 -272.845351)
			(xy 270.230475 -272.808514) (xy 270.204172 -272.766918) (xy 270.184881 -272.721642) (xy 270.173104 -272.673858)
			(xy 270.169144 -272.624804) (xy 269.423134 -272.624804) (xy 268.948154 -273.099784) (xy 276.343884 -273.099784)
			(xy 276.347844 -273.05073) (xy 276.359621 -273.002946) (xy 276.378912 -272.95767) (xy 276.405215 -272.916074)
			(xy 276.43785 -272.879237) (xy 276.475971 -272.848112) (xy 276.518592 -272.823505) (xy 276.564608 -272.806053)
			(xy 276.612827 -272.796209) (xy 276.662002 -272.794228) (xy 276.710857 -272.80016) (xy 276.758128 -272.813852)
			(xy 276.80259 -272.83495) (xy 276.843093 -272.862906) (xy 276.878586 -272.896998) (xy 276.908151 -272.936342)
			(xy 276.931022 -272.979919) (xy 276.946606 -273.0266) (xy 276.954501 -273.075177) (xy 276.954996 -273.099784)
			(xy 278.244058 -273.099784) (xy 278.248018 -273.05073) (xy 278.259795 -273.002946) (xy 278.279086 -272.95767)
			(xy 278.305389 -272.916074) (xy 278.338024 -272.879237) (xy 278.376145 -272.848112) (xy 278.418766 -272.823505)
			(xy 278.464782 -272.806053) (xy 278.513001 -272.796209) (xy 278.562176 -272.794228) (xy 278.611031 -272.80016)
			(xy 278.658302 -272.813852) (xy 278.702764 -272.83495) (xy 278.743267 -272.862906) (xy 278.77876 -272.896998)
			(xy 278.808325 -272.936342) (xy 278.831196 -272.979919) (xy 278.84678 -273.0266) (xy 278.854675 -273.075177)
			(xy 278.85517 -273.099784) (xy 280.143978 -273.099784) (xy 280.147938 -273.05073) (xy 280.159715 -273.002946)
			(xy 280.179006 -272.95767) (xy 280.205309 -272.916074) (xy 280.237944 -272.879237) (xy 280.276065 -272.848112)
			(xy 280.318686 -272.823505) (xy 280.364702 -272.806053) (xy 280.412921 -272.796209) (xy 280.462096 -272.794228)
			(xy 280.510951 -272.80016) (xy 280.558222 -272.813852) (xy 280.602684 -272.83495) (xy 280.643187 -272.862906)
			(xy 280.67868 -272.896998) (xy 280.708245 -272.936342) (xy 280.731116 -272.979919) (xy 280.7467 -273.0266)
			(xy 280.754595 -273.075177) (xy 280.75509 -273.099784) (xy 282.043898 -273.099784) (xy 282.047858 -273.05073)
			(xy 282.059635 -273.002946) (xy 282.078926 -272.95767) (xy 282.105229 -272.916074) (xy 282.137864 -272.879237)
			(xy 282.175985 -272.848112) (xy 282.218606 -272.823505) (xy 282.264622 -272.806053) (xy 282.312841 -272.796209)
			(xy 282.362016 -272.794228) (xy 282.410871 -272.80016) (xy 282.458142 -272.813852) (xy 282.502604 -272.83495)
			(xy 282.543107 -272.862906) (xy 282.5786 -272.896998) (xy 282.608165 -272.936342) (xy 282.631036 -272.979919)
			(xy 282.64662 -273.0266) (xy 282.654515 -273.075177) (xy 282.65501 -273.099784) (xy 283.944072 -273.099784)
			(xy 283.948032 -273.05073) (xy 283.959809 -273.002946) (xy 283.9791 -272.95767) (xy 284.005403 -272.916074)
			(xy 284.038038 -272.879237) (xy 284.076159 -272.848112) (xy 284.11878 -272.823505) (xy 284.164796 -272.806053)
			(xy 284.213015 -272.796209) (xy 284.26219 -272.794228) (xy 284.311045 -272.80016) (xy 284.358316 -272.813852)
			(xy 284.402778 -272.83495) (xy 284.443281 -272.862906) (xy 284.478774 -272.896998) (xy 284.508339 -272.936342)
			(xy 284.53121 -272.979919) (xy 284.546794 -273.0266) (xy 284.554689 -273.075177) (xy 284.555184 -273.099784)
			(xy 285.843992 -273.099784) (xy 285.847952 -273.05073) (xy 285.859729 -273.002946) (xy 285.87902 -272.95767)
			(xy 285.905323 -272.916074) (xy 285.937958 -272.879237) (xy 285.976079 -272.848112) (xy 286.0187 -272.823505)
			(xy 286.064716 -272.806053) (xy 286.112935 -272.796209) (xy 286.16211 -272.794228) (xy 286.210965 -272.80016)
			(xy 286.258236 -272.813852) (xy 286.302698 -272.83495) (xy 286.343201 -272.862906) (xy 286.378694 -272.896998)
			(xy 286.408259 -272.936342) (xy 286.43113 -272.979919) (xy 286.446714 -273.0266) (xy 286.454609 -273.075177)
			(xy 286.455104 -273.099784) (xy 287.743912 -273.099784) (xy 287.747872 -273.05073) (xy 287.759649 -273.002946)
			(xy 287.77894 -272.95767) (xy 287.805243 -272.916074) (xy 287.837878 -272.879237) (xy 287.875999 -272.848112)
			(xy 287.91862 -272.823505) (xy 287.964636 -272.806053) (xy 288.012855 -272.796209) (xy 288.06203 -272.794228)
			(xy 288.110885 -272.80016) (xy 288.158156 -272.813852) (xy 288.202618 -272.83495) (xy 288.243121 -272.862906)
			(xy 288.278614 -272.896998) (xy 288.308179 -272.936342) (xy 288.33105 -272.979919) (xy 288.346634 -273.0266)
			(xy 288.354529 -273.075177) (xy 288.355024 -273.099784) (xy 288.354529 -273.124391) (xy 288.346634 -273.172968)
			(xy 288.33105 -273.219649) (xy 288.308179 -273.263226) (xy 288.278614 -273.30257) (xy 288.243121 -273.336662)
			(xy 288.202618 -273.364618) (xy 288.158156 -273.385716) (xy 288.110885 -273.399408) (xy 288.06203 -273.40534)
			(xy 288.012855 -273.403359) (xy 287.964636 -273.393515) (xy 287.91862 -273.376063) (xy 287.875999 -273.351456)
			(xy 287.837878 -273.320331) (xy 287.805243 -273.283494) (xy 287.77894 -273.241898) (xy 287.759649 -273.196622)
			(xy 287.747872 -273.148838) (xy 287.743912 -273.099784) (xy 286.455104 -273.099784) (xy 286.454609 -273.124391)
			(xy 286.446714 -273.172968) (xy 286.43113 -273.219649) (xy 286.408259 -273.263226) (xy 286.378694 -273.30257)
			(xy 286.343201 -273.336662) (xy 286.302698 -273.364618) (xy 286.258236 -273.385716) (xy 286.210965 -273.399408)
			(xy 286.16211 -273.40534) (xy 286.112935 -273.403359) (xy 286.064716 -273.393515) (xy 286.0187 -273.376063)
			(xy 285.976079 -273.351456) (xy 285.937958 -273.320331) (xy 285.905323 -273.283494) (xy 285.87902 -273.241898)
			(xy 285.859729 -273.196622) (xy 285.847952 -273.148838) (xy 285.843992 -273.099784) (xy 284.555184 -273.099784)
			(xy 284.554689 -273.124391) (xy 284.546794 -273.172968) (xy 284.53121 -273.219649) (xy 284.508339 -273.263226)
			(xy 284.478774 -273.30257) (xy 284.443281 -273.336662) (xy 284.402778 -273.364618) (xy 284.358316 -273.385716)
			(xy 284.311045 -273.399408) (xy 284.26219 -273.40534) (xy 284.213015 -273.403359) (xy 284.164796 -273.393515)
			(xy 284.11878 -273.376063) (xy 284.076159 -273.351456) (xy 284.038038 -273.320331) (xy 284.005403 -273.283494)
			(xy 283.9791 -273.241898) (xy 283.959809 -273.196622) (xy 283.948032 -273.148838) (xy 283.944072 -273.099784)
			(xy 282.65501 -273.099784) (xy 282.654515 -273.124391) (xy 282.64662 -273.172968) (xy 282.631036 -273.219649)
			(xy 282.608165 -273.263226) (xy 282.5786 -273.30257) (xy 282.543107 -273.336662) (xy 282.502604 -273.364618)
			(xy 282.458142 -273.385716) (xy 282.410871 -273.399408) (xy 282.362016 -273.40534) (xy 282.312841 -273.403359)
			(xy 282.264622 -273.393515) (xy 282.218606 -273.376063) (xy 282.175985 -273.351456) (xy 282.137864 -273.320331)
			(xy 282.105229 -273.283494) (xy 282.078926 -273.241898) (xy 282.059635 -273.196622) (xy 282.047858 -273.148838)
			(xy 282.043898 -273.099784) (xy 280.75509 -273.099784) (xy 280.754595 -273.124391) (xy 280.7467 -273.172968)
			(xy 280.731116 -273.219649) (xy 280.708245 -273.263226) (xy 280.67868 -273.30257) (xy 280.643187 -273.336662)
			(xy 280.602684 -273.364618) (xy 280.558222 -273.385716) (xy 280.510951 -273.399408) (xy 280.462096 -273.40534)
			(xy 280.412921 -273.403359) (xy 280.364702 -273.393515) (xy 280.318686 -273.376063) (xy 280.276065 -273.351456)
			(xy 280.237944 -273.320331) (xy 280.205309 -273.283494) (xy 280.179006 -273.241898) (xy 280.159715 -273.196622)
			(xy 280.147938 -273.148838) (xy 280.143978 -273.099784) (xy 278.85517 -273.099784) (xy 278.854675 -273.124391)
			(xy 278.84678 -273.172968) (xy 278.831196 -273.219649) (xy 278.808325 -273.263226) (xy 278.77876 -273.30257)
			(xy 278.743267 -273.336662) (xy 278.702764 -273.364618) (xy 278.658302 -273.385716) (xy 278.611031 -273.399408)
			(xy 278.562176 -273.40534) (xy 278.513001 -273.403359) (xy 278.464782 -273.393515) (xy 278.418766 -273.376063)
			(xy 278.376145 -273.351456) (xy 278.338024 -273.320331) (xy 278.305389 -273.283494) (xy 278.279086 -273.241898)
			(xy 278.259795 -273.196622) (xy 278.248018 -273.148838) (xy 278.244058 -273.099784) (xy 276.954996 -273.099784)
			(xy 276.954501 -273.124391) (xy 276.946606 -273.172968) (xy 276.931022 -273.219649) (xy 276.908151 -273.263226)
			(xy 276.878586 -273.30257) (xy 276.843093 -273.336662) (xy 276.80259 -273.364618) (xy 276.758128 -273.385716)
			(xy 276.710857 -273.399408) (xy 276.662002 -273.40534) (xy 276.612827 -273.403359) (xy 276.564608 -273.393515)
			(xy 276.518592 -273.376063) (xy 276.475971 -273.351456) (xy 276.43785 -273.320331) (xy 276.405215 -273.283494)
			(xy 276.378912 -273.241898) (xy 276.359621 -273.196622) (xy 276.347844 -273.148838) (xy 276.343884 -273.099784)
			(xy 268.948154 -273.099784) (xy 268.473174 -273.574764) (xy 272.069064 -273.574764) (xy 272.073024 -273.52571)
			(xy 272.084801 -273.477926) (xy 272.104092 -273.43265) (xy 272.130395 -273.391054) (xy 272.16303 -273.354217)
			(xy 272.201151 -273.323092) (xy 272.243772 -273.298485) (xy 272.289788 -273.281033) (xy 272.338007 -273.271189)
			(xy 272.387182 -273.269208) (xy 272.436037 -273.27514) (xy 272.483308 -273.288832) (xy 272.52777 -273.30993)
			(xy 272.568273 -273.337886) (xy 272.603766 -273.371978) (xy 272.633331 -273.411322) (xy 272.656202 -273.454899)
			(xy 272.671786 -273.50158) (xy 272.679681 -273.550157) (xy 272.680176 -273.574764) (xy 273.968984 -273.574764)
			(xy 273.972944 -273.52571) (xy 273.984721 -273.477926) (xy 274.004012 -273.43265) (xy 274.030315 -273.391054)
			(xy 274.06295 -273.354217) (xy 274.101071 -273.323092) (xy 274.143692 -273.298485) (xy 274.189708 -273.281033)
			(xy 274.237927 -273.271189) (xy 274.287102 -273.269208) (xy 274.335957 -273.27514) (xy 274.383228 -273.288832)
			(xy 274.42769 -273.30993) (xy 274.468193 -273.337886) (xy 274.503686 -273.371978) (xy 274.533251 -273.411322)
			(xy 274.556122 -273.454899) (xy 274.571706 -273.50158) (xy 274.579601 -273.550157) (xy 274.580096 -273.574764)
			(xy 274.579601 -273.599371) (xy 274.571706 -273.647948) (xy 274.556122 -273.694629) (xy 274.533251 -273.738206)
			(xy 274.503686 -273.77755) (xy 274.468193 -273.811642) (xy 274.42769 -273.839598) (xy 274.383228 -273.860696)
			(xy 274.335957 -273.874388) (xy 274.287102 -273.88032) (xy 274.237927 -273.878339) (xy 274.189708 -273.868495)
			(xy 274.143692 -273.851043) (xy 274.101071 -273.826436) (xy 274.06295 -273.795311) (xy 274.030315 -273.758474)
			(xy 274.004012 -273.716878) (xy 273.984721 -273.671602) (xy 273.972944 -273.623818) (xy 273.968984 -273.574764)
			(xy 272.680176 -273.574764) (xy 272.679681 -273.599371) (xy 272.671786 -273.647948) (xy 272.656202 -273.694629)
			(xy 272.633331 -273.738206) (xy 272.603766 -273.77755) (xy 272.568273 -273.811642) (xy 272.52777 -273.839598)
			(xy 272.483308 -273.860696) (xy 272.436037 -273.874388) (xy 272.387182 -273.88032) (xy 272.338007 -273.878339)
			(xy 272.289788 -273.868495) (xy 272.243772 -273.851043) (xy 272.201151 -273.826436) (xy 272.16303 -273.795311)
			(xy 272.130395 -273.758474) (xy 272.104092 -273.716878) (xy 272.084801 -273.671602) (xy 272.073024 -273.623818)
			(xy 272.069064 -273.574764) (xy 268.473174 -273.574764) (xy 267.998194 -274.049744) (xy 276.343884 -274.049744)
			(xy 276.347844 -274.00069) (xy 276.359621 -273.952906) (xy 276.378912 -273.90763) (xy 276.405215 -273.866034)
			(xy 276.43785 -273.829197) (xy 276.475971 -273.798072) (xy 276.518592 -273.773465) (xy 276.564608 -273.756013)
			(xy 276.612827 -273.746169) (xy 276.662002 -273.744188) (xy 276.710857 -273.75012) (xy 276.758128 -273.763812)
			(xy 276.80259 -273.78491) (xy 276.843093 -273.812866) (xy 276.878586 -273.846958) (xy 276.908151 -273.886302)
			(xy 276.931022 -273.929879) (xy 276.946606 -273.97656) (xy 276.954501 -274.025137) (xy 276.954996 -274.049744)
			(xy 278.244058 -274.049744) (xy 278.248018 -274.00069) (xy 278.259795 -273.952906) (xy 278.279086 -273.90763)
			(xy 278.305389 -273.866034) (xy 278.338024 -273.829197) (xy 278.376145 -273.798072) (xy 278.418766 -273.773465)
			(xy 278.464782 -273.756013) (xy 278.513001 -273.746169) (xy 278.562176 -273.744188) (xy 278.611031 -273.75012)
			(xy 278.658302 -273.763812) (xy 278.702764 -273.78491) (xy 278.743267 -273.812866) (xy 278.77876 -273.846958)
			(xy 278.808325 -273.886302) (xy 278.831196 -273.929879) (xy 278.84678 -273.97656) (xy 278.854675 -274.025137)
			(xy 278.85517 -274.049744) (xy 280.143978 -274.049744) (xy 280.147938 -274.00069) (xy 280.159715 -273.952906)
			(xy 280.179006 -273.90763) (xy 280.205309 -273.866034) (xy 280.237944 -273.829197) (xy 280.276065 -273.798072)
			(xy 280.318686 -273.773465) (xy 280.364702 -273.756013) (xy 280.412921 -273.746169) (xy 280.462096 -273.744188)
			(xy 280.510951 -273.75012) (xy 280.558222 -273.763812) (xy 280.602684 -273.78491) (xy 280.643187 -273.812866)
			(xy 280.67868 -273.846958) (xy 280.708245 -273.886302) (xy 280.731116 -273.929879) (xy 280.7467 -273.97656)
			(xy 280.754595 -274.025137) (xy 280.75509 -274.049744) (xy 282.043898 -274.049744) (xy 282.047858 -274.00069)
			(xy 282.059635 -273.952906) (xy 282.078926 -273.90763) (xy 282.105229 -273.866034) (xy 282.137864 -273.829197)
			(xy 282.175985 -273.798072) (xy 282.218606 -273.773465) (xy 282.264622 -273.756013) (xy 282.312841 -273.746169)
			(xy 282.362016 -273.744188) (xy 282.410871 -273.75012) (xy 282.458142 -273.763812) (xy 282.502604 -273.78491)
			(xy 282.543107 -273.812866) (xy 282.5786 -273.846958) (xy 282.608165 -273.886302) (xy 282.631036 -273.929879)
			(xy 282.64662 -273.97656) (xy 282.654515 -274.025137) (xy 282.65501 -274.049744) (xy 283.944072 -274.049744)
			(xy 283.948032 -274.00069) (xy 283.959809 -273.952906) (xy 283.9791 -273.90763) (xy 284.005403 -273.866034)
			(xy 284.038038 -273.829197) (xy 284.076159 -273.798072) (xy 284.11878 -273.773465) (xy 284.164796 -273.756013)
			(xy 284.213015 -273.746169) (xy 284.26219 -273.744188) (xy 284.311045 -273.75012) (xy 284.358316 -273.763812)
			(xy 284.402778 -273.78491) (xy 284.443281 -273.812866) (xy 284.478774 -273.846958) (xy 284.508339 -273.886302)
			(xy 284.53121 -273.929879) (xy 284.546794 -273.97656) (xy 284.554689 -274.025137) (xy 284.555184 -274.049744)
			(xy 285.843992 -274.049744) (xy 285.847952 -274.00069) (xy 285.859729 -273.952906) (xy 285.87902 -273.90763)
			(xy 285.905323 -273.866034) (xy 285.937958 -273.829197) (xy 285.976079 -273.798072) (xy 286.0187 -273.773465)
			(xy 286.064716 -273.756013) (xy 286.112935 -273.746169) (xy 286.16211 -273.744188) (xy 286.210965 -273.75012)
			(xy 286.258236 -273.763812) (xy 286.302698 -273.78491) (xy 286.343201 -273.812866) (xy 286.378694 -273.846958)
			(xy 286.408259 -273.886302) (xy 286.43113 -273.929879) (xy 286.446714 -273.97656) (xy 286.454609 -274.025137)
			(xy 286.455104 -274.049744) (xy 287.743912 -274.049744) (xy 287.747872 -274.00069) (xy 287.759649 -273.952906)
			(xy 287.77894 -273.90763) (xy 287.805243 -273.866034) (xy 287.837878 -273.829197) (xy 287.875999 -273.798072)
			(xy 287.91862 -273.773465) (xy 287.964636 -273.756013) (xy 288.012855 -273.746169) (xy 288.06203 -273.744188)
			(xy 288.110885 -273.75012) (xy 288.158156 -273.763812) (xy 288.202618 -273.78491) (xy 288.243121 -273.812866)
			(xy 288.278614 -273.846958) (xy 288.308179 -273.886302) (xy 288.33105 -273.929879) (xy 288.346634 -273.97656)
			(xy 288.354529 -274.025137) (xy 288.355024 -274.049744) (xy 289.644086 -274.049744) (xy 289.648046 -274.00069)
			(xy 289.659823 -273.952906) (xy 289.679114 -273.90763) (xy 289.705417 -273.866034) (xy 289.738052 -273.829197)
			(xy 289.776173 -273.798072) (xy 289.818794 -273.773465) (xy 289.86481 -273.756013) (xy 289.913029 -273.746169)
			(xy 289.962204 -273.744188) (xy 290.011059 -273.75012) (xy 290.05833 -273.763812) (xy 290.102792 -273.78491)
			(xy 290.143295 -273.812866) (xy 290.178788 -273.846958) (xy 290.208353 -273.886302) (xy 290.231224 -273.929879)
			(xy 290.246808 -273.97656) (xy 290.254703 -274.025137) (xy 290.255198 -274.049744) (xy 290.254703 -274.074351)
			(xy 290.246808 -274.122928) (xy 290.231224 -274.169609) (xy 290.208353 -274.213186) (xy 290.178788 -274.25253)
			(xy 290.143295 -274.286622) (xy 290.102792 -274.314578) (xy 290.05833 -274.335676) (xy 290.011059 -274.349368)
			(xy 289.962204 -274.3553) (xy 289.913029 -274.353319) (xy 289.86481 -274.343475) (xy 289.818794 -274.326023)
			(xy 289.776173 -274.301416) (xy 289.738052 -274.270291) (xy 289.705417 -274.233454) (xy 289.679114 -274.191858)
			(xy 289.659823 -274.146582) (xy 289.648046 -274.098798) (xy 289.644086 -274.049744) (xy 288.355024 -274.049744)
			(xy 288.354529 -274.074351) (xy 288.346634 -274.122928) (xy 288.33105 -274.169609) (xy 288.308179 -274.213186)
			(xy 288.278614 -274.25253) (xy 288.243121 -274.286622) (xy 288.202618 -274.314578) (xy 288.158156 -274.335676)
			(xy 288.110885 -274.349368) (xy 288.06203 -274.3553) (xy 288.012855 -274.353319) (xy 287.964636 -274.343475)
			(xy 287.91862 -274.326023) (xy 287.875999 -274.301416) (xy 287.837878 -274.270291) (xy 287.805243 -274.233454)
			(xy 287.77894 -274.191858) (xy 287.759649 -274.146582) (xy 287.747872 -274.098798) (xy 287.743912 -274.049744)
			(xy 286.455104 -274.049744) (xy 286.454609 -274.074351) (xy 286.446714 -274.122928) (xy 286.43113 -274.169609)
			(xy 286.408259 -274.213186) (xy 286.378694 -274.25253) (xy 286.343201 -274.286622) (xy 286.302698 -274.314578)
			(xy 286.258236 -274.335676) (xy 286.210965 -274.349368) (xy 286.16211 -274.3553) (xy 286.112935 -274.353319)
			(xy 286.064716 -274.343475) (xy 286.0187 -274.326023) (xy 285.976079 -274.301416) (xy 285.937958 -274.270291)
			(xy 285.905323 -274.233454) (xy 285.87902 -274.191858) (xy 285.859729 -274.146582) (xy 285.847952 -274.098798)
			(xy 285.843992 -274.049744) (xy 284.555184 -274.049744) (xy 284.554689 -274.074351) (xy 284.546794 -274.122928)
			(xy 284.53121 -274.169609) (xy 284.508339 -274.213186) (xy 284.478774 -274.25253) (xy 284.443281 -274.286622)
			(xy 284.402778 -274.314578) (xy 284.358316 -274.335676) (xy 284.311045 -274.349368) (xy 284.26219 -274.3553)
			(xy 284.213015 -274.353319) (xy 284.164796 -274.343475) (xy 284.11878 -274.326023) (xy 284.076159 -274.301416)
			(xy 284.038038 -274.270291) (xy 284.005403 -274.233454) (xy 283.9791 -274.191858) (xy 283.959809 -274.146582)
			(xy 283.948032 -274.098798) (xy 283.944072 -274.049744) (xy 282.65501 -274.049744) (xy 282.654515 -274.074351)
			(xy 282.64662 -274.122928) (xy 282.631036 -274.169609) (xy 282.608165 -274.213186) (xy 282.5786 -274.25253)
			(xy 282.543107 -274.286622) (xy 282.502604 -274.314578) (xy 282.458142 -274.335676) (xy 282.410871 -274.349368)
			(xy 282.362016 -274.3553) (xy 282.312841 -274.353319) (xy 282.264622 -274.343475) (xy 282.218606 -274.326023)
			(xy 282.175985 -274.301416) (xy 282.137864 -274.270291) (xy 282.105229 -274.233454) (xy 282.078926 -274.191858)
			(xy 282.059635 -274.146582) (xy 282.047858 -274.098798) (xy 282.043898 -274.049744) (xy 280.75509 -274.049744)
			(xy 280.754595 -274.074351) (xy 280.7467 -274.122928) (xy 280.731116 -274.169609) (xy 280.708245 -274.213186)
			(xy 280.67868 -274.25253) (xy 280.643187 -274.286622) (xy 280.602684 -274.314578) (xy 280.558222 -274.335676)
			(xy 280.510951 -274.349368) (xy 280.462096 -274.3553) (xy 280.412921 -274.353319) (xy 280.364702 -274.343475)
			(xy 280.318686 -274.326023) (xy 280.276065 -274.301416) (xy 280.237944 -274.270291) (xy 280.205309 -274.233454)
			(xy 280.179006 -274.191858) (xy 280.159715 -274.146582) (xy 280.147938 -274.098798) (xy 280.143978 -274.049744)
			(xy 278.85517 -274.049744) (xy 278.854675 -274.074351) (xy 278.84678 -274.122928) (xy 278.831196 -274.169609)
			(xy 278.808325 -274.213186) (xy 278.77876 -274.25253) (xy 278.743267 -274.286622) (xy 278.702764 -274.314578)
			(xy 278.658302 -274.335676) (xy 278.611031 -274.349368) (xy 278.562176 -274.3553) (xy 278.513001 -274.353319)
			(xy 278.464782 -274.343475) (xy 278.418766 -274.326023) (xy 278.376145 -274.301416) (xy 278.338024 -274.270291)
			(xy 278.305389 -274.233454) (xy 278.279086 -274.191858) (xy 278.259795 -274.146582) (xy 278.248018 -274.098798)
			(xy 278.244058 -274.049744) (xy 276.954996 -274.049744) (xy 276.954501 -274.074351) (xy 276.946606 -274.122928)
			(xy 276.931022 -274.169609) (xy 276.908151 -274.213186) (xy 276.878586 -274.25253) (xy 276.843093 -274.286622)
			(xy 276.80259 -274.314578) (xy 276.758128 -274.335676) (xy 276.710857 -274.349368) (xy 276.662002 -274.3553)
			(xy 276.612827 -274.353319) (xy 276.564608 -274.343475) (xy 276.518592 -274.326023) (xy 276.475971 -274.301416)
			(xy 276.43785 -274.270291) (xy 276.405215 -274.233454) (xy 276.378912 -274.191858) (xy 276.359621 -274.146582)
			(xy 276.347844 -274.098798) (xy 276.343884 -274.049744) (xy 267.998194 -274.049744) (xy 267.52296 -274.524978)
			(xy 271.119104 -274.524978) (xy 271.123064 -274.475924) (xy 271.134841 -274.42814) (xy 271.154132 -274.382864)
			(xy 271.180435 -274.341268) (xy 271.21307 -274.304431) (xy 271.251191 -274.273306) (xy 271.293812 -274.248699)
			(xy 271.339828 -274.231247) (xy 271.388047 -274.221403) (xy 271.437222 -274.219422) (xy 271.486077 -274.225354)
			(xy 271.533348 -274.239046) (xy 271.57781 -274.260144) (xy 271.618313 -274.2881) (xy 271.653806 -274.322192)
			(xy 271.683371 -274.361536) (xy 271.706242 -274.405113) (xy 271.721826 -274.451794) (xy 271.729721 -274.500371)
			(xy 271.730216 -274.524978) (xy 273.019024 -274.524978) (xy 273.022984 -274.475924) (xy 273.034761 -274.42814)
			(xy 273.054052 -274.382864) (xy 273.080355 -274.341268) (xy 273.11299 -274.304431) (xy 273.151111 -274.273306)
			(xy 273.193732 -274.248699) (xy 273.239748 -274.231247) (xy 273.287967 -274.221403) (xy 273.337142 -274.219422)
			(xy 273.385997 -274.225354) (xy 273.433268 -274.239046) (xy 273.47773 -274.260144) (xy 273.518233 -274.2881)
			(xy 273.553726 -274.322192) (xy 273.583291 -274.361536) (xy 273.606162 -274.405113) (xy 273.621746 -274.451794)
			(xy 273.629641 -274.500371) (xy 273.630136 -274.524978) (xy 274.918944 -274.524978) (xy 274.922904 -274.475924)
			(xy 274.934681 -274.42814) (xy 274.953972 -274.382864) (xy 274.980275 -274.341268) (xy 275.01291 -274.304431)
			(xy 275.051031 -274.273306) (xy 275.093652 -274.248699) (xy 275.139668 -274.231247) (xy 275.187887 -274.221403)
			(xy 275.237062 -274.219422) (xy 275.285917 -274.225354) (xy 275.333188 -274.239046) (xy 275.37765 -274.260144)
			(xy 275.418153 -274.2881) (xy 275.453646 -274.322192) (xy 275.483211 -274.361536) (xy 275.506082 -274.405113)
			(xy 275.521666 -274.451794) (xy 275.529561 -274.500371) (xy 275.530056 -274.524978) (xy 275.529561 -274.549585)
			(xy 275.521666 -274.598162) (xy 275.506082 -274.644843) (xy 275.483211 -274.68842) (xy 275.453646 -274.727764)
			(xy 275.418153 -274.761856) (xy 275.37765 -274.789812) (xy 275.333188 -274.81091) (xy 275.285917 -274.824602)
			(xy 275.237062 -274.830534) (xy 275.187887 -274.828553) (xy 275.139668 -274.818709) (xy 275.093652 -274.801257)
			(xy 275.051031 -274.77665) (xy 275.01291 -274.745525) (xy 274.980275 -274.708688) (xy 274.953972 -274.667092)
			(xy 274.934681 -274.621816) (xy 274.922904 -274.574032) (xy 274.918944 -274.524978) (xy 273.630136 -274.524978)
			(xy 273.629641 -274.549585) (xy 273.621746 -274.598162) (xy 273.606162 -274.644843) (xy 273.583291 -274.68842)
			(xy 273.553726 -274.727764) (xy 273.518233 -274.761856) (xy 273.47773 -274.789812) (xy 273.433268 -274.81091)
			(xy 273.385997 -274.824602) (xy 273.337142 -274.830534) (xy 273.287967 -274.828553) (xy 273.239748 -274.818709)
			(xy 273.193732 -274.801257) (xy 273.151111 -274.77665) (xy 273.11299 -274.745525) (xy 273.080355 -274.708688)
			(xy 273.054052 -274.667092) (xy 273.034761 -274.621816) (xy 273.022984 -274.574032) (xy 273.019024 -274.524978)
			(xy 271.730216 -274.524978) (xy 271.729721 -274.549585) (xy 271.721826 -274.598162) (xy 271.706242 -274.644843)
			(xy 271.683371 -274.68842) (xy 271.653806 -274.727764) (xy 271.618313 -274.761856) (xy 271.57781 -274.789812)
			(xy 271.533348 -274.81091) (xy 271.486077 -274.824602) (xy 271.437222 -274.830534) (xy 271.388047 -274.828553)
			(xy 271.339828 -274.818709) (xy 271.293812 -274.801257) (xy 271.251191 -274.77665) (xy 271.21307 -274.745525)
			(xy 271.180435 -274.708688) (xy 271.154132 -274.667092) (xy 271.134841 -274.621816) (xy 271.123064 -274.574032)
			(xy 271.119104 -274.524978) (xy 267.52296 -274.524978) (xy 267.04798 -274.999958) (xy 277.294098 -274.999958)
			(xy 277.298058 -274.950904) (xy 277.309835 -274.90312) (xy 277.329126 -274.857844) (xy 277.355429 -274.816248)
			(xy 277.388064 -274.779411) (xy 277.426185 -274.748286) (xy 277.468806 -274.723679) (xy 277.514822 -274.706227)
			(xy 277.563041 -274.696383) (xy 277.612216 -274.694402) (xy 277.661071 -274.700334) (xy 277.708342 -274.714026)
			(xy 277.752804 -274.735124) (xy 277.793307 -274.76308) (xy 277.8288 -274.797172) (xy 277.858365 -274.836516)
			(xy 277.881236 -274.880093) (xy 277.89682 -274.926774) (xy 277.904715 -274.975351) (xy 277.90521 -274.999958)
			(xy 279.194018 -274.999958) (xy 279.197978 -274.950904) (xy 279.209755 -274.90312) (xy 279.229046 -274.857844)
			(xy 279.255349 -274.816248) (xy 279.287984 -274.779411) (xy 279.326105 -274.748286) (xy 279.368726 -274.723679)
			(xy 279.414742 -274.706227) (xy 279.462961 -274.696383) (xy 279.512136 -274.694402) (xy 279.560991 -274.700334)
			(xy 279.608262 -274.714026) (xy 279.652724 -274.735124) (xy 279.693227 -274.76308) (xy 279.72872 -274.797172)
			(xy 279.758285 -274.836516) (xy 279.781156 -274.880093) (xy 279.79674 -274.926774) (xy 279.804635 -274.975351)
			(xy 279.80513 -274.999958) (xy 281.093938 -274.999958) (xy 281.097898 -274.950904) (xy 281.109675 -274.90312)
			(xy 281.128966 -274.857844) (xy 281.155269 -274.816248) (xy 281.187904 -274.779411) (xy 281.226025 -274.748286)
			(xy 281.268646 -274.723679) (xy 281.314662 -274.706227) (xy 281.362881 -274.696383) (xy 281.412056 -274.694402)
			(xy 281.460911 -274.700334) (xy 281.508182 -274.714026) (xy 281.552644 -274.735124) (xy 281.593147 -274.76308)
			(xy 281.62864 -274.797172) (xy 281.658205 -274.836516) (xy 281.681076 -274.880093) (xy 281.69666 -274.926774)
			(xy 281.704555 -274.975351) (xy 281.70505 -274.999958) (xy 282.994112 -274.999958) (xy 282.998072 -274.950904)
			(xy 283.009849 -274.90312) (xy 283.02914 -274.857844) (xy 283.055443 -274.816248) (xy 283.088078 -274.779411)
			(xy 283.126199 -274.748286) (xy 283.16882 -274.723679) (xy 283.214836 -274.706227) (xy 283.263055 -274.696383)
			(xy 283.31223 -274.694402) (xy 283.361085 -274.700334) (xy 283.408356 -274.714026) (xy 283.452818 -274.735124)
			(xy 283.493321 -274.76308) (xy 283.528814 -274.797172) (xy 283.558379 -274.836516) (xy 283.58125 -274.880093)
			(xy 283.596834 -274.926774) (xy 283.604729 -274.975351) (xy 283.605224 -274.999958) (xy 284.894032 -274.999958)
			(xy 284.897992 -274.950904) (xy 284.909769 -274.90312) (xy 284.92906 -274.857844) (xy 284.955363 -274.816248)
			(xy 284.987998 -274.779411) (xy 285.026119 -274.748286) (xy 285.06874 -274.723679) (xy 285.114756 -274.706227)
			(xy 285.162975 -274.696383) (xy 285.21215 -274.694402) (xy 285.261005 -274.700334) (xy 285.308276 -274.714026)
			(xy 285.352738 -274.735124) (xy 285.393241 -274.76308) (xy 285.428734 -274.797172) (xy 285.458299 -274.836516)
			(xy 285.48117 -274.880093) (xy 285.496754 -274.926774) (xy 285.504649 -274.975351) (xy 285.505144 -274.999958)
			(xy 286.793952 -274.999958) (xy 286.797912 -274.950904) (xy 286.809689 -274.90312) (xy 286.82898 -274.857844)
			(xy 286.855283 -274.816248) (xy 286.887918 -274.779411) (xy 286.926039 -274.748286) (xy 286.96866 -274.723679)
			(xy 287.014676 -274.706227) (xy 287.062895 -274.696383) (xy 287.11207 -274.694402) (xy 287.160925 -274.700334)
			(xy 287.208196 -274.714026) (xy 287.252658 -274.735124) (xy 287.293161 -274.76308) (xy 287.328654 -274.797172)
			(xy 287.358219 -274.836516) (xy 287.38109 -274.880093) (xy 287.396674 -274.926774) (xy 287.404569 -274.975351)
			(xy 287.405064 -274.999958) (xy 288.694126 -274.999958) (xy 288.698086 -274.950904) (xy 288.709863 -274.90312)
			(xy 288.729154 -274.857844) (xy 288.755457 -274.816248) (xy 288.788092 -274.779411) (xy 288.826213 -274.748286)
			(xy 288.868834 -274.723679) (xy 288.91485 -274.706227) (xy 288.963069 -274.696383) (xy 289.012244 -274.694402)
			(xy 289.061099 -274.700334) (xy 289.10837 -274.714026) (xy 289.152832 -274.735124) (xy 289.193335 -274.76308)
			(xy 289.228828 -274.797172) (xy 289.258393 -274.836516) (xy 289.281264 -274.880093) (xy 289.296848 -274.926774)
			(xy 289.304743 -274.975351) (xy 289.305238 -274.999958) (xy 289.304743 -275.024565) (xy 289.296848 -275.073142)
			(xy 289.281264 -275.119823) (xy 289.258393 -275.1634) (xy 289.228828 -275.202744) (xy 289.193335 -275.236836)
			(xy 289.152832 -275.264792) (xy 289.10837 -275.28589) (xy 289.061099 -275.299582) (xy 289.012244 -275.305514)
			(xy 288.963069 -275.303533) (xy 288.91485 -275.293689) (xy 288.868834 -275.276237) (xy 288.826213 -275.25163)
			(xy 288.788092 -275.220505) (xy 288.755457 -275.183668) (xy 288.729154 -275.142072) (xy 288.709863 -275.096796)
			(xy 288.698086 -275.049012) (xy 288.694126 -274.999958) (xy 287.405064 -274.999958) (xy 287.404569 -275.024565)
			(xy 287.396674 -275.073142) (xy 287.38109 -275.119823) (xy 287.358219 -275.1634) (xy 287.328654 -275.202744)
			(xy 287.293161 -275.236836) (xy 287.252658 -275.264792) (xy 287.208196 -275.28589) (xy 287.160925 -275.299582)
			(xy 287.11207 -275.305514) (xy 287.062895 -275.303533) (xy 287.014676 -275.293689) (xy 286.96866 -275.276237)
			(xy 286.926039 -275.25163) (xy 286.887918 -275.220505) (xy 286.855283 -275.183668) (xy 286.82898 -275.142072)
			(xy 286.809689 -275.096796) (xy 286.797912 -275.049012) (xy 286.793952 -274.999958) (xy 285.505144 -274.999958)
			(xy 285.504649 -275.024565) (xy 285.496754 -275.073142) (xy 285.48117 -275.119823) (xy 285.458299 -275.1634)
			(xy 285.428734 -275.202744) (xy 285.393241 -275.236836) (xy 285.352738 -275.264792) (xy 285.308276 -275.28589)
			(xy 285.261005 -275.299582) (xy 285.21215 -275.305514) (xy 285.162975 -275.303533) (xy 285.114756 -275.293689)
			(xy 285.06874 -275.276237) (xy 285.026119 -275.25163) (xy 284.987998 -275.220505) (xy 284.955363 -275.183668)
			(xy 284.92906 -275.142072) (xy 284.909769 -275.096796) (xy 284.897992 -275.049012) (xy 284.894032 -274.999958)
			(xy 283.605224 -274.999958) (xy 283.604729 -275.024565) (xy 283.596834 -275.073142) (xy 283.58125 -275.119823)
			(xy 283.558379 -275.1634) (xy 283.528814 -275.202744) (xy 283.493321 -275.236836) (xy 283.452818 -275.264792)
			(xy 283.408356 -275.28589) (xy 283.361085 -275.299582) (xy 283.31223 -275.305514) (xy 283.263055 -275.303533)
			(xy 283.214836 -275.293689) (xy 283.16882 -275.276237) (xy 283.126199 -275.25163) (xy 283.088078 -275.220505)
			(xy 283.055443 -275.183668) (xy 283.02914 -275.142072) (xy 283.009849 -275.096796) (xy 282.998072 -275.049012)
			(xy 282.994112 -274.999958) (xy 281.70505 -274.999958) (xy 281.704555 -275.024565) (xy 281.69666 -275.073142)
			(xy 281.681076 -275.119823) (xy 281.658205 -275.1634) (xy 281.62864 -275.202744) (xy 281.593147 -275.236836)
			(xy 281.552644 -275.264792) (xy 281.508182 -275.28589) (xy 281.460911 -275.299582) (xy 281.412056 -275.305514)
			(xy 281.362881 -275.303533) (xy 281.314662 -275.293689) (xy 281.268646 -275.276237) (xy 281.226025 -275.25163)
			(xy 281.187904 -275.220505) (xy 281.155269 -275.183668) (xy 281.128966 -275.142072) (xy 281.109675 -275.096796)
			(xy 281.097898 -275.049012) (xy 281.093938 -274.999958) (xy 279.80513 -274.999958) (xy 279.804635 -275.024565)
			(xy 279.79674 -275.073142) (xy 279.781156 -275.119823) (xy 279.758285 -275.1634) (xy 279.72872 -275.202744)
			(xy 279.693227 -275.236836) (xy 279.652724 -275.264792) (xy 279.608262 -275.28589) (xy 279.560991 -275.299582)
			(xy 279.512136 -275.305514) (xy 279.462961 -275.303533) (xy 279.414742 -275.293689) (xy 279.368726 -275.276237)
			(xy 279.326105 -275.25163) (xy 279.287984 -275.220505) (xy 279.255349 -275.183668) (xy 279.229046 -275.142072)
			(xy 279.209755 -275.096796) (xy 279.197978 -275.049012) (xy 279.194018 -274.999958) (xy 277.90521 -274.999958)
			(xy 277.904715 -275.024565) (xy 277.89682 -275.073142) (xy 277.881236 -275.119823) (xy 277.858365 -275.1634)
			(xy 277.8288 -275.202744) (xy 277.793307 -275.236836) (xy 277.752804 -275.264792) (xy 277.708342 -275.28589)
			(xy 277.661071 -275.299582) (xy 277.612216 -275.305514) (xy 277.563041 -275.303533) (xy 277.514822 -275.293689)
			(xy 277.468806 -275.276237) (xy 277.426185 -275.25163) (xy 277.388064 -275.220505) (xy 277.355429 -275.183668)
			(xy 277.329126 -275.142072) (xy 277.309835 -275.096796) (xy 277.298058 -275.049012) (xy 277.294098 -274.999958)
			(xy 267.04798 -274.999958) (xy 266.573 -275.474938) (xy 271.119104 -275.474938) (xy 271.123064 -275.425884)
			(xy 271.134841 -275.3781) (xy 271.154132 -275.332824) (xy 271.180435 -275.291228) (xy 271.21307 -275.254391)
			(xy 271.251191 -275.223266) (xy 271.293812 -275.198659) (xy 271.339828 -275.181207) (xy 271.388047 -275.171363)
			(xy 271.437222 -275.169382) (xy 271.486077 -275.175314) (xy 271.533348 -275.189006) (xy 271.57781 -275.210104)
			(xy 271.618313 -275.23806) (xy 271.653806 -275.272152) (xy 271.683371 -275.311496) (xy 271.706242 -275.355073)
			(xy 271.721826 -275.401754) (xy 271.729721 -275.450331) (xy 271.730216 -275.474938) (xy 273.019024 -275.474938)
			(xy 273.022984 -275.425884) (xy 273.034761 -275.3781) (xy 273.054052 -275.332824) (xy 273.080355 -275.291228)
			(xy 273.11299 -275.254391) (xy 273.151111 -275.223266) (xy 273.193732 -275.198659) (xy 273.239748 -275.181207)
			(xy 273.287967 -275.171363) (xy 273.337142 -275.169382) (xy 273.385997 -275.175314) (xy 273.433268 -275.189006)
			(xy 273.47773 -275.210104) (xy 273.518233 -275.23806) (xy 273.553726 -275.272152) (xy 273.583291 -275.311496)
			(xy 273.606162 -275.355073) (xy 273.621746 -275.401754) (xy 273.629641 -275.450331) (xy 273.630136 -275.474938)
			(xy 274.918944 -275.474938) (xy 274.922904 -275.425884) (xy 274.934681 -275.3781) (xy 274.953972 -275.332824)
			(xy 274.980275 -275.291228) (xy 275.01291 -275.254391) (xy 275.051031 -275.223266) (xy 275.093652 -275.198659)
			(xy 275.139668 -275.181207) (xy 275.187887 -275.171363) (xy 275.237062 -275.169382) (xy 275.285917 -275.175314)
			(xy 275.333188 -275.189006) (xy 275.37765 -275.210104) (xy 275.418153 -275.23806) (xy 275.453646 -275.272152)
			(xy 275.483211 -275.311496) (xy 275.506082 -275.355073) (xy 275.521666 -275.401754) (xy 275.529561 -275.450331)
			(xy 275.530056 -275.474938) (xy 275.529561 -275.499545) (xy 275.521666 -275.548122) (xy 275.506082 -275.594803)
			(xy 275.483211 -275.63838) (xy 275.453646 -275.677724) (xy 275.418153 -275.711816) (xy 275.37765 -275.739772)
			(xy 275.333188 -275.76087) (xy 275.285917 -275.774562) (xy 275.237062 -275.780494) (xy 275.187887 -275.778513)
			(xy 275.139668 -275.768669) (xy 275.093652 -275.751217) (xy 275.051031 -275.72661) (xy 275.01291 -275.695485)
			(xy 274.980275 -275.658648) (xy 274.953972 -275.617052) (xy 274.934681 -275.571776) (xy 274.922904 -275.523992)
			(xy 274.918944 -275.474938) (xy 273.630136 -275.474938) (xy 273.629641 -275.499545) (xy 273.621746 -275.548122)
			(xy 273.606162 -275.594803) (xy 273.583291 -275.63838) (xy 273.553726 -275.677724) (xy 273.518233 -275.711816)
			(xy 273.47773 -275.739772) (xy 273.433268 -275.76087) (xy 273.385997 -275.774562) (xy 273.337142 -275.780494)
			(xy 273.287967 -275.778513) (xy 273.239748 -275.768669) (xy 273.193732 -275.751217) (xy 273.151111 -275.72661)
			(xy 273.11299 -275.695485) (xy 273.080355 -275.658648) (xy 273.054052 -275.617052) (xy 273.034761 -275.571776)
			(xy 273.022984 -275.523992) (xy 273.019024 -275.474938) (xy 271.730216 -275.474938) (xy 271.729721 -275.499545)
			(xy 271.721826 -275.548122) (xy 271.706242 -275.594803) (xy 271.683371 -275.63838) (xy 271.653806 -275.677724)
			(xy 271.618313 -275.711816) (xy 271.57781 -275.739772) (xy 271.533348 -275.76087) (xy 271.486077 -275.774562)
			(xy 271.437222 -275.780494) (xy 271.388047 -275.778513) (xy 271.339828 -275.768669) (xy 271.293812 -275.751217)
			(xy 271.251191 -275.72661) (xy 271.21307 -275.695485) (xy 271.180435 -275.658648) (xy 271.154132 -275.617052)
			(xy 271.134841 -275.571776) (xy 271.123064 -275.523992) (xy 271.119104 -275.474938) (xy 266.573 -275.474938)
			(xy 266.09802 -275.949918) (xy 277.294098 -275.949918) (xy 277.298058 -275.900864) (xy 277.309835 -275.85308)
			(xy 277.329126 -275.807804) (xy 277.355429 -275.766208) (xy 277.388064 -275.729371) (xy 277.426185 -275.698246)
			(xy 277.468806 -275.673639) (xy 277.514822 -275.656187) (xy 277.563041 -275.646343) (xy 277.612216 -275.644362)
			(xy 277.661071 -275.650294) (xy 277.708342 -275.663986) (xy 277.752804 -275.685084) (xy 277.793307 -275.71304)
			(xy 277.8288 -275.747132) (xy 277.858365 -275.786476) (xy 277.881236 -275.830053) (xy 277.89682 -275.876734)
			(xy 277.904715 -275.925311) (xy 277.90521 -275.949918) (xy 279.194018 -275.949918) (xy 279.197978 -275.900864)
			(xy 279.209755 -275.85308) (xy 279.229046 -275.807804) (xy 279.255349 -275.766208) (xy 279.287984 -275.729371)
			(xy 279.326105 -275.698246) (xy 279.368726 -275.673639) (xy 279.414742 -275.656187) (xy 279.462961 -275.646343)
			(xy 279.512136 -275.644362) (xy 279.560991 -275.650294) (xy 279.608262 -275.663986) (xy 279.652724 -275.685084)
			(xy 279.693227 -275.71304) (xy 279.72872 -275.747132) (xy 279.758285 -275.786476) (xy 279.781156 -275.830053)
			(xy 279.79674 -275.876734) (xy 279.804635 -275.925311) (xy 279.80513 -275.949918) (xy 281.093938 -275.949918)
			(xy 281.097898 -275.900864) (xy 281.109675 -275.85308) (xy 281.128966 -275.807804) (xy 281.155269 -275.766208)
			(xy 281.187904 -275.729371) (xy 281.226025 -275.698246) (xy 281.268646 -275.673639) (xy 281.314662 -275.656187)
			(xy 281.362881 -275.646343) (xy 281.412056 -275.644362) (xy 281.460911 -275.650294) (xy 281.508182 -275.663986)
			(xy 281.552644 -275.685084) (xy 281.593147 -275.71304) (xy 281.62864 -275.747132) (xy 281.658205 -275.786476)
			(xy 281.681076 -275.830053) (xy 281.69666 -275.876734) (xy 281.704555 -275.925311) (xy 281.70505 -275.949918)
			(xy 282.994112 -275.949918) (xy 282.998072 -275.900864) (xy 283.009849 -275.85308) (xy 283.02914 -275.807804)
			(xy 283.055443 -275.766208) (xy 283.088078 -275.729371) (xy 283.126199 -275.698246) (xy 283.16882 -275.673639)
			(xy 283.214836 -275.656187) (xy 283.263055 -275.646343) (xy 283.31223 -275.644362) (xy 283.361085 -275.650294)
			(xy 283.408356 -275.663986) (xy 283.452818 -275.685084) (xy 283.493321 -275.71304) (xy 283.528814 -275.747132)
			(xy 283.558379 -275.786476) (xy 283.58125 -275.830053) (xy 283.596834 -275.876734) (xy 283.604729 -275.925311)
			(xy 283.605224 -275.949918) (xy 284.894032 -275.949918) (xy 284.897992 -275.900864) (xy 284.909769 -275.85308)
			(xy 284.92906 -275.807804) (xy 284.955363 -275.766208) (xy 284.987998 -275.729371) (xy 285.026119 -275.698246)
			(xy 285.06874 -275.673639) (xy 285.114756 -275.656187) (xy 285.162975 -275.646343) (xy 285.21215 -275.644362)
			(xy 285.261005 -275.650294) (xy 285.308276 -275.663986) (xy 285.352738 -275.685084) (xy 285.393241 -275.71304)
			(xy 285.428734 -275.747132) (xy 285.458299 -275.786476) (xy 285.48117 -275.830053) (xy 285.496754 -275.876734)
			(xy 285.504649 -275.925311) (xy 285.505144 -275.949918) (xy 286.793952 -275.949918) (xy 286.797912 -275.900864)
			(xy 286.809689 -275.85308) (xy 286.82898 -275.807804) (xy 286.855283 -275.766208) (xy 286.887918 -275.729371)
			(xy 286.926039 -275.698246) (xy 286.96866 -275.673639) (xy 287.014676 -275.656187) (xy 287.062895 -275.646343)
			(xy 287.11207 -275.644362) (xy 287.160925 -275.650294) (xy 287.208196 -275.663986) (xy 287.252658 -275.685084)
			(xy 287.293161 -275.71304) (xy 287.328654 -275.747132) (xy 287.358219 -275.786476) (xy 287.38109 -275.830053)
			(xy 287.396674 -275.876734) (xy 287.404569 -275.925311) (xy 287.405064 -275.949918) (xy 288.694126 -275.949918)
			(xy 288.698086 -275.900864) (xy 288.709863 -275.85308) (xy 288.729154 -275.807804) (xy 288.755457 -275.766208)
			(xy 288.788092 -275.729371) (xy 288.826213 -275.698246) (xy 288.868834 -275.673639) (xy 288.91485 -275.656187)
			(xy 288.963069 -275.646343) (xy 289.012244 -275.644362) (xy 289.061099 -275.650294) (xy 289.10837 -275.663986)
			(xy 289.152832 -275.685084) (xy 289.193335 -275.71304) (xy 289.228828 -275.747132) (xy 289.258393 -275.786476)
			(xy 289.281264 -275.830053) (xy 289.296848 -275.876734) (xy 289.304743 -275.925311) (xy 289.305238 -275.949918)
			(xy 289.304743 -275.974525) (xy 289.296848 -276.023102) (xy 289.281264 -276.069783) (xy 289.258393 -276.11336)
			(xy 289.228828 -276.152704) (xy 289.193335 -276.186796) (xy 289.152832 -276.214752) (xy 289.10837 -276.23585)
			(xy 289.061099 -276.249542) (xy 289.012244 -276.255474) (xy 288.963069 -276.253493) (xy 288.91485 -276.243649)
			(xy 288.868834 -276.226197) (xy 288.826213 -276.20159) (xy 288.788092 -276.170465) (xy 288.755457 -276.133628)
			(xy 288.729154 -276.092032) (xy 288.709863 -276.046756) (xy 288.698086 -275.998972) (xy 288.694126 -275.949918)
			(xy 287.405064 -275.949918) (xy 287.404569 -275.974525) (xy 287.396674 -276.023102) (xy 287.38109 -276.069783)
			(xy 287.358219 -276.11336) (xy 287.328654 -276.152704) (xy 287.293161 -276.186796) (xy 287.252658 -276.214752)
			(xy 287.208196 -276.23585) (xy 287.160925 -276.249542) (xy 287.11207 -276.255474) (xy 287.062895 -276.253493)
			(xy 287.014676 -276.243649) (xy 286.96866 -276.226197) (xy 286.926039 -276.20159) (xy 286.887918 -276.170465)
			(xy 286.855283 -276.133628) (xy 286.82898 -276.092032) (xy 286.809689 -276.046756) (xy 286.797912 -275.998972)
			(xy 286.793952 -275.949918) (xy 285.505144 -275.949918) (xy 285.504649 -275.974525) (xy 285.496754 -276.023102)
			(xy 285.48117 -276.069783) (xy 285.458299 -276.11336) (xy 285.428734 -276.152704) (xy 285.393241 -276.186796)
			(xy 285.352738 -276.214752) (xy 285.308276 -276.23585) (xy 285.261005 -276.249542) (xy 285.21215 -276.255474)
			(xy 285.162975 -276.253493) (xy 285.114756 -276.243649) (xy 285.06874 -276.226197) (xy 285.026119 -276.20159)
			(xy 284.987998 -276.170465) (xy 284.955363 -276.133628) (xy 284.92906 -276.092032) (xy 284.909769 -276.046756)
			(xy 284.897992 -275.998972) (xy 284.894032 -275.949918) (xy 283.605224 -275.949918) (xy 283.604729 -275.974525)
			(xy 283.596834 -276.023102) (xy 283.58125 -276.069783) (xy 283.558379 -276.11336) (xy 283.528814 -276.152704)
			(xy 283.493321 -276.186796) (xy 283.452818 -276.214752) (xy 283.408356 -276.23585) (xy 283.361085 -276.249542)
			(xy 283.31223 -276.255474) (xy 283.263055 -276.253493) (xy 283.214836 -276.243649) (xy 283.16882 -276.226197)
			(xy 283.126199 -276.20159) (xy 283.088078 -276.170465) (xy 283.055443 -276.133628) (xy 283.02914 -276.092032)
			(xy 283.009849 -276.046756) (xy 282.998072 -275.998972) (xy 282.994112 -275.949918) (xy 281.70505 -275.949918)
			(xy 281.704555 -275.974525) (xy 281.69666 -276.023102) (xy 281.681076 -276.069783) (xy 281.658205 -276.11336)
			(xy 281.62864 -276.152704) (xy 281.593147 -276.186796) (xy 281.552644 -276.214752) (xy 281.508182 -276.23585)
			(xy 281.460911 -276.249542) (xy 281.412056 -276.255474) (xy 281.362881 -276.253493) (xy 281.314662 -276.243649)
			(xy 281.268646 -276.226197) (xy 281.226025 -276.20159) (xy 281.187904 -276.170465) (xy 281.155269 -276.133628)
			(xy 281.128966 -276.092032) (xy 281.109675 -276.046756) (xy 281.097898 -275.998972) (xy 281.093938 -275.949918)
			(xy 279.80513 -275.949918) (xy 279.804635 -275.974525) (xy 279.79674 -276.023102) (xy 279.781156 -276.069783)
			(xy 279.758285 -276.11336) (xy 279.72872 -276.152704) (xy 279.693227 -276.186796) (xy 279.652724 -276.214752)
			(xy 279.608262 -276.23585) (xy 279.560991 -276.249542) (xy 279.512136 -276.255474) (xy 279.462961 -276.253493)
			(xy 279.414742 -276.243649) (xy 279.368726 -276.226197) (xy 279.326105 -276.20159) (xy 279.287984 -276.170465)
			(xy 279.255349 -276.133628) (xy 279.229046 -276.092032) (xy 279.209755 -276.046756) (xy 279.197978 -275.998972)
			(xy 279.194018 -275.949918) (xy 277.90521 -275.949918) (xy 277.904715 -275.974525) (xy 277.89682 -276.023102)
			(xy 277.881236 -276.069783) (xy 277.858365 -276.11336) (xy 277.8288 -276.152704) (xy 277.793307 -276.186796)
			(xy 277.752804 -276.214752) (xy 277.708342 -276.23585) (xy 277.661071 -276.249542) (xy 277.612216 -276.255474)
			(xy 277.563041 -276.253493) (xy 277.514822 -276.243649) (xy 277.468806 -276.226197) (xy 277.426185 -276.20159)
			(xy 277.388064 -276.170465) (xy 277.355429 -276.133628) (xy 277.329126 -276.092032) (xy 277.309835 -276.046756)
			(xy 277.298058 -275.998972) (xy 277.294098 -275.949918) (xy 266.09802 -275.949918) (xy 263.503918 -278.54402)
			(xy 263.485149 -278.562055) (xy 263.443033 -278.59264) (xy 263.396657 -278.616271) (xy 263.347159 -278.632367)
			(xy 263.295754 -278.640534) (xy 263.26973 -278.641048) (xy 263.210802 -278.641048) (xy 263.205214 -278.645874)
			(xy 263.00303 -278.848058) (xy 262.99563 -278.854898) (xy 262.977031 -278.862614) (xy 262.966962 -278.863044)
			(xy 259.267452 -278.863044) (xy 259.257461 -278.863573) (xy 259.23902 -278.871278) (xy 259.231638 -278.87803)
			(xy 257.93065 -280.179018) (xy 257.923801 -280.186415) (xy 257.916065 -280.205014) (xy 257.915664 -280.215086)
			(xy 257.915664 -280.693114) (xy 263.537954 -280.693114) (xy 263.53852 -280.663733) (xy 263.547548 -280.605668)
			(xy 263.565376 -280.549675) (xy 263.591583 -280.49708) (xy 263.625547 -280.449128) (xy 263.666466 -280.406954)
			(xy 263.689592 -280.388822) (xy 263.698524 -280.38135) (xy 263.708977 -280.360569) (xy 263.709658 -280.348944)
			(xy 263.710928 -280.256996) (xy 263.701022 -280.235914) (xy 263.691878 -280.228548) (xy 263.670018 -280.210356)
			(xy 263.63148 -280.168533) (xy 263.599575 -280.121455) (xy 263.57501 -280.070163) (xy 263.558329 -280.015793)
			(xy 263.549902 -279.95955) (xy 263.549384 -279.931114) (xy 263.549845 -279.902465) (xy 263.558404 -279.84581)
			(xy 263.575347 -279.791075) (xy 263.600292 -279.739492) (xy 263.632676 -279.692224) (xy 263.671771 -279.650336)
			(xy 263.716696 -279.614772) (xy 263.766437 -279.586332) (xy 263.79297 -279.575514) (xy 263.793224 -279.575514)
			(xy 263.801605 -279.571793) (xy 263.815175 -279.559475) (xy 263.823543 -279.543171) (xy 263.824974 -279.534112)
			(xy 263.83742 -279.431242) (xy 263.825736 -279.405334) (xy 263.814306 -279.39746) (xy 263.793069 -279.38209)
			(xy 263.754616 -279.346457) (xy 263.7214 -279.305899) (xy 263.694043 -279.261178) (xy 263.673062 -279.213136)
			(xy 263.65885 -279.162675) (xy 263.651674 -279.110744) (xy 263.651238 -279.084532) (xy 263.651724 -279.057281)
			(xy 263.65948 -279.003333) (xy 263.674835 -278.951038) (xy 263.697477 -278.901461) (xy 263.726943 -278.855611)
			(xy 263.762634 -278.81442) (xy 263.803825 -278.778729) (xy 263.849675 -278.749263) (xy 263.899252 -278.726621)
			(xy 263.951547 -278.711266) (xy 264.005495 -278.70351) (xy 264.059997 -278.70351) (xy 264.113945 -278.711266)
			(xy 264.16624 -278.726621) (xy 264.215817 -278.749263) (xy 264.261667 -278.778729) (xy 264.302858 -278.81442)
			(xy 264.338549 -278.855611) (xy 264.368015 -278.901461) (xy 264.390657 -278.951038) (xy 264.406012 -279.003333)
			(xy 264.413768 -279.057281) (xy 264.414254 -279.084532) (xy 264.413723 -279.113178) (xy 264.405172 -279.169829)
			(xy 264.388239 -279.224561) (xy 264.363304 -279.276142) (xy 264.330929 -279.32341) (xy 264.291844 -279.3653)
			(xy 264.246929 -279.400867) (xy 264.197197 -279.429311) (xy 264.170668 -279.440132) (xy 264.170414 -279.440132)
			(xy 264.162025 -279.44384) (xy 264.148453 -279.456161) (xy 264.14009 -279.472472) (xy 264.138664 -279.481534)
			(xy 264.126218 -279.584404) (xy 264.137902 -279.610312) (xy 264.149332 -279.618186) (xy 264.170577 -279.633546)
			(xy 264.209032 -279.669179) (xy 264.24225 -279.709737) (xy 264.269607 -279.75446) (xy 264.290587 -279.802505)
			(xy 264.304796 -279.852968) (xy 264.311967 -279.904901) (xy 264.3124 -279.931114) (xy 264.311872 -279.960497)
			(xy 264.302839 -280.018564) (xy 264.285005 -280.074559) (xy 264.258791 -280.127154) (xy 264.224818 -280.175105)
			(xy 264.183891 -280.217276) (xy 264.160762 -280.235406) (xy 264.151826 -280.242875) (xy 264.141373 -280.263657)
			(xy 264.140696 -280.275284) (xy 264.139426 -280.367232) (xy 264.149332 -280.388314) (xy 264.158476 -280.39568)
			(xy 264.180292 -280.413923) (xy 264.218835 -280.455733) (xy 264.250747 -280.502801) (xy 264.275319 -280.554084)
			(xy 264.292009 -280.608445) (xy 264.300447 -280.664681) (xy 264.30097 -280.693114) (xy 264.934444 -280.693114)
			(xy 264.938515 -280.637492) (xy 264.950641 -280.583055) (xy 264.970564 -280.530964) (xy 264.99786 -280.482329)
			(xy 265.031946 -280.438186) (xy 265.072095 -280.399477) (xy 265.117453 -280.367026) (xy 265.167053 -280.341525)
			(xy 265.219837 -280.323518) (xy 265.27468 -280.313388) (xy 265.330414 -280.311351) (xy 265.385851 -280.317451)
			(xy 265.439808 -280.331557) (xy 265.491137 -280.353369) (xy 265.538743 -280.382423) (xy 265.581611 -280.418098)
			(xy 265.618828 -280.459635) (xy 265.649601 -280.506148) (xy 265.673273 -280.556645) (xy 265.689341 -280.610052)
			(xy 265.697461 -280.665228) (xy 265.69797 -280.693114) (xy 265.697461 -280.721) (xy 265.689341 -280.776176)
			(xy 265.673273 -280.829583) (xy 265.649601 -280.88008) (xy 265.618828 -280.926593) (xy 265.581611 -280.96813)
			(xy 265.538743 -281.003805) (xy 265.491137 -281.032859) (xy 265.439808 -281.054671) (xy 265.385851 -281.068777)
			(xy 265.330414 -281.074877) (xy 265.27468 -281.07284) (xy 265.219837 -281.06271) (xy 265.167053 -281.044703)
			(xy 265.117453 -281.019202) (xy 265.072095 -280.986751) (xy 265.031946 -280.948042) (xy 264.99786 -280.903899)
			(xy 264.970564 -280.855264) (xy 264.950641 -280.803173) (xy 264.938515 -280.748736) (xy 264.934444 -280.693114)
			(xy 264.30097 -280.693114) (xy 264.300484 -280.720365) (xy 264.292728 -280.774313) (xy 264.277373 -280.826608)
			(xy 264.254731 -280.876185) (xy 264.225265 -280.922035) (xy 264.189574 -280.963226) (xy 264.148383 -280.998917)
			(xy 264.102533 -281.028383) (xy 264.052956 -281.051025) (xy 264.000661 -281.06638) (xy 263.946713 -281.074136)
			(xy 263.892211 -281.074136) (xy 263.838263 -281.06638) (xy 263.785968 -281.051025) (xy 263.736391 -281.028383)
			(xy 263.690541 -280.998917) (xy 263.64935 -280.963226) (xy 263.613659 -280.922035) (xy 263.584193 -280.876185)
			(xy 263.561551 -280.826608) (xy 263.546196 -280.774313) (xy 263.53844 -280.720365) (xy 263.537954 -280.693114)
			(xy 257.915664 -280.693114) (xy 257.915664 -281.52598) (xy 257.916192 -281.536474) (xy 257.924597 -281.555709)
			(xy 257.939979 -281.569992) (xy 257.9497 -281.573986) (xy 258.040124 -281.605736) (xy 258.050156 -281.608698)
			(xy 258.070998 -281.607179) (xy 258.089531 -281.597524) (xy 258.096512 -281.589734) (xy 258.11473 -281.567977)
			(xy 258.156504 -281.529574) (xy 258.203506 -281.497782) (xy 258.254697 -281.4733) (xy 258.308949 -281.45667)
			(xy 258.365066 -281.448257) (xy 258.393438 -281.447748) (xy 258.420691 -281.448236) (xy 258.47464 -281.455998)
			(xy 258.526937 -281.471358) (xy 258.576515 -281.494004) (xy 258.622366 -281.523475) (xy 258.663556 -281.559171)
			(xy 258.699248 -281.600365) (xy 258.728714 -281.646219) (xy 258.751355 -281.695799) (xy 258.76671 -281.748097)
			(xy 258.774466 -281.802047) (xy 258.774466 -281.829256) (xy 259.496558 -281.829256) (xy 259.500629 -281.773634)
			(xy 259.512755 -281.719197) (xy 259.532678 -281.667106) (xy 259.559974 -281.618471) (xy 259.59406 -281.574328)
			(xy 259.634209 -281.535619) (xy 259.679567 -281.503168) (xy 259.729167 -281.477667) (xy 259.781951 -281.45966)
			(xy 259.836794 -281.44953) (xy 259.892528 -281.447493) (xy 259.947965 -281.453593) (xy 260.001922 -281.467699)
			(xy 260.053251 -281.489511) (xy 260.100857 -281.518565) (xy 260.143725 -281.55424) (xy 260.180942 -281.595777)
			(xy 260.211715 -281.64229) (xy 260.235387 -281.692787) (xy 260.251455 -281.746194) (xy 260.259575 -281.80137)
			(xy 260.260084 -281.829256) (xy 260.259575 -281.857142) (xy 260.251455 -281.912318) (xy 260.235387 -281.965725)
			(xy 260.211715 -282.016222) (xy 260.180942 -282.062735) (xy 260.143725 -282.104272) (xy 260.100857 -282.139947)
			(xy 260.053251 -282.169001) (xy 260.001922 -282.190813) (xy 259.947965 -282.204919) (xy 259.892528 -282.211019)
			(xy 259.836794 -282.208982) (xy 259.781951 -282.198852) (xy 259.729167 -282.180845) (xy 259.679567 -282.155344)
			(xy 259.634209 -282.122893) (xy 259.59406 -282.084184) (xy 259.559974 -282.040041) (xy 259.532678 -281.991406)
			(xy 259.512755 -281.939315) (xy 259.500629 -281.884878) (xy 259.496558 -281.829256) (xy 258.774466 -281.829256)
			(xy 258.774466 -281.856553) (xy 258.76671 -281.910503) (xy 258.751355 -281.962801) (xy 258.728714 -282.012381)
			(xy 258.699248 -282.058235) (xy 258.663556 -282.099429) (xy 258.622366 -282.135125) (xy 258.576515 -282.164596)
			(xy 258.526937 -282.187242) (xy 258.47464 -282.202602) (xy 258.420691 -282.210364) (xy 258.393438 -282.210764)
			(xy 258.365065 -282.210247) (xy 258.308944 -282.201846) (xy 258.254687 -282.185224) (xy 258.20349 -282.160748)
			(xy 258.156485 -282.128957) (xy 258.114707 -282.090554) (xy 258.096512 -282.068778) (xy 258.089553 -282.060952)
			(xy 258.071018 -282.051253) (xy 258.050152 -282.04976) (xy 258.040124 -282.052776) (xy 257.9497 -282.084526)
			(xy 257.939956 -282.088476) (xy 257.924562 -282.102766) (xy 257.91619 -282.122029) (xy 257.915664 -282.132532)
			(xy 257.915664 -283.012388) (xy 257.916149 -283.0224) (xy 257.923806 -283.040902) (xy 257.937958 -283.055067)
			(xy 257.956453 -283.062741) (xy 257.966464 -283.063188) (xy 257.977894 -283.063188) (xy 257.986244 -283.062934)
			(xy 258.002066 -283.057605) (xy 258.008882 -283.052774) (xy 258.015232 -283.047948) (xy 258.024122 -283.03474)
			(xy 258.026662 -283.026358) (xy 258.034665 -283.000158) (xy 258.05714 -282.950198) (xy 258.086528 -282.903965)
			(xy 258.122226 -282.862411) (xy 258.163501 -282.826389) (xy 258.209503 -282.796641) (xy 258.259286 -282.773777)
			(xy 258.311827 -282.758269) (xy 258.366047 -282.750434) (xy 258.420829 -282.750434) (xy 258.475049 -282.758269)
			(xy 258.52759 -282.773777) (xy 258.577373 -282.796641) (xy 258.623375 -282.826389) (xy 258.66465 -282.862411)
			(xy 258.700348 -282.903965) (xy 258.729736 -282.950198) (xy 258.752211 -283.000158) (xy 258.760214 -283.026358)
			(xy 258.760468 -283.026866) (xy 258.762967 -283.034539) (xy 258.772034 -283.047879) (xy 258.778248 -283.053028)
			(xy 258.784852 -283.057854) (xy 258.800346 -283.063188) (xy 259.45338 -283.063188) (xy 259.46173 -283.062937)
			(xy 259.477556 -283.057611) (xy 259.484368 -283.052774) (xy 259.490718 -283.047948) (xy 259.499608 -283.03474)
			(xy 259.502148 -283.026358) (xy 259.510151 -283.000158) (xy 259.532626 -282.950198) (xy 259.562014 -282.903965)
			(xy 259.597712 -282.862411) (xy 259.638987 -282.826389) (xy 259.684989 -282.796641) (xy 259.734772 -282.773777)
			(xy 259.787313 -282.758269) (xy 259.841533 -282.750434) (xy 259.896315 -282.750434) (xy 259.950535 -282.758269)
			(xy 260.003076 -282.773777) (xy 260.052859 -282.796641) (xy 260.098861 -282.826389) (xy 260.140136 -282.862411)
			(xy 260.175834 -282.903965) (xy 260.205222 -282.950198) (xy 260.227697 -283.000158) (xy 260.2357 -283.026358)
			(xy 260.2357 -283.026866) (xy 260.238295 -283.034643) (xy 260.247625 -283.048112) (xy 260.253988 -283.053282)
			(xy 260.260592 -283.058362) (xy 260.276086 -283.063442) (xy 260.59892 -283.063442) (xy 260.608988 -283.06387)
			(xy 260.627583 -283.071594) (xy 260.634988 -283.078428) (xy 260.831584 -283.275024) (xy 260.838428 -283.282423)
			(xy 260.846157 -283.301021) (xy 260.84657 -283.311092) (xy 260.84657 -283.893514) (xy 263.537954 -283.893514)
			(xy 263.53852 -283.864133) (xy 263.547548 -283.806068) (xy 263.565376 -283.750075) (xy 263.591583 -283.69748)
			(xy 263.625547 -283.649528) (xy 263.666466 -283.607354) (xy 263.689592 -283.589222) (xy 263.698524 -283.58175)
			(xy 263.708977 -283.560969) (xy 263.709658 -283.549344) (xy 263.710928 -283.457396) (xy 263.701022 -283.436314)
			(xy 263.691878 -283.428948) (xy 263.670018 -283.410756) (xy 263.63148 -283.368933) (xy 263.599575 -283.321855)
			(xy 263.57501 -283.270563) (xy 263.558329 -283.216193) (xy 263.549902 -283.15995) (xy 263.549384 -283.131514)
			(xy 263.54987 -283.104263) (xy 263.557626 -283.050315) (xy 263.572981 -282.99802) (xy 263.595623 -282.948443)
			(xy 263.625089 -282.902593) (xy 263.66078 -282.861402) (xy 263.701971 -282.825711) (xy 263.747821 -282.796245)
			(xy 263.797398 -282.773603) (xy 263.849693 -282.758248) (xy 263.903641 -282.750492) (xy 263.958143 -282.750492)
			(xy 264.012091 -282.758248) (xy 264.064386 -282.773603) (xy 264.113963 -282.796245) (xy 264.159813 -282.825711)
			(xy 264.201004 -282.861402) (xy 264.236695 -282.902593) (xy 264.266161 -282.948443) (xy 264.288803 -282.99802)
			(xy 264.304158 -283.050315) (xy 264.311914 -283.104263) (xy 264.3124 -283.131514) (xy 264.311872 -283.160897)
			(xy 264.302839 -283.218964) (xy 264.285005 -283.274959) (xy 264.258791 -283.327554) (xy 264.224818 -283.375505)
			(xy 264.183891 -283.417676) (xy 264.160762 -283.435806) (xy 264.151826 -283.443275) (xy 264.141373 -283.464057)
			(xy 264.140696 -283.475684) (xy 264.139426 -283.567632) (xy 264.149332 -283.588714) (xy 264.158476 -283.59608)
			(xy 264.180292 -283.614323) (xy 264.218835 -283.656133) (xy 264.250747 -283.703201) (xy 264.275319 -283.754484)
			(xy 264.292009 -283.808845) (xy 264.300447 -283.865081) (xy 264.30097 -283.893514) (xy 264.934444 -283.893514)
			(xy 264.938515 -283.837892) (xy 264.950641 -283.783455) (xy 264.970564 -283.731364) (xy 264.99786 -283.682729)
			(xy 265.031946 -283.638586) (xy 265.072095 -283.599877) (xy 265.117453 -283.567426) (xy 265.167053 -283.541925)
			(xy 265.219837 -283.523918) (xy 265.27468 -283.513788) (xy 265.330414 -283.511751) (xy 265.385851 -283.517851)
			(xy 265.439808 -283.531957) (xy 265.491137 -283.553769) (xy 265.538743 -283.582823) (xy 265.581611 -283.618498)
			(xy 265.618828 -283.660035) (xy 265.649601 -283.706548) (xy 265.673273 -283.757045) (xy 265.689341 -283.810452)
			(xy 265.697461 -283.865628) (xy 265.69797 -283.893514) (xy 265.697461 -283.9214) (xy 265.689341 -283.976576)
			(xy 265.673273 -284.029983) (xy 265.649601 -284.08048) (xy 265.618828 -284.126993) (xy 265.581611 -284.16853)
			(xy 265.538743 -284.204205) (xy 265.491137 -284.233259) (xy 265.439808 -284.255071) (xy 265.385851 -284.269177)
			(xy 265.330414 -284.275277) (xy 265.27468 -284.27324) (xy 265.219837 -284.26311) (xy 265.167053 -284.245103)
			(xy 265.117453 -284.219602) (xy 265.072095 -284.187151) (xy 265.031946 -284.148442) (xy 264.99786 -284.104299)
			(xy 264.970564 -284.055664) (xy 264.950641 -284.003573) (xy 264.938515 -283.949136) (xy 264.934444 -283.893514)
			(xy 264.30097 -283.893514) (xy 264.300484 -283.920765) (xy 264.292728 -283.974713) (xy 264.277373 -284.027008)
			(xy 264.254731 -284.076585) (xy 264.225265 -284.122435) (xy 264.189574 -284.163626) (xy 264.148383 -284.199317)
			(xy 264.102533 -284.228783) (xy 264.052956 -284.251425) (xy 264.000661 -284.26678) (xy 263.946713 -284.274536)
			(xy 263.892211 -284.274536) (xy 263.838263 -284.26678) (xy 263.785968 -284.251425) (xy 263.736391 -284.228783)
			(xy 263.690541 -284.199317) (xy 263.64935 -284.163626) (xy 263.613659 -284.122435) (xy 263.584193 -284.076585)
			(xy 263.561551 -284.027008) (xy 263.546196 -283.974713) (xy 263.53844 -283.920765) (xy 263.537954 -283.893514)
			(xy 260.84657 -283.893514) (xy 260.84657 -285.922974) (xy 260.846903 -285.930869) (xy 260.851819 -285.945876)
			(xy 260.856222 -285.952438) (xy 260.86054 -285.958788) (xy 260.872986 -285.967932) (xy 260.88086 -285.970726)
			(xy 260.907118 -285.980178) (xy 260.956764 -286.005668) (xy 261.002167 -286.038118) (xy 261.042358 -286.076836)
			(xy 261.076481 -286.120995) (xy 261.103806 -286.169655) (xy 261.123751 -286.221776) (xy 261.135891 -286.276247)
			(xy 261.139966 -286.331905) (xy 261.135889 -286.387562) (xy 261.123749 -286.442033) (xy 261.103802 -286.494153)
			(xy 261.076476 -286.542812) (xy 261.042352 -286.586971) (xy 261.00216 -286.625688) (xy 260.956756 -286.658137)
			(xy 260.90711 -286.683625) (xy 260.88086 -286.693102) (xy 260.880606 -286.693102) (xy 260.873287 -286.695961)
			(xy 260.86074 -286.705402) (xy 260.855968 -286.711644) (xy 260.851396 -286.717994) (xy 260.84657 -286.732726)
			(xy 260.84657 -287.093914) (xy 263.537954 -287.093914) (xy 263.53852 -287.064533) (xy 263.547548 -287.006468)
			(xy 263.565376 -286.950475) (xy 263.591583 -286.89788) (xy 263.625547 -286.849928) (xy 263.666466 -286.807754)
			(xy 263.689592 -286.789622) (xy 263.698524 -286.78215) (xy 263.708977 -286.761369) (xy 263.709658 -286.749744)
			(xy 263.710928 -286.657796) (xy 263.701022 -286.636714) (xy 263.691878 -286.629348) (xy 263.670018 -286.611156)
			(xy 263.63148 -286.569333) (xy 263.599575 -286.522255) (xy 263.57501 -286.470963) (xy 263.558329 -286.416593)
			(xy 263.549902 -286.36035) (xy 263.549384 -286.331914) (xy 263.54987 -286.304663) (xy 263.557626 -286.250715)
			(xy 263.572981 -286.19842) (xy 263.595623 -286.148843) (xy 263.625089 -286.102993) (xy 263.66078 -286.061802)
			(xy 263.701971 -286.026111) (xy 263.747821 -285.996645) (xy 263.797398 -285.974003) (xy 263.849693 -285.958648)
			(xy 263.903641 -285.950892) (xy 263.958143 -285.950892) (xy 264.012091 -285.958648) (xy 264.064386 -285.974003)
			(xy 264.113963 -285.996645) (xy 264.159813 -286.026111) (xy 264.201004 -286.061802) (xy 264.236695 -286.102993)
			(xy 264.266161 -286.148843) (xy 264.288803 -286.19842) (xy 264.304158 -286.250715) (xy 264.311914 -286.304663)
			(xy 264.3124 -286.331914) (xy 264.311872 -286.361297) (xy 264.302839 -286.419364) (xy 264.285005 -286.475359)
			(xy 264.258791 -286.527954) (xy 264.224818 -286.575905) (xy 264.183891 -286.618076) (xy 264.160762 -286.636206)
			(xy 264.151826 -286.643675) (xy 264.141373 -286.664457) (xy 264.140696 -286.676084) (xy 264.139426 -286.768032)
			(xy 264.149332 -286.789114) (xy 264.158476 -286.79648) (xy 264.180292 -286.814723) (xy 264.218835 -286.856533)
			(xy 264.250747 -286.903601) (xy 264.275319 -286.954884) (xy 264.292009 -287.009245) (xy 264.300447 -287.065481)
			(xy 264.30097 -287.093914) (xy 264.934444 -287.093914) (xy 264.938515 -287.038292) (xy 264.950641 -286.983855)
			(xy 264.970564 -286.931764) (xy 264.99786 -286.883129) (xy 265.031946 -286.838986) (xy 265.072095 -286.800277)
			(xy 265.117453 -286.767826) (xy 265.167053 -286.742325) (xy 265.219837 -286.724318) (xy 265.27468 -286.714188)
			(xy 265.330414 -286.712151) (xy 265.385851 -286.718251) (xy 265.439808 -286.732357) (xy 265.491137 -286.754169)
			(xy 265.538743 -286.783223) (xy 265.581611 -286.818898) (xy 265.618828 -286.860435) (xy 265.649601 -286.906948)
			(xy 265.673273 -286.957445) (xy 265.689341 -287.010852) (xy 265.697461 -287.066028) (xy 265.69797 -287.093914)
			(xy 265.697461 -287.1218) (xy 265.689341 -287.176976) (xy 265.673273 -287.230383) (xy 265.649601 -287.28088)
			(xy 265.618828 -287.327393) (xy 265.581611 -287.36893) (xy 265.538743 -287.404605) (xy 265.491137 -287.433659)
			(xy 265.439808 -287.455471) (xy 265.385851 -287.469577) (xy 265.330414 -287.475677) (xy 265.27468 -287.47364)
			(xy 265.219837 -287.46351) (xy 265.167053 -287.445503) (xy 265.117453 -287.420002) (xy 265.072095 -287.387551)
			(xy 265.031946 -287.348842) (xy 264.99786 -287.304699) (xy 264.970564 -287.256064) (xy 264.950641 -287.203973)
			(xy 264.938515 -287.149536) (xy 264.934444 -287.093914) (xy 264.30097 -287.093914) (xy 264.300484 -287.121165)
			(xy 264.292728 -287.175113) (xy 264.277373 -287.227408) (xy 264.254731 -287.276985) (xy 264.225265 -287.322835)
			(xy 264.189574 -287.364026) (xy 264.148383 -287.399717) (xy 264.102533 -287.429183) (xy 264.052956 -287.451825)
			(xy 264.000661 -287.46718) (xy 263.946713 -287.474936) (xy 263.892211 -287.474936) (xy 263.838263 -287.46718)
			(xy 263.785968 -287.451825) (xy 263.736391 -287.429183) (xy 263.690541 -287.399717) (xy 263.64935 -287.364026)
			(xy 263.613659 -287.322835) (xy 263.584193 -287.276985) (xy 263.561551 -287.227408) (xy 263.546196 -287.175113)
			(xy 263.53844 -287.121165) (xy 263.537954 -287.093914) (xy 260.84657 -287.093914) (xy 260.84657 -289.123374)
			(xy 260.846903 -289.131269) (xy 260.851819 -289.146276) (xy 260.856222 -289.152838) (xy 260.86054 -289.159188)
			(xy 260.872986 -289.168332) (xy 260.88086 -289.171126) (xy 260.907118 -289.180578) (xy 260.956764 -289.206068)
			(xy 261.002167 -289.238518) (xy 261.042358 -289.277236) (xy 261.076481 -289.321395) (xy 261.103806 -289.370055)
			(xy 261.123751 -289.422176) (xy 261.135891 -289.476647) (xy 261.139966 -289.532305) (xy 261.135889 -289.587962)
			(xy 261.123749 -289.642433) (xy 261.103802 -289.694553) (xy 261.076476 -289.743212) (xy 261.042352 -289.787371)
			(xy 261.00216 -289.826088) (xy 260.956756 -289.858537) (xy 260.90711 -289.884025) (xy 260.88086 -289.893502)
			(xy 260.880606 -289.893502) (xy 260.873287 -289.896361) (xy 260.86074 -289.905802) (xy 260.855968 -289.912044)
			(xy 260.851396 -289.918394) (xy 260.84657 -289.933126) (xy 260.84657 -290.294314) (xy 263.537954 -290.294314)
			(xy 263.53852 -290.264933) (xy 263.547548 -290.206868) (xy 263.565376 -290.150875) (xy 263.591583 -290.09828)
			(xy 263.625547 -290.050328) (xy 263.666466 -290.008154) (xy 263.689592 -289.990022) (xy 263.698524 -289.98255)
			(xy 263.708977 -289.961769) (xy 263.709658 -289.950144) (xy 263.710928 -289.858196) (xy 263.701022 -289.837114)
			(xy 263.691878 -289.829748) (xy 263.670018 -289.811556) (xy 263.63148 -289.769733) (xy 263.599575 -289.722655)
			(xy 263.57501 -289.671363) (xy 263.558329 -289.616993) (xy 263.549902 -289.56075) (xy 263.549384 -289.532314)
			(xy 263.54987 -289.505063) (xy 263.557626 -289.451115) (xy 263.572981 -289.39882) (xy 263.595623 -289.349243)
			(xy 263.625089 -289.303393) (xy 263.66078 -289.262202) (xy 263.701971 -289.226511) (xy 263.747821 -289.197045)
			(xy 263.797398 -289.174403) (xy 263.849693 -289.159048) (xy 263.903641 -289.151292) (xy 263.958143 -289.151292)
			(xy 264.012091 -289.159048) (xy 264.064386 -289.174403) (xy 264.113963 -289.197045) (xy 264.159813 -289.226511)
			(xy 264.201004 -289.262202) (xy 264.236695 -289.303393) (xy 264.266161 -289.349243) (xy 264.288803 -289.39882)
			(xy 264.304158 -289.451115) (xy 264.311914 -289.505063) (xy 264.3124 -289.532314) (xy 264.311872 -289.561697)
			(xy 264.302839 -289.619764) (xy 264.285005 -289.675759) (xy 264.258791 -289.728354) (xy 264.224818 -289.776305)
			(xy 264.183891 -289.818476) (xy 264.160762 -289.836606) (xy 264.151826 -289.844075) (xy 264.141373 -289.864857)
			(xy 264.140696 -289.876484) (xy 264.139426 -289.968432) (xy 264.149332 -289.989514) (xy 264.158476 -289.99688)
			(xy 264.180292 -290.015123) (xy 264.218835 -290.056933) (xy 264.250747 -290.104001) (xy 264.275319 -290.155284)
			(xy 264.292009 -290.209645) (xy 264.300447 -290.265881) (xy 264.30097 -290.294314) (xy 264.934444 -290.294314)
			(xy 264.938515 -290.238692) (xy 264.950641 -290.184255) (xy 264.970564 -290.132164) (xy 264.99786 -290.083529)
			(xy 265.031946 -290.039386) (xy 265.072095 -290.000677) (xy 265.117453 -289.968226) (xy 265.167053 -289.942725)
			(xy 265.219837 -289.924718) (xy 265.27468 -289.914588) (xy 265.330414 -289.912551) (xy 265.385851 -289.918651)
			(xy 265.439808 -289.932757) (xy 265.491137 -289.954569) (xy 265.538743 -289.983623) (xy 265.581611 -290.019298)
			(xy 265.618828 -290.060835) (xy 265.649601 -290.107348) (xy 265.673273 -290.157845) (xy 265.689341 -290.211252)
			(xy 265.697461 -290.266428) (xy 265.69797 -290.294314) (xy 265.697461 -290.3222) (xy 265.689341 -290.377376)
			(xy 265.673273 -290.430783) (xy 265.649601 -290.48128) (xy 265.618828 -290.527793) (xy 265.581611 -290.56933)
			(xy 265.538743 -290.605005) (xy 265.491137 -290.634059) (xy 265.439808 -290.655871) (xy 265.385851 -290.669977)
			(xy 265.330414 -290.676077) (xy 265.27468 -290.67404) (xy 265.219837 -290.66391) (xy 265.167053 -290.645903)
			(xy 265.117453 -290.620402) (xy 265.072095 -290.587951) (xy 265.031946 -290.549242) (xy 264.99786 -290.505099)
			(xy 264.970564 -290.456464) (xy 264.950641 -290.404373) (xy 264.938515 -290.349936) (xy 264.934444 -290.294314)
			(xy 264.30097 -290.294314) (xy 264.300484 -290.321565) (xy 264.292728 -290.375513) (xy 264.277373 -290.427808)
			(xy 264.254731 -290.477385) (xy 264.225265 -290.523235) (xy 264.189574 -290.564426) (xy 264.148383 -290.600117)
			(xy 264.102533 -290.629583) (xy 264.052956 -290.652225) (xy 264.000661 -290.66758) (xy 263.946713 -290.675336)
			(xy 263.892211 -290.675336) (xy 263.838263 -290.66758) (xy 263.785968 -290.652225) (xy 263.736391 -290.629583)
			(xy 263.690541 -290.600117) (xy 263.64935 -290.564426) (xy 263.613659 -290.523235) (xy 263.584193 -290.477385)
			(xy 263.561551 -290.427808) (xy 263.546196 -290.375513) (xy 263.53844 -290.321565) (xy 263.537954 -290.294314)
			(xy 260.84657 -290.294314) (xy 260.84657 -292.323774) (xy 260.846903 -292.331669) (xy 260.851819 -292.346676)
			(xy 260.856222 -292.353238) (xy 260.86054 -292.359588) (xy 260.872986 -292.368732) (xy 260.88086 -292.371526)
			(xy 260.907118 -292.380978) (xy 260.956764 -292.406468) (xy 261.002167 -292.438918) (xy 261.042358 -292.477636)
			(xy 261.076481 -292.521795) (xy 261.103806 -292.570455) (xy 261.123751 -292.622576) (xy 261.135891 -292.677047)
			(xy 261.139966 -292.732705) (xy 261.135889 -292.788362) (xy 261.123749 -292.842833) (xy 261.103802 -292.894953)
			(xy 261.076476 -292.943612) (xy 261.042352 -292.987771) (xy 261.00216 -293.026488) (xy 260.956756 -293.058937)
			(xy 260.90711 -293.084425) (xy 260.88086 -293.093902) (xy 260.880606 -293.093902) (xy 260.873287 -293.096761)
			(xy 260.86074 -293.106202) (xy 260.855968 -293.112444) (xy 260.851396 -293.118794) (xy 260.84657 -293.133526)
			(xy 260.84657 -293.494714) (xy 263.537954 -293.494714) (xy 263.53852 -293.465333) (xy 263.547548 -293.407268)
			(xy 263.565376 -293.351275) (xy 263.591583 -293.29868) (xy 263.625547 -293.250728) (xy 263.666466 -293.208554)
			(xy 263.689592 -293.190422) (xy 263.698524 -293.18295) (xy 263.708977 -293.162169) (xy 263.709658 -293.150544)
			(xy 263.710928 -293.058596) (xy 263.701022 -293.037514) (xy 263.691878 -293.030148) (xy 263.670018 -293.011956)
			(xy 263.63148 -292.970133) (xy 263.599575 -292.923055) (xy 263.57501 -292.871763) (xy 263.558329 -292.817393)
			(xy 263.549902 -292.76115) (xy 263.549384 -292.732714) (xy 263.54987 -292.705463) (xy 263.557626 -292.651515)
			(xy 263.572981 -292.59922) (xy 263.595623 -292.549643) (xy 263.625089 -292.503793) (xy 263.66078 -292.462602)
			(xy 263.701971 -292.426911) (xy 263.747821 -292.397445) (xy 263.797398 -292.374803) (xy 263.849693 -292.359448)
			(xy 263.903641 -292.351692) (xy 263.958143 -292.351692) (xy 264.012091 -292.359448) (xy 264.064386 -292.374803)
			(xy 264.113963 -292.397445) (xy 264.159813 -292.426911) (xy 264.201004 -292.462602) (xy 264.236695 -292.503793)
			(xy 264.266161 -292.549643) (xy 264.288803 -292.59922) (xy 264.304158 -292.651515) (xy 264.311914 -292.705463)
			(xy 264.3124 -292.732714) (xy 264.311872 -292.762097) (xy 264.302839 -292.820164) (xy 264.285005 -292.876159)
			(xy 264.258791 -292.928754) (xy 264.224818 -292.976705) (xy 264.183891 -293.018876) (xy 264.160762 -293.037006)
			(xy 264.151826 -293.044475) (xy 264.141373 -293.065257) (xy 264.140696 -293.076884) (xy 264.139426 -293.168832)
			(xy 264.149332 -293.189914) (xy 264.158476 -293.19728) (xy 264.180292 -293.215523) (xy 264.218835 -293.257333)
			(xy 264.250747 -293.304401) (xy 264.275319 -293.355684) (xy 264.292009 -293.410045) (xy 264.300447 -293.466281)
			(xy 264.30097 -293.494714) (xy 264.934444 -293.494714) (xy 264.938515 -293.439092) (xy 264.950641 -293.384655)
			(xy 264.970564 -293.332564) (xy 264.99786 -293.283929) (xy 265.031946 -293.239786) (xy 265.072095 -293.201077)
			(xy 265.117453 -293.168626) (xy 265.167053 -293.143125) (xy 265.219837 -293.125118) (xy 265.27468 -293.114988)
			(xy 265.330414 -293.112951) (xy 265.385851 -293.119051) (xy 265.439808 -293.133157) (xy 265.491137 -293.154969)
			(xy 265.538743 -293.184023) (xy 265.581611 -293.219698) (xy 265.618828 -293.261235) (xy 265.649601 -293.307748)
			(xy 265.673273 -293.358245) (xy 265.689341 -293.411652) (xy 265.697461 -293.466828) (xy 265.69797 -293.494714)
			(xy 265.697461 -293.5226) (xy 265.689341 -293.577776) (xy 265.673273 -293.631183) (xy 265.649601 -293.68168)
			(xy 265.618828 -293.728193) (xy 265.581611 -293.76973) (xy 265.538743 -293.805405) (xy 265.491137 -293.834459)
			(xy 265.439808 -293.856271) (xy 265.385851 -293.870377) (xy 265.330414 -293.876477) (xy 265.27468 -293.87444)
			(xy 265.219837 -293.86431) (xy 265.167053 -293.846303) (xy 265.117453 -293.820802) (xy 265.072095 -293.788351)
			(xy 265.031946 -293.749642) (xy 264.99786 -293.705499) (xy 264.970564 -293.656864) (xy 264.950641 -293.604773)
			(xy 264.938515 -293.550336) (xy 264.934444 -293.494714) (xy 264.30097 -293.494714) (xy 264.300484 -293.521965)
			(xy 264.292728 -293.575913) (xy 264.277373 -293.628208) (xy 264.254731 -293.677785) (xy 264.225265 -293.723635)
			(xy 264.189574 -293.764826) (xy 264.148383 -293.800517) (xy 264.102533 -293.829983) (xy 264.052956 -293.852625)
			(xy 264.000661 -293.86798) (xy 263.946713 -293.875736) (xy 263.892211 -293.875736) (xy 263.838263 -293.86798)
			(xy 263.785968 -293.852625) (xy 263.736391 -293.829983) (xy 263.690541 -293.800517) (xy 263.64935 -293.764826)
			(xy 263.613659 -293.723635) (xy 263.584193 -293.677785) (xy 263.561551 -293.628208) (xy 263.546196 -293.575913)
			(xy 263.53844 -293.521965) (xy 263.537954 -293.494714) (xy 260.84657 -293.494714) (xy 260.84657 -295.524174)
			(xy 260.846903 -295.532069) (xy 260.851819 -295.547076) (xy 260.856222 -295.553638) (xy 260.86054 -295.559988)
			(xy 260.872986 -295.569132) (xy 260.88086 -295.571926) (xy 260.907118 -295.581378) (xy 260.956764 -295.606868)
			(xy 261.002167 -295.639318) (xy 261.042358 -295.678036) (xy 261.076481 -295.722195) (xy 261.103806 -295.770855)
			(xy 261.123751 -295.822976) (xy 261.135891 -295.877447) (xy 261.139966 -295.933105) (xy 261.135889 -295.988762)
			(xy 261.123749 -296.043233) (xy 261.103802 -296.095353) (xy 261.076476 -296.144012) (xy 261.042352 -296.188171)
			(xy 261.00216 -296.226888) (xy 260.956756 -296.259337) (xy 260.90711 -296.284825) (xy 260.88086 -296.294302)
			(xy 260.880606 -296.294302) (xy 260.873287 -296.297161) (xy 260.86074 -296.306602) (xy 260.855968 -296.312844)
			(xy 260.851396 -296.319194) (xy 260.84657 -296.333926) (xy 260.84657 -296.695114) (xy 263.537954 -296.695114)
			(xy 263.53852 -296.665733) (xy 263.547548 -296.607668) (xy 263.565376 -296.551675) (xy 263.591583 -296.49908)
			(xy 263.625547 -296.451128) (xy 263.666466 -296.408954) (xy 263.689592 -296.390822) (xy 263.698524 -296.38335)
			(xy 263.708977 -296.362569) (xy 263.709658 -296.350944) (xy 263.710928 -296.258996) (xy 263.701022 -296.237914)
			(xy 263.691878 -296.230548) (xy 263.670018 -296.212356) (xy 263.63148 -296.170533) (xy 263.599575 -296.123455)
			(xy 263.57501 -296.072163) (xy 263.558329 -296.017793) (xy 263.549902 -295.96155) (xy 263.549384 -295.933114)
			(xy 263.54987 -295.905863) (xy 263.557626 -295.851915) (xy 263.572981 -295.79962) (xy 263.595623 -295.750043)
			(xy 263.625089 -295.704193) (xy 263.66078 -295.663002) (xy 263.701971 -295.627311) (xy 263.747821 -295.597845)
			(xy 263.797398 -295.575203) (xy 263.849693 -295.559848) (xy 263.903641 -295.552092) (xy 263.958143 -295.552092)
			(xy 264.012091 -295.559848) (xy 264.064386 -295.575203) (xy 264.113963 -295.597845) (xy 264.159813 -295.627311)
			(xy 264.201004 -295.663002) (xy 264.236695 -295.704193) (xy 264.266161 -295.750043) (xy 264.288803 -295.79962)
			(xy 264.304158 -295.851915) (xy 264.311914 -295.905863) (xy 264.3124 -295.933114) (xy 264.311872 -295.962497)
			(xy 264.302839 -296.020564) (xy 264.285005 -296.076559) (xy 264.258791 -296.129154) (xy 264.224818 -296.177105)
			(xy 264.183891 -296.219276) (xy 264.160762 -296.237406) (xy 264.151826 -296.244875) (xy 264.141373 -296.265657)
			(xy 264.140696 -296.277284) (xy 264.139426 -296.369232) (xy 264.149332 -296.390314) (xy 264.158476 -296.39768)
			(xy 264.180292 -296.415923) (xy 264.218835 -296.457733) (xy 264.250747 -296.504801) (xy 264.275319 -296.556084)
			(xy 264.292009 -296.610445) (xy 264.300447 -296.666681) (xy 264.30097 -296.695114) (xy 264.934444 -296.695114)
			(xy 264.938515 -296.639492) (xy 264.950641 -296.585055) (xy 264.970564 -296.532964) (xy 264.99786 -296.484329)
			(xy 265.031946 -296.440186) (xy 265.072095 -296.401477) (xy 265.117453 -296.369026) (xy 265.167053 -296.343525)
			(xy 265.219837 -296.325518) (xy 265.27468 -296.315388) (xy 265.330414 -296.313351) (xy 265.385851 -296.319451)
			(xy 265.439808 -296.333557) (xy 265.491137 -296.355369) (xy 265.538743 -296.384423) (xy 265.581611 -296.420098)
			(xy 265.618828 -296.461635) (xy 265.649601 -296.508148) (xy 265.673273 -296.558645) (xy 265.689341 -296.612052)
			(xy 265.697461 -296.667228) (xy 265.69797 -296.695114) (xy 265.697461 -296.723) (xy 265.689341 -296.778176)
			(xy 265.673273 -296.831583) (xy 265.649601 -296.88208) (xy 265.618828 -296.928593) (xy 265.581611 -296.97013)
			(xy 265.538743 -297.005805) (xy 265.491137 -297.034859) (xy 265.439808 -297.056671) (xy 265.385851 -297.070777)
			(xy 265.330414 -297.076877) (xy 265.27468 -297.07484) (xy 265.219837 -297.06471) (xy 265.167053 -297.046703)
			(xy 265.117453 -297.021202) (xy 265.072095 -296.988751) (xy 265.031946 -296.950042) (xy 264.99786 -296.905899)
			(xy 264.970564 -296.857264) (xy 264.950641 -296.805173) (xy 264.938515 -296.750736) (xy 264.934444 -296.695114)
			(xy 264.30097 -296.695114) (xy 264.300484 -296.722365) (xy 264.292728 -296.776313) (xy 264.277373 -296.828608)
			(xy 264.254731 -296.878185) (xy 264.225265 -296.924035) (xy 264.189574 -296.965226) (xy 264.148383 -297.000917)
			(xy 264.102533 -297.030383) (xy 264.052956 -297.053025) (xy 264.000661 -297.06838) (xy 263.946713 -297.076136)
			(xy 263.892211 -297.076136) (xy 263.838263 -297.06838) (xy 263.785968 -297.053025) (xy 263.736391 -297.030383)
			(xy 263.690541 -297.000917) (xy 263.64935 -296.965226) (xy 263.613659 -296.924035) (xy 263.584193 -296.878185)
			(xy 263.561551 -296.828608) (xy 263.546196 -296.776313) (xy 263.53844 -296.722365) (xy 263.537954 -296.695114)
			(xy 260.84657 -296.695114) (xy 260.84657 -298.724574) (xy 260.846903 -298.732469) (xy 260.851819 -298.747476)
			(xy 260.856222 -298.754038) (xy 260.86054 -298.760388) (xy 260.872986 -298.769532) (xy 260.88086 -298.772326)
			(xy 260.907118 -298.781778) (xy 260.956764 -298.807268) (xy 261.002167 -298.839718) (xy 261.042358 -298.878436)
			(xy 261.076481 -298.922595) (xy 261.103806 -298.971255) (xy 261.123751 -299.023376) (xy 261.135891 -299.077847)
			(xy 261.139966 -299.133505) (xy 261.135889 -299.189162) (xy 261.123749 -299.243633) (xy 261.103802 -299.295753)
			(xy 261.076476 -299.344412) (xy 261.042352 -299.388571) (xy 261.00216 -299.427288) (xy 260.956756 -299.459737)
			(xy 260.90711 -299.485225) (xy 260.88086 -299.494702) (xy 260.880606 -299.494702) (xy 260.873287 -299.497561)
			(xy 260.86074 -299.507002) (xy 260.855968 -299.513244) (xy 260.851396 -299.519594) (xy 260.84657 -299.534326)
			(xy 260.84657 -300.47057) (xy 260.846133 -300.480634) (xy 260.838398 -300.499217) (xy 260.831584 -300.506638)
			(xy 260.755892 -300.58233) (xy 260.749407 -300.589424) (xy 260.741823 -300.607068) (xy 260.741275 -300.626265)
			(xy 260.744208 -300.635416) (xy 260.74497 -300.637448) (xy 260.748076 -300.64436) (xy 260.757635 -300.656107)
			(xy 260.763766 -300.660562) (xy 260.769608 -300.664626) (xy 260.784086 -300.668944)
		)
		(stroke
			(width 0)
			(type solid)
		)
		(fill yes)
		(layer "In5.Cu")
		(net "GND")
	)
	(gr_poly
		(pts
			(xy 136.741408 -216.882726) (xy 136.753254 -216.882106) (xy 136.774446 -216.871512) (xy 136.782048 -216.862406)
			(xy 136.782048 -214.537544) (xy 136.781794 -214.52586) (xy 136.782098 -214.505521) (xy 136.787059 -214.465147)
			(xy 136.7917 -214.445342) (xy 136.79297 -214.435944) (xy 136.792557 -214.425919) (xy 136.784894 -214.407392)
			(xy 136.770719 -214.393214) (xy 136.752195 -214.385545) (xy 136.74217 -214.385144) (xy 136.718548 -214.393272)
			(xy 136.714809 -214.394687) (xy 136.707789 -214.39851) (xy 136.704578 -214.400892) (xy 136.67954 -214.419057)
			(xy 136.624824 -214.447905) (xy 136.566176 -214.467566) (xy 136.505128 -214.477526) (xy 136.4742 -214.478108)
			(xy 136.446376 -214.477603) (xy 136.391319 -214.469514) (xy 136.338023 -214.453508) (xy 136.287619 -214.429926)
			(xy 136.241179 -214.399267) (xy 136.199688 -214.362183) (xy 136.164028 -214.319462) (xy 136.14908 -214.29599)
			(xy 136.144046 -214.288608) (xy 136.130016 -214.277567) (xy 136.113057 -214.271987) (xy 136.104122 -214.27186)
			(xy 136.002268 -214.274908) (xy 135.979154 -214.289386) (xy 135.972804 -214.301324) (xy 135.958463 -214.327101)
			(xy 135.923064 -214.374284) (xy 135.880822 -214.415453) (xy 135.832744 -214.449626) (xy 135.779977 -214.475988)
			(xy 135.72378 -214.493909) (xy 135.665493 -214.502962) (xy 135.636 -214.503508) (xy 135.608749 -214.503022)
			(xy 135.554801 -214.495266) (xy 135.502506 -214.479911) (xy 135.452929 -214.457269) (xy 135.407079 -214.427803)
			(xy 135.365888 -214.392112) (xy 135.330197 -214.350921) (xy 135.300731 -214.305071) (xy 135.278089 -214.255494)
			(xy 135.262734 -214.203199) (xy 135.254978 -214.149251) (xy 135.254978 -214.094749) (xy 135.262734 -214.040801)
			(xy 135.278089 -213.988506) (xy 135.300731 -213.938929) (xy 135.330197 -213.893079) (xy 135.365888 -213.851888)
			(xy 135.407079 -213.816197) (xy 135.452929 -213.786731) (xy 135.502506 -213.764089) (xy 135.554801 -213.748734)
			(xy 135.608749 -213.740978) (xy 135.636 -213.740492) (xy 135.663824 -213.740997) (xy 135.718881 -213.749086)
			(xy 135.772177 -213.765092) (xy 135.822581 -213.788674) (xy 135.869021 -213.819333) (xy 135.910512 -213.856417)
			(xy 135.946172 -213.899138) (xy 135.96112 -213.92261) (xy 135.966154 -213.929992) (xy 135.980184 -213.941033)
			(xy 135.997143 -213.946613) (xy 136.006078 -213.94674) (xy 136.107932 -213.943692) (xy 136.131046 -213.929214)
			(xy 136.137396 -213.917276) (xy 136.151737 -213.891499) (xy 136.187136 -213.844316) (xy 136.229378 -213.803147)
			(xy 136.277456 -213.768974) (xy 136.330223 -213.742612) (xy 136.38642 -213.724691) (xy 136.444707 -213.715638)
			(xy 136.4742 -213.715092) (xy 136.503139 -213.715628) (xy 136.560354 -213.724368) (xy 136.615593 -213.741648)
			(xy 136.667588 -213.767072) (xy 136.715148 -213.800056) (xy 136.757182 -213.839844) (xy 136.792725 -213.885524)
			(xy 136.820962 -213.936047) (xy 136.841246 -213.990255) (xy 136.853111 -214.046904) (xy 136.8552 -214.075772)
			(xy 136.856169 -214.085513) (xy 136.864441 -214.103236) (xy 136.878728 -214.116594) (xy 136.887712 -214.120476)
			(xy 136.974072 -214.15375) (xy 136.983381 -214.156805) (xy 137.002953 -214.156391) (xy 137.020947 -214.148683)
			(xy 137.028174 -214.142066) (xy 137.574528 -213.595712) (xy 137.575225 -213.588927) (xy 137.573411 -213.575413)
			(xy 137.570972 -213.569042) (xy 137.546334 -213.516464) (xy 137.529316 -213.480142) (xy 137.525806 -213.473354)
			(xy 137.515464 -213.462114) (xy 137.508996 -213.458044) (xy 137.502392 -213.454234) (xy 137.487914 -213.450932)
			(xy 137.479532 -213.451694) (xy 137.446766 -213.453218) (xy 137.419514 -213.45273) (xy 137.365567 -213.444968)
			(xy 137.313273 -213.429609) (xy 137.263697 -213.406963) (xy 137.217848 -213.377493) (xy 137.17666 -213.341797)
			(xy 137.140971 -213.300604) (xy 137.111508 -213.254751) (xy 137.08887 -213.205171) (xy 137.073519 -213.152875)
			(xy 137.065766 -213.098926) (xy 137.06577 -213.044422) (xy 137.07353 -212.990475) (xy 137.088889 -212.93818)
			(xy 137.111533 -212.888604) (xy 137.141002 -212.842754) (xy 137.176697 -212.801566) (xy 137.21789 -212.765876)
			(xy 137.263742 -212.736412) (xy 137.313321 -212.713773) (xy 137.365618 -212.69842) (xy 137.419566 -212.690666)
			(xy 137.47407 -212.690669) (xy 137.528018 -212.698428) (xy 137.580312 -212.713786) (xy 137.629889 -212.736429)
			(xy 137.675739 -212.765898) (xy 137.716929 -212.801591) (xy 137.752619 -212.842783) (xy 137.782084 -212.888635)
			(xy 137.804724 -212.938214) (xy 137.820078 -212.99051) (xy 137.827833 -213.044458) (xy 137.828274 -213.07171)
			(xy 137.827004 -213.104222) (xy 137.826496 -213.109048) (xy 137.826715 -213.115651) (xy 137.830188 -213.128395)
			(xy 137.833354 -213.134194) (xy 137.837164 -213.140798) (xy 137.842752 -213.145878) (xy 137.845583 -213.148363)
			(xy 137.851832 -213.152569) (xy 137.855198 -213.15426) (xy 137.89152 -213.171278) (xy 137.944098 -213.195916)
			(xy 137.950462 -213.198379) (xy 137.963982 -213.200185) (xy 137.970768 -213.199472) (xy 139.375134 -211.794852)
			(xy 139.38198 -211.787454) (xy 139.389708 -211.768855) (xy 139.39012 -211.758784) (xy 139.39012 -210.967066)
			(xy 139.38631 -210.959446) (xy 139.377928 -210.942936) (xy 139.372086 -210.93049) (xy 139.371578 -210.928966)
			(xy 139.369546 -210.92414) (xy 139.369038 -210.922616) (xy 139.363958 -210.91017) (xy 139.363704 -210.909154)
			(xy 139.36218 -210.905598) (xy 139.357834 -210.897407) (xy 139.344449 -210.884594) (xy 139.327389 -210.877363)
			(xy 139.308874 -210.876654) (xy 139.29995 -210.879182) (xy 139.293854 -210.881976) (xy 139.285056 -210.886782)
			(xy 139.271848 -210.901846) (xy 139.2682 -210.911186) (xy 139.267438 -210.913472) (xy 139.259365 -210.939561)
			(xy 139.236794 -210.989291) (xy 139.207365 -211.035296) (xy 139.171679 -211.076635) (xy 139.130464 -211.112466)
			(xy 139.084563 -211.142055) (xy 139.034912 -211.164799) (xy 138.982527 -211.180233) (xy 138.928476 -211.188042)
			(xy 138.90117 -211.188554) (xy 138.873917 -211.188066) (xy 138.819966 -211.180305) (xy 138.767668 -211.164946)
			(xy 138.718089 -211.1423) (xy 138.672237 -211.112829) (xy 138.631045 -211.077134) (xy 138.595353 -211.035939)
			(xy 138.565886 -210.990085) (xy 138.543244 -210.940503) (xy 138.527888 -210.888205) (xy 138.520132 -210.834253)
			(xy 138.520132 -210.779747) (xy 138.527888 -210.725795) (xy 138.543244 -210.673497) (xy 138.565886 -210.623915)
			(xy 138.595353 -210.578061) (xy 138.631045 -210.536866) (xy 138.672237 -210.501171) (xy 138.718089 -210.4717)
			(xy 138.767668 -210.449054) (xy 138.819966 -210.433695) (xy 138.873917 -210.425934) (xy 138.90117 -210.425538)
			(xy 138.927947 -210.425986) (xy 138.980977 -210.433458) (xy 139.032444 -210.448261) (xy 139.08134 -210.470105)
			(xy 139.126708 -210.498561) (xy 139.167659 -210.533072) (xy 139.20339 -210.572962) (xy 139.21867 -210.594956)
			(xy 139.221464 -210.599274) (xy 139.224882 -210.603122) (xy 139.232943 -210.609518) (xy 139.237466 -210.611974)
			(xy 139.243308 -210.615022) (xy 139.249404 -210.616292) (xy 139.262358 -210.617562) (xy 139.35075 -210.614514)
			(xy 139.356074 -210.613964) (xy 139.366328 -210.610899) (xy 139.37107 -210.608418) (xy 139.37869 -210.603846)
			(xy 139.38758 -210.594702) (xy 139.390882 -210.58886) (xy 139.405576 -210.564248) (xy 139.441186 -210.519332)
			(xy 139.48311 -210.480243) (xy 139.530406 -210.44786) (xy 139.58201 -210.422909) (xy 139.636765 -210.405952)
			(xy 139.693438 -210.397369) (xy 139.722098 -210.396836) (xy 139.749834 -210.39734) (xy 139.804719 -210.405385)
			(xy 139.857861 -210.42129) (xy 139.908141 -210.44472) (xy 139.954499 -210.475183) (xy 139.99596 -210.512035)
			(xy 140.031648 -210.554502) (xy 140.060813 -210.601687) (xy 140.082841 -210.652598) (xy 140.097266 -210.706161)
			(xy 140.101066 -210.73364) (xy 140.10259 -210.748118) (xy 140.10386 -210.778344) (xy 140.10343 -210.803409)
			(xy 140.097955 -210.844453) (xy 141.925761 -210.844453) (xy 141.925761 -210.789947) (xy 141.933518 -210.735997)
			(xy 141.948874 -210.6837) (xy 141.971516 -210.634121) (xy 142.000984 -210.588268) (xy 142.036677 -210.547076)
			(xy 142.07787 -210.511383) (xy 142.123722 -210.481915) (xy 142.173302 -210.459273) (xy 142.225599 -210.443918)
			(xy 142.279549 -210.436161) (xy 142.306802 -210.435698) (xy 142.333057 -210.436163) (xy 142.385073 -210.443349)
			(xy 142.435613 -210.457597) (xy 142.483722 -210.478638) (xy 142.528493 -210.506077) (xy 142.569079 -210.539393)
			(xy 142.587218 -210.55838) (xy 142.59433 -210.566254) (xy 142.614396 -210.57489) (xy 142.70101 -210.573366)
			(xy 142.711622 -210.572606) (xy 142.730913 -210.563701) (xy 142.738348 -210.556094) (xy 142.738602 -210.55584)
			(xy 142.756788 -210.535505) (xy 142.798011 -210.499772) (xy 142.843901 -210.470271) (xy 142.893524 -210.447605)
			(xy 142.945869 -210.432236) (xy 142.999869 -210.424475) (xy 143.027146 -210.424014) (xy 143.054397 -210.424459)
			(xy 143.108343 -210.432221) (xy 143.160635 -210.447581) (xy 143.210209 -210.470226) (xy 143.256056 -210.499696)
			(xy 143.297243 -210.535389) (xy 143.332932 -210.576581) (xy 143.362396 -210.622431) (xy 143.385035 -210.672008)
			(xy 143.400389 -210.724302) (xy 143.408144 -210.778249) (xy 143.408144 -210.832751) (xy 143.400389 -210.886698)
			(xy 143.385035 -210.938992) (xy 143.362396 -210.988569) (xy 143.332932 -211.034419) (xy 143.297243 -211.075611)
			(xy 143.256056 -211.111304) (xy 143.210209 -211.140774) (xy 143.160635 -211.163419) (xy 143.108343 -211.178779)
			(xy 143.054397 -211.186541) (xy 143.027146 -211.18703) (xy 143.000889 -211.186622) (xy 142.94887 -211.179429)
			(xy 142.898328 -211.165171) (xy 142.850218 -211.144118) (xy 142.805449 -211.116669) (xy 142.764866 -211.08334)
			(xy 142.74673 -211.064348) (xy 142.739618 -211.056474) (xy 142.719552 -211.047838) (xy 142.632938 -211.049362)
			(xy 142.622321 -211.050086) (xy 142.60303 -211.059015) (xy 142.5956 -211.066634) (xy 142.595346 -211.066888)
			(xy 142.57712 -211.087186) (xy 142.535907 -211.122925) (xy 142.490026 -211.152432) (xy 142.44041 -211.175105)
			(xy 142.388072 -211.190482) (xy 142.334077 -211.19825) (xy 142.306802 -211.198714) (xy 142.279549 -211.198239)
			(xy 142.225599 -211.190482) (xy 142.173302 -211.175127) (xy 142.123722 -211.152485) (xy 142.07787 -211.123017)
			(xy 142.036677 -211.087324) (xy 142.000984 -211.046132) (xy 141.971516 -211.000279) (xy 141.948874 -210.9507)
			(xy 141.933518 -210.898403) (xy 141.925761 -210.844453) (xy 140.097955 -210.844453) (xy 140.096802 -210.853101)
			(xy 140.090652 -210.877404) (xy 140.084895 -210.897727) (xy 140.069492 -210.937061) (xy 140.059918 -210.95589)
			(xy 140.057222 -210.961421) (xy 140.054269 -210.973362) (xy 140.054076 -210.979512) (xy 140.054076 -211.906104)
			(xy 140.05433 -211.917788) (xy 140.053846 -211.943897) (xy 140.045678 -211.995473) (xy 140.029544 -212.045137)
			(xy 140.005838 -212.091665) (xy 139.975146 -212.133911) (xy 139.957048 -212.152738) (xy 138.397234 -213.712552)
			(xy 139.125196 -213.712552) (xy 139.129267 -213.65693) (xy 139.141393 -213.602493) (xy 139.161316 -213.550402)
			(xy 139.188612 -213.501767) (xy 139.222698 -213.457624) (xy 139.262847 -213.418915) (xy 139.308205 -213.386464)
			(xy 139.357805 -213.360963) (xy 139.410589 -213.342956) (xy 139.465432 -213.332826) (xy 139.521166 -213.330789)
			(xy 139.576603 -213.336889) (xy 139.63056 -213.350995) (xy 139.681889 -213.372807) (xy 139.729495 -213.401861)
			(xy 139.772363 -213.437536) (xy 139.80958 -213.479073) (xy 139.82726 -213.505796) (xy 142.064484 -213.505796)
			(xy 142.068555 -213.450174) (xy 142.080681 -213.395737) (xy 142.100604 -213.343646) (xy 142.1279 -213.295011)
			(xy 142.161986 -213.250868) (xy 142.202135 -213.212159) (xy 142.247493 -213.179708) (xy 142.297093 -213.154207)
			(xy 142.349877 -213.1362) (xy 142.40472 -213.12607) (xy 142.460454 -213.124033) (xy 142.515891 -213.130133)
			(xy 142.569848 -213.144239) (xy 142.621177 -213.166051) (xy 142.668783 -213.195105) (xy 142.711651 -213.23078)
			(xy 142.748868 -213.272317) (xy 142.779641 -213.31883) (xy 142.803313 -213.369327) (xy 142.819381 -213.422734)
			(xy 142.827501 -213.47791) (xy 142.82801 -213.505796) (xy 142.827501 -213.533682) (xy 142.819381 -213.588858)
			(xy 142.803313 -213.642265) (xy 142.779641 -213.692762) (xy 142.748868 -213.739275) (xy 142.711651 -213.780812)
			(xy 142.668783 -213.816487) (xy 142.621177 -213.845541) (xy 142.569848 -213.867353) (xy 142.515891 -213.881459)
			(xy 142.460454 -213.887559) (xy 142.40472 -213.885522) (xy 142.349877 -213.875392) (xy 142.297093 -213.857385)
			(xy 142.247493 -213.831884) (xy 142.202135 -213.799433) (xy 142.161986 -213.760724) (xy 142.1279 -213.716581)
			(xy 142.100604 -213.667946) (xy 142.080681 -213.615855) (xy 142.068555 -213.561418) (xy 142.064484 -213.505796)
			(xy 139.82726 -213.505796) (xy 139.840353 -213.525586) (xy 139.864025 -213.576083) (xy 139.880093 -213.62949)
			(xy 139.888213 -213.684666) (xy 139.888722 -213.712552) (xy 139.888213 -213.740438) (xy 139.880093 -213.795614)
			(xy 139.864025 -213.849021) (xy 139.840353 -213.899518) (xy 139.80958 -213.946031) (xy 139.800752 -213.955884)
			(xy 144.949926 -213.955884) (xy 144.950412 -213.928633) (xy 144.958168 -213.874685) (xy 144.973523 -213.82239)
			(xy 144.996165 -213.772813) (xy 145.025631 -213.726963) (xy 145.061322 -213.685772) (xy 145.102513 -213.650081)
			(xy 145.148363 -213.620615) (xy 145.19794 -213.597973) (xy 145.250235 -213.582618) (xy 145.304183 -213.574862)
			(xy 145.358685 -213.574862) (xy 145.412633 -213.582618) (xy 145.464928 -213.597973) (xy 145.514505 -213.620615)
			(xy 145.560355 -213.650081) (xy 145.601546 -213.685772) (xy 145.637237 -213.726963) (xy 145.666703 -213.772813)
			(xy 145.689345 -213.82239) (xy 145.7047 -213.874685) (xy 145.712456 -213.928633) (xy 145.712942 -213.955884)
			(xy 145.712434 -213.984697) (xy 145.703781 -214.041669) (xy 145.686654 -214.096691) (xy 145.661445 -214.14851)
			(xy 145.628725 -214.195946) (xy 145.589241 -214.23792) (xy 145.566892 -214.256112) (xy 145.555627 -214.265392)
			(xy 145.538637 -214.289116) (xy 145.52905 -214.316677) (xy 145.52765 -214.345823) (xy 145.53455 -214.374176)
			(xy 145.549188 -214.399419) (xy 145.570368 -214.419492) (xy 145.583148 -214.426546) (xy 145.60623 -214.438854)
			(xy 145.649072 -214.46887) (xy 145.687409 -214.504461) (xy 145.720521 -214.544959) (xy 145.747786 -214.589602)
			(xy 145.768693 -214.637554) (xy 145.782848 -214.687913) (xy 145.789987 -214.739734) (xy 145.790412 -214.76589)
			(xy 145.789926 -214.793141) (xy 145.78217 -214.847089) (xy 145.766815 -214.899384) (xy 145.744173 -214.948961)
			(xy 145.714707 -214.994811) (xy 145.679016 -215.036002) (xy 145.637825 -215.071693) (xy 145.591975 -215.101159)
			(xy 145.542398 -215.123801) (xy 145.490103 -215.139156) (xy 145.436155 -215.146912) (xy 145.381653 -215.146912)
			(xy 145.327705 -215.139156) (xy 145.27541 -215.123801) (xy 145.225833 -215.101159) (xy 145.179983 -215.071693)
			(xy 145.138792 -215.036002) (xy 145.103101 -214.994811) (xy 145.073635 -214.948961) (xy 145.050993 -214.899384)
			(xy 145.035638 -214.847089) (xy 145.027882 -214.793141) (xy 145.027396 -214.76589) (xy 145.027909 -214.737077)
			(xy 145.036565 -214.680106) (xy 145.053692 -214.625085) (xy 145.0789 -214.573267) (xy 145.111618 -214.525831)
			(xy 145.151098 -214.483856) (xy 145.173446 -214.465662) (xy 145.184624 -214.456288) (xy 145.201607 -214.432585)
			(xy 145.211195 -214.405048) (xy 145.212605 -214.375923) (xy 145.205722 -214.347588) (xy 145.191109 -214.322356)
			(xy 145.169956 -214.302285) (xy 145.15719 -214.295228) (xy 145.134124 -214.282891) (xy 145.091286 -214.252876)
			(xy 145.052951 -214.217287) (xy 145.01984 -214.176794) (xy 144.992574 -214.132155) (xy 144.971664 -214.084209)
			(xy 144.957503 -214.033855) (xy 144.950356 -213.982038) (xy 144.949926 -213.955884) (xy 139.800752 -213.955884)
			(xy 139.772363 -213.987568) (xy 139.729495 -214.023243) (xy 139.681889 -214.052297) (xy 139.63056 -214.074109)
			(xy 139.576603 -214.088215) (xy 139.521166 -214.094315) (xy 139.465432 -214.092278) (xy 139.410589 -214.082148)
			(xy 139.357805 -214.064141) (xy 139.308205 -214.03864) (xy 139.262847 -214.006189) (xy 139.222698 -213.96748)
			(xy 139.188612 -213.923337) (xy 139.161316 -213.874702) (xy 139.141393 -213.822611) (xy 139.129267 -213.768174)
			(xy 139.125196 -213.712552) (xy 138.397234 -213.712552) (xy 137.46099 -214.648796) (xy 137.454133 -214.65619)
			(xy 137.446383 -214.674789) (xy 137.446004 -214.684864) (xy 137.446004 -214.982806) (xy 138.297666 -214.982806)
			(xy 138.298108 -214.95645) (xy 138.305352 -214.904238) (xy 138.319716 -214.853521) (xy 138.340927 -214.805266)
			(xy 138.368581 -214.76039) (xy 138.40215 -214.71975) (xy 138.440996 -214.684119) (xy 138.484378 -214.654177)
			(xy 138.507724 -214.641938) (xy 138.520794 -214.634782) (xy 138.542412 -214.614295) (xy 138.5572 -214.588443)
			(xy 138.563901 -214.559423) (xy 138.561945 -214.529704) (xy 138.551498 -214.501813) (xy 138.533448 -214.478122)
			(xy 138.521694 -214.468964) (xy 138.501067 -214.453536) (xy 138.463757 -214.418023) (xy 138.431567 -214.37781)
			(xy 138.405084 -214.33363) (xy 138.38479 -214.286287) (xy 138.371054 -214.236642) (xy 138.364127 -214.185601)
			(xy 138.363706 -214.159846) (xy 138.364192 -214.132595) (xy 138.371948 -214.078647) (xy 138.387303 -214.026352)
			(xy 138.409945 -213.976775) (xy 138.439411 -213.930925) (xy 138.475102 -213.889734) (xy 138.516293 -213.854043)
			(xy 138.562143 -213.824577) (xy 138.61172 -213.801935) (xy 138.664015 -213.78658) (xy 138.717963 -213.778824)
			(xy 138.772465 -213.778824) (xy 138.826413 -213.78658) (xy 138.878708 -213.801935) (xy 138.928285 -213.824577)
			(xy 138.974135 -213.854043) (xy 139.015326 -213.889734) (xy 139.051017 -213.930925) (xy 139.080483 -213.976775)
			(xy 139.103125 -214.026352) (xy 139.11848 -214.078647) (xy 139.126236 -214.132595) (xy 139.126722 -214.159846)
			(xy 139.126247 -214.186201) (xy 139.119009 -214.238412) (xy 139.104651 -214.289128) (xy 139.083445 -214.337384)
			(xy 139.055796 -214.38226) (xy 139.02223 -214.4229) (xy 138.983388 -214.458532) (xy 138.940009 -214.488474)
			(xy 138.916664 -214.500714) (xy 138.90355 -214.507796) (xy 138.88193 -214.528299) (xy 138.867143 -214.554167)
			(xy 138.865997 -214.559134) (xy 144.141442 -214.559134) (xy 144.145513 -214.503512) (xy 144.157639 -214.449075)
			(xy 144.177562 -214.396984) (xy 144.204858 -214.348349) (xy 144.238944 -214.304206) (xy 144.279093 -214.265497)
			(xy 144.324451 -214.233046) (xy 144.374051 -214.207545) (xy 144.426835 -214.189538) (xy 144.481678 -214.179408)
			(xy 144.537412 -214.177371) (xy 144.592849 -214.183471) (xy 144.646806 -214.197577) (xy 144.698135 -214.219389)
			(xy 144.745741 -214.248443) (xy 144.788609 -214.284118) (xy 144.825826 -214.325655) (xy 144.856599 -214.372168)
			(xy 144.880271 -214.422665) (xy 144.896339 -214.476072) (xy 144.904459 -214.531248) (xy 144.904968 -214.559134)
			(xy 144.904459 -214.58702) (xy 144.896339 -214.642196) (xy 144.880271 -214.695603) (xy 144.856599 -214.7461)
			(xy 144.825826 -214.792613) (xy 144.788609 -214.83415) (xy 144.745741 -214.869825) (xy 144.698135 -214.898879)
			(xy 144.646806 -214.920691) (xy 144.592849 -214.934797) (xy 144.537412 -214.940897) (xy 144.481678 -214.93886)
			(xy 144.426835 -214.92873) (xy 144.374051 -214.910723) (xy 144.324451 -214.885222) (xy 144.279093 -214.852771)
			(xy 144.238944 -214.814062) (xy 144.204858 -214.769919) (xy 144.177562 -214.721284) (xy 144.157639 -214.669193)
			(xy 144.145513 -214.614756) (xy 144.141442 -214.559134) (xy 138.865997 -214.559134) (xy 138.860447 -214.583201)
			(xy 138.862412 -214.612932) (xy 138.87287 -214.640832) (xy 138.890933 -214.664529) (xy 138.902694 -214.673688)
			(xy 138.923295 -214.689149) (xy 138.960607 -214.724656) (xy 138.992799 -214.764863) (xy 139.019286 -214.809037)
			(xy 139.039584 -214.856375) (xy 139.053325 -214.906015) (xy 139.060258 -214.957053) (xy 139.060293 -214.959184)
			(xy 141.653766 -214.959184) (xy 141.657837 -214.903562) (xy 141.669963 -214.849125) (xy 141.689886 -214.797034)
			(xy 141.717182 -214.748399) (xy 141.751268 -214.704256) (xy 141.791417 -214.665547) (xy 141.836775 -214.633096)
			(xy 141.886375 -214.607595) (xy 141.939159 -214.589588) (xy 141.994002 -214.579458) (xy 142.049736 -214.577421)
			(xy 142.105173 -214.583521) (xy 142.15913 -214.597627) (xy 142.210459 -214.619439) (xy 142.258065 -214.648493)
			(xy 142.300933 -214.684168) (xy 142.33815 -214.725705) (xy 142.368923 -214.772218) (xy 142.392595 -214.822715)
			(xy 142.408663 -214.876122) (xy 142.416783 -214.931298) (xy 142.417292 -214.959184) (xy 142.416783 -214.98707)
			(xy 142.408663 -215.042246) (xy 142.392595 -215.095653) (xy 142.368923 -215.14615) (xy 142.33815 -215.192663)
			(xy 142.300933 -215.2342) (xy 142.258065 -215.269875) (xy 142.210459 -215.298929) (xy 142.15913 -215.320741)
			(xy 142.105173 -215.334847) (xy 142.049736 -215.340947) (xy 141.994002 -215.33891) (xy 141.939159 -215.32878)
			(xy 141.886375 -215.310773) (xy 141.836775 -215.285272) (xy 141.791417 -215.252821) (xy 141.751268 -215.214112)
			(xy 141.717182 -215.169969) (xy 141.689886 -215.121334) (xy 141.669963 -215.069243) (xy 141.657837 -215.014806)
			(xy 141.653766 -214.959184) (xy 139.060293 -214.959184) (xy 139.060682 -214.982806) (xy 139.060196 -215.010057)
			(xy 139.05244 -215.064005) (xy 139.037085 -215.1163) (xy 139.014443 -215.165877) (xy 138.984977 -215.211727)
			(xy 138.949286 -215.252918) (xy 138.908095 -215.288609) (xy 138.862245 -215.318075) (xy 138.812668 -215.340717)
			(xy 138.760373 -215.356072) (xy 138.706425 -215.363828) (xy 138.651923 -215.363828) (xy 138.597975 -215.356072)
			(xy 138.54568 -215.340717) (xy 138.496103 -215.318075) (xy 138.450253 -215.288609) (xy 138.409062 -215.252918)
			(xy 138.373371 -215.211727) (xy 138.343905 -215.165877) (xy 138.321263 -215.1163) (xy 138.305908 -215.064005)
			(xy 138.298152 -215.010057) (xy 138.297666 -214.982806) (xy 137.446004 -214.982806) (xy 137.446004 -215.981026)
			(xy 138.10818 -215.981026) (xy 138.112251 -215.925404) (xy 138.124377 -215.870967) (xy 138.1443 -215.818876)
			(xy 138.171596 -215.770241) (xy 138.205682 -215.726098) (xy 138.245831 -215.687389) (xy 138.291189 -215.654938)
			(xy 138.340789 -215.629437) (xy 138.393573 -215.61143) (xy 138.448416 -215.6013) (xy 138.50415 -215.599263)
			(xy 138.559587 -215.605363) (xy 138.613544 -215.619469) (xy 138.664873 -215.641281) (xy 138.712479 -215.670335)
			(xy 138.755347 -215.70601) (xy 138.792564 -215.747547) (xy 138.823337 -215.79406) (xy 138.847009 -215.844557)
			(xy 138.863077 -215.897964) (xy 138.871197 -215.95314) (xy 138.871706 -215.981026) (xy 138.871335 -216.001346)
			(xy 138.978892 -216.001346) (xy 138.982963 -215.945724) (xy 138.995089 -215.891287) (xy 139.015012 -215.839196)
			(xy 139.042308 -215.790561) (xy 139.076394 -215.746418) (xy 139.116543 -215.707709) (xy 139.161901 -215.675258)
			(xy 139.211501 -215.649757) (xy 139.264285 -215.63175) (xy 139.319128 -215.62162) (xy 139.374862 -215.619583)
			(xy 139.430299 -215.625683) (xy 139.484256 -215.639789) (xy 139.535585 -215.661601) (xy 139.583191 -215.690655)
			(xy 139.626059 -215.72633) (xy 139.663276 -215.767867) (xy 139.694049 -215.81438) (xy 139.717721 -215.864877)
			(xy 139.733789 -215.918284) (xy 139.741909 -215.97346) (xy 139.742418 -216.001346) (xy 139.741909 -216.029232)
			(xy 139.733789 -216.084408) (xy 139.717721 -216.137815) (xy 139.694049 -216.188312) (xy 139.663276 -216.234825)
			(xy 139.626059 -216.276362) (xy 139.583191 -216.312037) (xy 139.535585 -216.341091) (xy 139.484256 -216.362903)
			(xy 139.430299 -216.377009) (xy 139.374862 -216.383109) (xy 139.319128 -216.381072) (xy 139.264285 -216.370942)
			(xy 139.211501 -216.352935) (xy 139.161901 -216.327434) (xy 139.116543 -216.294983) (xy 139.076394 -216.256274)
			(xy 139.042308 -216.212131) (xy 139.015012 -216.163496) (xy 138.995089 -216.111405) (xy 138.982963 -216.056968)
			(xy 138.978892 -216.001346) (xy 138.871335 -216.001346) (xy 138.871197 -216.008912) (xy 138.863077 -216.064088)
			(xy 138.847009 -216.117495) (xy 138.823337 -216.167992) (xy 138.792564 -216.214505) (xy 138.755347 -216.256042)
			(xy 138.712479 -216.291717) (xy 138.664873 -216.320771) (xy 138.613544 -216.342583) (xy 138.559587 -216.356689)
			(xy 138.50415 -216.362789) (xy 138.448416 -216.360752) (xy 138.393573 -216.350622) (xy 138.340789 -216.332615)
			(xy 138.291189 -216.307114) (xy 138.245831 -216.274663) (xy 138.205682 -216.235954) (xy 138.171596 -216.191811)
			(xy 138.1443 -216.143176) (xy 138.124377 -216.091085) (xy 138.112251 -216.036648) (xy 138.10818 -215.981026)
			(xy 137.446004 -215.981026) (xy 137.446004 -216.862152) (xy 137.45357 -216.871328) (xy 137.474769 -216.882041)
			(xy 137.486644 -216.882726) (xy 144.17548 -216.882726) (xy 144.183608 -216.881964) (xy 144.184116 -216.881964)
			(xy 144.191635 -216.880364) (xy 144.205323 -216.873387) (xy 144.21104 -216.868248) (xy 146.001994 -215.077294)
			(xy 146.007189 -215.071616) (xy 146.014173 -215.057911) (xy 146.01571 -215.05037) (xy 146.01571 -215.049862)
			(xy 146.016472 -215.041734) (xy 146.016472 -211.099654) (xy 146.016083 -211.090161) (xy 146.009196 -211.072468)
			(xy 145.996374 -211.058465) (xy 145.988024 -211.053934) (xy 145.905728 -211.013802) (xy 145.897092 -211.010125)
			(xy 145.8784 -211.008595) (xy 145.860393 -211.013838) (xy 145.852642 -211.019136) (xy 145.852388 -211.01939)
			(xy 145.832233 -211.034574) (xy 145.788682 -211.060064) (xy 145.74215 -211.079589) (xy 145.693449 -211.092807)
			(xy 145.643431 -211.099488) (xy 145.6182 -211.099908) (xy 145.590949 -211.099422) (xy 145.537001 -211.091666)
			(xy 145.484706 -211.076311) (xy 145.435129 -211.053669) (xy 145.389279 -211.024203) (xy 145.348088 -210.988512)
			(xy 145.312397 -210.947321) (xy 145.282931 -210.901471) (xy 145.260289 -210.851894) (xy 145.244934 -210.799599)
			(xy 145.237178 -210.745651) (xy 145.237178 -210.691149) (xy 145.244934 -210.637201) (xy 145.260289 -210.584906)
			(xy 145.282931 -210.535329) (xy 145.312397 -210.489479) (xy 145.348088 -210.448288) (xy 145.389279 -210.412597)
			(xy 145.435129 -210.383131) (xy 145.484706 -210.360489) (xy 145.537001 -210.345134) (xy 145.590949 -210.337378)
			(xy 145.6182 -210.336892) (xy 145.643405 -210.33733) (xy 145.693369 -210.344033) (xy 145.742016 -210.357257)
			(xy 145.788497 -210.37677) (xy 145.832005 -210.402234) (xy 145.852134 -210.41741) (xy 145.852642 -210.41741)
			(xy 145.852642 -210.417664) (xy 145.860323 -210.423113) (xy 145.878376 -210.428427) (xy 145.897127 -210.426831)
			(xy 145.905728 -210.422998) (xy 145.988024 -210.382866) (xy 145.996393 -210.378353) (xy 146.009256 -210.364368)
			(xy 146.016114 -210.346648) (xy 146.016472 -210.337146) (xy 146.016472 -199.375268) (xy 146.016142 -199.366663)
			(xy 146.010436 -199.350427) (xy 146.005296 -199.343518) (xy 146.004788 -199.34301) (xy 146.00174 -199.339454)
			(xy 145.838672 -199.176386) (xy 145.831384 -199.169692) (xy 145.813185 -199.161971) (xy 145.793418 -199.161734)
			(xy 145.784062 -199.164956) (xy 145.69567 -199.20331) (xy 145.688735 -199.206566) (xy 145.677102 -199.216522)
			(xy 145.67281 -199.222868) (xy 145.669 -199.229218) (xy 145.664936 -199.243696) (xy 145.66519 -199.25157)
			(xy 145.665444 -199.264778) (xy 145.664983 -199.292034) (xy 145.657227 -199.345993) (xy 145.641872 -199.398298)
			(xy 145.619229 -199.447885) (xy 145.589759 -199.493745) (xy 145.554062 -199.534945) (xy 145.512865 -199.570644)
			(xy 145.467007 -199.600117) (xy 145.417421 -199.622763) (xy 145.365117 -199.638122) (xy 145.311159 -199.645881)
			(xy 145.256646 -199.645881) (xy 145.202689 -199.638123) (xy 145.150384 -199.622765) (xy 145.100798 -199.60012)
			(xy 145.054939 -199.570647) (xy 145.013742 -199.534948) (xy 144.978044 -199.49375) (xy 144.948574 -199.44789)
			(xy 144.92593 -199.398303) (xy 144.910574 -199.345998) (xy 144.902818 -199.29204) (xy 144.90282 -199.237527)
			(xy 144.910581 -199.18357) (xy 144.925942 -199.131266) (xy 144.94859 -199.081681) (xy 144.978064 -199.035824)
			(xy 145.013765 -198.994628) (xy 145.054966 -198.958933) (xy 145.100827 -198.929464) (xy 145.150415 -198.906823)
			(xy 145.202721 -198.89147) (xy 145.25668 -198.883716) (xy 145.283936 -198.88327) (xy 145.297144 -198.883524)
			(xy 145.297398 -198.883524) (xy 145.304968 -198.88347) (xy 145.319555 -198.879456) (xy 145.3261 -198.87565)
			(xy 145.33245 -198.87184) (xy 145.337276 -198.865998) (xy 145.339624 -198.863143) (xy 145.343579 -198.856898)
			(xy 145.34515 -198.853552) (xy 145.377916 -198.778114) (xy 145.383758 -198.764652) (xy 145.386927 -198.75529)
			(xy 145.38666 -198.735546) (xy 145.378977 -198.717356) (xy 145.372328 -198.710042) (xy 145.160746 -198.49846)
			(xy 145.157013 -198.494943) (xy 145.148435 -198.489322) (xy 145.143728 -198.487284) (xy 145.135092 -198.483728)
			(xy 142.780258 -198.483728) (xy 142.77467 -198.483982) (xy 142.761462 -198.487284) (xy 142.756253 -198.48953)
			(xy 142.746902 -198.495944) (xy 142.74292 -198.499984) (xy 142.689072 -198.566278) (xy 142.686425 -198.570185)
			(xy 142.682457 -198.578748) (xy 142.681198 -198.583296) (xy 142.678658 -198.59371) (xy 142.680944 -198.60514)
			(xy 142.684411 -198.623678) (xy 142.6881 -198.661212) (xy 142.68831 -198.68007) (xy 142.68831 -198.685404)
			(xy 142.687482 -198.712875) (xy 142.678899 -198.767158) (xy 142.662605 -198.819645) (xy 142.651226 -198.844662)
			(xy 142.650972 -198.845424) (xy 142.64832 -198.851543) (xy 142.646015 -198.864673) (xy 142.6464 -198.871332)
			(xy 142.647112 -198.87732) (xy 142.650954 -198.888746) (xy 142.65402 -198.893938) (xy 142.708376 -198.968614)
			(xy 142.712611 -198.974093) (xy 142.723424 -198.982735) (xy 142.729712 -198.985632) (xy 142.736014 -198.988078)
			(xy 142.749405 -198.989886) (xy 142.756128 -198.989188) (xy 142.756382 -198.989188) (xy 142.759684 -198.98868)
			(xy 142.771574 -198.98732) (xy 142.795468 -198.985922) (xy 142.807436 -198.985886) (xy 142.808198 -198.985886)
			(xy 142.83538 -198.986474) (xy 142.889165 -198.994403) (xy 142.941281 -199.009887) (xy 142.99067 -199.032613)
			(xy 143.036334 -199.06212) (xy 143.077346 -199.097811) (xy 143.112876 -199.138962) (xy 143.142204 -199.18474)
			(xy 143.164736 -199.234218) (xy 143.180017 -199.286394) (xy 143.187736 -199.34021) (xy 143.188182 -199.367394)
			(xy 143.187719 -199.394646) (xy 143.179963 -199.448597) (xy 143.164607 -199.500894) (xy 143.141964 -199.550473)
			(xy 143.112496 -199.596325) (xy 143.076802 -199.637516) (xy 143.035609 -199.673208) (xy 142.989755 -199.702674)
			(xy 142.940175 -199.725314) (xy 142.887877 -199.740667) (xy 142.833926 -199.74842) (xy 142.806674 -199.748902)
			(xy 142.779652 -199.748431) (xy 142.72615 -199.740802) (xy 142.674258 -199.725701) (xy 142.625017 -199.70343)
			(xy 142.57941 -199.674435) (xy 142.538351 -199.639295) (xy 142.50266 -199.598713) (xy 142.473051 -199.553501)
			(xy 142.450118 -199.504565) (xy 142.434318 -199.452882) (xy 142.425969 -199.399487) (xy 142.425166 -199.372474)
			(xy 142.425166 -199.36714) (xy 142.425676 -199.338856) (xy 142.434023 -199.282908) (xy 142.450538 -199.228806)
			(xy 142.46225 -199.203056) (xy 142.46352 -199.200516) (xy 142.465693 -199.194808) (xy 142.467498 -199.182732)
			(xy 142.467076 -199.17664) (xy 142.466247 -199.169795) (xy 142.461341 -199.156915) (xy 142.457424 -199.15124)
			(xy 142.4051 -199.079358) (xy 142.400862 -199.073883) (xy 142.390046 -199.06525) (xy 142.383764 -199.06234)
			(xy 142.377463 -199.059893) (xy 142.364072 -199.05809) (xy 142.357348 -199.058784) (xy 142.357094 -199.058784)
			(xy 142.353792 -199.059292) (xy 142.336774 -199.06107) (xy 142.336266 -199.06107) (xy 142.31493 -199.062086)
			(xy 142.30858 -199.062086) (xy 142.306802 -199.062086) (xy 142.294128 -199.062001) (xy 142.268833 -199.060352)
			(xy 142.256256 -199.058784) (xy 142.255494 -199.058784) (xy 142.248833 -199.058165) (xy 142.235581 -199.059955)
			(xy 142.229332 -199.06234) (xy 142.22349 -199.06488) (xy 142.212568 -199.073516) (xy 142.209774 -199.07758)
			(xy 142.155926 -199.15124) (xy 142.152035 -199.156928) (xy 142.147126 -199.169802) (xy 142.146274 -199.17664)
			(xy 142.145881 -199.183502) (xy 142.148327 -199.197021) (xy 142.1511 -199.20331) (xy 142.16271 -199.228827)
			(xy 142.179156 -199.28242) (xy 142.187583 -199.337842) (xy 142.188184 -199.36587) (xy 142.188184 -199.372474)
			(xy 142.187355 -199.399488) (xy 142.179017 -199.452886) (xy 142.163227 -199.504574) (xy 142.1403 -199.553515)
			(xy 142.110696 -199.598731) (xy 142.075008 -199.639317) (xy 142.033949 -199.67446) (xy 141.988341 -199.703457)
			(xy 141.939097 -199.725728) (xy 141.887204 -199.740826) (xy 141.833699 -199.74845) (xy 141.806676 -199.748902)
			(xy 141.779426 -199.748415) (xy 141.725482 -199.740655) (xy 141.673191 -199.725298) (xy 141.623618 -199.702656)
			(xy 141.577771 -199.67319) (xy 141.536584 -199.637499) (xy 141.500896 -199.59631) (xy 141.471432 -199.550461)
			(xy 141.448793 -199.500887) (xy 141.433439 -199.448595) (xy 141.425684 -199.39465) (xy 141.425684 -199.34015)
			(xy 141.433439 -199.286205) (xy 141.448793 -199.233913) (xy 141.471432 -199.184339) (xy 141.500896 -199.13849)
			(xy 141.536584 -199.097301) (xy 141.577771 -199.06161) (xy 141.623618 -199.032144) (xy 141.673191 -199.009502)
			(xy 141.725482 -198.994145) (xy 141.779426 -198.986385) (xy 141.806676 -198.985886) (xy 141.80693 -198.985886)
			(xy 141.819541 -198.98598) (xy 141.844707 -198.987636) (xy 141.857222 -198.989188) (xy 141.857984 -198.989188)
			(xy 141.864643 -198.989797) (xy 141.877887 -198.987988) (xy 141.884146 -198.985632) (xy 141.889988 -198.983092)
			(xy 141.90091 -198.974456) (xy 141.903704 -198.970392) (xy 141.957552 -198.896732) (xy 141.961436 -198.891041)
			(xy 141.96633 -198.878166) (xy 141.967204 -198.871332) (xy 141.967592 -198.864471) (xy 141.965139 -198.850955)
			(xy 141.962378 -198.844662) (xy 141.950676 -198.818908) (xy 141.934153 -198.764808) (xy 141.925802 -198.708861)
			(xy 141.925294 -198.680578) (xy 141.925294 -198.66483) (xy 141.925548 -198.660004) (xy 141.926564 -198.64832)
			(xy 141.926564 -198.647812) (xy 141.930374 -198.617332) (xy 141.93266 -198.604886) (xy 141.933676 -198.599298)
			(xy 141.934946 -198.59371) (xy 141.932406 -198.583296) (xy 141.931149 -198.578747) (xy 141.927184 -198.570183)
			(xy 141.924532 -198.566278) (xy 141.870684 -198.499984) (xy 141.866728 -198.495914) (xy 141.857368 -198.489497)
			(xy 141.852142 -198.487284) (xy 141.838934 -198.483982) (xy 141.833346 -198.483728) (xy 139.984988 -198.483728)
			(xy 139.975078 -198.4842) (xy 139.956741 -198.491721) (xy 139.942627 -198.505636) (xy 139.934846 -198.523865)
			(xy 139.934188 -198.533766) (xy 139.933254 -198.562618) (xy 139.924851 -198.619731) (xy 139.90914 -198.675279)
			(xy 139.886385 -198.728333) (xy 139.856967 -198.778002) (xy 139.821379 -198.823455) (xy 139.780218 -198.86393)
			(xy 139.734173 -198.898748) (xy 139.684016 -198.927326) (xy 139.630587 -198.949185) (xy 139.574782 -198.963959)
			(xy 139.517536 -198.9714) (xy 139.488672 -198.971916) (xy 139.488418 -198.971916) (xy 139.459136 -198.971436)
			(xy 139.401079 -198.963738) (xy 139.344528 -198.948511) (xy 139.290456 -198.926017) (xy 139.264898 -198.911718)
			(xy 139.259021 -198.908572) (xy 139.246159 -198.905091) (xy 139.239498 -198.90486) (xy 138.674602 -198.90486)
			(xy 138.671554 -198.905368) (xy 138.654984 -198.907207) (xy 138.621663 -198.908355) (xy 138.605006 -198.907654)
			(xy 138.594592 -198.906638) (xy 138.58476 -198.905814) (xy 138.565192 -198.903272) (xy 138.555476 -198.901558)
			(xy 138.527208 -198.895799) (xy 138.472707 -198.876895) (xy 138.421676 -198.849995) (xy 138.375281 -198.815713)
			(xy 138.354562 -198.79564) (xy 138.351514 -198.792592) (xy 138.347244 -198.789067) (xy 138.337502 -198.783808)
			(xy 138.33221 -198.782178) (xy 138.326368 -198.7804) (xy 138.31316 -198.7804) (xy 138.263884 -198.792592)
			(xy 138.221466 -198.803006) (xy 138.215042 -198.804832) (xy 138.203346 -198.81127) (xy 138.198352 -198.815706)
			(xy 138.194034 -198.820024) (xy 138.187176 -198.830946) (xy 138.185144 -198.83755) (xy 138.176317 -198.864866)
			(xy 138.151609 -198.916681) (xy 138.119413 -198.964206) (xy 138.100308 -198.985632) (xy 138.093958 -198.992744)
			(xy 138.090656 -199.001126) (xy 138.08915 -199.004974) (xy 138.087239 -199.013014) (xy 138.086846 -199.017128)
			(xy 138.086084 -199.052434) (xy 138.086084 -199.052942) (xy 138.085576 -199.088756) (xy 138.085709 -199.092773)
			(xy 138.08712 -199.100684) (xy 138.08837 -199.104504) (xy 138.091418 -199.11314) (xy 138.097514 -199.120506)
			(xy 138.114552 -199.141282) (xy 138.143239 -199.186714) (xy 138.165269 -199.23572) (xy 138.180207 -199.287332)
			(xy 138.187759 -199.340529) (xy 138.188192 -199.367394) (xy 138.187806 -199.389051) (xy 139.706084 -199.389051)
			(xy 139.706084 -199.334549) (xy 139.71384 -199.280603) (xy 139.729195 -199.228309) (xy 139.751835 -199.178733)
			(xy 139.781301 -199.132884) (xy 139.816991 -199.091694) (xy 139.85818 -199.056003) (xy 139.90403 -199.026537)
			(xy 139.953605 -199.003896) (xy 140.005899 -198.988541) (xy 140.059845 -198.980784) (xy 140.087096 -198.980298)
			(xy 140.113832 -198.980702) (xy 140.166781 -198.988169) (xy 140.218168 -199.002958) (xy 140.266986 -199.024779)
			(xy 140.312277 -199.053204) (xy 140.353155 -199.087676) (xy 140.371322 -199.107298) (xy 140.378838 -199.11496)
			(xy 140.398443 -199.123645) (xy 140.409168 -199.124062) (xy 140.484606 -199.124062) (xy 140.495301 -199.123524)
			(xy 140.514856 -199.114848) (xy 140.522452 -199.107298) (xy 140.540622 -199.087683) (xy 140.581506 -199.053225)
			(xy 140.6268 -199.024812) (xy 140.675616 -199.003) (xy 140.727 -198.988215) (xy 140.779944 -198.980748)
			(xy 140.806678 -198.980298) (xy 140.833932 -198.980748) (xy 140.887886 -198.988502) (xy 140.940188 -199.003857)
			(xy 140.989771 -199.026498) (xy 141.035628 -199.055966) (xy 141.076824 -199.09166) (xy 141.112521 -199.132854)
			(xy 141.141991 -199.178709) (xy 141.164636 -199.228292) (xy 141.179993 -199.280592) (xy 141.187751 -199.334546)
			(xy 141.187751 -199.389054) (xy 141.179993 -199.443008) (xy 141.164636 -199.495308) (xy 141.141991 -199.544891)
			(xy 141.112521 -199.590746) (xy 141.076824 -199.63194) (xy 141.035628 -199.667634) (xy 140.989771 -199.697102)
			(xy 140.940188 -199.719743) (xy 140.887886 -199.735098) (xy 140.833932 -199.742852) (xy 140.806678 -199.743314)
			(xy 140.779944 -199.742856) (xy 140.726997 -199.735399) (xy 140.675612 -199.72062) (xy 140.626794 -199.69881)
			(xy 140.581501 -199.670394) (xy 140.54062 -199.635931) (xy 140.522452 -199.616314) (xy 140.514944 -199.608643)
			(xy 140.495333 -199.599962) (xy 140.484606 -199.59955) (xy 140.409168 -199.59955) (xy 140.398477 -199.600125)
			(xy 140.378922 -199.608774) (xy 140.371322 -199.616314) (xy 140.353167 -199.635944) (xy 140.31228 -199.6704)
			(xy 140.266983 -199.698811) (xy 140.218163 -199.720621) (xy 140.166777 -199.735402) (xy 140.113831 -199.742865)
			(xy 140.087096 -199.743314) (xy 140.059845 -199.742816) (xy 140.005899 -199.735059) (xy 139.953605 -199.719704)
			(xy 139.90403 -199.697063) (xy 139.85818 -199.667597) (xy 139.816991 -199.631906) (xy 139.781301 -199.590716)
			(xy 139.751835 -199.544867) (xy 139.729195 -199.495291) (xy 139.71384 -199.442997) (xy 139.706084 -199.389051)
			(xy 138.187806 -199.389051) (xy 138.187706 -199.394645) (xy 138.17995 -199.448593) (xy 138.164595 -199.500888)
			(xy 138.141953 -199.550465) (xy 138.112487 -199.596315) (xy 138.076796 -199.637506) (xy 138.035605 -199.673197)
			(xy 137.989755 -199.702663) (xy 137.940178 -199.725305) (xy 137.887883 -199.74066) (xy 137.833935 -199.748416)
			(xy 137.779433 -199.748416) (xy 137.725485 -199.74066) (xy 137.67319 -199.725305) (xy 137.623613 -199.702663)
			(xy 137.577763 -199.673197) (xy 137.536572 -199.637506) (xy 137.500881 -199.596315) (xy 137.471415 -199.550465)
			(xy 137.448773 -199.500888) (xy 137.433418 -199.448593) (xy 137.425662 -199.394645) (xy 137.425176 -199.367394)
			(xy 137.425176 -199.36714) (xy 137.425724 -199.338713) (xy 137.434199 -199.282494) (xy 137.450907 -199.228151)
			(xy 137.475481 -199.176881) (xy 137.507379 -199.129818) (xy 137.526268 -199.108568) (xy 137.529824 -199.105012)
			(xy 137.532872 -199.101456) (xy 137.536174 -199.093074) (xy 137.536682 -199.092058) (xy 137.537894 -199.088548)
			(xy 137.539425 -199.081281) (xy 137.53973 -199.07758) (xy 137.540492 -199.041766) (xy 137.540492 -199.041258)
			(xy 137.541254 -199.00773) (xy 137.541284 -199.003076) (xy 137.539872 -198.993877) (xy 137.53846 -198.989442)
			(xy 137.535412 -198.98106) (xy 137.529316 -198.973694) (xy 137.52195 -198.964804) (xy 137.515854 -198.95693)
			(xy 137.512044 -198.95185) (xy 137.506964 -198.944992) (xy 137.503154 -198.94169) (xy 137.493248 -198.934832)
			(xy 137.471404 -198.923402) (xy 137.466241 -198.921082) (xy 137.455217 -198.918525) (xy 137.44956 -198.918322)
			(xy 137.390632 -198.918322) (xy 137.38505 -198.918466) (xy 137.374154 -198.920901) (xy 137.369042 -198.923148)
			(xy 137.34415 -198.936356) (xy 137.339578 -198.939658) (xy 137.332974 -198.945246) (xy 137.329418 -198.950072)
			(xy 137.313988 -198.970731) (xy 137.278459 -199.008101) (xy 137.23822 -199.040344) (xy 137.194003 -199.066872)
			(xy 137.146616 -199.087201) (xy 137.096922 -199.100961) (xy 137.045828 -199.107901) (xy 137.020046 -199.108314)
			(xy 136.992791 -199.107854) (xy 136.938835 -199.100102) (xy 136.886531 -199.08475) (xy 136.836945 -199.06211)
			(xy 136.791085 -199.032644) (xy 136.749887 -198.99695) (xy 136.714187 -198.955756) (xy 136.684715 -198.909901)
			(xy 136.662068 -198.860318) (xy 136.646709 -198.808016) (xy 136.63895 -198.754061) (xy 136.638538 -198.726806)
			(xy 136.639055 -198.698435) (xy 136.647469 -198.642319) (xy 136.655302 -198.615046) (xy 136.655302 -198.614792)
			(xy 136.656318 -198.611744) (xy 136.65735 -198.606726) (xy 136.657615 -198.596486) (xy 136.656826 -198.591424)
			(xy 136.654794 -198.57974) (xy 136.597136 -198.50227) (xy 136.589581 -198.494036) (xy 136.569428 -198.484434)
			(xy 136.558274 -198.483728) (xy 135.703818 -198.483728) (xy 135.692376 -198.484425) (xy 135.671799 -198.494454)
			(xy 135.664194 -198.503032) (xy 135.656574 -198.513192) (xy 135.656574 -198.5137) (xy 135.61441 -198.570088)
			(xy 135.611051 -198.574967) (xy 135.606431 -198.585871) (xy 135.605266 -198.591678) (xy 135.603996 -198.599298)
			(xy 135.605774 -198.61149) (xy 135.60679 -198.614792) (xy 135.60679 -198.6153) (xy 135.614585 -198.642516)
			(xy 135.622997 -198.6985) (xy 135.623554 -198.726806) (xy 135.623068 -198.754057) (xy 135.615312 -198.808005)
			(xy 135.599957 -198.8603) (xy 135.577315 -198.909877) (xy 135.547849 -198.955727) (xy 135.512158 -198.996918)
			(xy 135.470967 -199.032609) (xy 135.425117 -199.062075) (xy 135.37554 -199.084717) (xy 135.323245 -199.100072)
			(xy 135.269297 -199.107828) (xy 135.214795 -199.107828) (xy 135.160847 -199.100072) (xy 135.108552 -199.084717)
			(xy 135.058975 -199.062075) (xy 135.013125 -199.032609) (xy 134.971934 -198.996918) (xy 134.936243 -198.955727)
			(xy 134.906777 -198.909877) (xy 134.884135 -198.8603) (xy 134.86878 -198.808005) (xy 134.861024 -198.754057)
			(xy 134.860538 -198.726806) (xy 134.861055 -198.698435) (xy 134.869469 -198.642319) (xy 134.877302 -198.615046)
			(xy 134.877302 -198.614792) (xy 134.878318 -198.611744) (xy 134.87935 -198.606726) (xy 134.879615 -198.596486)
			(xy 134.878826 -198.591424) (xy 134.876794 -198.57974) (xy 134.853172 -198.547736) (xy 134.820406 -198.503794)
			(xy 134.818882 -198.502016) (xy 134.796022 -198.500492) (xy 134.785055 -198.5002) (xy 134.764518 -198.507846)
			(xy 134.756398 -198.515224) (xy 133.872224 -199.399398) (xy 135.42467 -199.399398) (xy 135.428741 -199.343776)
			(xy 135.440867 -199.289339) (xy 135.46079 -199.237248) (xy 135.488086 -199.188613) (xy 135.522172 -199.14447)
			(xy 135.562321 -199.105761) (xy 135.607679 -199.07331) (xy 135.657279 -199.047809) (xy 135.710063 -199.029802)
			(xy 135.764906 -199.019672) (xy 135.82064 -199.017635) (xy 135.876077 -199.023735) (xy 135.930034 -199.037841)
			(xy 135.981363 -199.059653) (xy 136.028969 -199.088707) (xy 136.071837 -199.124382) (xy 136.109054 -199.165919)
			(xy 136.139827 -199.212432) (xy 136.163499 -199.262929) (xy 136.179567 -199.316336) (xy 136.187687 -199.371512)
			(xy 136.188196 -199.399398) (xy 136.187687 -199.427284) (xy 136.179567 -199.48246) (xy 136.163499 -199.535867)
			(xy 136.139827 -199.586364) (xy 136.109054 -199.632877) (xy 136.071837 -199.674414) (xy 136.028969 -199.710089)
			(xy 135.981363 -199.739143) (xy 135.930034 -199.760955) (xy 135.876077 -199.775061) (xy 135.82064 -199.781161)
			(xy 135.764906 -199.779124) (xy 135.710063 -199.768994) (xy 135.657279 -199.750987) (xy 135.607679 -199.725486)
			(xy 135.562321 -199.693035) (xy 135.522172 -199.654326) (xy 135.488086 -199.610183) (xy 135.46079 -199.561548)
			(xy 135.440867 -199.509457) (xy 135.428741 -199.45502) (xy 135.42467 -199.399398) (xy 133.872224 -199.399398)
			(xy 133.289294 -199.982328) (xy 144.191226 -199.982328) (xy 144.195297 -199.926706) (xy 144.207423 -199.872269)
			(xy 144.227346 -199.820178) (xy 144.254642 -199.771543) (xy 144.288728 -199.7274) (xy 144.328877 -199.688691)
			(xy 144.374235 -199.65624) (xy 144.423835 -199.630739) (xy 144.476619 -199.612732) (xy 144.531462 -199.602602)
			(xy 144.587196 -199.600565) (xy 144.642633 -199.606665) (xy 144.69659 -199.620771) (xy 144.747919 -199.642583)
			(xy 144.795525 -199.671637) (xy 144.838393 -199.707312) (xy 144.87561 -199.748849) (xy 144.906383 -199.795362)
			(xy 144.930055 -199.845859) (xy 144.946123 -199.899266) (xy 144.954243 -199.954442) (xy 144.954752 -199.982328)
			(xy 144.954243 -200.010214) (xy 144.946123 -200.06539) (xy 144.930055 -200.118797) (xy 144.906383 -200.169294)
			(xy 144.87561 -200.215807) (xy 144.838393 -200.257344) (xy 144.795525 -200.293019) (xy 144.747919 -200.322073)
			(xy 144.69659 -200.343885) (xy 144.642633 -200.357991) (xy 144.587196 -200.364091) (xy 144.531462 -200.362054)
			(xy 144.476619 -200.351924) (xy 144.423835 -200.333917) (xy 144.374235 -200.308416) (xy 144.328877 -200.275965)
			(xy 144.288728 -200.237256) (xy 144.254642 -200.193113) (xy 144.227346 -200.144478) (xy 144.207423 -200.092387)
			(xy 144.195297 -200.03795) (xy 144.191226 -199.982328) (xy 133.289294 -199.982328) (xy 133.081522 -200.1901)
			(xy 133.074673 -200.197498) (xy 133.066935 -200.216096) (xy 133.066536 -200.226168) (xy 133.066536 -201.036936)
			(xy 133.06598 -201.072905) (xy 133.057018 -201.144283) (xy 133.039238 -201.213989) (xy 133.012917 -201.280938)
			(xy 132.996178 -201.31278) (xy 132.99313 -201.318368) (xy 132.989828 -201.33056) (xy 132.988558 -201.342244)
			(xy 132.988558 -201.346308) (xy 132.990336 -201.356468) (xy 132.994146 -201.369168) (xy 132.997448 -201.374756)
			(xy 133.009836 -201.396716) (xy 133.029364 -201.443202) (xy 133.042604 -201.491854) (xy 133.049327 -201.541824)
			(xy 133.049772 -201.567034) (xy 133.049772 -201.574146) (xy 133.048857 -201.601098) (xy 133.040375 -201.654353)
			(xy 133.024475 -201.705883) (xy 133.001477 -201.754659) (xy 132.971837 -201.79971) (xy 132.936148 -201.840137)
			(xy 132.89512 -201.875135) (xy 132.849572 -201.904004) (xy 132.829098 -201.913236) (xy 134.558532 -201.913236)
			(xy 134.559008 -201.886206) (xy 134.566653 -201.832688) (xy 134.581782 -201.780788) (xy 134.60409 -201.731544)
			(xy 134.63313 -201.685946) (xy 134.66832 -201.644907) (xy 134.688326 -201.626724) (xy 134.68858 -201.62647)
			(xy 134.695388 -201.61985) (xy 134.703859 -201.602867) (xy 134.70509 -201.59345) (xy 134.711694 -201.5236)
			(xy 134.712152 -201.513993) (xy 134.706665 -201.495577) (xy 134.701026 -201.487786) (xy 134.701026 -201.487532)
			(xy 134.685688 -201.467302) (xy 134.659944 -201.423546) (xy 134.640228 -201.376762) (xy 134.626889 -201.327778)
			(xy 134.620161 -201.277458) (xy 134.619746 -201.252074) (xy 134.620232 -201.224823) (xy 134.627988 -201.170875)
			(xy 134.643343 -201.11858) (xy 134.665985 -201.069003) (xy 134.695451 -201.023153) (xy 134.731142 -200.981962)
			(xy 134.772333 -200.946271) (xy 134.818183 -200.916805) (xy 134.86776 -200.894163) (xy 134.920055 -200.878808)
			(xy 134.974003 -200.871052) (xy 135.028505 -200.871052) (xy 135.082453 -200.878808) (xy 135.134748 -200.894163)
			(xy 135.184325 -200.916805) (xy 135.230175 -200.946271) (xy 135.271366 -200.981962) (xy 135.307057 -201.023153)
			(xy 135.336523 -201.069003) (xy 135.359165 -201.11858) (xy 135.37452 -201.170875) (xy 135.382276 -201.224823)
			(xy 135.382762 -201.252074) (xy 135.382295 -201.279105) (xy 135.374648 -201.332622) (xy 135.359518 -201.384523)
			(xy 135.337208 -201.433767) (xy 135.308167 -201.479365) (xy 135.272975 -201.520404) (xy 135.252968 -201.538586)
			(xy 135.252714 -201.53884) (xy 135.245902 -201.545456) (xy 135.237433 -201.562442) (xy 135.236204 -201.57186)
			(xy 135.2296 -201.64171) (xy 135.229307 -201.647806) (xy 136.924794 -201.647806) (xy 136.928865 -201.592184)
			(xy 136.940991 -201.537747) (xy 136.960914 -201.485656) (xy 136.98821 -201.437021) (xy 137.022296 -201.392878)
			(xy 137.062445 -201.354169) (xy 137.107803 -201.321718) (xy 137.157403 -201.296217) (xy 137.210187 -201.27821)
			(xy 137.26503 -201.26808) (xy 137.320764 -201.266043) (xy 137.376201 -201.272143) (xy 137.430158 -201.286249)
			(xy 137.481487 -201.308061) (xy 137.529093 -201.337115) (xy 137.571961 -201.37279) (xy 137.609178 -201.414327)
			(xy 137.639951 -201.46084) (xy 137.663623 -201.511337) (xy 137.679691 -201.564744) (xy 137.687811 -201.61992)
			(xy 137.688255 -201.64425) (xy 137.924792 -201.64425) (xy 137.928863 -201.588628) (xy 137.940989 -201.534191)
			(xy 137.960912 -201.4821) (xy 137.988208 -201.433465) (xy 138.022294 -201.389322) (xy 138.062443 -201.350613)
			(xy 138.107801 -201.318162) (xy 138.157401 -201.292661) (xy 138.210185 -201.274654) (xy 138.265028 -201.264524)
			(xy 138.320762 -201.262487) (xy 138.376199 -201.268587) (xy 138.430156 -201.282693) (xy 138.481485 -201.304505)
			(xy 138.529091 -201.333559) (xy 138.571959 -201.369234) (xy 138.609176 -201.410771) (xy 138.639949 -201.457284)
			(xy 138.663621 -201.507781) (xy 138.679689 -201.561188) (xy 138.686979 -201.610722) (xy 139.424662 -201.610722)
			(xy 139.428733 -201.5551) (xy 139.440859 -201.500663) (xy 139.460782 -201.448572) (xy 139.488078 -201.399937)
			(xy 139.522164 -201.355794) (xy 139.562313 -201.317085) (xy 139.607671 -201.284634) (xy 139.657271 -201.259133)
			(xy 139.710055 -201.241126) (xy 139.764898 -201.230996) (xy 139.820632 -201.228959) (xy 139.876069 -201.235059)
			(xy 139.930026 -201.249165) (xy 139.981355 -201.270977) (xy 140.028961 -201.300031) (xy 140.071829 -201.335706)
			(xy 140.109046 -201.377243) (xy 140.139819 -201.423756) (xy 140.163491 -201.474253) (xy 140.179559 -201.52766)
			(xy 140.187679 -201.582836) (xy 140.188188 -201.610722) (xy 140.187679 -201.638608) (xy 140.179559 -201.693784)
			(xy 140.163491 -201.747191) (xy 140.139819 -201.797688) (xy 140.109046 -201.844201) (xy 140.071829 -201.885738)
			(xy 140.028961 -201.921413) (xy 139.981355 -201.950467) (xy 139.930026 -201.972279) (xy 139.876069 -201.986385)
			(xy 139.820632 -201.992485) (xy 139.764898 -201.990448) (xy 139.710055 -201.980318) (xy 139.657271 -201.962311)
			(xy 139.607671 -201.93681) (xy 139.562313 -201.904359) (xy 139.522164 -201.86565) (xy 139.488078 -201.821507)
			(xy 139.460782 -201.772872) (xy 139.440859 -201.720781) (xy 139.428733 -201.666344) (xy 139.424662 -201.610722)
			(xy 138.686979 -201.610722) (xy 138.687809 -201.616364) (xy 138.688318 -201.64425) (xy 138.687809 -201.672136)
			(xy 138.679689 -201.727312) (xy 138.663621 -201.780719) (xy 138.639949 -201.831216) (xy 138.609176 -201.877729)
			(xy 138.571959 -201.919266) (xy 138.529091 -201.954941) (xy 138.481485 -201.983995) (xy 138.430156 -202.005807)
			(xy 138.376199 -202.019913) (xy 138.320762 -202.026013) (xy 138.265028 -202.023976) (xy 138.210185 -202.013846)
			(xy 138.157401 -201.995839) (xy 138.107801 -201.970338) (xy 138.062443 -201.937887) (xy 138.022294 -201.899178)
			(xy 137.988208 -201.855035) (xy 137.960912 -201.8064) (xy 137.940989 -201.754309) (xy 137.928863 -201.699872)
			(xy 137.924792 -201.64425) (xy 137.688255 -201.64425) (xy 137.68832 -201.647806) (xy 137.687811 -201.675692)
			(xy 137.679691 -201.730868) (xy 137.663623 -201.784275) (xy 137.639951 -201.834772) (xy 137.609178 -201.881285)
			(xy 137.571961 -201.922822) (xy 137.529093 -201.958497) (xy 137.481487 -201.987551) (xy 137.430158 -202.009363)
			(xy 137.376201 -202.023469) (xy 137.320764 -202.029569) (xy 137.26503 -202.027532) (xy 137.210187 -202.017402)
			(xy 137.157403 -201.999395) (xy 137.107803 -201.973894) (xy 137.062445 -201.941443) (xy 137.022296 -201.902734)
			(xy 136.98821 -201.858591) (xy 136.960914 -201.809956) (xy 136.940991 -201.757865) (xy 136.928865 -201.703428)
			(xy 136.924794 -201.647806) (xy 135.229307 -201.647806) (xy 135.229138 -201.651317) (xy 135.234628 -201.669733)
			(xy 135.240268 -201.677524) (xy 135.240268 -201.677778) (xy 135.25561 -201.698005) (xy 135.281353 -201.741762)
			(xy 135.301069 -201.788546) (xy 135.314407 -201.837531) (xy 135.321133 -201.887852) (xy 135.321548 -201.913236)
			(xy 135.321062 -201.940487) (xy 135.313306 -201.994435) (xy 135.297951 -202.04673) (xy 135.275309 -202.096307)
			(xy 135.245843 -202.142157) (xy 135.210152 -202.183348) (xy 135.168961 -202.219039) (xy 135.123111 -202.248505)
			(xy 135.073534 -202.271147) (xy 135.033827 -202.282806) (xy 141.411196 -202.282806) (xy 141.415267 -202.227184)
			(xy 141.427393 -202.172747) (xy 141.447316 -202.120656) (xy 141.474612 -202.072021) (xy 141.508698 -202.027878)
			(xy 141.548847 -201.989169) (xy 141.594205 -201.956718) (xy 141.643805 -201.931217) (xy 141.696589 -201.91321)
			(xy 141.751432 -201.90308) (xy 141.807166 -201.901043) (xy 141.862603 -201.907143) (xy 141.91656 -201.921249)
			(xy 141.967889 -201.943061) (xy 142.015495 -201.972115) (xy 142.058363 -202.00779) (xy 142.09558 -202.049327)
			(xy 142.126353 -202.09584) (xy 142.150025 -202.146337) (xy 142.166093 -202.199744) (xy 142.174213 -202.25492)
			(xy 142.174722 -202.282806) (xy 142.174213 -202.310692) (xy 142.166093 -202.365868) (xy 142.150025 -202.419275)
			(xy 142.126353 -202.469772) (xy 142.09558 -202.516285) (xy 142.058363 -202.557822) (xy 142.015495 -202.593497)
			(xy 141.967889 -202.622551) (xy 141.91656 -202.644363) (xy 141.862603 -202.658469) (xy 141.807166 -202.664569)
			(xy 141.751432 -202.662532) (xy 141.696589 -202.652402) (xy 141.643805 -202.634395) (xy 141.594205 -202.608894)
			(xy 141.548847 -202.576443) (xy 141.508698 -202.537734) (xy 141.474612 -202.493591) (xy 141.447316 -202.444956)
			(xy 141.427393 -202.392865) (xy 141.415267 -202.338428) (xy 141.411196 -202.282806) (xy 135.033827 -202.282806)
			(xy 135.021239 -202.286502) (xy 134.967291 -202.294258) (xy 134.912789 -202.294258) (xy 134.858841 -202.286502)
			(xy 134.806546 -202.271147) (xy 134.756969 -202.248505) (xy 134.711119 -202.219039) (xy 134.669928 -202.183348)
			(xy 134.634237 -202.142157) (xy 134.604771 -202.096307) (xy 134.582129 -202.04673) (xy 134.566774 -201.994435)
			(xy 134.559018 -201.940487) (xy 134.558532 -201.913236) (xy 132.829098 -201.913236) (xy 132.800412 -201.926171)
			(xy 132.748619 -201.941192) (xy 132.695228 -201.948768) (xy 132.668264 -201.949304) (xy 132.66801 -201.949304)
			(xy 132.638835 -201.948748) (xy 132.581165 -201.939872) (xy 132.525511 -201.92234) (xy 132.4991 -201.909934)
			(xy 132.498846 -201.90968) (xy 132.490972 -201.90587) (xy 132.484876 -201.902568) (xy 132.478297 -201.899904)
			(xy 132.464242 -201.897961) (xy 132.45719 -201.898758) (xy 132.450939 -201.899946) (xy 132.439247 -201.904957)
			(xy 132.434076 -201.908664) (xy 132.433568 -201.908664) (xy 132.428742 -201.912982) (xy 132.4102 -201.931524)
			(xy 132.407099 -201.934787) (xy 132.401994 -201.9422) (xy 132.40004 -201.946256) (xy 132.40004 -201.988166)
			(xy 132.404104 -201.997564) (xy 132.413429 -202.02082) (xy 132.426599 -202.069165) (xy 132.433336 -202.118816)
			(xy 132.433822 -202.143868) (xy 132.433822 -202.150218) (xy 132.433029 -202.177026) (xy 132.424848 -202.23003)
			(xy 132.409326 -202.281367) (xy 132.386768 -202.330024) (xy 132.357618 -202.375042) (xy 132.322451 -202.415535)
			(xy 132.28196 -202.450704) (xy 132.236943 -202.479857) (xy 132.188288 -202.502418) (xy 132.136952 -202.517943)
			(xy 132.083948 -202.526127) (xy 132.05714 -202.5269) (xy 132.05206 -202.5269) (xy 132.025086 -202.526432)
			(xy 131.971676 -202.51883) (xy 131.919868 -202.503783) (xy 131.895088 -202.493118) (xy 131.894834 -202.493118)
			(xy 131.87426 -202.488546) (xy 131.864717 -202.488998) (xy 131.846976 -202.496051) (xy 131.839716 -202.502262)
			(xy 131.747514 -202.594464) (xy 131.740712 -202.601812) (xy 131.733001 -202.620275) (xy 131.732528 -202.630278)
			(xy 131.732528 -203.812902) (xy 131.732528 -203.813156) (xy 131.732753 -203.81953) (xy 131.735955 -203.831872)
			(xy 131.738878 -203.83754) (xy 131.76377 -203.8477) (xy 131.789728 -203.859124) (xy 131.838327 -203.888355)
			(xy 131.882208 -203.924282) (xy 131.920455 -203.966157) (xy 131.95227 -204.013106) (xy 131.976988 -204.064148)
			(xy 131.98602 -204.091032) (xy 131.989068 -204.100938) (xy 132.009134 -204.12456) (xy 132.012858 -204.128607)
			(xy 132.021695 -204.13515) (xy 132.02666 -204.137514) (xy 132.07492 -204.159612) (xy 132.082794 -204.163168)
			(xy 132.10413 -204.163168) (xy 132.11429 -204.15885) (xy 132.138638 -204.148582) (xy 132.189459 -204.134104)
			(xy 132.241793 -204.126789) (xy 132.268214 -204.126338) (xy 132.295461 -204.126825) (xy 132.349401 -204.134582)
			(xy 132.401688 -204.149937) (xy 132.451257 -204.172576) (xy 132.4971 -204.202039) (xy 132.538284 -204.237726)
			(xy 132.552251 -204.253846) (xy 138.236196 -204.253846) (xy 138.240267 -204.198224) (xy 138.252393 -204.143787)
			(xy 138.272316 -204.091696) (xy 138.299612 -204.043061) (xy 138.333698 -203.998918) (xy 138.373847 -203.960209)
			(xy 138.419205 -203.927758) (xy 138.468805 -203.902257) (xy 138.521589 -203.88425) (xy 138.576432 -203.87412)
			(xy 138.632166 -203.872083) (xy 138.687603 -203.878183) (xy 138.74156 -203.892289) (xy 138.792889 -203.914101)
			(xy 138.840495 -203.943155) (xy 138.883363 -203.97883) (xy 138.92058 -204.020367) (xy 138.951353 -204.06688)
			(xy 138.975025 -204.117377) (xy 138.991093 -204.170784) (xy 138.999213 -204.22596) (xy 138.999722 -204.253846)
			(xy 138.999213 -204.281732) (xy 138.991093 -204.336908) (xy 138.975025 -204.390315) (xy 138.951353 -204.440812)
			(xy 138.92058 -204.487325) (xy 138.883363 -204.528862) (xy 138.840495 -204.564537) (xy 138.792889 -204.593591)
			(xy 138.74156 -204.615403) (xy 138.687603 -204.629509) (xy 138.632166 -204.635609) (xy 138.576432 -204.633572)
			(xy 138.521589 -204.623442) (xy 138.468805 -204.605435) (xy 138.419205 -204.579934) (xy 138.373847 -204.547483)
			(xy 138.333698 -204.508774) (xy 138.299612 -204.464631) (xy 138.272316 -204.415996) (xy 138.252393 -204.363905)
			(xy 138.240267 -204.309468) (xy 138.236196 -204.253846) (xy 132.552251 -204.253846) (xy 132.573969 -204.278911)
			(xy 132.603431 -204.324755) (xy 132.626068 -204.374325) (xy 132.641421 -204.426613) (xy 132.649176 -204.480553)
			(xy 132.649176 -204.535047) (xy 132.641421 -204.588987) (xy 132.626068 -204.641275) (xy 132.603431 -204.690845)
			(xy 132.573969 -204.736689) (xy 132.538284 -204.777874) (xy 132.4971 -204.813561) (xy 132.451257 -204.843024)
			(xy 132.401688 -204.865663) (xy 132.349401 -204.881018) (xy 132.295461 -204.888775) (xy 132.29212 -204.888846)
			(xy 134.823198 -204.888846) (xy 134.827269 -204.833224) (xy 134.839395 -204.778787) (xy 134.859318 -204.726696)
			(xy 134.886614 -204.678061) (xy 134.9207 -204.633918) (xy 134.960849 -204.595209) (xy 135.006207 -204.562758)
			(xy 135.055807 -204.537257) (xy 135.108591 -204.51925) (xy 135.163434 -204.50912) (xy 135.219168 -204.507083)
			(xy 135.274605 -204.513183) (xy 135.328562 -204.527289) (xy 135.379891 -204.549101) (xy 135.427497 -204.578155)
			(xy 135.470365 -204.61383) (xy 135.507582 -204.655367) (xy 135.538355 -204.70188) (xy 135.562027 -204.752377)
			(xy 135.578095 -204.805784) (xy 135.586215 -204.86096) (xy 135.586724 -204.888846) (xy 135.586215 -204.916732)
			(xy 135.581348 -204.949806) (xy 142.112746 -204.949806) (xy 142.113281 -204.920905) (xy 142.121993 -204.863763)
			(xy 142.139233 -204.808592) (xy 142.164606 -204.756657) (xy 142.197531 -204.709148) (xy 142.237251 -204.667156)
			(xy 142.282857 -204.631643) (xy 142.307818 -204.617066) (xy 142.320744 -204.609132) (xy 142.341656 -204.587188)
			(xy 142.355216 -204.560078) (xy 142.360231 -204.530184) (xy 142.356262 -204.500133) (xy 142.343657 -204.472567)
			(xy 142.323523 -204.449907) (xy 142.310866 -204.441552) (xy 142.287296 -204.426632) (xy 142.244404 -204.390967)
			(xy 142.207164 -204.349435) (xy 142.176371 -204.302921) (xy 142.152682 -204.252418) (xy 142.136601 -204.199003)
			(xy 142.128472 -204.143815) (xy 142.127986 -204.115924) (xy 142.128472 -204.088673) (xy 142.136228 -204.034725)
			(xy 142.151583 -203.98243) (xy 142.174225 -203.932853) (xy 142.203691 -203.887003) (xy 142.239382 -203.845812)
			(xy 142.280573 -203.810121) (xy 142.326423 -203.780655) (xy 142.376 -203.758013) (xy 142.428295 -203.742658)
			(xy 142.482243 -203.734902) (xy 142.536745 -203.734902) (xy 142.590693 -203.742658) (xy 142.642988 -203.758013)
			(xy 142.692565 -203.780655) (xy 142.738415 -203.810121) (xy 142.779606 -203.845812) (xy 142.815297 -203.887003)
			(xy 142.844763 -203.932853) (xy 142.867405 -203.98243) (xy 142.88276 -204.034725) (xy 142.890516 -204.088673)
			(xy 142.891002 -204.115924) (xy 142.890466 -204.144825) (xy 142.881751 -204.201965) (xy 142.864509 -204.257135)
			(xy 142.839136 -204.309069) (xy 142.806212 -204.356578) (xy 142.766493 -204.398571) (xy 142.72089 -204.434086)
			(xy 142.69593 -204.448664) (xy 142.682972 -204.456555) (xy 142.662048 -204.478504) (xy 142.648483 -204.505624)
			(xy 142.643468 -204.535531) (xy 142.647445 -204.565593) (xy 142.660064 -204.593166) (xy 142.680215 -204.615826)
			(xy 142.692882 -204.624178) (xy 142.716477 -204.63906) (xy 142.759366 -204.674734) (xy 142.796603 -204.716273)
			(xy 142.827392 -204.762793) (xy 142.835881 -204.780896) (xy 143.716756 -204.780896) (xy 143.717147 -204.754953)
			(xy 143.72418 -204.703546) (xy 143.738115 -204.653566) (xy 143.758696 -204.605936) (xy 143.785543 -204.561536)
			(xy 143.81816 -204.521184) (xy 143.855945 -204.485625) (xy 143.898201 -204.455515) (xy 143.920972 -204.443076)
			(xy 143.933789 -204.435839) (xy 143.954848 -204.415288) (xy 143.969177 -204.389588) (xy 143.975588 -204.36087)
			(xy 143.973549 -204.331516) (xy 143.963229 -204.30396) (xy 143.945484 -204.280488) (xy 143.933926 -204.271372)
			(xy 143.910266 -204.253256) (xy 143.868345 -204.210911) (xy 143.833515 -204.162565) (xy 143.806622 -204.109392)
			(xy 143.78832 -204.052687) (xy 143.779053 -203.993825) (xy 143.778478 -203.964032) (xy 143.778964 -203.936781)
			(xy 143.78672 -203.882833) (xy 143.802075 -203.830538) (xy 143.824717 -203.780961) (xy 143.854183 -203.735111)
			(xy 143.889874 -203.69392) (xy 143.931065 -203.658229) (xy 143.976915 -203.628763) (xy 144.026492 -203.606121)
			(xy 144.078787 -203.590766) (xy 144.132735 -203.58301) (xy 144.187237 -203.58301) (xy 144.241185 -203.590766)
			(xy 144.29348 -203.606121) (xy 144.343057 -203.628763) (xy 144.388907 -203.658229) (xy 144.430098 -203.69392)
			(xy 144.465789 -203.735111) (xy 144.495255 -203.780961) (xy 144.517897 -203.830538) (xy 144.533252 -203.882833)
			(xy 144.541008 -203.936781) (xy 144.541494 -203.964032) (xy 144.541018 -203.989972) (xy 144.533996 -204.041374)
			(xy 144.520071 -204.091351) (xy 144.499502 -204.138979) (xy 144.472667 -204.183379) (xy 144.440062 -204.223733)
			(xy 144.402288 -204.259295) (xy 144.360043 -204.28941) (xy 144.337278 -204.301852) (xy 144.324522 -204.309189)
			(xy 144.30346 -204.329716) (xy 144.289124 -204.355395) (xy 144.282703 -204.384096) (xy 144.284731 -204.413436)
			(xy 144.295039 -204.440981) (xy 144.312772 -204.464444) (xy 144.324324 -204.473556) (xy 144.347986 -204.491669)
			(xy 144.38991 -204.534013) (xy 144.424742 -204.582359) (xy 144.451635 -204.635533) (xy 144.469935 -204.69224)
			(xy 144.479199 -204.751102) (xy 144.479772 -204.780896) (xy 144.479286 -204.808147) (xy 144.47153 -204.862095)
			(xy 144.456175 -204.91439) (xy 144.433533 -204.963967) (xy 144.404067 -205.009817) (xy 144.368376 -205.051008)
			(xy 144.327185 -205.086699) (xy 144.281335 -205.116165) (xy 144.231758 -205.138807) (xy 144.179463 -205.154162)
			(xy 144.125515 -205.161918) (xy 144.071013 -205.161918) (xy 144.017065 -205.154162) (xy 143.96477 -205.138807)
			(xy 143.915193 -205.116165) (xy 143.869343 -205.086699) (xy 143.828152 -205.051008) (xy 143.792461 -205.009817)
			(xy 143.762995 -204.963967) (xy 143.740353 -204.91439) (xy 143.724998 -204.862095) (xy 143.717242 -204.808147)
			(xy 143.716756 -204.780896) (xy 142.835881 -204.780896) (xy 142.851077 -204.813302) (xy 142.867153 -204.866721)
			(xy 142.875278 -204.921913) (xy 142.875762 -204.949806) (xy 142.875276 -204.977057) (xy 142.86752 -205.031005)
			(xy 142.852165 -205.0833) (xy 142.829523 -205.132877) (xy 142.800057 -205.178727) (xy 142.764366 -205.219918)
			(xy 142.723175 -205.255609) (xy 142.677325 -205.285075) (xy 142.627748 -205.307717) (xy 142.575453 -205.323072)
			(xy 142.521505 -205.330828) (xy 142.467003 -205.330828) (xy 142.413055 -205.323072) (xy 142.36076 -205.307717)
			(xy 142.311183 -205.285075) (xy 142.265333 -205.255609) (xy 142.224142 -205.219918) (xy 142.188451 -205.178727)
			(xy 142.158985 -205.132877) (xy 142.136343 -205.0833) (xy 142.120988 -205.031005) (xy 142.113232 -204.977057)
			(xy 142.112746 -204.949806) (xy 135.581348 -204.949806) (xy 135.578095 -204.971908) (xy 135.562027 -205.025315)
			(xy 135.538355 -205.075812) (xy 135.507582 -205.122325) (xy 135.470365 -205.163862) (xy 135.427497 -205.199537)
			(xy 135.379891 -205.228591) (xy 135.328562 -205.250403) (xy 135.274605 -205.264509) (xy 135.219168 -205.270609)
			(xy 135.163434 -205.268572) (xy 135.108591 -205.258442) (xy 135.055807 -205.240435) (xy 135.006207 -205.214934)
			(xy 134.960849 -205.182483) (xy 134.9207 -205.143774) (xy 134.886614 -205.099631) (xy 134.859318 -205.050996)
			(xy 134.839395 -204.998905) (xy 134.827269 -204.944468) (xy 134.823198 -204.888846) (xy 132.29212 -204.888846)
			(xy 132.268214 -204.889354) (xy 132.241281 -204.888892) (xy 132.18795 -204.881318) (xy 132.136215 -204.866319)
			(xy 132.087103 -204.844192) (xy 132.041592 -204.815378) (xy 132.000585 -204.78045) (xy 131.964899 -204.740102)
			(xy 131.935242 -204.695135) (xy 131.912204 -204.646445) (xy 131.903724 -204.620876) (xy 131.900422 -204.610208)
			(xy 131.893564 -204.602334) (xy 131.890177 -204.598686) (xy 131.88224 -204.59268) (xy 131.877816 -204.590396)
			(xy 131.868672 -204.586332) (xy 131.80441 -204.557122) (xy 131.79806 -204.55509) (xy 131.781804 -204.562456)
			(xy 131.781296 -204.562964) (xy 131.760722 -204.572108) (xy 131.760214 -204.572108) (xy 131.738878 -204.581252)
			(xy 131.736846 -204.5843) (xy 131.734814 -204.590904) (xy 131.733763 -204.594562) (xy 131.732621 -204.602085)
			(xy 131.732528 -204.60589) (xy 131.732528 -205.650846) (xy 137.982196 -205.650846) (xy 137.986267 -205.595224)
			(xy 137.998393 -205.540787) (xy 138.018316 -205.488696) (xy 138.045612 -205.440061) (xy 138.079698 -205.395918)
			(xy 138.119847 -205.357209) (xy 138.165205 -205.324758) (xy 138.214805 -205.299257) (xy 138.267589 -205.28125)
			(xy 138.322432 -205.27112) (xy 138.378166 -205.269083) (xy 138.433603 -205.275183) (xy 138.48756 -205.289289)
			(xy 138.538889 -205.311101) (xy 138.586495 -205.340155) (xy 138.629363 -205.37583) (xy 138.66658 -205.417367)
			(xy 138.697353 -205.46388) (xy 138.721025 -205.514377) (xy 138.737093 -205.567784) (xy 138.745213 -205.62296)
			(xy 138.745722 -205.650846) (xy 138.745213 -205.678732) (xy 138.737093 -205.733908) (xy 138.721025 -205.787315)
			(xy 138.697353 -205.837812) (xy 138.66658 -205.884325) (xy 138.629363 -205.925862) (xy 138.586495 -205.961537)
			(xy 138.538889 -205.990591) (xy 138.48756 -206.012403) (xy 138.433603 -206.026509) (xy 138.378166 -206.032609)
			(xy 138.322432 -206.030572) (xy 138.267589 -206.020442) (xy 138.214805 -206.002435) (xy 138.165205 -205.976934)
			(xy 138.119847 -205.944483) (xy 138.079698 -205.905774) (xy 138.045612 -205.861631) (xy 138.018316 -205.812996)
			(xy 137.998393 -205.760905) (xy 137.986267 -205.706468) (xy 137.982196 -205.650846) (xy 131.732528 -205.650846)
			(xy 131.732528 -205.814422) (xy 131.73289 -205.823438) (xy 131.739136 -205.840354) (xy 131.74472 -205.847442)
			(xy 131.750562 -205.8543) (xy 131.766056 -205.862936) (xy 131.775454 -205.86446) (xy 131.802004 -205.869162)
			(xy 131.853526 -205.885058) (xy 131.902298 -205.908049) (xy 131.947347 -205.937676) (xy 131.987777 -205.973349)
			(xy 132.022784 -206.014359) (xy 132.051669 -206.059887) (xy 132.056096 -206.069692) (xy 140.301216 -206.069692)
			(xy 140.305287 -206.01407) (xy 140.317413 -205.959633) (xy 140.337336 -205.907542) (xy 140.364632 -205.858907)
			(xy 140.398718 -205.814764) (xy 140.438867 -205.776055) (xy 140.484225 -205.743604) (xy 140.533825 -205.718103)
			(xy 140.586609 -205.700096) (xy 140.641452 -205.689966) (xy 140.697186 -205.687929) (xy 140.752623 -205.694029)
			(xy 140.80658 -205.708135) (xy 140.857909 -205.729947) (xy 140.905515 -205.759001) (xy 140.948383 -205.794676)
			(xy 140.9856 -205.836213) (xy 141.016373 -205.882726) (xy 141.040045 -205.933223) (xy 141.056113 -205.98663)
			(xy 141.064233 -206.041806) (xy 141.064482 -206.055468) (xy 142.213836 -206.055468) (xy 142.217907 -205.999846)
			(xy 142.230033 -205.945409) (xy 142.249956 -205.893318) (xy 142.277252 -205.844683) (xy 142.311338 -205.80054)
			(xy 142.351487 -205.761831) (xy 142.396845 -205.72938) (xy 142.446445 -205.703879) (xy 142.499229 -205.685872)
			(xy 142.554072 -205.675742) (xy 142.609806 -205.673705) (xy 142.665243 -205.679805) (xy 142.7192 -205.693911)
			(xy 142.770529 -205.715723) (xy 142.818135 -205.744777) (xy 142.861003 -205.780452) (xy 142.89822 -205.821989)
			(xy 142.928993 -205.868502) (xy 142.952665 -205.918999) (xy 142.968733 -205.972406) (xy 142.976853 -206.027582)
			(xy 142.977362 -206.055468) (xy 142.976853 -206.083354) (xy 142.968733 -206.13853) (xy 142.952665 -206.191937)
			(xy 142.928993 -206.242434) (xy 142.89822 -206.288947) (xy 142.861003 -206.330484) (xy 142.818135 -206.366159)
			(xy 142.770529 -206.395213) (xy 142.7192 -206.417025) (xy 142.665243 -206.431131) (xy 142.609806 -206.437231)
			(xy 142.554072 -206.435194) (xy 142.499229 -206.425064) (xy 142.446445 -206.407057) (xy 142.396845 -206.381556)
			(xy 142.351487 -206.349105) (xy 142.311338 -206.310396) (xy 142.277252 -206.266253) (xy 142.249956 -206.217618)
			(xy 142.230033 -206.165527) (xy 142.217907 -206.11109) (xy 142.213836 -206.055468) (xy 141.064482 -206.055468)
			(xy 141.064742 -206.069692) (xy 141.064233 -206.097578) (xy 141.056113 -206.152754) (xy 141.040045 -206.206161)
			(xy 141.016373 -206.256658) (xy 140.9856 -206.303171) (xy 140.948383 -206.344708) (xy 140.905515 -206.380383)
			(xy 140.857909 -206.409437) (xy 140.80658 -206.431249) (xy 140.752623 -206.445355) (xy 140.697186 -206.451455)
			(xy 140.641452 -206.449418) (xy 140.586609 -206.439288) (xy 140.533825 -206.421281) (xy 140.484225 -206.39578)
			(xy 140.438867 -206.363329) (xy 140.398718 -206.32462) (xy 140.364632 -206.280477) (xy 140.337336 -206.231842)
			(xy 140.317413 -206.179751) (xy 140.305287 -206.125314) (xy 140.301216 -206.069692) (xy 132.056096 -206.069692)
			(xy 132.073857 -206.109029) (xy 132.088907 -206.160804) (xy 132.096519 -206.214183) (xy 132.097018 -206.241142)
			(xy 132.096925 -206.254841) (xy 132.095021 -206.282173) (xy 132.093208 -206.295752) (xy 132.092954 -206.296768)
			(xy 132.092517 -206.30129) (xy 132.093028 -206.310358) (xy 132.09397 -206.314802) (xy 132.09651 -206.32293)
			(xy 132.09905 -206.328518) (xy 132.106924 -206.338678) (xy 132.184648 -206.398876) (xy 132.193792 -206.403956)
			(xy 132.217668 -206.403956) (xy 132.22732 -206.40294) (xy 132.241036 -206.4004) (xy 132.24129 -206.4004)
			(xy 132.263354 -206.392231) (xy 132.308988 -206.380782) (xy 132.355687 -206.375051) (xy 132.379212 -206.374746)
			(xy 132.383784 -206.374746) (xy 132.41082 -206.375542) (xy 132.464269 -206.383825) (xy 132.516013 -206.399574)
			(xy 132.565014 -206.422474) (xy 132.610288 -206.452065) (xy 132.623765 -206.4639) (xy 134.571994 -206.4639)
			(xy 134.57248 -206.436649) (xy 134.580236 -206.382701) (xy 134.595591 -206.330406) (xy 134.618233 -206.280829)
			(xy 134.647699 -206.234979) (xy 134.68339 -206.193788) (xy 134.724581 -206.158097) (xy 134.770431 -206.128631)
			(xy 134.820008 -206.105989) (xy 134.872303 -206.090634) (xy 134.926251 -206.082878) (xy 134.980753 -206.082878)
			(xy 135.034701 -206.090634) (xy 135.086996 -206.105989) (xy 135.136573 -206.128631) (xy 135.182423 -206.158097)
			(xy 135.223614 -206.193788) (xy 135.259305 -206.234979) (xy 135.288771 -206.280829) (xy 135.311413 -206.330406)
			(xy 135.326768 -206.382701) (xy 135.334524 -206.436649) (xy 135.33501 -206.4639) (xy 143.777968 -206.4639)
			(xy 143.782039 -206.408278) (xy 143.794165 -206.353841) (xy 143.814088 -206.30175) (xy 143.841384 -206.253115)
			(xy 143.87547 -206.208972) (xy 143.915619 -206.170263) (xy 143.960977 -206.137812) (xy 144.010577 -206.112311)
			(xy 144.063361 -206.094304) (xy 144.118204 -206.084174) (xy 144.173938 -206.082137) (xy 144.229375 -206.088237)
			(xy 144.283332 -206.102343) (xy 144.334661 -206.124155) (xy 144.382267 -206.153209) (xy 144.425135 -206.188884)
			(xy 144.462352 -206.230421) (xy 144.493125 -206.276934) (xy 144.516797 -206.327431) (xy 144.532865 -206.380838)
			(xy 144.540985 -206.436014) (xy 144.541494 -206.4639) (xy 144.540985 -206.491786) (xy 144.532865 -206.546962)
			(xy 144.516797 -206.600369) (xy 144.493125 -206.650866) (xy 144.462352 -206.697379) (xy 144.425135 -206.738916)
			(xy 144.382267 -206.774591) (xy 144.334661 -206.803645) (xy 144.283332 -206.825457) (xy 144.229375 -206.839563)
			(xy 144.173938 -206.845663) (xy 144.118204 -206.843626) (xy 144.063361 -206.833496) (xy 144.010577 -206.815489)
			(xy 143.960977 -206.789988) (xy 143.915619 -206.757537) (xy 143.87547 -206.718828) (xy 143.841384 -206.674685)
			(xy 143.814088 -206.62605) (xy 143.794165 -206.573959) (xy 143.782039 -206.519522) (xy 143.777968 -206.4639)
			(xy 135.33501 -206.4639) (xy 135.334491 -206.49226) (xy 135.326099 -206.548355) (xy 135.309486 -206.602586)
			(xy 135.28502 -206.653757) (xy 135.253239 -206.700736) (xy 135.234426 -206.721964) (xy 135.227383 -206.730425)
			(xy 135.220673 -206.751369) (xy 135.221472 -206.76235) (xy 135.23214 -206.850234) (xy 135.244078 -206.869538)
			(xy 135.253222 -206.87538) (xy 135.275462 -206.890573) (xy 135.315799 -206.926268) (xy 135.350716 -206.96728)
			(xy 135.379521 -207.012793) (xy 135.401641 -207.061904) (xy 135.416636 -207.113637) (xy 135.424209 -207.166965)
			(xy 135.424672 -207.193896) (xy 135.424186 -207.221147) (xy 135.41643 -207.275095) (xy 135.401075 -207.32739)
			(xy 135.378433 -207.376967) (xy 135.360273 -207.405224) (xy 136.98296 -207.405224) (xy 136.987031 -207.349602)
			(xy 136.999157 -207.295165) (xy 137.01908 -207.243074) (xy 137.046376 -207.194439) (xy 137.080462 -207.150296)
			(xy 137.120611 -207.111587) (xy 137.165969 -207.079136) (xy 137.215569 -207.053635) (xy 137.268353 -207.035628)
			(xy 137.323196 -207.025498) (xy 137.37893 -207.023461) (xy 137.434367 -207.029561) (xy 137.488324 -207.043667)
			(xy 137.539653 -207.065479) (xy 137.587259 -207.094533) (xy 137.630127 -207.130208) (xy 137.667344 -207.171745)
			(xy 137.698117 -207.218258) (xy 137.721789 -207.268755) (xy 137.737857 -207.322162) (xy 137.740848 -207.342486)
			(xy 138.016994 -207.342486) (xy 138.021065 -207.286864) (xy 138.033191 -207.232427) (xy 138.053114 -207.180336)
			(xy 138.08041 -207.131701) (xy 138.114496 -207.087558) (xy 138.154645 -207.048849) (xy 138.200003 -207.016398)
			(xy 138.249603 -206.990897) (xy 138.302387 -206.97289) (xy 138.35723 -206.96276) (xy 138.412964 -206.960723)
			(xy 138.468401 -206.966823) (xy 138.522358 -206.980929) (xy 138.573687 -207.002741) (xy 138.621293 -207.031795)
			(xy 138.664161 -207.06747) (xy 138.701378 -207.109007) (xy 138.732151 -207.15552) (xy 138.755823 -207.206017)
			(xy 138.771891 -207.259424) (xy 138.780011 -207.3146) (xy 138.78052 -207.342486) (xy 138.780011 -207.370372)
			(xy 138.771891 -207.425548) (xy 138.755823 -207.478955) (xy 138.732151 -207.529452) (xy 138.701378 -207.575965)
			(xy 138.664161 -207.617502) (xy 138.621293 -207.653177) (xy 138.573687 -207.682231) (xy 138.522358 -207.704043)
			(xy 138.468401 -207.718149) (xy 138.412964 -207.724249) (xy 138.35723 -207.722212) (xy 138.302387 -207.712082)
			(xy 138.249603 -207.694075) (xy 138.200003 -207.668574) (xy 138.154645 -207.636123) (xy 138.114496 -207.597414)
			(xy 138.08041 -207.553271) (xy 138.053114 -207.504636) (xy 138.033191 -207.452545) (xy 138.021065 -207.398108)
			(xy 138.016994 -207.342486) (xy 137.740848 -207.342486) (xy 137.745977 -207.377338) (xy 137.746486 -207.405224)
			(xy 137.745977 -207.43311) (xy 137.737857 -207.488286) (xy 137.721789 -207.541693) (xy 137.698117 -207.59219)
			(xy 137.667344 -207.638703) (xy 137.630127 -207.68024) (xy 137.587259 -207.715915) (xy 137.539653 -207.744969)
			(xy 137.488324 -207.766781) (xy 137.434367 -207.780887) (xy 137.37893 -207.786987) (xy 137.323196 -207.78495)
			(xy 137.268353 -207.77482) (xy 137.215569 -207.756813) (xy 137.165969 -207.731312) (xy 137.120611 -207.698861)
			(xy 137.080462 -207.660152) (xy 137.046376 -207.616009) (xy 137.01908 -207.567374) (xy 136.999157 -207.515283)
			(xy 136.987031 -207.460846) (xy 136.98296 -207.405224) (xy 135.360273 -207.405224) (xy 135.348967 -207.422817)
			(xy 135.313276 -207.464008) (xy 135.272085 -207.499699) (xy 135.226235 -207.529165) (xy 135.176658 -207.551807)
			(xy 135.124363 -207.567162) (xy 135.070415 -207.574918) (xy 135.015913 -207.574918) (xy 134.961965 -207.567162)
			(xy 134.90967 -207.551807) (xy 134.860093 -207.529165) (xy 134.814243 -207.499699) (xy 134.773052 -207.464008)
			(xy 134.737361 -207.422817) (xy 134.707895 -207.376967) (xy 134.685253 -207.32739) (xy 134.669898 -207.275095)
			(xy 134.662142 -207.221147) (xy 134.661656 -207.193896) (xy 134.662182 -207.165537) (xy 134.670573 -207.109442)
			(xy 134.687185 -207.055211) (xy 134.71165 -207.00404) (xy 134.743428 -206.95706) (xy 134.76224 -206.935832)
			(xy 134.769293 -206.927379) (xy 134.775994 -206.906428) (xy 134.775194 -206.895446) (xy 134.764526 -206.807562)
			(xy 134.752588 -206.788258) (xy 134.743444 -206.782416) (xy 134.721194 -206.767236) (xy 134.680859 -206.731538)
			(xy 134.645944 -206.690523) (xy 134.617141 -206.645008) (xy 134.595023 -206.595895) (xy 134.580029 -206.54416)
			(xy 134.572457 -206.490832) (xy 134.571994 -206.4639) (xy 132.623765 -206.4639) (xy 132.650929 -206.487754)
			(xy 132.686122 -206.528826) (xy 132.715161 -206.574458) (xy 132.737463 -206.623733) (xy 132.752582 -206.675664)
			(xy 132.760214 -206.72921) (xy 132.76072 -206.756254) (xy 132.760234 -206.783505) (xy 132.752478 -206.837453)
			(xy 132.737123 -206.889748) (xy 132.714481 -206.939325) (xy 132.685015 -206.985175) (xy 132.649324 -207.026366)
			(xy 132.608133 -207.062057) (xy 132.562283 -207.091523) (xy 132.512706 -207.114165) (xy 132.460411 -207.12952)
			(xy 132.406463 -207.137276) (xy 132.351961 -207.137276) (xy 132.298013 -207.12952) (xy 132.245718 -207.114165)
			(xy 132.196141 -207.091523) (xy 132.150291 -207.062057) (xy 132.1091 -207.026366) (xy 132.073409 -206.985175)
			(xy 132.043943 -206.939325) (xy 132.021301 -206.889748) (xy 132.005946 -206.837453) (xy 131.99819 -206.783505)
			(xy 131.997704 -206.756254) (xy 131.997797 -206.742555) (xy 131.999701 -206.715223) (xy 132.001514 -206.701644)
			(xy 132.001514 -206.700882) (xy 132.002198 -206.694236) (xy 132.00053 -206.680986) (xy 131.998212 -206.67472)
			(xy 131.995672 -206.668878) (xy 131.991862 -206.664052) (xy 131.982972 -206.654908) (xy 131.947412 -206.627222)
			(xy 131.910582 -206.598774) (xy 131.905527 -206.59539) (xy 131.894229 -206.590891) (xy 131.88823 -206.589884)
			(xy 131.881626 -206.589122) (xy 131.868418 -206.590646) (xy 131.862068 -206.59344) (xy 131.828032 -206.605886)
			(xy 131.827778 -206.605886) (xy 131.82092 -206.607918) (xy 131.801362 -206.612998) (xy 131.800854 -206.612998)
			(xy 131.784852 -206.6163) (xy 131.784344 -206.6163) (xy 131.775708 -206.617824) (xy 131.775454 -206.617824)
			(xy 131.772406 -206.618332) (xy 131.764355 -206.620427) (xy 131.750092 -206.62897) (xy 131.744466 -206.635096)
			(xy 131.738878 -206.6417) (xy 131.73583 -206.650082) (xy 131.734308 -206.65437) (xy 131.732643 -206.663314)
			(xy 131.732528 -206.667862) (xy 131.732528 -208.516474) (xy 132.095492 -208.516474) (xy 132.099563 -208.460852)
			(xy 132.111689 -208.406415) (xy 132.131612 -208.354324) (xy 132.158908 -208.305689) (xy 132.192994 -208.261546)
			(xy 132.233143 -208.222837) (xy 132.278501 -208.190386) (xy 132.328101 -208.164885) (xy 132.380885 -208.146878)
			(xy 132.435728 -208.136748) (xy 132.491462 -208.134711) (xy 132.546899 -208.140811) (xy 132.600856 -208.154917)
			(xy 132.652185 -208.176729) (xy 132.699791 -208.205783) (xy 132.742659 -208.241458) (xy 132.779876 -208.282995)
			(xy 132.802933 -208.317846) (xy 141.030196 -208.317846) (xy 141.034267 -208.262224) (xy 141.046393 -208.207787)
			(xy 141.066316 -208.155696) (xy 141.093612 -208.107061) (xy 141.127698 -208.062918) (xy 141.167847 -208.024209)
			(xy 141.213205 -207.991758) (xy 141.262805 -207.966257) (xy 141.315589 -207.94825) (xy 141.370432 -207.93812)
			(xy 141.426166 -207.936083) (xy 141.481603 -207.942183) (xy 141.53556 -207.956289) (xy 141.586889 -207.978101)
			(xy 141.623754 -208.0006) (xy 142.467582 -208.0006) (xy 142.471653 -207.944978) (xy 142.483779 -207.890541)
			(xy 142.503702 -207.83845) (xy 142.530998 -207.789815) (xy 142.565084 -207.745672) (xy 142.605233 -207.706963)
			(xy 142.650591 -207.674512) (xy 142.700191 -207.649011) (xy 142.752975 -207.631004) (xy 142.807818 -207.620874)
			(xy 142.863552 -207.618837) (xy 142.918989 -207.624937) (xy 142.972946 -207.639043) (xy 143.024275 -207.660855)
			(xy 143.071881 -207.689909) (xy 143.114749 -207.725584) (xy 143.151966 -207.767121) (xy 143.182739 -207.813634)
			(xy 143.206411 -207.864131) (xy 143.222479 -207.917538) (xy 143.230599 -207.972714) (xy 143.231108 -208.0006)
			(xy 143.230599 -208.028486) (xy 143.222479 -208.083662) (xy 143.206411 -208.137069) (xy 143.182739 -208.187566)
			(xy 143.151966 -208.234079) (xy 143.114749 -208.275616) (xy 143.071881 -208.311291) (xy 143.024275 -208.340345)
			(xy 142.972946 -208.362157) (xy 142.918989 -208.376263) (xy 142.863552 -208.382363) (xy 142.807818 -208.380326)
			(xy 142.752975 -208.370196) (xy 142.700191 -208.352189) (xy 142.650591 -208.326688) (xy 142.605233 -208.294237)
			(xy 142.565084 -208.255528) (xy 142.530998 -208.211385) (xy 142.503702 -208.16275) (xy 142.483779 -208.110659)
			(xy 142.471653 -208.056222) (xy 142.467582 -208.0006) (xy 141.623754 -208.0006) (xy 141.634495 -208.007155)
			(xy 141.677363 -208.04283) (xy 141.71458 -208.084367) (xy 141.745353 -208.13088) (xy 141.769025 -208.181377)
			(xy 141.785093 -208.234784) (xy 141.793213 -208.28996) (xy 141.793722 -208.317846) (xy 141.793213 -208.345732)
			(xy 141.785093 -208.400908) (xy 141.769025 -208.454315) (xy 141.745353 -208.504812) (xy 141.71458 -208.551325)
			(xy 141.677363 -208.592862) (xy 141.634495 -208.628537) (xy 141.586889 -208.657591) (xy 141.53556 -208.679403)
			(xy 141.481603 -208.693509) (xy 141.426166 -208.699609) (xy 141.370432 -208.697572) (xy 141.315589 -208.687442)
			(xy 141.262805 -208.669435) (xy 141.213205 -208.643934) (xy 141.167847 -208.611483) (xy 141.127698 -208.572774)
			(xy 141.093612 -208.528631) (xy 141.066316 -208.479996) (xy 141.046393 -208.427905) (xy 141.034267 -208.373468)
			(xy 141.030196 -208.317846) (xy 132.802933 -208.317846) (xy 132.810649 -208.329508) (xy 132.834321 -208.380005)
			(xy 132.850389 -208.433412) (xy 132.858509 -208.488588) (xy 132.859018 -208.516474) (xy 132.858509 -208.54436)
			(xy 132.850389 -208.599536) (xy 132.834321 -208.652943) (xy 132.810649 -208.70344) (xy 132.779876 -208.749953)
			(xy 132.742659 -208.79149) (xy 132.699791 -208.827165) (xy 132.652185 -208.856219) (xy 132.600856 -208.878031)
			(xy 132.546899 -208.892137) (xy 132.491462 -208.898237) (xy 132.435728 -208.8962) (xy 132.380885 -208.88607)
			(xy 132.328101 -208.868063) (xy 132.278501 -208.842562) (xy 132.233143 -208.810111) (xy 132.192994 -208.771402)
			(xy 132.158908 -208.727259) (xy 132.131612 -208.678624) (xy 132.111689 -208.626533) (xy 132.099563 -208.572096)
			(xy 132.095492 -208.516474) (xy 131.732528 -208.516474) (xy 131.732528 -208.964022) (xy 134.571484 -208.964022)
			(xy 134.575555 -208.9084) (xy 134.587681 -208.853963) (xy 134.607604 -208.801872) (xy 134.6349 -208.753237)
			(xy 134.668986 -208.709094) (xy 134.709135 -208.670385) (xy 134.754493 -208.637934) (xy 134.804093 -208.612433)
			(xy 134.856877 -208.594426) (xy 134.91172 -208.584296) (xy 134.967454 -208.582259) (xy 135.022891 -208.588359)
			(xy 135.076848 -208.602465) (xy 135.128177 -208.624277) (xy 135.175783 -208.653331) (xy 135.218651 -208.689006)
			(xy 135.255868 -208.730543) (xy 135.286641 -208.777056) (xy 135.310313 -208.827553) (xy 135.326381 -208.88096)
			(xy 135.334501 -208.936136) (xy 135.33501 -208.964022) (xy 135.334501 -208.991908) (xy 135.326381 -209.047084)
			(xy 135.316524 -209.079846) (xy 137.982196 -209.079846) (xy 137.986267 -209.024224) (xy 137.998393 -208.969787)
			(xy 138.018316 -208.917696) (xy 138.045612 -208.869061) (xy 138.079698 -208.824918) (xy 138.119847 -208.786209)
			(xy 138.165205 -208.753758) (xy 138.214805 -208.728257) (xy 138.267589 -208.71025) (xy 138.322432 -208.70012)
			(xy 138.378166 -208.698083) (xy 138.433603 -208.704183) (xy 138.48756 -208.718289) (xy 138.538889 -208.740101)
			(xy 138.586495 -208.769155) (xy 138.629363 -208.80483) (xy 138.66658 -208.846367) (xy 138.697353 -208.89288)
			(xy 138.721025 -208.943377) (xy 138.737093 -208.996784) (xy 138.745213 -209.05196) (xy 138.745722 -209.079846)
			(xy 138.74569 -209.081624) (xy 138.927838 -209.081624) (xy 138.931909 -209.026002) (xy 138.944035 -208.971565)
			(xy 138.963958 -208.919474) (xy 138.991254 -208.870839) (xy 139.02534 -208.826696) (xy 139.065489 -208.787987)
			(xy 139.110847 -208.755536) (xy 139.160447 -208.730035) (xy 139.213231 -208.712028) (xy 139.268074 -208.701898)
			(xy 139.323808 -208.699861) (xy 139.379245 -208.705961) (xy 139.433202 -208.720067) (xy 139.484531 -208.741879)
			(xy 139.532137 -208.770933) (xy 139.575005 -208.806608) (xy 139.592242 -208.825846) (xy 141.792196 -208.825846)
			(xy 141.796267 -208.770224) (xy 141.808393 -208.715787) (xy 141.828316 -208.663696) (xy 141.855612 -208.615061)
			(xy 141.889698 -208.570918) (xy 141.929847 -208.532209) (xy 141.975205 -208.499758) (xy 142.024805 -208.474257)
			(xy 142.077589 -208.45625) (xy 142.132432 -208.44612) (xy 142.188166 -208.444083) (xy 142.243603 -208.450183)
			(xy 142.29756 -208.464289) (xy 142.348889 -208.486101) (xy 142.396495 -208.515155) (xy 142.439363 -208.55083)
			(xy 142.47658 -208.592367) (xy 142.507353 -208.63888) (xy 142.531025 -208.689377) (xy 142.547093 -208.742784)
			(xy 142.555213 -208.79796) (xy 142.555722 -208.825846) (xy 142.555213 -208.853732) (xy 142.547093 -208.908908)
			(xy 142.531025 -208.962315) (xy 142.507353 -209.012812) (xy 142.47658 -209.059325) (xy 142.439363 -209.100862)
			(xy 142.396495 -209.136537) (xy 142.348889 -209.165591) (xy 142.29756 -209.187403) (xy 142.243603 -209.201509)
			(xy 142.188166 -209.207609) (xy 142.132432 -209.205572) (xy 142.077589 -209.195442) (xy 142.024805 -209.177435)
			(xy 141.975205 -209.151934) (xy 141.929847 -209.119483) (xy 141.889698 -209.080774) (xy 141.855612 -209.036631)
			(xy 141.828316 -208.987996) (xy 141.808393 -208.935905) (xy 141.796267 -208.881468) (xy 141.792196 -208.825846)
			(xy 139.592242 -208.825846) (xy 139.612222 -208.848145) (xy 139.642995 -208.894658) (xy 139.666667 -208.945155)
			(xy 139.682735 -208.998562) (xy 139.690855 -209.053738) (xy 139.691364 -209.081624) (xy 139.690855 -209.10951)
			(xy 139.682735 -209.164686) (xy 139.666667 -209.218093) (xy 139.642995 -209.26859) (xy 139.612222 -209.315103)
			(xy 139.575005 -209.35664) (xy 139.532137 -209.392315) (xy 139.484531 -209.421369) (xy 139.433202 -209.443181)
			(xy 139.379245 -209.457287) (xy 139.323808 -209.463387) (xy 139.268074 -209.46135) (xy 139.213231 -209.45122)
			(xy 139.160447 -209.433213) (xy 139.110847 -209.407712) (xy 139.065489 -209.375261) (xy 139.02534 -209.336552)
			(xy 138.991254 -209.292409) (xy 138.963958 -209.243774) (xy 138.944035 -209.191683) (xy 138.931909 -209.137246)
			(xy 138.927838 -209.081624) (xy 138.74569 -209.081624) (xy 138.745213 -209.107732) (xy 138.737093 -209.162908)
			(xy 138.721025 -209.216315) (xy 138.697353 -209.266812) (xy 138.66658 -209.313325) (xy 138.629363 -209.354862)
			(xy 138.586495 -209.390537) (xy 138.538889 -209.419591) (xy 138.48756 -209.441403) (xy 138.433603 -209.455509)
			(xy 138.378166 -209.461609) (xy 138.322432 -209.459572) (xy 138.267589 -209.449442) (xy 138.214805 -209.431435)
			(xy 138.165205 -209.405934) (xy 138.119847 -209.373483) (xy 138.079698 -209.334774) (xy 138.045612 -209.290631)
			(xy 138.018316 -209.241996) (xy 137.998393 -209.189905) (xy 137.986267 -209.135468) (xy 137.982196 -209.079846)
			(xy 135.316524 -209.079846) (xy 135.310313 -209.100491) (xy 135.286641 -209.150988) (xy 135.255868 -209.197501)
			(xy 135.218651 -209.239038) (xy 135.175783 -209.274713) (xy 135.128177 -209.303767) (xy 135.076848 -209.325579)
			(xy 135.022891 -209.339685) (xy 134.967454 -209.345785) (xy 134.91172 -209.343748) (xy 134.856877 -209.333618)
			(xy 134.804093 -209.315611) (xy 134.754493 -209.29011) (xy 134.709135 -209.257659) (xy 134.668986 -209.21895)
			(xy 134.6349 -209.174807) (xy 134.607604 -209.126172) (xy 134.587681 -209.074081) (xy 134.575555 -209.019644)
			(xy 134.571484 -208.964022) (xy 131.732528 -208.964022) (xy 131.732528 -209.463894) (xy 132.328156 -209.463894)
			(xy 132.332227 -209.408272) (xy 132.344353 -209.353835) (xy 132.364276 -209.301744) (xy 132.391572 -209.253109)
			(xy 132.425658 -209.208966) (xy 132.465807 -209.170257) (xy 132.511165 -209.137806) (xy 132.560765 -209.112305)
			(xy 132.613549 -209.094298) (xy 132.668392 -209.084168) (xy 132.724126 -209.082131) (xy 132.779563 -209.088231)
			(xy 132.83352 -209.102337) (xy 132.884849 -209.124149) (xy 132.932455 -209.153203) (xy 132.975323 -209.188878)
			(xy 133.01254 -209.230415) (xy 133.043313 -209.276928) (xy 133.066985 -209.327425) (xy 133.083053 -209.380832)
			(xy 133.091173 -209.436008) (xy 133.091682 -209.463894) (xy 133.091173 -209.49178) (xy 133.083053 -209.546956)
			(xy 133.066985 -209.600363) (xy 133.043313 -209.65086) (xy 133.01254 -209.697373) (xy 132.975323 -209.73891)
			(xy 132.932455 -209.774585) (xy 132.884849 -209.803639) (xy 132.83352 -209.825451) (xy 132.779563 -209.839557)
			(xy 132.724126 -209.845657) (xy 132.668392 -209.84362) (xy 132.613549 -209.83349) (xy 132.560765 -209.815483)
			(xy 132.511165 -209.789982) (xy 132.465807 -209.757531) (xy 132.425658 -209.718822) (xy 132.391572 -209.674679)
			(xy 132.364276 -209.626044) (xy 132.344353 -209.573953) (xy 132.332227 -209.519516) (xy 132.328156 -209.463894)
			(xy 131.732528 -209.463894) (xy 131.732528 -209.633312) (xy 131.733007 -209.644061) (xy 131.741826 -209.663664)
			(xy 131.749546 -209.671158) (xy 131.769344 -209.689329) (xy 131.804144 -209.730275) (xy 131.83285 -209.775702)
			(xy 131.854893 -209.82471) (xy 131.869835 -209.876327) (xy 131.877381 -209.929532) (xy 131.877381 -209.983268)
			(xy 131.869835 -210.036473) (xy 131.854893 -210.08809) (xy 131.83285 -210.137098) (xy 131.804144 -210.182525)
			(xy 131.769344 -210.223471) (xy 131.749546 -210.241642) (xy 131.741937 -210.249212) (xy 131.733161 -210.268772)
			(xy 131.732528 -210.279488) (xy 131.732528 -210.39709) (xy 137.064748 -210.39709) (xy 137.068819 -210.341468)
			(xy 137.080945 -210.287031) (xy 137.100868 -210.23494) (xy 137.128164 -210.186305) (xy 137.16225 -210.142162)
			(xy 137.202399 -210.103453) (xy 137.247757 -210.071002) (xy 137.297357 -210.045501) (xy 137.350141 -210.027494)
			(xy 137.404984 -210.017364) (xy 137.460718 -210.015327) (xy 137.516155 -210.021427) (xy 137.570112 -210.035533)
			(xy 137.621441 -210.057345) (xy 137.669047 -210.086399) (xy 137.711915 -210.122074) (xy 137.749132 -210.163611)
			(xy 137.779905 -210.210124) (xy 137.794799 -210.241896) (xy 143.716756 -210.241896) (xy 143.717306 -210.214112)
			(xy 143.725348 -210.159129) (xy 143.74129 -210.105898) (xy 143.764794 -210.055546) (xy 143.795362 -210.009141)
			(xy 143.832345 -209.967668) (xy 143.874959 -209.932006) (xy 143.898366 -209.91703) (xy 143.909807 -209.909486)
			(xy 143.928518 -209.889481) (xy 143.941234 -209.865219) (xy 143.94704 -209.838449) (xy 143.945516 -209.811099)
			(xy 143.936772 -209.785139) (xy 143.921439 -209.76244) (xy 143.91132 -209.7532) (xy 143.890865 -209.734994)
			(xy 143.854862 -209.693735) (xy 143.82513 -209.647751) (xy 143.80228 -209.597988) (xy 143.78678 -209.545469)
			(xy 143.77895 -209.491273) (xy 143.778478 -209.463894) (xy 143.778964 -209.436643) (xy 143.78672 -209.382695)
			(xy 143.802075 -209.3304) (xy 143.824717 -209.280823) (xy 143.854183 -209.234973) (xy 143.889874 -209.193782)
			(xy 143.931065 -209.158091) (xy 143.976915 -209.128625) (xy 144.026492 -209.105983) (xy 144.078787 -209.090628)
			(xy 144.132735 -209.082872) (xy 144.187237 -209.082872) (xy 144.241185 -209.090628) (xy 144.29348 -209.105983)
			(xy 144.343057 -209.128625) (xy 144.388907 -209.158091) (xy 144.430098 -209.193782) (xy 144.465789 -209.234973)
			(xy 144.495255 -209.280823) (xy 144.517897 -209.3304) (xy 144.533252 -209.382695) (xy 144.541008 -209.436643)
			(xy 144.541494 -209.463894) (xy 144.541038 -209.491682) (xy 144.532982 -209.546669) (xy 144.517025 -209.599904)
			(xy 144.493506 -209.650257) (xy 144.462924 -209.696661) (xy 144.425926 -209.73813) (xy 144.383298 -209.773787)
			(xy 144.359884 -209.78876) (xy 144.348452 -209.796318) (xy 144.329733 -209.816317) (xy 144.31701 -209.840577)
			(xy 144.311201 -209.867346) (xy 144.312724 -209.894697) (xy 144.32147 -209.920656) (xy 144.336808 -209.943352)
			(xy 144.34693 -209.95259) (xy 144.36737 -209.970812) (xy 144.403376 -210.012066) (xy 144.433111 -210.058046)
			(xy 144.455965 -210.107806) (xy 144.471467 -210.160323) (xy 144.479299 -210.214517) (xy 144.479772 -210.241896)
			(xy 144.479286 -210.269147) (xy 144.47153 -210.323095) (xy 144.456175 -210.37539) (xy 144.433533 -210.424967)
			(xy 144.404067 -210.470817) (xy 144.368376 -210.512008) (xy 144.327185 -210.547699) (xy 144.281335 -210.577165)
			(xy 144.231758 -210.599807) (xy 144.179463 -210.615162) (xy 144.125515 -210.622918) (xy 144.071013 -210.622918)
			(xy 144.017065 -210.615162) (xy 143.96477 -210.599807) (xy 143.915193 -210.577165) (xy 143.869343 -210.547699)
			(xy 143.828152 -210.512008) (xy 143.792461 -210.470817) (xy 143.762995 -210.424967) (xy 143.740353 -210.37539)
			(xy 143.724998 -210.323095) (xy 143.717242 -210.269147) (xy 143.716756 -210.241896) (xy 137.794799 -210.241896)
			(xy 137.803577 -210.260621) (xy 137.819645 -210.314028) (xy 137.827765 -210.369204) (xy 137.828274 -210.39709)
			(xy 137.827765 -210.424976) (xy 137.819645 -210.480152) (xy 137.803577 -210.533559) (xy 137.779905 -210.584056)
			(xy 137.749132 -210.630569) (xy 137.711915 -210.672106) (xy 137.669047 -210.707781) (xy 137.621441 -210.736835)
			(xy 137.570112 -210.758647) (xy 137.516155 -210.772753) (xy 137.460718 -210.778853) (xy 137.404984 -210.776816)
			(xy 137.350141 -210.766686) (xy 137.297357 -210.748679) (xy 137.247757 -210.723178) (xy 137.202399 -210.690727)
			(xy 137.16225 -210.652018) (xy 137.128164 -210.607875) (xy 137.100868 -210.55924) (xy 137.080945 -210.507149)
			(xy 137.068819 -210.452712) (xy 137.064748 -210.39709) (xy 131.732528 -210.39709) (xy 131.732528 -211.627974)
			(xy 131.732782 -211.6328) (xy 131.734123 -211.642798) (xy 131.743561 -211.660607) (xy 131.75107 -211.667344)
			(xy 131.773489 -211.68396) (xy 131.81368 -211.722672) (xy 131.832361 -211.746846) (xy 134.826246 -211.746846)
			(xy 134.830317 -211.691224) (xy 134.842443 -211.636787) (xy 134.862366 -211.584696) (xy 134.889662 -211.536061)
			(xy 134.923748 -211.491918) (xy 134.963897 -211.453209) (xy 135.009255 -211.420758) (xy 135.058855 -211.395257)
			(xy 135.111639 -211.37725) (xy 135.166482 -211.36712) (xy 135.222216 -211.365083) (xy 135.277653 -211.371183)
			(xy 135.33161 -211.385289) (xy 135.382939 -211.407101) (xy 135.430545 -211.436155) (xy 135.473413 -211.47183)
			(xy 135.51063 -211.513367) (xy 135.541403 -211.55988) (xy 135.565075 -211.610377) (xy 135.581143 -211.663784)
			(xy 135.589263 -211.71896) (xy 135.589772 -211.746846) (xy 135.589263 -211.774732) (xy 135.581143 -211.829908)
			(xy 135.565075 -211.883315) (xy 135.541403 -211.933812) (xy 135.51063 -211.980325) (xy 135.473413 -212.021862)
			(xy 135.430545 -212.057537) (xy 135.382939 -212.086591) (xy 135.33161 -212.108403) (xy 135.277653 -212.122509)
			(xy 135.222216 -212.128609) (xy 135.166482 -212.126572) (xy 135.111639 -212.116442) (xy 135.058855 -212.098435)
			(xy 135.009255 -212.072934) (xy 134.963897 -212.040483) (xy 134.923748 -212.001774) (xy 134.889662 -211.957631)
			(xy 134.862366 -211.908996) (xy 134.842443 -211.856905) (xy 134.830317 -211.802468) (xy 134.826246 -211.746846)
			(xy 131.832361 -211.746846) (xy 131.847802 -211.766827) (xy 131.875127 -211.815482) (xy 131.895072 -211.867598)
			(xy 131.90721 -211.922065) (xy 131.911283 -211.977719) (xy 131.907205 -212.033372) (xy 131.895061 -212.087837)
			(xy 131.875111 -212.139952) (xy 131.847782 -212.188604) (xy 131.813655 -212.232755) (xy 131.77346 -212.271463)
			(xy 131.75107 -212.28812) (xy 131.743584 -212.29487) (xy 131.734175 -212.312679) (xy 131.732782 -212.322664)
			(xy 131.732528 -212.32749) (xy 131.732528 -213.016846) (xy 135.924796 -213.016846) (xy 135.928867 -212.961224)
			(xy 135.940993 -212.906787) (xy 135.960916 -212.854696) (xy 135.988212 -212.806061) (xy 136.022298 -212.761918)
			(xy 136.062447 -212.723209) (xy 136.107805 -212.690758) (xy 136.157405 -212.665257) (xy 136.210189 -212.64725)
			(xy 136.265032 -212.63712) (xy 136.320766 -212.635083) (xy 136.376203 -212.641183) (xy 136.43016 -212.655289)
			(xy 136.481489 -212.677101) (xy 136.529095 -212.706155) (xy 136.571963 -212.74183) (xy 136.60918 -212.783367)
			(xy 136.639953 -212.82988) (xy 136.663625 -212.880377) (xy 136.679693 -212.933784) (xy 136.687813 -212.98896)
			(xy 136.688322 -213.016846) (xy 136.687813 -213.044732) (xy 136.679693 -213.099908) (xy 136.663625 -213.153315)
			(xy 136.639953 -213.203812) (xy 136.60918 -213.250325) (xy 136.571963 -213.291862) (xy 136.529095 -213.327537)
			(xy 136.481489 -213.356591) (xy 136.43016 -213.378403) (xy 136.376203 -213.392509) (xy 136.320766 -213.398609)
			(xy 136.265032 -213.396572) (xy 136.210189 -213.386442) (xy 136.157405 -213.368435) (xy 136.107805 -213.342934)
			(xy 136.062447 -213.310483) (xy 136.022298 -213.271774) (xy 135.988212 -213.227631) (xy 135.960916 -213.178996)
			(xy 135.940993 -213.126905) (xy 135.928867 -213.072468) (xy 135.924796 -213.016846) (xy 131.732528 -213.016846)
			(xy 131.732528 -214.917782) (xy 131.880862 -214.917782) (xy 131.884933 -214.86216) (xy 131.897059 -214.807723)
			(xy 131.916982 -214.755632) (xy 131.944278 -214.706997) (xy 131.978364 -214.662854) (xy 132.018513 -214.624145)
			(xy 132.063871 -214.591694) (xy 132.113471 -214.566193) (xy 132.166255 -214.548186) (xy 132.221098 -214.538056)
			(xy 132.276832 -214.536019) (xy 132.332269 -214.542119) (xy 132.386226 -214.556225) (xy 132.437555 -214.578037)
			(xy 132.485161 -214.607091) (xy 132.528029 -214.642766) (xy 132.550501 -214.667846) (xy 132.902196 -214.667846)
			(xy 132.906267 -214.612224) (xy 132.918393 -214.557787) (xy 132.938316 -214.505696) (xy 132.965612 -214.457061)
			(xy 132.999698 -214.412918) (xy 133.039847 -214.374209) (xy 133.085205 -214.341758) (xy 133.134805 -214.316257)
			(xy 133.187589 -214.29825) (xy 133.242432 -214.28812) (xy 133.298166 -214.286083) (xy 133.353603 -214.292183)
			(xy 133.40756 -214.306289) (xy 133.458889 -214.328101) (xy 133.506495 -214.357155) (xy 133.549363 -214.39283)
			(xy 133.58658 -214.434367) (xy 133.617353 -214.48088) (xy 133.641025 -214.531377) (xy 133.657093 -214.584784)
			(xy 133.665213 -214.63996) (xy 133.665722 -214.667846) (xy 134.426196 -214.667846) (xy 134.430267 -214.612224)
			(xy 134.442393 -214.557787) (xy 134.462316 -214.505696) (xy 134.489612 -214.457061) (xy 134.523698 -214.412918)
			(xy 134.563847 -214.374209) (xy 134.609205 -214.341758) (xy 134.658805 -214.316257) (xy 134.711589 -214.29825)
			(xy 134.766432 -214.28812) (xy 134.822166 -214.286083) (xy 134.877603 -214.292183) (xy 134.93156 -214.306289)
			(xy 134.982889 -214.328101) (xy 135.030495 -214.357155) (xy 135.073363 -214.39283) (xy 135.11058 -214.434367)
			(xy 135.141353 -214.48088) (xy 135.165025 -214.531377) (xy 135.181093 -214.584784) (xy 135.189213 -214.63996)
			(xy 135.189722 -214.667846) (xy 135.189213 -214.695732) (xy 135.181093 -214.750908) (xy 135.165025 -214.804315)
			(xy 135.141353 -214.854812) (xy 135.11058 -214.901325) (xy 135.073363 -214.942862) (xy 135.030495 -214.978537)
			(xy 134.982889 -215.007591) (xy 134.93156 -215.029403) (xy 134.877603 -215.043509) (xy 134.822166 -215.049609)
			(xy 134.766432 -215.047572) (xy 134.711589 -215.037442) (xy 134.658805 -215.019435) (xy 134.609205 -214.993934)
			(xy 134.563847 -214.961483) (xy 134.523698 -214.922774) (xy 134.489612 -214.878631) (xy 134.462316 -214.829996)
			(xy 134.442393 -214.777905) (xy 134.430267 -214.723468) (xy 134.426196 -214.667846) (xy 133.665722 -214.667846)
			(xy 133.665213 -214.695732) (xy 133.657093 -214.750908) (xy 133.641025 -214.804315) (xy 133.617353 -214.854812)
			(xy 133.58658 -214.901325) (xy 133.549363 -214.942862) (xy 133.506495 -214.978537) (xy 133.458889 -215.007591)
			(xy 133.40756 -215.029403) (xy 133.353603 -215.043509) (xy 133.298166 -215.049609) (xy 133.242432 -215.047572)
			(xy 133.187589 -215.037442) (xy 133.134805 -215.019435) (xy 133.085205 -214.993934) (xy 133.039847 -214.961483)
			(xy 132.999698 -214.922774) (xy 132.965612 -214.878631) (xy 132.938316 -214.829996) (xy 132.918393 -214.777905)
			(xy 132.906267 -214.723468) (xy 132.902196 -214.667846) (xy 132.550501 -214.667846) (xy 132.565246 -214.684303)
			(xy 132.596019 -214.730816) (xy 132.619691 -214.781313) (xy 132.635759 -214.83472) (xy 132.643879 -214.889896)
			(xy 132.644388 -214.917782) (xy 132.643879 -214.945668) (xy 132.635759 -215.000844) (xy 132.619691 -215.054251)
			(xy 132.596019 -215.104748) (xy 132.56965 -215.144604) (xy 133.662164 -215.144604) (xy 133.666235 -215.088982)
			(xy 133.678361 -215.034545) (xy 133.698284 -214.982454) (xy 133.72558 -214.933819) (xy 133.759666 -214.889676)
			(xy 133.799815 -214.850967) (xy 133.845173 -214.818516) (xy 133.894773 -214.793015) (xy 133.947557 -214.775008)
			(xy 134.0024 -214.764878) (xy 134.058134 -214.762841) (xy 134.113571 -214.768941) (xy 134.167528 -214.783047)
			(xy 134.218857 -214.804859) (xy 134.266463 -214.833913) (xy 134.309331 -214.869588) (xy 134.346548 -214.911125)
			(xy 134.377321 -214.957638) (xy 134.400993 -215.008135) (xy 134.417061 -215.061542) (xy 134.425181 -215.116718)
			(xy 134.42569 -215.144604) (xy 134.425181 -215.17249) (xy 134.417061 -215.227666) (xy 134.400993 -215.281073)
			(xy 134.377321 -215.33157) (xy 134.346548 -215.378083) (xy 134.309331 -215.41962) (xy 134.266463 -215.455295)
			(xy 134.218857 -215.484349) (xy 134.167528 -215.506161) (xy 134.113571 -215.520267) (xy 134.058134 -215.526367)
			(xy 134.0024 -215.52433) (xy 133.947557 -215.5142) (xy 133.894773 -215.496193) (xy 133.845173 -215.470692)
			(xy 133.799815 -215.438241) (xy 133.759666 -215.399532) (xy 133.72558 -215.355389) (xy 133.698284 -215.306754)
			(xy 133.678361 -215.254663) (xy 133.666235 -215.200226) (xy 133.662164 -215.144604) (xy 132.56965 -215.144604)
			(xy 132.565246 -215.151261) (xy 132.528029 -215.192798) (xy 132.485161 -215.228473) (xy 132.437555 -215.257527)
			(xy 132.386226 -215.279339) (xy 132.332269 -215.293445) (xy 132.276832 -215.299545) (xy 132.221098 -215.297508)
			(xy 132.166255 -215.287378) (xy 132.113471 -215.269371) (xy 132.063871 -215.24387) (xy 132.018513 -215.211419)
			(xy 131.978364 -215.17271) (xy 131.944278 -215.128567) (xy 131.916982 -215.079932) (xy 131.897059 -215.027841)
			(xy 131.884933 -214.973404) (xy 131.880862 -214.917782) (xy 131.732528 -214.917782) (xy 131.732528 -215.27897)
			(xy 131.73329 -215.287098) (xy 131.73329 -215.287606) (xy 131.734887 -215.295126) (xy 131.741858 -215.308821)
			(xy 131.747006 -215.31453) (xy 132.289296 -215.85682) (xy 135.41451 -215.85682) (xy 135.418581 -215.801198)
			(xy 135.430707 -215.746761) (xy 135.45063 -215.69467) (xy 135.477926 -215.646035) (xy 135.512012 -215.601892)
			(xy 135.552161 -215.563183) (xy 135.597519 -215.530732) (xy 135.647119 -215.505231) (xy 135.699903 -215.487224)
			(xy 135.754746 -215.477094) (xy 135.81048 -215.475057) (xy 135.865917 -215.481157) (xy 135.919874 -215.495263)
			(xy 135.971203 -215.517075) (xy 136.018809 -215.546129) (xy 136.061677 -215.581804) (xy 136.098894 -215.623341)
			(xy 136.129667 -215.669854) (xy 136.153339 -215.720351) (xy 136.169407 -215.773758) (xy 136.177527 -215.828934)
			(xy 136.178036 -215.85682) (xy 136.177527 -215.884706) (xy 136.169407 -215.939882) (xy 136.153339 -215.993289)
			(xy 136.129667 -216.043786) (xy 136.098894 -216.090299) (xy 136.061677 -216.131836) (xy 136.018809 -216.167511)
			(xy 135.971203 -216.196565) (xy 135.919874 -216.218377) (xy 135.865917 -216.232483) (xy 135.81048 -216.238583)
			(xy 135.754746 -216.236546) (xy 135.699903 -216.226416) (xy 135.647119 -216.208409) (xy 135.597519 -216.182908)
			(xy 135.552161 -216.150457) (xy 135.512012 -216.111748) (xy 135.477926 -216.067605) (xy 135.45063 -216.01897)
			(xy 135.430707 -215.966879) (xy 135.418581 -215.912442) (xy 135.41451 -215.85682) (xy 132.289296 -215.85682)
			(xy 133.300724 -216.868248) (xy 133.306405 -216.873437) (xy 133.320112 -216.880407) (xy 133.327648 -216.881964)
			(xy 133.328156 -216.881964) (xy 133.336284 -216.882726)
		)
		(stroke
			(width 0)
			(type solid)
		)
		(fill yes)
		(layer "In5.Cu")
		(net "P1V8_CLI_VCORE")
	)
	(gr_poly
		(pts
			(xy 43.183556 -276.80158) (xy 43.189144 -276.78634) (xy 43.198256 -276.762798) (xy 43.222588 -276.71857)
			(xy 43.253358 -276.678553) (xy 43.289851 -276.643677) (xy 43.331221 -276.614751) (xy 43.376506 -276.592447)
			(xy 43.424653 -276.577284) (xy 43.474546 -276.569613) (xy 43.525026 -276.569613) (xy 43.574919 -276.577284)
			(xy 43.623066 -276.592447) (xy 43.668351 -276.614751) (xy 43.709721 -276.643677) (xy 43.746214 -276.678553)
			(xy 43.776984 -276.71857) (xy 43.801316 -276.762798) (xy 43.810428 -276.78634) (xy 43.816016 -276.80158)
			(xy 43.841924 -276.819614) (xy 44.107608 -276.819614) (xy 44.133516 -276.80158) (xy 44.139104 -276.78634)
			(xy 44.148216 -276.762798) (xy 44.172548 -276.71857) (xy 44.203318 -276.678553) (xy 44.239811 -276.643677)
			(xy 44.281181 -276.614751) (xy 44.326466 -276.592447) (xy 44.374613 -276.577284) (xy 44.424506 -276.569613)
			(xy 44.474986 -276.569613) (xy 44.524879 -276.577284) (xy 44.573026 -276.592447) (xy 44.618311 -276.614751)
			(xy 44.659681 -276.643677) (xy 44.696174 -276.678553) (xy 44.726944 -276.71857) (xy 44.751276 -276.762798)
			(xy 44.760388 -276.78634) (xy 44.765976 -276.80158) (xy 44.791884 -276.819614) (xy 45.057822 -276.819614)
			(xy 45.08373 -276.80158) (xy 45.089318 -276.78634) (xy 45.09843 -276.762798) (xy 45.122762 -276.71857)
			(xy 45.153532 -276.678553) (xy 45.190025 -276.643677) (xy 45.231395 -276.614751) (xy 45.27668 -276.592447)
			(xy 45.324827 -276.577284) (xy 45.37472 -276.569613) (xy 45.4252 -276.569613) (xy 45.475093 -276.577284)
			(xy 45.52324 -276.592447) (xy 45.568525 -276.614751) (xy 45.609895 -276.643677) (xy 45.646388 -276.678553)
			(xy 45.677158 -276.71857) (xy 45.70149 -276.762798) (xy 45.710602 -276.78634) (xy 45.71619 -276.80158)
			(xy 45.742098 -276.819614) (xy 46.007782 -276.819614) (xy 46.03369 -276.80158) (xy 46.039278 -276.78634)
			(xy 46.04839 -276.762798) (xy 46.072722 -276.71857) (xy 46.103492 -276.678553) (xy 46.139985 -276.643677)
			(xy 46.181355 -276.614751) (xy 46.22664 -276.592447) (xy 46.274787 -276.577284) (xy 46.32468 -276.569613)
			(xy 46.37516 -276.569613) (xy 46.425053 -276.577284) (xy 46.4732 -276.592447) (xy 46.518485 -276.614751)
			(xy 46.559855 -276.643677) (xy 46.596348 -276.678553) (xy 46.627118 -276.71857) (xy 46.65145 -276.762798)
			(xy 46.660562 -276.78634) (xy 46.66615 -276.80158) (xy 46.692058 -276.819614) (xy 46.957742 -276.819614)
			(xy 46.98365 -276.80158) (xy 46.989238 -276.78634) (xy 46.99835 -276.762798) (xy 47.022682 -276.71857)
			(xy 47.053452 -276.678553) (xy 47.089945 -276.643677) (xy 47.131315 -276.614751) (xy 47.1766 -276.592447)
			(xy 47.224747 -276.577284) (xy 47.27464 -276.569613) (xy 47.32512 -276.569613) (xy 47.375013 -276.577284)
			(xy 47.42316 -276.592447) (xy 47.468445 -276.614751) (xy 47.509815 -276.643677) (xy 47.546308 -276.678553)
			(xy 47.577078 -276.71857) (xy 47.60141 -276.762798) (xy 47.610522 -276.78634) (xy 47.61611 -276.80158)
			(xy 47.642018 -276.819614) (xy 47.907702 -276.819614) (xy 47.93361 -276.80158) (xy 47.939198 -276.78634)
			(xy 47.94831 -276.762798) (xy 47.972642 -276.71857) (xy 48.003412 -276.678553) (xy 48.039905 -276.643677)
			(xy 48.081275 -276.614751) (xy 48.12656 -276.592447) (xy 48.174707 -276.577284) (xy 48.2246 -276.569613)
			(xy 48.27508 -276.569613) (xy 48.324973 -276.577284) (xy 48.37312 -276.592447) (xy 48.418405 -276.614751)
			(xy 48.459775 -276.643677) (xy 48.496268 -276.678553) (xy 48.527038 -276.71857) (xy 48.55137 -276.762798)
			(xy 48.560482 -276.78634) (xy 48.56607 -276.80158) (xy 48.591978 -276.819614) (xy 48.857662 -276.819614)
			(xy 48.88357 -276.80158) (xy 48.889158 -276.78634) (xy 48.89827 -276.762798) (xy 48.922602 -276.71857)
			(xy 48.953372 -276.678553) (xy 48.989865 -276.643677) (xy 49.031235 -276.614751) (xy 49.07652 -276.592447)
			(xy 49.124667 -276.577284) (xy 49.17456 -276.569613) (xy 49.22504 -276.569613) (xy 49.274933 -276.577284)
			(xy 49.32308 -276.592447) (xy 49.368365 -276.614751) (xy 49.409735 -276.643677) (xy 49.446228 -276.678553)
			(xy 49.476998 -276.71857) (xy 49.50133 -276.762798) (xy 49.510442 -276.78634) (xy 49.51603 -276.80158)
			(xy 49.541938 -276.819614) (xy 49.807622 -276.819614) (xy 49.83353 -276.80158) (xy 49.839118 -276.78634)
			(xy 49.84823 -276.762798) (xy 49.872562 -276.71857) (xy 49.903332 -276.678553) (xy 49.939825 -276.643677)
			(xy 49.981195 -276.614751) (xy 50.02648 -276.592447) (xy 50.074627 -276.577284) (xy 50.12452 -276.569613)
			(xy 50.175 -276.569613) (xy 50.224893 -276.577284) (xy 50.27304 -276.592447) (xy 50.318325 -276.614751)
			(xy 50.359695 -276.643677) (xy 50.396188 -276.678553) (xy 50.426958 -276.71857) (xy 50.45129 -276.762798)
			(xy 50.460402 -276.78634) (xy 50.46599 -276.80158) (xy 50.491898 -276.819614) (xy 50.757836 -276.819614)
			(xy 50.783744 -276.80158) (xy 50.789332 -276.78634) (xy 50.798444 -276.762798) (xy 50.822776 -276.71857)
			(xy 50.853546 -276.678553) (xy 50.890039 -276.643677) (xy 50.931409 -276.614751) (xy 50.976694 -276.592447)
			(xy 51.024841 -276.577284) (xy 51.074734 -276.569613) (xy 51.125214 -276.569613) (xy 51.175107 -276.577284)
			(xy 51.223254 -276.592447) (xy 51.268539 -276.614751) (xy 51.309909 -276.643677) (xy 51.346402 -276.678553)
			(xy 51.377172 -276.71857) (xy 51.401504 -276.762798) (xy 51.410616 -276.78634) (xy 51.416204 -276.80158)
			(xy 51.442112 -276.819614) (xy 51.707796 -276.819614) (xy 51.733704 -276.80158) (xy 51.739292 -276.78634)
			(xy 51.748404 -276.762798) (xy 51.772736 -276.71857) (xy 51.803506 -276.678553) (xy 51.839999 -276.643677)
			(xy 51.881369 -276.614751) (xy 51.926654 -276.592447) (xy 51.974801 -276.577284) (xy 52.024694 -276.569613)
			(xy 52.075174 -276.569613) (xy 52.125067 -276.577284) (xy 52.173214 -276.592447) (xy 52.218499 -276.614751)
			(xy 52.259869 -276.643677) (xy 52.296362 -276.678553) (xy 52.327132 -276.71857) (xy 52.351464 -276.762798)
			(xy 52.360576 -276.78634) (xy 52.366164 -276.80158) (xy 52.392072 -276.819614) (xy 52.657756 -276.819614)
			(xy 52.683664 -276.80158) (xy 52.689252 -276.78634) (xy 52.698364 -276.762798) (xy 52.722696 -276.71857)
			(xy 52.753466 -276.678553) (xy 52.789959 -276.643677) (xy 52.831329 -276.614751) (xy 52.876614 -276.592447)
			(xy 52.924761 -276.577284) (xy 52.974654 -276.569613) (xy 53.025134 -276.569613) (xy 53.075027 -276.577284)
			(xy 53.123174 -276.592447) (xy 53.168459 -276.614751) (xy 53.209829 -276.643677) (xy 53.246322 -276.678553)
			(xy 53.277092 -276.71857) (xy 53.301424 -276.762798) (xy 53.310536 -276.78634) (xy 53.316124 -276.80158)
			(xy 53.342032 -276.819614) (xy 53.607716 -276.819614) (xy 53.633624 -276.80158) (xy 53.639212 -276.78634)
			(xy 53.648324 -276.762798) (xy 53.672656 -276.71857) (xy 53.703426 -276.678553) (xy 53.739919 -276.643677)
			(xy 53.781289 -276.614751) (xy 53.826574 -276.592447) (xy 53.874721 -276.577284) (xy 53.924614 -276.569613)
			(xy 53.975094 -276.569613) (xy 54.024987 -276.577284) (xy 54.073134 -276.592447) (xy 54.118419 -276.614751)
			(xy 54.159789 -276.643677) (xy 54.196282 -276.678553) (xy 54.227052 -276.71857) (xy 54.251384 -276.762798)
			(xy 54.260496 -276.78634) (xy 54.266084 -276.80158) (xy 54.291992 -276.819614) (xy 54.557676 -276.819614)
			(xy 54.583584 -276.80158) (xy 54.589172 -276.78634) (xy 54.598284 -276.762798) (xy 54.622616 -276.71857)
			(xy 54.653386 -276.678553) (xy 54.689879 -276.643677) (xy 54.731249 -276.614751) (xy 54.776534 -276.592447)
			(xy 54.824681 -276.577284) (xy 54.874574 -276.569613) (xy 54.925054 -276.569613) (xy 54.974947 -276.577284)
			(xy 55.023094 -276.592447) (xy 55.068379 -276.614751) (xy 55.109749 -276.643677) (xy 55.146242 -276.678553)
			(xy 55.177012 -276.71857) (xy 55.201344 -276.762798) (xy 55.210456 -276.78634) (xy 55.216044 -276.80158)
			(xy 55.241952 -276.819614) (xy 55.507636 -276.819614) (xy 55.533544 -276.80158) (xy 55.539132 -276.78634)
			(xy 55.548244 -276.762798) (xy 55.572576 -276.71857) (xy 55.603346 -276.678553) (xy 55.639839 -276.643677)
			(xy 55.681209 -276.614751) (xy 55.726494 -276.592447) (xy 55.774641 -276.577284) (xy 55.824534 -276.569613)
			(xy 55.875014 -276.569613) (xy 55.924907 -276.577284) (xy 55.973054 -276.592447) (xy 56.018339 -276.614751)
			(xy 56.059709 -276.643677) (xy 56.096202 -276.678553) (xy 56.126972 -276.71857) (xy 56.151304 -276.762798)
			(xy 56.160416 -276.78634) (xy 56.166004 -276.80158) (xy 56.191912 -276.819614) (xy 56.45785 -276.819614)
			(xy 56.483758 -276.80158) (xy 56.489346 -276.78634) (xy 56.498458 -276.762798) (xy 56.52279 -276.71857)
			(xy 56.55356 -276.678553) (xy 56.590053 -276.643677) (xy 56.631423 -276.614751) (xy 56.676708 -276.592447)
			(xy 56.724855 -276.577284) (xy 56.774748 -276.569613) (xy 56.825228 -276.569613) (xy 56.875121 -276.577284)
			(xy 56.923268 -276.592447) (xy 56.968553 -276.614751) (xy 57.009923 -276.643677) (xy 57.046416 -276.678553)
			(xy 57.077186 -276.71857) (xy 57.101518 -276.762798) (xy 57.11063 -276.78634) (xy 57.116218 -276.80158)
			(xy 57.142126 -276.819614) (xy 57.40781 -276.819614) (xy 57.433718 -276.80158) (xy 57.439306 -276.78634)
			(xy 57.448418 -276.762798) (xy 57.47275 -276.71857) (xy 57.50352 -276.678553) (xy 57.540013 -276.643677)
			(xy 57.581383 -276.614751) (xy 57.626668 -276.592447) (xy 57.674815 -276.577284) (xy 57.724708 -276.569613)
			(xy 57.775188 -276.569613) (xy 57.825081 -276.577284) (xy 57.873228 -276.592447) (xy 57.918513 -276.614751)
			(xy 57.959883 -276.643677) (xy 57.996376 -276.678553) (xy 58.027146 -276.71857) (xy 58.051478 -276.762798)
			(xy 58.06059 -276.78634) (xy 58.066178 -276.80158) (xy 58.092086 -276.819614) (xy 58.35777 -276.819614)
			(xy 58.383678 -276.80158) (xy 58.389266 -276.78634) (xy 58.398375 -276.762798) (xy 58.422704 -276.71857)
			(xy 58.453473 -276.678554) (xy 58.489968 -276.643681) (xy 58.531339 -276.614761) (xy 58.576626 -276.592465)
			(xy 58.624776 -276.577313) (xy 58.674669 -276.569656) (xy 58.699908 -276.56917) (xy 58.727525 -276.569728)
			(xy 58.781989 -276.578916) (xy 58.834167 -276.597035) (xy 58.858658 -276.60981) (xy 58.858912 -276.60981)
			(xy 58.868746 -276.614618) (xy 58.890554 -276.616212) (xy 58.911041 -276.608568) (xy 58.91911 -276.601174)
			(xy 58.969148 -276.551136) (xy 58.97599 -276.543737) (xy 58.983709 -276.525138) (xy 58.984134 -276.515068)
			(xy 58.984134 -276.313646) (xy 58.983839 -276.304959) (xy 58.978125 -276.288557) (xy 58.967241 -276.275022)
			(xy 58.960004 -276.270212) (xy 58.874914 -276.217888) (xy 58.848752 -276.216872) (xy 58.837068 -276.222714)
			(xy 58.815671 -276.232962) (xy 58.770498 -276.247453) (xy 58.723628 -276.254786) (xy 58.699908 -276.255226)
			(xy 58.674648 -276.254734) (xy 58.624818 -276.24642) (xy 58.577036 -276.230017) (xy 58.532605 -276.205974)
			(xy 58.492738 -276.174945) (xy 58.458521 -276.137777) (xy 58.43089 -276.095484) (xy 58.410596 -276.04922)
			(xy 58.398194 -276.000247) (xy 58.394022 -275.9499) (xy 58.398194 -275.899553) (xy 58.410596 -275.85058)
			(xy 58.43089 -275.804316) (xy 58.458521 -275.762023) (xy 58.492738 -275.724855) (xy 58.532605 -275.693826)
			(xy 58.577036 -275.669783) (xy 58.624818 -275.65338) (xy 58.674648 -275.645066) (xy 58.699908 -275.64461)
			(xy 58.723628 -275.645059) (xy 58.770497 -275.652391) (xy 58.81567 -275.666878) (xy 58.837068 -275.677122)
			(xy 58.848752 -275.682964) (xy 58.874914 -275.681948) (xy 58.960004 -275.629624) (xy 58.967201 -275.624765)
			(xy 58.978073 -275.611241) (xy 58.983818 -275.594867) (xy 58.984134 -275.58619) (xy 58.984134 -275.363686)
			(xy 58.98383 -275.355005) (xy 58.978103 -275.338617) (xy 58.967213 -275.325099) (xy 58.960004 -275.320252)
			(xy 58.874914 -275.267928) (xy 58.848752 -275.266912) (xy 58.837068 -275.272754) (xy 58.815671 -275.283001)
			(xy 58.770498 -275.297489) (xy 58.723628 -275.304822) (xy 58.699908 -275.305266) (xy 58.674653 -275.304774)
			(xy 58.624833 -275.296462) (xy 58.57706 -275.280062) (xy 58.532638 -275.256023) (xy 58.492778 -275.225)
			(xy 58.458569 -275.18784) (xy 58.430942 -275.145556) (xy 58.410653 -275.099301) (xy 58.398253 -275.050337)
			(xy 58.394082 -275) (xy 58.398253 -274.949663) (xy 58.410653 -274.900699) (xy 58.430942 -274.854444)
			(xy 58.458569 -274.81216) (xy 58.492778 -274.775) (xy 58.532638 -274.743977) (xy 58.57706 -274.719938)
			(xy 58.624833 -274.703538) (xy 58.674653 -274.695226) (xy 58.699908 -274.69465) (xy 58.718196 -274.695158)
			(xy 58.71845 -274.695158) (xy 58.727618 -274.695335) (xy 58.745122 -274.689918) (xy 58.759565 -274.678642)
			(xy 58.764678 -274.671028) (xy 58.811414 -274.594574) (xy 58.815915 -274.586545) (xy 58.81941 -274.568488)
			(xy 58.816262 -274.550368) (xy 58.811922 -274.54225) (xy 58.794396 -274.511008) (xy 58.791083 -274.505352)
			(xy 58.782079 -274.495833) (xy 58.776616 -274.492212) (xy 58.737822 -274.467172) (xy 58.664671 -274.410816)
			(xy 58.630566 -274.37969) (xy 58.62602 -274.375719) (xy 58.615497 -274.369814) (xy 58.609738 -274.368006)
			(xy 58.586688 -274.361026) (xy 58.542744 -274.341321) (xy 58.502121 -274.315452) (xy 58.465678 -274.283967)
			(xy 58.434186 -274.247531) (xy 58.40831 -274.206913) (xy 58.388596 -274.162973) (xy 58.381646 -274.139914)
			(xy 58.379853 -274.134149) (xy 58.373938 -274.123629) (xy 58.369962 -274.119086) (xy 58.339099 -274.085358)
			(xy 58.283154 -274.013042) (xy 58.23425 -273.93579) (xy 58.19282 -273.854286) (xy 58.159229 -273.769251)
			(xy 58.133776 -273.681435) (xy 58.116685 -273.591617) (xy 58.108107 -273.500591) (xy 58.10758 -273.454876)
			(xy 58.10758 -273.41576) (xy 58.107197 -273.406197) (xy 58.100194 -273.388403) (xy 58.087115 -273.374451)
			(xy 58.078624 -273.37004) (xy 57.982612 -273.324066) (xy 57.953656 -273.327622) (xy 57.942226 -273.33702)
			(xy 57.921679 -273.352982) (xy 57.876283 -273.378398) (xy 57.827238 -273.395759) (xy 57.775961 -273.404562)
			(xy 57.749948 -273.405092) (xy 57.724689 -273.404603) (xy 57.674859 -273.396295) (xy 57.627076 -273.379898)
			(xy 57.582645 -273.355859) (xy 57.542776 -273.324834) (xy 57.508559 -273.287669) (xy 57.480925 -273.245379)
			(xy 57.460631 -273.199117) (xy 57.448228 -273.150145) (xy 57.444056 -273.0998) (xy 57.448228 -273.049455)
			(xy 57.460631 -273.000483) (xy 57.480925 -272.954221) (xy 57.508559 -272.911931) (xy 57.542776 -272.874766)
			(xy 57.582645 -272.843741) (xy 57.627076 -272.819702) (xy 57.674859 -272.803305) (xy 57.724689 -272.794997)
			(xy 57.749948 -272.794476) (xy 57.77596 -272.795003) (xy 57.827233 -272.803819) (xy 57.876273 -272.821186)
			(xy 57.921665 -272.846605) (xy 57.942226 -272.862548) (xy 57.953656 -272.871946) (xy 57.982612 -272.875502)
			(xy 58.078624 -272.829528) (xy 58.087056 -272.825042) (xy 58.100072 -272.811084) (xy 58.10712 -272.793348)
			(xy 58.10758 -272.783808) (xy 58.10758 -272.105628) (xy 58.107463 -272.100938) (xy 58.105684 -272.091728)
			(xy 58.104024 -272.08734) (xy 58.087802 -272.044075) (xy 58.062494 -271.955201) (xy 58.045505 -271.864369)
			(xy 58.036981 -271.772356) (xy 58.03646 -271.726152) (xy 58.03646 -270.248888) (xy 58.034682 -270.235426)
			(xy 33.079182 -180.985414) (xy 33.07568 -180.97491) (xy 33.061326 -180.958083) (xy 33.041221 -180.948865)
			(xy 33.03016 -180.94833) (xy 28.011628 -180.94833) (xy 28.001605 -180.948745) (xy 27.983084 -180.956411)
			(xy 27.96891 -180.970586) (xy 27.961245 -180.989107) (xy 27.960828 -180.99913) (xy 27.960828 -189.392814)
			(xy 27.961254 -189.402882) (xy 27.968975 -189.421481) (xy 27.975814 -189.428882) (xy 29.994352 -191.44742)
			(xy 30.002711 -191.455005) (xy 30.023905 -191.462689) (xy 30.046348 -191.460564) (xy 30.056328 -191.455294)
			(xy 30.078521 -191.442584) (xy 30.125582 -191.422562) (xy 30.174894 -191.408999) (xy 30.225575 -191.40214)
			(xy 30.251146 -191.4017) (xy 30.280122 -191.402235) (xy 30.337409 -191.410992) (xy 30.392712 -191.428312)
			(xy 30.44476 -191.453798) (xy 30.492354 -191.486863) (xy 30.5344 -191.526745) (xy 30.569929 -191.572528)
			(xy 30.598126 -191.623159) (xy 30.608778 -191.650112) (xy 30.612588 -191.660526) (xy 32.803084 -193.851022)
			(xy 32.821114 -193.869794) (xy 32.851688 -193.911912) (xy 32.875309 -193.958289) (xy 32.891396 -194.007785)
			(xy 32.899554 -194.059188) (xy 32.900112 -194.08521) (xy 32.900112 -202.81773) (xy 32.900541 -202.827798)
			(xy 32.908264 -202.846393) (xy 32.915098 -202.853798) (xy 33.630616 -203.569062) (xy 33.648652 -203.587831)
			(xy 33.679241 -203.629945) (xy 33.702874 -203.676321) (xy 33.718974 -203.725819) (xy 33.727144 -203.777225)
			(xy 33.727644 -203.80325) (xy 33.727644 -214.66937) (xy 33.728081 -214.679434) (xy 33.735818 -214.698015)
			(xy 33.74263 -214.705438) (xy 36.175696 -217.13825) (xy 36.193729 -217.157021) (xy 36.224312 -217.199137)
			(xy 36.247942 -217.245513) (xy 36.264039 -217.29501) (xy 36.272208 -217.346414) (xy 36.272724 -217.372438)
			(xy 36.272724 -240.653062) (xy 36.272817 -240.658081) (xy 36.27474 -240.667931) (xy 36.276534 -240.67262)
			(xy 40.362632 -250.536964) (xy 40.370632 -250.557173) (xy 40.381915 -250.599147) (xy 40.387641 -250.642233)
			(xy 40.388032 -250.663964) (xy 40.388032 -250.68784) (xy 40.38855 -250.699286) (xy 40.398459 -250.719921)
			(xy 40.407082 -250.727464) (xy 40.469566 -250.776994) (xy 40.478833 -250.783626) (xy 40.500998 -250.788772)
			(xy 40.512238 -250.7869) (xy 40.512492 -250.7869) (xy 40.533656 -250.782293) (xy 40.576687 -250.777328)
			(xy 40.598344 -250.776994) (xy 40.625593 -250.777483) (xy 40.679536 -250.785244) (xy 40.731825 -250.800603)
			(xy 40.781396 -250.823247) (xy 40.827241 -250.852714) (xy 40.868426 -250.888405) (xy 40.904112 -250.929594)
			(xy 40.933574 -250.975442) (xy 40.956212 -251.025016) (xy 40.971565 -251.077307) (xy 40.97932 -251.131251)
			(xy 40.97932 -251.185749) (xy 40.971565 -251.239693) (xy 40.956212 -251.291984) (xy 40.933574 -251.341558)
			(xy 40.904112 -251.387406) (xy 40.868426 -251.428595) (xy 40.827241 -251.464286) (xy 40.781396 -251.493753)
			(xy 40.731825 -251.516397) (xy 40.679536 -251.531756) (xy 40.625593 -251.539517) (xy 40.598344 -251.54001)
			(xy 40.57675 -251.539667) (xy 40.533847 -251.534702) (xy 40.512746 -251.530104) (xy 40.512238 -251.530104)
			(xy 40.501062 -251.527564) (xy 40.47871 -251.532644) (xy 40.407082 -251.58954) (xy 40.398571 -251.597172)
			(xy 40.388689 -251.61775) (xy 40.388032 -251.629164) (xy 40.388032 -252.98273) (xy 40.387544 -253.008816)
			(xy 40.379372 -253.060345) (xy 40.363236 -253.109959) (xy 40.339532 -253.156436) (xy 40.308845 -253.198629)
			(xy 40.29075 -253.217426) (xy 39.959026 -253.54915) (xy 39.954855 -253.553501) (xy 39.948557 -253.563776)
			(xy 39.94658 -253.56947) (xy 39.94658 -253.569724) (xy 39.938142 -253.59528) (xy 39.915086 -253.643909)
			(xy 39.885426 -253.688817) (xy 39.849751 -253.729112) (xy 39.808769 -253.763996) (xy 39.763292 -253.792776)
			(xy 39.714223 -253.814881) (xy 39.662535 -253.829873) (xy 39.609253 -253.837454) (xy 39.582344 -253.837948)
			(xy 39.555088 -253.837488) (xy 39.50113 -253.829737) (xy 39.448825 -253.814385) (xy 39.399236 -253.791745)
			(xy 39.353375 -253.762279) (xy 39.312174 -253.726586) (xy 39.276471 -253.685393) (xy 39.246995 -253.639537)
			(xy 39.224345 -253.589954) (xy 39.208981 -253.537652) (xy 39.201218 -253.483696) (xy 39.200836 -253.45644)
			(xy 39.201301 -253.429541) (xy 39.208866 -253.376277) (xy 39.223838 -253.324604) (xy 39.245919 -253.275547)
			(xy 39.274673 -253.230077) (xy 39.309528 -253.189097) (xy 39.349794 -253.153419) (xy 39.394672 -253.123751)
			(xy 39.443273 -253.100681) (xy 39.468806 -253.092204) (xy 39.469314 -253.092204) (xy 39.474977 -253.09016)
			(xy 39.485242 -253.083876) (xy 39.489634 -253.079758) (xy 39.70909 -252.860302) (xy 39.715938 -252.852904)
			(xy 39.723675 -252.834306) (xy 39.724076 -252.824234) (xy 39.724076 -250.740164) (xy 39.723985 -250.735145)
			(xy 39.722067 -250.725292) (xy 39.720266 -250.720606) (xy 35.634422 -240.856262) (xy 35.626478 -240.83613)
			(xy 35.61529 -240.79432) (xy 35.609644 -240.75141) (xy 35.609276 -240.72977) (xy 35.609276 -227.038916)
			(xy 35.608733 -227.028969) (xy 35.60106 -227.010606) (xy 35.587006 -226.996515) (xy 35.578034 -226.99218)
			(xy 35.568591 -226.988645) (xy 35.548443 -226.988557) (xy 35.529834 -226.996278) (xy 35.522408 -227.003102)
			(xy 35.471862 -227.053648) (xy 35.464464 -227.060494) (xy 35.445865 -227.068223) (xy 35.435794 -227.068634)
			(xy 33.749996 -227.068634) (xy 33.739927 -227.069059) (xy 33.721327 -227.076778) (xy 33.713928 -227.08362)
			(xy 25.409398 -235.388404) (xy 25.402552 -235.395803) (xy 25.39482 -235.414401) (xy 25.394412 -235.424472)
			(xy 25.394412 -243.185442) (xy 25.393982 -243.195509) (xy 25.386258 -243.214104) (xy 25.379426 -243.22151)
			(xy 21.371306 -247.229376) (xy 21.364471 -247.236778) (xy 21.356763 -247.255377) (xy 21.35632 -247.265444)
			(xy 21.35632 -249.00382) (xy 24.976836 -249.00382) (xy 24.97731 -248.976214) (xy 24.985267 -248.921579)
			(xy 25.001016 -248.868662) (xy 25.02423 -248.818567) (xy 25.054422 -248.772343) (xy 25.090963 -248.730954)
			(xy 25.11171 -248.712736) (xy 25.11933 -248.706386) (xy 25.128728 -248.688352) (xy 25.136094 -248.596658)
			(xy 25.129998 -248.577354) (xy 25.123394 -248.569734) (xy 25.10644 -248.54898) (xy 25.07791 -248.503616)
			(xy 25.056009 -248.454706) (xy 25.041166 -248.403212) (xy 25.033674 -248.350149) (xy 25.033224 -248.323354)
			(xy 25.03371 -248.296103) (xy 25.041466 -248.242155) (xy 25.056821 -248.18986) (xy 25.079463 -248.140283)
			(xy 25.108929 -248.094433) (xy 25.14462 -248.053242) (xy 25.185811 -248.017551) (xy 25.231661 -247.988085)
			(xy 25.281238 -247.965443) (xy 25.333533 -247.950088) (xy 25.387481 -247.942332) (xy 25.441983 -247.942332)
			(xy 25.495931 -247.950088) (xy 25.548226 -247.965443) (xy 25.597803 -247.988085) (xy 25.643653 -248.017551)
			(xy 25.684844 -248.053242) (xy 25.720535 -248.094433) (xy 25.750001 -248.140283) (xy 25.772643 -248.18986)
			(xy 25.787998 -248.242155) (xy 25.795754 -248.296103) (xy 25.79624 -248.323354) (xy 25.795756 -248.35096)
			(xy 25.787803 -248.405595) (xy 25.772056 -248.458512) (xy 25.748844 -248.508607) (xy 25.718653 -248.554832)
			(xy 25.682113 -248.596221) (xy 25.661366 -248.614438) (xy 25.653746 -248.620788) (xy 25.644348 -248.638822)
			(xy 25.636982 -248.730516) (xy 25.643078 -248.74982) (xy 25.649682 -248.75744) (xy 25.666636 -248.778194)
			(xy 25.695163 -248.82356) (xy 25.717063 -248.87247) (xy 25.731907 -248.923962) (xy 25.7394 -248.977025)
			(xy 25.739852 -249.00382) (xy 25.992836 -249.00382) (xy 25.993288 -248.97683) (xy 26.000894 -248.92339)
			(xy 26.015958 -248.871555) (xy 26.038178 -248.822361) (xy 26.067112 -248.776791) (xy 26.10218 -248.735755)
			(xy 26.122122 -248.717562) (xy 26.129418 -248.710472) (xy 26.138188 -248.692132) (xy 26.13914 -248.682002)
			(xy 26.14295 -248.609612) (xy 26.14299 -248.59934) (xy 26.135915 -248.580076) (xy 26.129234 -248.572274)
			(xy 26.110197 -248.550977) (xy 26.078029 -248.503778) (xy 26.053252 -248.452311) (xy 26.036422 -248.397728)
			(xy 26.027912 -248.341246) (xy 26.02738 -248.312686) (xy 26.027866 -248.285435) (xy 26.035622 -248.231487)
			(xy 26.050977 -248.179192) (xy 26.073619 -248.129615) (xy 26.103085 -248.083765) (xy 26.138776 -248.042574)
			(xy 26.179967 -248.006883) (xy 26.225817 -247.977417) (xy 26.275394 -247.954775) (xy 26.327689 -247.93942)
			(xy 26.381637 -247.931664) (xy 26.436139 -247.931664) (xy 26.490087 -247.93942) (xy 26.542382 -247.954775)
			(xy 26.591959 -247.977417) (xy 26.637809 -248.006883) (xy 26.679 -248.042574) (xy 26.714691 -248.083765)
			(xy 26.744157 -248.129615) (xy 26.766799 -248.179192) (xy 26.782154 -248.231487) (xy 26.78991 -248.285435)
			(xy 26.790396 -248.312686) (xy 26.789971 -248.339677) (xy 26.782362 -248.39312) (xy 26.767295 -248.444956)
			(xy 26.745069 -248.49415) (xy 26.71613 -248.539719) (xy 26.681056 -248.580753) (xy 26.66111 -248.598944)
			(xy 26.653801 -248.606022) (xy 26.64504 -248.624372) (xy 26.644092 -248.634504) (xy 26.640282 -248.706894)
			(xy 26.640231 -248.717167) (xy 26.647313 -248.736431) (xy 26.653998 -248.744232) (xy 26.673026 -248.765536)
			(xy 26.705199 -248.812732) (xy 26.729978 -248.864197) (xy 26.74681 -248.918779) (xy 26.75532 -248.975261)
			(xy 26.755852 -249.00382) (xy 26.755366 -249.031071) (xy 26.74761 -249.085019) (xy 26.732255 -249.137314)
			(xy 26.709613 -249.186891) (xy 26.680147 -249.232741) (xy 26.644456 -249.273932) (xy 26.603265 -249.309623)
			(xy 26.557415 -249.339089) (xy 26.507838 -249.361731) (xy 26.455543 -249.377086) (xy 26.401595 -249.384842)
			(xy 26.347093 -249.384842) (xy 26.293145 -249.377086) (xy 26.24085 -249.361731) (xy 26.191273 -249.339089)
			(xy 26.145423 -249.309623) (xy 26.104232 -249.273932) (xy 26.068541 -249.232741) (xy 26.039075 -249.186891)
			(xy 26.016433 -249.137314) (xy 26.001078 -249.085019) (xy 25.993322 -249.031071) (xy 25.992836 -249.00382)
			(xy 25.739852 -249.00382) (xy 25.739366 -249.031071) (xy 25.73161 -249.085019) (xy 25.716255 -249.137314)
			(xy 25.693613 -249.186891) (xy 25.664147 -249.232741) (xy 25.628456 -249.273932) (xy 25.587265 -249.309623)
			(xy 25.541415 -249.339089) (xy 25.491838 -249.361731) (xy 25.439543 -249.377086) (xy 25.385595 -249.384842)
			(xy 25.331093 -249.384842) (xy 25.277145 -249.377086) (xy 25.22485 -249.361731) (xy 25.175273 -249.339089)
			(xy 25.129423 -249.309623) (xy 25.088232 -249.273932) (xy 25.052541 -249.232741) (xy 25.023075 -249.186891)
			(xy 25.000433 -249.137314) (xy 24.985078 -249.085019) (xy 24.977322 -249.031071) (xy 24.976836 -249.00382)
			(xy 21.35632 -249.00382) (xy 21.35632 -251.158502) (xy 23.960326 -251.158502) (xy 23.964397 -251.10288)
			(xy 23.976523 -251.048443) (xy 23.996446 -250.996352) (xy 24.023742 -250.947717) (xy 24.057828 -250.903574)
			(xy 24.097977 -250.864865) (xy 24.143335 -250.832414) (xy 24.192935 -250.806913) (xy 24.245719 -250.788906)
			(xy 24.300562 -250.778776) (xy 24.356296 -250.776739) (xy 24.411733 -250.782839) (xy 24.46569 -250.796945)
			(xy 24.517019 -250.818757) (xy 24.564625 -250.847811) (xy 24.607493 -250.883486) (xy 24.64471 -250.925023)
			(xy 24.675483 -250.971536) (xy 24.699155 -251.022033) (xy 24.715223 -251.07544) (xy 24.723343 -251.130616)
			(xy 24.723792 -251.1552) (xy 25.068782 -251.1552) (xy 25.072853 -251.099578) (xy 25.084979 -251.045141)
			(xy 25.104902 -250.99305) (xy 25.132198 -250.944415) (xy 25.166284 -250.900272) (xy 25.206433 -250.861563)
			(xy 25.251791 -250.829112) (xy 25.301391 -250.803611) (xy 25.354175 -250.785604) (xy 25.409018 -250.775474)
			(xy 25.464752 -250.773437) (xy 25.520189 -250.779537) (xy 25.574146 -250.793643) (xy 25.625475 -250.815455)
			(xy 25.673081 -250.844509) (xy 25.715949 -250.880184) (xy 25.753166 -250.921721) (xy 25.783939 -250.968234)
			(xy 25.807611 -251.018731) (xy 25.823679 -251.072138) (xy 25.831799 -251.127314) (xy 25.832308 -251.1552)
			(xy 25.832248 -251.158502) (xy 25.992326 -251.158502) (xy 25.996397 -251.10288) (xy 26.008523 -251.048443)
			(xy 26.028446 -250.996352) (xy 26.055742 -250.947717) (xy 26.089828 -250.903574) (xy 26.129977 -250.864865)
			(xy 26.175335 -250.832414) (xy 26.224935 -250.806913) (xy 26.277719 -250.788906) (xy 26.332562 -250.778776)
			(xy 26.388296 -250.776739) (xy 26.443733 -250.782839) (xy 26.49769 -250.796945) (xy 26.549019 -250.818757)
			(xy 26.596625 -250.847811) (xy 26.639493 -250.883486) (xy 26.67671 -250.925023) (xy 26.707483 -250.971536)
			(xy 26.731155 -251.022033) (xy 26.747223 -251.07544) (xy 26.755343 -251.130616) (xy 26.755852 -251.158502)
			(xy 27.008326 -251.158502) (xy 27.012397 -251.10288) (xy 27.024523 -251.048443) (xy 27.044446 -250.996352)
			(xy 27.071742 -250.947717) (xy 27.105828 -250.903574) (xy 27.145977 -250.864865) (xy 27.191335 -250.832414)
			(xy 27.240935 -250.806913) (xy 27.293719 -250.788906) (xy 27.348562 -250.778776) (xy 27.404296 -250.776739)
			(xy 27.459733 -250.782839) (xy 27.51369 -250.796945) (xy 27.565019 -250.818757) (xy 27.612625 -250.847811)
			(xy 27.655493 -250.883486) (xy 27.69271 -250.925023) (xy 27.723483 -250.971536) (xy 27.747155 -251.022033)
			(xy 27.763223 -251.07544) (xy 27.771343 -251.130616) (xy 27.771852 -251.158502) (xy 28.024326 -251.158502)
			(xy 28.028397 -251.10288) (xy 28.040523 -251.048443) (xy 28.060446 -250.996352) (xy 28.087742 -250.947717)
			(xy 28.121828 -250.903574) (xy 28.161977 -250.864865) (xy 28.207335 -250.832414) (xy 28.256935 -250.806913)
			(xy 28.309719 -250.788906) (xy 28.364562 -250.778776) (xy 28.420296 -250.776739) (xy 28.475733 -250.782839)
			(xy 28.52969 -250.796945) (xy 28.581019 -250.818757) (xy 28.628625 -250.847811) (xy 28.671493 -250.883486)
			(xy 28.70871 -250.925023) (xy 28.739483 -250.971536) (xy 28.763155 -251.022033) (xy 28.779223 -251.07544)
			(xy 28.787343 -251.130616) (xy 28.787852 -251.158502) (xy 29.040326 -251.158502) (xy 29.044397 -251.10288)
			(xy 29.056523 -251.048443) (xy 29.076446 -250.996352) (xy 29.103742 -250.947717) (xy 29.137828 -250.903574)
			(xy 29.177977 -250.864865) (xy 29.223335 -250.832414) (xy 29.272935 -250.806913) (xy 29.325719 -250.788906)
			(xy 29.380562 -250.778776) (xy 29.436296 -250.776739) (xy 29.491733 -250.782839) (xy 29.54569 -250.796945)
			(xy 29.597019 -250.818757) (xy 29.644625 -250.847811) (xy 29.687493 -250.883486) (xy 29.72471 -250.925023)
			(xy 29.755483 -250.971536) (xy 29.779155 -251.022033) (xy 29.795223 -251.07544) (xy 29.803343 -251.130616)
			(xy 29.803852 -251.158502) (xy 30.056326 -251.158502) (xy 30.060397 -251.10288) (xy 30.072523 -251.048443)
			(xy 30.092446 -250.996352) (xy 30.119742 -250.947717) (xy 30.153828 -250.903574) (xy 30.193977 -250.864865)
			(xy 30.239335 -250.832414) (xy 30.288935 -250.806913) (xy 30.341719 -250.788906) (xy 30.396562 -250.778776)
			(xy 30.452296 -250.776739) (xy 30.507733 -250.782839) (xy 30.56169 -250.796945) (xy 30.613019 -250.818757)
			(xy 30.660625 -250.847811) (xy 30.703493 -250.883486) (xy 30.74071 -250.925023) (xy 30.771483 -250.971536)
			(xy 30.795155 -251.022033) (xy 30.811223 -251.07544) (xy 30.819343 -251.130616) (xy 30.819852 -251.158502)
			(xy 31.072326 -251.158502) (xy 31.076397 -251.10288) (xy 31.088523 -251.048443) (xy 31.108446 -250.996352)
			(xy 31.135742 -250.947717) (xy 31.169828 -250.903574) (xy 31.209977 -250.864865) (xy 31.255335 -250.832414)
			(xy 31.304935 -250.806913) (xy 31.357719 -250.788906) (xy 31.412562 -250.778776) (xy 31.468296 -250.776739)
			(xy 31.523733 -250.782839) (xy 31.57769 -250.796945) (xy 31.629019 -250.818757) (xy 31.676625 -250.847811)
			(xy 31.719493 -250.883486) (xy 31.75671 -250.925023) (xy 31.787483 -250.971536) (xy 31.811155 -251.022033)
			(xy 31.827223 -251.07544) (xy 31.835343 -251.130616) (xy 31.835852 -251.158502) (xy 32.088326 -251.158502)
			(xy 32.092397 -251.10288) (xy 32.104523 -251.048443) (xy 32.124446 -250.996352) (xy 32.151742 -250.947717)
			(xy 32.185828 -250.903574) (xy 32.225977 -250.864865) (xy 32.271335 -250.832414) (xy 32.320935 -250.806913)
			(xy 32.373719 -250.788906) (xy 32.428562 -250.778776) (xy 32.484296 -250.776739) (xy 32.539733 -250.782839)
			(xy 32.59369 -250.796945) (xy 32.645019 -250.818757) (xy 32.692625 -250.847811) (xy 32.735493 -250.883486)
			(xy 32.77271 -250.925023) (xy 32.803483 -250.971536) (xy 32.827155 -251.022033) (xy 32.843223 -251.07544)
			(xy 32.851343 -251.130616) (xy 32.851852 -251.158502) (xy 33.104326 -251.158502) (xy 33.108397 -251.10288)
			(xy 33.120523 -251.048443) (xy 33.140446 -250.996352) (xy 33.167742 -250.947717) (xy 33.201828 -250.903574)
			(xy 33.241977 -250.864865) (xy 33.287335 -250.832414) (xy 33.336935 -250.806913) (xy 33.389719 -250.788906)
			(xy 33.444562 -250.778776) (xy 33.500296 -250.776739) (xy 33.555733 -250.782839) (xy 33.60969 -250.796945)
			(xy 33.661019 -250.818757) (xy 33.708625 -250.847811) (xy 33.751493 -250.883486) (xy 33.78871 -250.925023)
			(xy 33.819483 -250.971536) (xy 33.843155 -251.022033) (xy 33.859223 -251.07544) (xy 33.867343 -251.130616)
			(xy 33.867852 -251.158502) (xy 34.120326 -251.158502) (xy 34.124397 -251.10288) (xy 34.136523 -251.048443)
			(xy 34.156446 -250.996352) (xy 34.183742 -250.947717) (xy 34.217828 -250.903574) (xy 34.257977 -250.864865)
			(xy 34.303335 -250.832414) (xy 34.352935 -250.806913) (xy 34.405719 -250.788906) (xy 34.460562 -250.778776)
			(xy 34.516296 -250.776739) (xy 34.571733 -250.782839) (xy 34.62569 -250.796945) (xy 34.677019 -250.818757)
			(xy 34.724625 -250.847811) (xy 34.767493 -250.883486) (xy 34.80471 -250.925023) (xy 34.835483 -250.971536)
			(xy 34.859155 -251.022033) (xy 34.875223 -251.07544) (xy 34.883343 -251.130616) (xy 34.883852 -251.158502)
			(xy 35.136326 -251.158502) (xy 35.140397 -251.10288) (xy 35.152523 -251.048443) (xy 35.172446 -250.996352)
			(xy 35.199742 -250.947717) (xy 35.233828 -250.903574) (xy 35.273977 -250.864865) (xy 35.319335 -250.832414)
			(xy 35.368935 -250.806913) (xy 35.421719 -250.788906) (xy 35.476562 -250.778776) (xy 35.532296 -250.776739)
			(xy 35.587733 -250.782839) (xy 35.64169 -250.796945) (xy 35.693019 -250.818757) (xy 35.740625 -250.847811)
			(xy 35.783493 -250.883486) (xy 35.82071 -250.925023) (xy 35.851483 -250.971536) (xy 35.875155 -251.022033)
			(xy 35.891223 -251.07544) (xy 35.899343 -251.130616) (xy 35.899852 -251.158502) (xy 36.152326 -251.158502)
			(xy 36.156397 -251.10288) (xy 36.168523 -251.048443) (xy 36.188446 -250.996352) (xy 36.215742 -250.947717)
			(xy 36.249828 -250.903574) (xy 36.289977 -250.864865) (xy 36.335335 -250.832414) (xy 36.384935 -250.806913)
			(xy 36.437719 -250.788906) (xy 36.492562 -250.778776) (xy 36.548296 -250.776739) (xy 36.603733 -250.782839)
			(xy 36.65769 -250.796945) (xy 36.709019 -250.818757) (xy 36.756625 -250.847811) (xy 36.799493 -250.883486)
			(xy 36.83671 -250.925023) (xy 36.867483 -250.971536) (xy 36.891155 -251.022033) (xy 36.907223 -251.07544)
			(xy 36.915343 -251.130616) (xy 36.915852 -251.158502) (xy 37.168326 -251.158502) (xy 37.172397 -251.10288)
			(xy 37.184523 -251.048443) (xy 37.204446 -250.996352) (xy 37.231742 -250.947717) (xy 37.265828 -250.903574)
			(xy 37.305977 -250.864865) (xy 37.351335 -250.832414) (xy 37.400935 -250.806913) (xy 37.453719 -250.788906)
			(xy 37.508562 -250.778776) (xy 37.564296 -250.776739) (xy 37.619733 -250.782839) (xy 37.67369 -250.796945)
			(xy 37.725019 -250.818757) (xy 37.772625 -250.847811) (xy 37.815493 -250.883486) (xy 37.85271 -250.925023)
			(xy 37.883483 -250.971536) (xy 37.907155 -251.022033) (xy 37.923223 -251.07544) (xy 37.931343 -251.130616)
			(xy 37.931852 -251.158502) (xy 38.184326 -251.158502) (xy 38.188397 -251.10288) (xy 38.200523 -251.048443)
			(xy 38.220446 -250.996352) (xy 38.247742 -250.947717) (xy 38.281828 -250.903574) (xy 38.321977 -250.864865)
			(xy 38.367335 -250.832414) (xy 38.416935 -250.806913) (xy 38.469719 -250.788906) (xy 38.524562 -250.778776)
			(xy 38.580296 -250.776739) (xy 38.635733 -250.782839) (xy 38.68969 -250.796945) (xy 38.741019 -250.818757)
			(xy 38.788625 -250.847811) (xy 38.831493 -250.883486) (xy 38.86871 -250.925023) (xy 38.899483 -250.971536)
			(xy 38.923155 -251.022033) (xy 38.939223 -251.07544) (xy 38.947343 -251.130616) (xy 38.947852 -251.158502)
			(xy 38.947343 -251.186388) (xy 38.939223 -251.241564) (xy 38.923155 -251.294971) (xy 38.899483 -251.345468)
			(xy 38.86871 -251.391981) (xy 38.831493 -251.433518) (xy 38.788625 -251.469193) (xy 38.741019 -251.498247)
			(xy 38.68969 -251.520059) (xy 38.635733 -251.534165) (xy 38.580296 -251.540265) (xy 38.524562 -251.538228)
			(xy 38.469719 -251.528098) (xy 38.416935 -251.510091) (xy 38.367335 -251.48459) (xy 38.321977 -251.452139)
			(xy 38.281828 -251.41343) (xy 38.247742 -251.369287) (xy 38.220446 -251.320652) (xy 38.200523 -251.268561)
			(xy 38.188397 -251.214124) (xy 38.184326 -251.158502) (xy 37.931852 -251.158502) (xy 37.931343 -251.186388)
			(xy 37.923223 -251.241564) (xy 37.907155 -251.294971) (xy 37.883483 -251.345468) (xy 37.85271 -251.391981)
			(xy 37.815493 -251.433518) (xy 37.772625 -251.469193) (xy 37.725019 -251.498247) (xy 37.67369 -251.520059)
			(xy 37.619733 -251.534165) (xy 37.564296 -251.540265) (xy 37.508562 -251.538228) (xy 37.453719 -251.528098)
			(xy 37.400935 -251.510091) (xy 37.351335 -251.48459) (xy 37.305977 -251.452139) (xy 37.265828 -251.41343)
			(xy 37.231742 -251.369287) (xy 37.204446 -251.320652) (xy 37.184523 -251.268561) (xy 37.172397 -251.214124)
			(xy 37.168326 -251.158502) (xy 36.915852 -251.158502) (xy 36.915343 -251.186388) (xy 36.907223 -251.241564)
			(xy 36.891155 -251.294971) (xy 36.867483 -251.345468) (xy 36.83671 -251.391981) (xy 36.799493 -251.433518)
			(xy 36.756625 -251.469193) (xy 36.709019 -251.498247) (xy 36.65769 -251.520059) (xy 36.603733 -251.534165)
			(xy 36.548296 -251.540265) (xy 36.492562 -251.538228) (xy 36.437719 -251.528098) (xy 36.384935 -251.510091)
			(xy 36.335335 -251.48459) (xy 36.289977 -251.452139) (xy 36.249828 -251.41343) (xy 36.215742 -251.369287)
			(xy 36.188446 -251.320652) (xy 36.168523 -251.268561) (xy 36.156397 -251.214124) (xy 36.152326 -251.158502)
			(xy 35.899852 -251.158502) (xy 35.899343 -251.186388) (xy 35.891223 -251.241564) (xy 35.875155 -251.294971)
			(xy 35.851483 -251.345468) (xy 35.82071 -251.391981) (xy 35.783493 -251.433518) (xy 35.740625 -251.469193)
			(xy 35.693019 -251.498247) (xy 35.64169 -251.520059) (xy 35.587733 -251.534165) (xy 35.532296 -251.540265)
			(xy 35.476562 -251.538228) (xy 35.421719 -251.528098) (xy 35.368935 -251.510091) (xy 35.319335 -251.48459)
			(xy 35.273977 -251.452139) (xy 35.233828 -251.41343) (xy 35.199742 -251.369287) (xy 35.172446 -251.320652)
			(xy 35.152523 -251.268561) (xy 35.140397 -251.214124) (xy 35.136326 -251.158502) (xy 34.883852 -251.158502)
			(xy 34.883343 -251.186388) (xy 34.875223 -251.241564) (xy 34.859155 -251.294971) (xy 34.835483 -251.345468)
			(xy 34.80471 -251.391981) (xy 34.767493 -251.433518) (xy 34.724625 -251.469193) (xy 34.677019 -251.498247)
			(xy 34.62569 -251.520059) (xy 34.571733 -251.534165) (xy 34.516296 -251.540265) (xy 34.460562 -251.538228)
			(xy 34.405719 -251.528098) (xy 34.352935 -251.510091) (xy 34.303335 -251.48459) (xy 34.257977 -251.452139)
			(xy 34.217828 -251.41343) (xy 34.183742 -251.369287) (xy 34.156446 -251.320652) (xy 34.136523 -251.268561)
			(xy 34.124397 -251.214124) (xy 34.120326 -251.158502) (xy 33.867852 -251.158502) (xy 33.867343 -251.186388)
			(xy 33.859223 -251.241564) (xy 33.843155 -251.294971) (xy 33.819483 -251.345468) (xy 33.78871 -251.391981)
			(xy 33.751493 -251.433518) (xy 33.708625 -251.469193) (xy 33.661019 -251.498247) (xy 33.60969 -251.520059)
			(xy 33.555733 -251.534165) (xy 33.500296 -251.540265) (xy 33.444562 -251.538228) (xy 33.389719 -251.528098)
			(xy 33.336935 -251.510091) (xy 33.287335 -251.48459) (xy 33.241977 -251.452139) (xy 33.201828 -251.41343)
			(xy 33.167742 -251.369287) (xy 33.140446 -251.320652) (xy 33.120523 -251.268561) (xy 33.108397 -251.214124)
			(xy 33.104326 -251.158502) (xy 32.851852 -251.158502) (xy 32.851343 -251.186388) (xy 32.843223 -251.241564)
			(xy 32.827155 -251.294971) (xy 32.803483 -251.345468) (xy 32.77271 -251.391981) (xy 32.735493 -251.433518)
			(xy 32.692625 -251.469193) (xy 32.645019 -251.498247) (xy 32.59369 -251.520059) (xy 32.539733 -251.534165)
			(xy 32.484296 -251.540265) (xy 32.428562 -251.538228) (xy 32.373719 -251.528098) (xy 32.320935 -251.510091)
			(xy 32.271335 -251.48459) (xy 32.225977 -251.452139) (xy 32.185828 -251.41343) (xy 32.151742 -251.369287)
			(xy 32.124446 -251.320652) (xy 32.104523 -251.268561) (xy 32.092397 -251.214124) (xy 32.088326 -251.158502)
			(xy 31.835852 -251.158502) (xy 31.835343 -251.186388) (xy 31.827223 -251.241564) (xy 31.811155 -251.294971)
			(xy 31.787483 -251.345468) (xy 31.75671 -251.391981) (xy 31.719493 -251.433518) (xy 31.676625 -251.469193)
			(xy 31.629019 -251.498247) (xy 31.57769 -251.520059) (xy 31.523733 -251.534165) (xy 31.468296 -251.540265)
			(xy 31.412562 -251.538228) (xy 31.357719 -251.528098) (xy 31.304935 -251.510091) (xy 31.255335 -251.48459)
			(xy 31.209977 -251.452139) (xy 31.169828 -251.41343) (xy 31.135742 -251.369287) (xy 31.108446 -251.320652)
			(xy 31.088523 -251.268561) (xy 31.076397 -251.214124) (xy 31.072326 -251.158502) (xy 30.819852 -251.158502)
			(xy 30.819343 -251.186388) (xy 30.811223 -251.241564) (xy 30.795155 -251.294971) (xy 30.771483 -251.345468)
			(xy 30.74071 -251.391981) (xy 30.703493 -251.433518) (xy 30.660625 -251.469193) (xy 30.613019 -251.498247)
			(xy 30.56169 -251.520059) (xy 30.507733 -251.534165) (xy 30.452296 -251.540265) (xy 30.396562 -251.538228)
			(xy 30.341719 -251.528098) (xy 30.288935 -251.510091) (xy 30.239335 -251.48459) (xy 30.193977 -251.452139)
			(xy 30.153828 -251.41343) (xy 30.119742 -251.369287) (xy 30.092446 -251.320652) (xy 30.072523 -251.268561)
			(xy 30.060397 -251.214124) (xy 30.056326 -251.158502) (xy 29.803852 -251.158502) (xy 29.803343 -251.186388)
			(xy 29.795223 -251.241564) (xy 29.779155 -251.294971) (xy 29.755483 -251.345468) (xy 29.72471 -251.391981)
			(xy 29.687493 -251.433518) (xy 29.644625 -251.469193) (xy 29.597019 -251.498247) (xy 29.54569 -251.520059)
			(xy 29.491733 -251.534165) (xy 29.436296 -251.540265) (xy 29.380562 -251.538228) (xy 29.325719 -251.528098)
			(xy 29.272935 -251.510091) (xy 29.223335 -251.48459) (xy 29.177977 -251.452139) (xy 29.137828 -251.41343)
			(xy 29.103742 -251.369287) (xy 29.076446 -251.320652) (xy 29.056523 -251.268561) (xy 29.044397 -251.214124)
			(xy 29.040326 -251.158502) (xy 28.787852 -251.158502) (xy 28.787343 -251.186388) (xy 28.779223 -251.241564)
			(xy 28.763155 -251.294971) (xy 28.739483 -251.345468) (xy 28.70871 -251.391981) (xy 28.671493 -251.433518)
			(xy 28.628625 -251.469193) (xy 28.581019 -251.498247) (xy 28.52969 -251.520059) (xy 28.475733 -251.534165)
			(xy 28.420296 -251.540265) (xy 28.364562 -251.538228) (xy 28.309719 -251.528098) (xy 28.256935 -251.510091)
			(xy 28.207335 -251.48459) (xy 28.161977 -251.452139) (xy 28.121828 -251.41343) (xy 28.087742 -251.369287)
			(xy 28.060446 -251.320652) (xy 28.040523 -251.268561) (xy 28.028397 -251.214124) (xy 28.024326 -251.158502)
			(xy 27.771852 -251.158502) (xy 27.771343 -251.186388) (xy 27.763223 -251.241564) (xy 27.747155 -251.294971)
			(xy 27.723483 -251.345468) (xy 27.69271 -251.391981) (xy 27.655493 -251.433518) (xy 27.612625 -251.469193)
			(xy 27.565019 -251.498247) (xy 27.51369 -251.520059) (xy 27.459733 -251.534165) (xy 27.404296 -251.540265)
			(xy 27.348562 -251.538228) (xy 27.293719 -251.528098) (xy 27.240935 -251.510091) (xy 27.191335 -251.48459)
			(xy 27.145977 -251.452139) (xy 27.105828 -251.41343) (xy 27.071742 -251.369287) (xy 27.044446 -251.320652)
			(xy 27.024523 -251.268561) (xy 27.012397 -251.214124) (xy 27.008326 -251.158502) (xy 26.755852 -251.158502)
			(xy 26.755343 -251.186388) (xy 26.747223 -251.241564) (xy 26.731155 -251.294971) (xy 26.707483 -251.345468)
			(xy 26.67671 -251.391981) (xy 26.639493 -251.433518) (xy 26.596625 -251.469193) (xy 26.549019 -251.498247)
			(xy 26.49769 -251.520059) (xy 26.443733 -251.534165) (xy 26.388296 -251.540265) (xy 26.332562 -251.538228)
			(xy 26.277719 -251.528098) (xy 26.224935 -251.510091) (xy 26.175335 -251.48459) (xy 26.129977 -251.452139)
			(xy 26.089828 -251.41343) (xy 26.055742 -251.369287) (xy 26.028446 -251.320652) (xy 26.008523 -251.268561)
			(xy 25.996397 -251.214124) (xy 25.992326 -251.158502) (xy 25.832248 -251.158502) (xy 25.831799 -251.183086)
			(xy 25.823679 -251.238262) (xy 25.807611 -251.291669) (xy 25.783939 -251.342166) (xy 25.753166 -251.388679)
			(xy 25.715949 -251.430216) (xy 25.673081 -251.465891) (xy 25.625475 -251.494945) (xy 25.574146 -251.516757)
			(xy 25.520189 -251.530863) (xy 25.464752 -251.536963) (xy 25.409018 -251.534926) (xy 25.354175 -251.524796)
			(xy 25.301391 -251.506789) (xy 25.251791 -251.481288) (xy 25.206433 -251.448837) (xy 25.166284 -251.410128)
			(xy 25.132198 -251.365985) (xy 25.104902 -251.31735) (xy 25.084979 -251.265259) (xy 25.072853 -251.210822)
			(xy 25.068782 -251.1552) (xy 24.723792 -251.1552) (xy 24.723852 -251.158502) (xy 24.723343 -251.186388)
			(xy 24.715223 -251.241564) (xy 24.699155 -251.294971) (xy 24.675483 -251.345468) (xy 24.64471 -251.391981)
			(xy 24.607493 -251.433518) (xy 24.564625 -251.469193) (xy 24.517019 -251.498247) (xy 24.46569 -251.520059)
			(xy 24.411733 -251.534165) (xy 24.356296 -251.540265) (xy 24.300562 -251.538228) (xy 24.245719 -251.528098)
			(xy 24.192935 -251.510091) (xy 24.143335 -251.48459) (xy 24.097977 -251.452139) (xy 24.057828 -251.41343)
			(xy 24.023742 -251.369287) (xy 23.996446 -251.320652) (xy 23.976523 -251.268561) (xy 23.964397 -251.214124)
			(xy 23.960326 -251.158502) (xy 21.35632 -251.158502) (xy 21.35632 -253.251208) (xy 21.356753 -253.260887)
			(xy 21.363915 -253.278872) (xy 21.377191 -253.292961) (xy 21.385784 -253.297436) (xy 21.482812 -253.342648)
			(xy 21.512022 -253.338584) (xy 21.523452 -253.328932) (xy 21.54417 -253.312086) (xy 21.589423 -253.28374)
			(xy 21.638183 -253.261974) (xy 21.689499 -253.247213) (xy 21.742372 -253.239743) (xy 21.76907 -253.23927)
			(xy 21.769324 -253.23927) (xy 21.796576 -253.239757) (xy 21.850524 -253.247517) (xy 21.902819 -253.262875)
			(xy 21.952396 -253.285519) (xy 21.998246 -253.314988) (xy 22.039436 -253.350681) (xy 22.075127 -253.391873)
			(xy 22.104592 -253.437725) (xy 22.127233 -253.487304) (xy 22.142588 -253.5396) (xy 22.150344 -253.593548)
			(xy 22.150344 -253.648052) (xy 22.142588 -253.702) (xy 22.127233 -253.754296) (xy 22.104592 -253.803875)
			(xy 22.075127 -253.849727) (xy 22.039436 -253.890919) (xy 21.998246 -253.926612) (xy 21.952396 -253.956081)
			(xy 21.902819 -253.978725) (xy 21.850524 -253.994083) (xy 21.796576 -254.001843) (xy 21.769324 -254.002286)
			(xy 21.76907 -254.002286) (xy 21.742369 -254.001842) (xy 21.689488 -253.994394) (xy 21.638166 -253.979635)
			(xy 21.589408 -253.957853) (xy 21.544169 -253.929476) (xy 21.523452 -253.912624) (xy 21.512022 -253.902972)
			(xy 21.482812 -253.898908) (xy 21.385784 -253.94412) (xy 21.377156 -253.948558) (xy 21.363822 -253.962628)
			(xy 21.356688 -253.980653) (xy 21.35632 -253.990348) (xy 21.35632 -255.910588) (xy 21.87651 -255.910588)
			(xy 21.880581 -255.854966) (xy 21.892707 -255.800529) (xy 21.91263 -255.748438) (xy 21.939926 -255.699803)
			(xy 21.974012 -255.65566) (xy 22.014161 -255.616951) (xy 22.059519 -255.5845) (xy 22.109119 -255.558999)
			(xy 22.161903 -255.540992) (xy 22.216746 -255.530862) (xy 22.27248 -255.528825) (xy 22.327917 -255.534925)
			(xy 22.381874 -255.549031) (xy 22.433203 -255.570843) (xy 22.480809 -255.599897) (xy 22.523677 -255.635572)
			(xy 22.560894 -255.677109) (xy 22.568491 -255.688592) (xy 23.595074 -255.688592) (xy 23.599145 -255.63297)
			(xy 23.611271 -255.578533) (xy 23.631194 -255.526442) (xy 23.65849 -255.477807) (xy 23.692576 -255.433664)
			(xy 23.732725 -255.394955) (xy 23.778083 -255.362504) (xy 23.827683 -255.337003) (xy 23.880467 -255.318996)
			(xy 23.93531 -255.308866) (xy 23.991044 -255.306829) (xy 24.046481 -255.312929) (xy 24.100438 -255.327035)
			(xy 24.151767 -255.348847) (xy 24.199373 -255.377901) (xy 24.242241 -255.413576) (xy 24.279458 -255.455113)
			(xy 24.310231 -255.501626) (xy 24.333903 -255.552123) (xy 24.349971 -255.60553) (xy 24.358091 -255.660706)
			(xy 24.3586 -255.688592) (xy 24.358091 -255.716478) (xy 24.349971 -255.771654) (xy 24.333903 -255.825061)
			(xy 24.310231 -255.875558) (xy 24.279458 -255.922071) (xy 24.242241 -255.963608) (xy 24.199373 -255.999283)
			(xy 24.151767 -256.028337) (xy 24.100438 -256.050149) (xy 24.046481 -256.064255) (xy 23.991044 -256.070355)
			(xy 23.93531 -256.068318) (xy 23.880467 -256.058188) (xy 23.827683 -256.040181) (xy 23.778083 -256.01468)
			(xy 23.732725 -255.982229) (xy 23.692576 -255.94352) (xy 23.65849 -255.899377) (xy 23.631194 -255.850742)
			(xy 23.611271 -255.798651) (xy 23.599145 -255.744214) (xy 23.595074 -255.688592) (xy 22.568491 -255.688592)
			(xy 22.591667 -255.723622) (xy 22.615339 -255.774119) (xy 22.631407 -255.827526) (xy 22.639527 -255.882702)
			(xy 22.640036 -255.910588) (xy 22.639527 -255.938474) (xy 22.631407 -255.99365) (xy 22.615339 -256.047057)
			(xy 22.591667 -256.097554) (xy 22.560894 -256.144067) (xy 22.523677 -256.185604) (xy 22.480809 -256.221279)
			(xy 22.433203 -256.250333) (xy 22.381874 -256.272145) (xy 22.327917 -256.286251) (xy 22.27248 -256.292351)
			(xy 22.216746 -256.290314) (xy 22.161903 -256.280184) (xy 22.109119 -256.262177) (xy 22.059519 -256.236676)
			(xy 22.014161 -256.204225) (xy 21.974012 -256.165516) (xy 21.939926 -256.121373) (xy 21.91263 -256.072738)
			(xy 21.892707 -256.020647) (xy 21.880581 -255.96621) (xy 21.87651 -255.910588) (xy 21.35632 -255.910588)
			(xy 21.35632 -256.479621) (xy 25.279328 -256.479621) (xy 25.279328 -256.425119) (xy 25.287084 -256.371171)
			(xy 25.302439 -256.318876) (xy 25.325081 -256.269299) (xy 25.354547 -256.223449) (xy 25.390238 -256.182258)
			(xy 25.431429 -256.146567) (xy 25.477279 -256.117101) (xy 25.526856 -256.094459) (xy 25.579151 -256.079104)
			(xy 25.633099 -256.071348) (xy 25.66035 -256.070862) (xy 25.686666 -256.071276) (xy 25.738798 -256.078519)
			(xy 25.789442 -256.092847) (xy 25.837641 -256.11399) (xy 25.882483 -256.141546) (xy 25.92312 -256.174995)
			(xy 25.941274 -256.194052) (xy 25.94881 -256.201437) (xy 25.968079 -256.209972) (xy 25.978612 -256.210562)
			(xy 26.053288 -256.210562) (xy 26.06384 -256.210051) (xy 26.083136 -256.201504) (xy 26.090626 -256.194052)
			(xy 26.108767 -256.174982) (xy 26.149401 -256.141528) (xy 26.194244 -256.113972) (xy 26.242448 -256.092836)
			(xy 26.293097 -256.078522) (xy 26.345233 -256.071299) (xy 26.37155 -256.070862) (xy 26.398801 -256.071348)
			(xy 26.452749 -256.079104) (xy 26.505044 -256.094459) (xy 26.554621 -256.117101) (xy 26.600471 -256.146567)
			(xy 26.641662 -256.182258) (xy 26.677353 -256.223449) (xy 26.706819 -256.269299) (xy 26.729461 -256.318876)
			(xy 26.744816 -256.371171) (xy 26.752572 -256.425119) (xy 26.752572 -256.479621) (xy 26.744816 -256.533569)
			(xy 26.729461 -256.585864) (xy 26.706819 -256.635441) (xy 26.677353 -256.681291) (xy 26.641662 -256.722482)
			(xy 26.600471 -256.758173) (xy 26.554621 -256.787639) (xy 26.505044 -256.810281) (xy 26.452749 -256.825636)
			(xy 26.398801 -256.833392) (xy 26.37155 -256.833878) (xy 26.345235 -256.833451) (xy 26.293104 -256.826209)
			(xy 26.24246 -256.811882) (xy 26.194261 -256.790742) (xy 26.149419 -256.763189) (xy 26.108781 -256.729743)
			(xy 26.090626 -256.710688) (xy 26.083098 -256.703294) (xy 26.063823 -256.694766) (xy 26.053288 -256.694178)
			(xy 25.978612 -256.694178) (xy 25.968062 -256.694706) (xy 25.948767 -256.703243) (xy 25.941274 -256.710688)
			(xy 25.923122 -256.729747) (xy 25.882492 -256.763204) (xy 25.837651 -256.790763) (xy 25.789449 -256.811901)
			(xy 25.738801 -256.826217) (xy 25.686666 -256.83344) (xy 25.66035 -256.833878) (xy 25.633099 -256.833392)
			(xy 25.579151 -256.825636) (xy 25.526856 -256.810281) (xy 25.477279 -256.787639) (xy 25.431429 -256.758173)
			(xy 25.390238 -256.722482) (xy 25.354547 -256.681291) (xy 25.325081 -256.635441) (xy 25.302439 -256.585864)
			(xy 25.287084 -256.533569) (xy 25.279328 -256.479621) (xy 21.35632 -256.479621) (xy 21.35632 -257.474212)
			(xy 21.97176 -257.474212) (xy 21.975831 -257.41859) (xy 21.987957 -257.364153) (xy 22.00788 -257.312062)
			(xy 22.035176 -257.263427) (xy 22.069262 -257.219284) (xy 22.109411 -257.180575) (xy 22.154769 -257.148124)
			(xy 22.204369 -257.122623) (xy 22.257153 -257.104616) (xy 22.311996 -257.094486) (xy 22.36773 -257.092449)
			(xy 22.423167 -257.098549) (xy 22.477124 -257.112655) (xy 22.528453 -257.134467) (xy 22.534104 -257.137916)
			(xy 34.296096 -257.137916) (xy 34.296647 -257.108534) (xy 34.305675 -257.050468) (xy 34.323505 -256.994474)
			(xy 34.349715 -256.941879) (xy 34.383683 -256.893927) (xy 34.424606 -256.851754) (xy 34.447734 -256.833624)
			(xy 34.456655 -256.826141) (xy 34.467116 -256.805369) (xy 34.4678 -256.793746) (xy 34.46907 -256.701798)
			(xy 34.459164 -256.680716) (xy 34.45002 -256.67335) (xy 34.42817 -256.655146) (xy 34.389629 -256.613328)
			(xy 34.357722 -256.566252) (xy 34.333155 -256.514962) (xy 34.316472 -256.460593) (xy 34.308044 -256.404351)
			(xy 34.307526 -256.375916) (xy 34.308012 -256.348665) (xy 34.315768 -256.294717) (xy 34.331123 -256.242422)
			(xy 34.353765 -256.192845) (xy 34.383231 -256.146995) (xy 34.418922 -256.105804) (xy 34.460113 -256.070113)
			(xy 34.505963 -256.040647) (xy 34.55554 -256.018005) (xy 34.607835 -256.00265) (xy 34.661783 -255.994894)
			(xy 34.716285 -255.994894) (xy 34.770233 -256.00265) (xy 34.822528 -256.018005) (xy 34.872105 -256.040647)
			(xy 34.917955 -256.070113) (xy 34.959146 -256.105804) (xy 34.994837 -256.146995) (xy 35.024303 -256.192845)
			(xy 35.046945 -256.242422) (xy 35.0623 -256.294717) (xy 35.070056 -256.348665) (xy 35.070542 -256.375916)
			(xy 35.069999 -256.405298) (xy 35.060967 -256.463364) (xy 35.043134 -256.519357) (xy 35.016923 -256.571952)
			(xy 34.982954 -256.619904) (xy 34.942031 -256.662077) (xy 34.918904 -256.680208) (xy 34.909958 -256.687666)
			(xy 34.899513 -256.708457) (xy 34.898838 -256.720086) (xy 34.897568 -256.812034) (xy 34.907474 -256.833116)
			(xy 34.916618 -256.840482) (xy 34.938443 -256.858714) (xy 34.976984 -256.900528) (xy 35.008893 -256.947598)
			(xy 35.033464 -256.998883) (xy 35.050153 -257.053245) (xy 35.058589 -257.109483) (xy 35.059112 -257.137916)
			(xy 35.692586 -257.137916) (xy 35.696657 -257.082294) (xy 35.708783 -257.027857) (xy 35.728706 -256.975766)
			(xy 35.756002 -256.927131) (xy 35.790088 -256.882988) (xy 35.830237 -256.844279) (xy 35.875595 -256.811828)
			(xy 35.925195 -256.786327) (xy 35.977979 -256.76832) (xy 36.032822 -256.75819) (xy 36.088556 -256.756153)
			(xy 36.143993 -256.762253) (xy 36.19795 -256.776359) (xy 36.249279 -256.798171) (xy 36.296885 -256.827225)
			(xy 36.339753 -256.8629) (xy 36.37697 -256.904437) (xy 36.407743 -256.95095) (xy 36.431415 -257.001447)
			(xy 36.447483 -257.054854) (xy 36.455603 -257.11003) (xy 36.456112 -257.137916) (xy 36.455603 -257.165802)
			(xy 36.447483 -257.220978) (xy 36.431415 -257.274385) (xy 36.407743 -257.324882) (xy 36.37697 -257.371395)
			(xy 36.339753 -257.412932) (xy 36.296885 -257.448607) (xy 36.249279 -257.477661) (xy 36.19795 -257.499473)
			(xy 36.143993 -257.513579) (xy 36.088556 -257.519679) (xy 36.032822 -257.517642) (xy 35.977979 -257.507512)
			(xy 35.925195 -257.489505) (xy 35.875595 -257.464004) (xy 35.830237 -257.431553) (xy 35.790088 -257.392844)
			(xy 35.756002 -257.348701) (xy 35.728706 -257.300066) (xy 35.708783 -257.247975) (xy 35.696657 -257.193538)
			(xy 35.692586 -257.137916) (xy 35.059112 -257.137916) (xy 35.058626 -257.165167) (xy 35.05087 -257.219115)
			(xy 35.035515 -257.27141) (xy 35.012873 -257.320987) (xy 34.983407 -257.366837) (xy 34.947716 -257.408028)
			(xy 34.906525 -257.443719) (xy 34.860675 -257.473185) (xy 34.811098 -257.495827) (xy 34.758803 -257.511182)
			(xy 34.704855 -257.518938) (xy 34.650353 -257.518938) (xy 34.596405 -257.511182) (xy 34.54411 -257.495827)
			(xy 34.494533 -257.473185) (xy 34.448683 -257.443719) (xy 34.407492 -257.408028) (xy 34.371801 -257.366837)
			(xy 34.342335 -257.320987) (xy 34.319693 -257.27141) (xy 34.304338 -257.219115) (xy 34.296582 -257.165167)
			(xy 34.296096 -257.137916) (xy 22.534104 -257.137916) (xy 22.576059 -257.163521) (xy 22.618927 -257.199196)
			(xy 22.656144 -257.240733) (xy 22.686917 -257.287246) (xy 22.710589 -257.337743) (xy 22.726657 -257.39115)
			(xy 22.734777 -257.446326) (xy 22.735286 -257.474212) (xy 22.734777 -257.502098) (xy 22.726657 -257.557274)
			(xy 22.710589 -257.610681) (xy 22.686917 -257.661178) (xy 22.656144 -257.707691) (xy 22.618927 -257.749228)
			(xy 22.576059 -257.784903) (xy 22.528453 -257.813957) (xy 22.477124 -257.835769) (xy 22.423167 -257.849875)
			(xy 22.36773 -257.855975) (xy 22.311996 -257.853938) (xy 22.257153 -257.843808) (xy 22.204369 -257.825801)
			(xy 22.154769 -257.8003) (xy 22.109411 -257.767849) (xy 22.069262 -257.72914) (xy 22.035176 -257.684997)
			(xy 22.00788 -257.636362) (xy 21.987957 -257.584271) (xy 21.975831 -257.529834) (xy 21.97176 -257.474212)
			(xy 21.35632 -257.474212) (xy 21.35632 -258.649978) (xy 22.926292 -258.649978) (xy 22.930363 -258.594356)
			(xy 22.942489 -258.539919) (xy 22.962412 -258.487828) (xy 22.989708 -258.439193) (xy 23.023794 -258.39505)
			(xy 23.063943 -258.356341) (xy 23.109301 -258.32389) (xy 23.158901 -258.298389) (xy 23.211685 -258.280382)
			(xy 23.266528 -258.270252) (xy 23.322262 -258.268215) (xy 23.375363 -258.274058) (xy 28.769562 -258.274058)
			(xy 28.773633 -258.218436) (xy 28.785759 -258.163999) (xy 28.805682 -258.111908) (xy 28.832978 -258.063273)
			(xy 28.867064 -258.01913) (xy 28.907213 -257.980421) (xy 28.952571 -257.94797) (xy 29.002171 -257.922469)
			(xy 29.054955 -257.904462) (xy 29.109798 -257.894332) (xy 29.165532 -257.892295) (xy 29.220969 -257.898395)
			(xy 29.274926 -257.912501) (xy 29.326255 -257.934313) (xy 29.373861 -257.963367) (xy 29.416729 -257.999042)
			(xy 29.453946 -258.040579) (xy 29.484719 -258.087092) (xy 29.508391 -258.137589) (xy 29.524459 -258.190996)
			(xy 29.532579 -258.246172) (xy 29.533088 -258.274058) (xy 30.2547 -258.274058) (xy 30.258771 -258.218436)
			(xy 30.270897 -258.163999) (xy 30.29082 -258.111908) (xy 30.318116 -258.063273) (xy 30.352202 -258.01913)
			(xy 30.392351 -257.980421) (xy 30.437709 -257.94797) (xy 30.487309 -257.922469) (xy 30.540093 -257.904462)
			(xy 30.594936 -257.894332) (xy 30.65067 -257.892295) (xy 30.706107 -257.898395) (xy 30.760064 -257.912501)
			(xy 30.811393 -257.934313) (xy 30.858999 -257.963367) (xy 30.901867 -257.999042) (xy 30.939084 -258.040579)
			(xy 30.969857 -258.087092) (xy 30.993529 -258.137589) (xy 31.009597 -258.190996) (xy 31.017717 -258.246172)
			(xy 31.018226 -258.274058) (xy 31.017717 -258.301944) (xy 31.009597 -258.35712) (xy 30.993529 -258.410527)
			(xy 30.969857 -258.461024) (xy 30.939084 -258.507537) (xy 30.901867 -258.549074) (xy 30.858999 -258.584749)
			(xy 30.811393 -258.613803) (xy 30.760064 -258.635615) (xy 30.706107 -258.649721) (xy 30.65067 -258.655821)
			(xy 30.594936 -258.653784) (xy 30.540093 -258.643654) (xy 30.487309 -258.625647) (xy 30.437709 -258.600146)
			(xy 30.392351 -258.567695) (xy 30.352202 -258.528986) (xy 30.318116 -258.484843) (xy 30.29082 -258.436208)
			(xy 30.270897 -258.384117) (xy 30.258771 -258.32968) (xy 30.2547 -258.274058) (xy 29.533088 -258.274058)
			(xy 29.532579 -258.301944) (xy 29.524459 -258.35712) (xy 29.508391 -258.410527) (xy 29.484719 -258.461024)
			(xy 29.453946 -258.507537) (xy 29.416729 -258.549074) (xy 29.373861 -258.584749) (xy 29.326255 -258.613803)
			(xy 29.274926 -258.635615) (xy 29.220969 -258.649721) (xy 29.165532 -258.655821) (xy 29.109798 -258.653784)
			(xy 29.054955 -258.643654) (xy 29.002171 -258.625647) (xy 28.952571 -258.600146) (xy 28.907213 -258.567695)
			(xy 28.867064 -258.528986) (xy 28.832978 -258.484843) (xy 28.805682 -258.436208) (xy 28.785759 -258.384117)
			(xy 28.773633 -258.32968) (xy 28.769562 -258.274058) (xy 23.375363 -258.274058) (xy 23.377699 -258.274315)
			(xy 23.431656 -258.288421) (xy 23.482985 -258.310233) (xy 23.530591 -258.339287) (xy 23.573459 -258.374962)
			(xy 23.610676 -258.416499) (xy 23.641449 -258.463012) (xy 23.665121 -258.513509) (xy 23.681189 -258.566916)
			(xy 23.689309 -258.622092) (xy 23.689818 -258.649978) (xy 23.689309 -258.677864) (xy 23.687357 -258.691126)
			(xy 24.410668 -258.691126) (xy 24.414739 -258.635504) (xy 24.426865 -258.581067) (xy 24.446788 -258.528976)
			(xy 24.474084 -258.480341) (xy 24.50817 -258.436198) (xy 24.548319 -258.397489) (xy 24.593677 -258.365038)
			(xy 24.643277 -258.339537) (xy 24.696061 -258.32153) (xy 24.750904 -258.3114) (xy 24.806638 -258.309363)
			(xy 24.862075 -258.315463) (xy 24.916032 -258.329569) (xy 24.967361 -258.351381) (xy 25.014967 -258.380435)
			(xy 25.057835 -258.41611) (xy 25.095052 -258.457647) (xy 25.125825 -258.50416) (xy 25.149497 -258.554657)
			(xy 25.165565 -258.608064) (xy 25.173685 -258.66324) (xy 25.174194 -258.691126) (xy 25.173685 -258.719012)
			(xy 25.165565 -258.774188) (xy 25.149497 -258.827595) (xy 25.125825 -258.878092) (xy 25.095052 -258.924605)
			(xy 25.057835 -258.966142) (xy 25.014967 -259.001817) (xy 24.967361 -259.030871) (xy 24.916032 -259.052683)
			(xy 24.862075 -259.066789) (xy 24.806638 -259.072889) (xy 24.750904 -259.070852) (xy 24.696061 -259.060722)
			(xy 24.643277 -259.042715) (xy 24.593677 -259.017214) (xy 24.548319 -258.984763) (xy 24.50817 -258.946054)
			(xy 24.474084 -258.901911) (xy 24.446788 -258.853276) (xy 24.426865 -258.801185) (xy 24.414739 -258.746748)
			(xy 24.410668 -258.691126) (xy 23.687357 -258.691126) (xy 23.681189 -258.73304) (xy 23.665121 -258.786447)
			(xy 23.641449 -258.836944) (xy 23.610676 -258.883457) (xy 23.573459 -258.924994) (xy 23.530591 -258.960669)
			(xy 23.482985 -258.989723) (xy 23.431656 -259.011535) (xy 23.377699 -259.025641) (xy 23.322262 -259.031741)
			(xy 23.266528 -259.029704) (xy 23.211685 -259.019574) (xy 23.158901 -259.001567) (xy 23.109301 -258.976066)
			(xy 23.063943 -258.943615) (xy 23.023794 -258.904906) (xy 22.989708 -258.860763) (xy 22.962412 -258.812128)
			(xy 22.942489 -258.760037) (xy 22.930363 -258.7056) (xy 22.926292 -258.649978) (xy 21.35632 -258.649978)
			(xy 21.35632 -259.1816) (xy 21.356744 -259.19167) (xy 21.36446 -259.210272) (xy 21.371306 -259.217668)
			(xy 21.994114 -259.840222) (xy 22.002599 -259.84788) (xy 22.024102 -259.855539) (xy 22.035516 -259.854954)
			(xy 22.12594 -259.844794) (xy 22.145498 -259.832856) (xy 22.151594 -259.82295) (xy 22.166698 -259.800092)
			(xy 22.202414 -259.758548) (xy 22.243702 -259.722535) (xy 22.289713 -259.692795) (xy 22.339503 -259.669936)
			(xy 22.39205 -259.65443) (xy 22.446273 -259.646594) (xy 22.473666 -259.646166) (xy 22.500921 -259.646627)
			(xy 22.554877 -259.654379) (xy 22.607181 -259.669732) (xy 22.656767 -259.692372) (xy 22.702626 -259.721839)
			(xy 22.743825 -259.757533) (xy 22.779525 -259.798726) (xy 22.808999 -259.84458) (xy 22.831647 -259.894163)
			(xy 22.847008 -259.946464) (xy 22.854769 -260.000419) (xy 22.855174 -260.027674) (xy 22.854662 -260.05632)
			(xy 22.852503 -260.0706) (xy 23.642826 -260.0706) (xy 23.646897 -260.014978) (xy 23.659023 -259.960541)
			(xy 23.678946 -259.90845) (xy 23.706242 -259.859815) (xy 23.740328 -259.815672) (xy 23.780477 -259.776963)
			(xy 23.825835 -259.744512) (xy 23.875435 -259.719011) (xy 23.928219 -259.701004) (xy 23.983062 -259.690874)
			(xy 24.038796 -259.688837) (xy 24.094233 -259.694937) (xy 24.14819 -259.709043) (xy 24.199519 -259.730855)
			(xy 24.247125 -259.759909) (xy 24.289993 -259.795584) (xy 24.32721 -259.837121) (xy 24.357983 -259.883634)
			(xy 24.381655 -259.934131) (xy 24.397723 -259.987538) (xy 24.405843 -260.042714) (xy 24.406352 -260.0706)
			(xy 24.405843 -260.098486) (xy 24.397723 -260.153662) (xy 24.381655 -260.207069) (xy 24.357983 -260.257566)
			(xy 24.32721 -260.304079) (xy 24.289993 -260.345616) (xy 24.247125 -260.381291) (xy 24.199519 -260.410345)
			(xy 24.14819 -260.432157) (xy 24.094233 -260.446263) (xy 24.038796 -260.452363) (xy 23.983062 -260.450326)
			(xy 23.928219 -260.440196) (xy 23.875435 -260.422189) (xy 23.825835 -260.396688) (xy 23.780477 -260.364237)
			(xy 23.740328 -260.325528) (xy 23.706242 -260.281385) (xy 23.678946 -260.23275) (xy 23.659023 -260.180659)
			(xy 23.646897 -260.126222) (xy 23.642826 -260.0706) (xy 22.852503 -260.0706) (xy 22.846099 -260.112967)
			(xy 22.82916 -260.167697) (xy 22.804228 -260.219279) (xy 22.771863 -260.266552) (xy 22.732792 -260.308453)
			(xy 22.710648 -260.326632) (xy 22.702266 -260.333236) (xy 22.69236 -260.352286) (xy 22.686518 -260.437884)
			(xy 22.686225 -260.448518) (xy 22.693464 -260.468502) (xy 22.700488 -260.476492) (xy 22.720111 -260.497753)
			(xy 22.753361 -260.5451) (xy 22.779073 -260.596927) (xy 22.79666 -260.652045) (xy 22.805715 -260.709188)
			(xy 22.806406 -260.738112) (xy 22.806406 -260.748018) (xy 22.814026 -260.76656) (xy 24.0411 -261.993634)
			(xy 24.048495 -262.000488) (xy 24.067094 -262.008233) (xy 24.077168 -262.00862) (xy 25.431496 -262.00862)
			(xy 25.443057 -262.008013) (xy 25.46383 -261.997842) (xy 25.471374 -261.989062) (xy 25.52827 -261.916672)
			(xy 25.532842 -261.894066) (xy 25.530048 -261.882636) (xy 25.524823 -261.860138) (xy 25.519218 -261.81429)
			(xy 25.518872 -261.791196) (xy 25.518872 -261.790688) (xy 25.519394 -261.762267) (xy 25.527816 -261.706052)
			(xy 25.544472 -261.651706) (xy 25.568995 -261.600426) (xy 25.600843 -261.553344) (xy 25.639315 -261.5115)
			(xy 25.661112 -261.493254) (xy 25.669599 -261.485679) (xy 25.679516 -261.465239) (xy 25.680162 -261.453884)
			(xy 25.680162 -261.147052) (xy 25.680596 -261.136987) (xy 25.688329 -261.118401) (xy 25.695148 -261.110984)
			(xy 26.750264 -260.055868) (xy 26.757663 -260.049024) (xy 26.776262 -260.041302) (xy 26.786332 -260.040882)
			(xy 27.648154 -260.040882) (xy 27.674824 -260.021324) (xy 27.679904 -260.005322) (xy 27.688938 -259.978363)
			(xy 27.713864 -259.927263) (xy 27.746097 -259.880427) (xy 27.784922 -259.838892) (xy 27.829481 -259.803578)
			(xy 27.878785 -259.775266) (xy 27.931746 -259.754584) (xy 27.987188 -259.741988) (xy 28.043886 -259.737758)
			(xy 28.100584 -259.741988) (xy 28.156026 -259.754584) (xy 28.208987 -259.775266) (xy 28.258291 -259.803578)
			(xy 28.30285 -259.838892) (xy 28.341675 -259.880427) (xy 28.373908 -259.927263) (xy 28.398834 -259.978363)
			(xy 28.407868 -260.005322) (xy 28.412948 -260.021324) (xy 28.439618 -260.040882) (xy 34.421318 -260.040882)
			(xy 34.429355 -260.040522) (xy 34.444622 -260.035478) (xy 34.45129 -260.030976) (xy 34.478722 -260.012942)
			(xy 34.485879 -260.008205) (xy 34.496768 -259.994951) (xy 34.502657 -259.978841) (xy 34.503106 -259.97027)
			(xy 34.50336 -259.939028) (xy 34.503203 -259.930459) (xy 34.497878 -259.914179) (xy 34.487478 -259.900569)
			(xy 34.4805 -259.895594) (xy 34.458108 -259.88042) (xy 34.417439 -259.844759) (xy 34.382217 -259.803709)
			(xy 34.353148 -259.758095) (xy 34.330816 -259.70883) (xy 34.315669 -259.656905) (xy 34.30801 -259.603361)
			(xy 34.307526 -259.576316) (xy 34.308012 -259.549065) (xy 34.315768 -259.495117) (xy 34.331123 -259.442822)
			(xy 34.353765 -259.393245) (xy 34.383231 -259.347395) (xy 34.418922 -259.306204) (xy 34.460113 -259.270513)
			(xy 34.505963 -259.241047) (xy 34.55554 -259.218405) (xy 34.607835 -259.20305) (xy 34.661783 -259.195294)
			(xy 34.716285 -259.195294) (xy 34.770233 -259.20305) (xy 34.822528 -259.218405) (xy 34.872105 -259.241047)
			(xy 34.917955 -259.270513) (xy 34.959146 -259.306204) (xy 34.994837 -259.347395) (xy 35.024303 -259.393245)
			(xy 35.046945 -259.442822) (xy 35.0623 -259.495117) (xy 35.070056 -259.549065) (xy 35.070542 -259.576316)
			(xy 35.070063 -259.604182) (xy 35.061957 -259.659321) (xy 35.045906 -259.71269) (xy 35.022252 -259.763153)
			(xy 34.991499 -259.809631) (xy 34.954304 -259.851135) (xy 34.91146 -259.886777) (xy 34.887916 -259.90169)
			(xy 34.880758 -259.906426) (xy 34.869869 -259.919679) (xy 34.863985 -259.935791) (xy 34.863532 -259.944362)
			(xy 34.863278 -259.975604) (xy 34.86344 -259.98417) (xy 34.868775 -260.000439) (xy 34.879182 -260.014034)
			(xy 34.886138 -260.019038) (xy 34.903664 -260.030976) (xy 34.917126 -260.040882) (xy 34.92373 -260.040882)
			(xy 35.635946 -260.753098) (xy 35.643347 -260.759937) (xy 35.661945 -260.767655) (xy 35.672014 -260.768084)
			(xy 35.72002 -260.768084) (xy 35.729864 -260.767638) (xy 35.748101 -260.760221) (xy 35.762178 -260.746458)
			(xy 35.766502 -260.737604) (xy 35.80384 -260.65226) (xy 35.807357 -260.643044) (xy 35.807826 -260.623344)
			(xy 35.800814 -260.604927) (xy 35.794442 -260.597396) (xy 35.775494 -260.576114) (xy 35.743475 -260.528983)
			(xy 35.718819 -260.477616) (xy 35.702075 -260.423153) (xy 35.693616 -260.366805) (xy 35.693096 -260.338316)
			(xy 35.693582 -260.311065) (xy 35.701338 -260.257117) (xy 35.716693 -260.204822) (xy 35.739335 -260.155245)
			(xy 35.768801 -260.109395) (xy 35.804492 -260.068204) (xy 35.845683 -260.032513) (xy 35.891533 -260.003047)
			(xy 35.94111 -259.980405) (xy 35.993405 -259.96505) (xy 36.047353 -259.957294) (xy 36.101855 -259.957294)
			(xy 36.155803 -259.96505) (xy 36.208098 -259.980405) (xy 36.257675 -260.003047) (xy 36.303525 -260.032513)
			(xy 36.344716 -260.068204) (xy 36.380407 -260.109395) (xy 36.409873 -260.155245) (xy 36.432515 -260.204822)
			(xy 36.44787 -260.257117) (xy 36.455626 -260.311065) (xy 36.456112 -260.338316) (xy 36.455584 -260.366805)
			(xy 36.447116 -260.423149) (xy 36.430372 -260.47761) (xy 36.405723 -260.52898) (xy 36.373715 -260.576117)
			(xy 36.354766 -260.597396) (xy 36.348418 -260.604936) (xy 36.341451 -260.623355) (xy 36.341877 -260.643043)
			(xy 36.345368 -260.65226) (xy 36.382706 -260.737604) (xy 36.38707 -260.746428) (xy 36.401153 -260.760159)
			(xy 36.419356 -260.767608) (xy 36.429188 -260.768084) (xy 40.997886 -260.768084) (xy 41.01916 -260.768271)
			(xy 41.061525 -260.772213) (xy 41.082468 -260.775958) (xy 41.08704 -260.776974) (xy 41.238932 -260.776974)
			(xy 41.249 -260.777402) (xy 41.267599 -260.785122) (xy 41.275 -260.79196) (xy 45.392086 -264.909046)
			(xy 45.398927 -264.916446) (xy 45.406647 -264.935045) (xy 45.407072 -264.945114) (xy 45.407072 -267.742162)
			(xy 45.406559 -267.752063) (xy 45.398985 -267.770365) (xy 45.39234 -267.777722) (xy 45.391324 -267.778992)
			(xy 45.383704 -267.79728) (xy 45.383704 -268.549882) (xy 45.383235 -268.579011) (xy 45.375599 -268.636766)
			(xy 45.360482 -268.693029) (xy 45.338143 -268.746834) (xy 45.308965 -268.797259) (xy 45.273448 -268.843439)
			(xy 45.253148 -268.864334) (xy 43.914822 -270.20266) (xy 43.907983 -270.210061) (xy 43.900267 -270.228659)
			(xy 43.899836 -270.238728) (xy 43.899836 -270.761968) (xy 43.899376 -270.791086) (xy 43.891764 -270.848824)
			(xy 43.87668 -270.905073) (xy 43.854382 -270.958872) (xy 43.825251 -271.009299) (xy 43.789786 -271.055492)
			(xy 43.769534 -271.07642) (xy 42.932096 -271.913858) (xy 42.911192 -271.934138) (xy 42.865001 -271.969614)
			(xy 42.81457 -271.998751) (xy 42.760766 -272.02105) (xy 42.70451 -272.03613) (xy 42.646765 -272.043731)
			(xy 42.617644 -272.04416) (xy 41.146984 -272.04416) (xy 41.136916 -272.044588) (xy 41.118322 -272.052313)
			(xy 41.110916 -272.059146) (xy 40.955468 -272.214594) (xy 40.948068 -272.221436) (xy 40.92947 -272.22916)
			(xy 40.9194 -272.22958) (xy 40.456612 -272.22958) (xy 40.446528 -272.229998) (xy 40.427915 -272.237762)
			(xy 40.413757 -272.252124) (xy 40.409622 -272.26133) (xy 40.374316 -272.34896) (xy 40.370933 -272.358441)
			(xy 40.371132 -272.378553) (xy 40.379068 -272.397034) (xy 40.386 -272.404332) (xy 40.386254 -272.404586)
			(xy 40.403704 -272.421962) (xy 40.433323 -272.4613) (xy 40.45624 -272.504884) (xy 40.471863 -272.551582)
			(xy 40.479785 -272.600183) (xy 40.480234 -272.624804) (xy 41.769042 -272.624804) (xy 41.773002 -272.57575)
			(xy 41.784779 -272.527966) (xy 41.80407 -272.48269) (xy 41.830373 -272.441094) (xy 41.863008 -272.404257)
			(xy 41.901129 -272.373132) (xy 41.94375 -272.348525) (xy 41.989766 -272.331073) (xy 42.037985 -272.321229)
			(xy 42.08716 -272.319248) (xy 42.136015 -272.32518) (xy 42.183286 -272.338872) (xy 42.227748 -272.35997)
			(xy 42.268251 -272.387926) (xy 42.303744 -272.422018) (xy 42.333309 -272.461362) (xy 42.35618 -272.504939)
			(xy 42.371764 -272.55162) (xy 42.379659 -272.600197) (xy 42.380154 -272.624804) (xy 42.379659 -272.649411)
			(xy 42.371764 -272.697988) (xy 42.35618 -272.744669) (xy 42.333309 -272.788246) (xy 42.303744 -272.82759)
			(xy 42.268251 -272.861682) (xy 42.227748 -272.889638) (xy 42.183286 -272.910736) (xy 42.136015 -272.924428)
			(xy 42.08716 -272.93036) (xy 42.037985 -272.928379) (xy 41.989766 -272.918535) (xy 41.94375 -272.901083)
			(xy 41.901129 -272.876476) (xy 41.863008 -272.845351) (xy 41.830373 -272.808514) (xy 41.80407 -272.766918)
			(xy 41.784779 -272.721642) (xy 41.773002 -272.673858) (xy 41.769042 -272.624804) (xy 40.480234 -272.624804)
			(xy 40.479763 -272.648796) (xy 40.472257 -272.696189) (xy 40.457429 -272.741824) (xy 40.435646 -272.784578)
			(xy 40.407443 -272.823398) (xy 40.373515 -272.857329) (xy 40.334696 -272.885534) (xy 40.291944 -272.907321)
			(xy 40.24631 -272.922152) (xy 40.198918 -272.929661) (xy 40.174926 -272.930112) (xy 40.14609 -272.929419)
			(xy 40.089451 -272.918547) (xy 40.062404 -272.908522) (xy 40.06215 -272.908522) (xy 40.050384 -272.904701)
			(xy 40.025824 -272.907336) (xy 40.01516 -272.913602) (xy 39.945564 -272.960846) (xy 39.935546 -272.968375)
			(xy 39.92383 -272.990493) (xy 39.923212 -273.00301) (xy 39.923212 -273.099784) (xy 44.143942 -273.099784)
			(xy 44.147902 -273.05073) (xy 44.159679 -273.002946) (xy 44.17897 -272.95767) (xy 44.205273 -272.916074)
			(xy 44.237908 -272.879237) (xy 44.276029 -272.848112) (xy 44.31865 -272.823505) (xy 44.364666 -272.806053)
			(xy 44.412885 -272.796209) (xy 44.46206 -272.794228) (xy 44.510915 -272.80016) (xy 44.558186 -272.813852)
			(xy 44.602648 -272.83495) (xy 44.643151 -272.862906) (xy 44.678644 -272.896998) (xy 44.708209 -272.936342)
			(xy 44.73108 -272.979919) (xy 44.746664 -273.0266) (xy 44.754559 -273.075177) (xy 44.755054 -273.099784)
			(xy 46.044116 -273.099784) (xy 46.048076 -273.05073) (xy 46.059853 -273.002946) (xy 46.079144 -272.95767)
			(xy 46.105447 -272.916074) (xy 46.138082 -272.879237) (xy 46.176203 -272.848112) (xy 46.218824 -272.823505)
			(xy 46.26484 -272.806053) (xy 46.313059 -272.796209) (xy 46.362234 -272.794228) (xy 46.411089 -272.80016)
			(xy 46.45836 -272.813852) (xy 46.502822 -272.83495) (xy 46.543325 -272.862906) (xy 46.578818 -272.896998)
			(xy 46.608383 -272.936342) (xy 46.631254 -272.979919) (xy 46.646838 -273.0266) (xy 46.654733 -273.075177)
			(xy 46.655228 -273.099784) (xy 47.944036 -273.099784) (xy 47.947996 -273.05073) (xy 47.959773 -273.002946)
			(xy 47.979064 -272.95767) (xy 48.005367 -272.916074) (xy 48.038002 -272.879237) (xy 48.076123 -272.848112)
			(xy 48.118744 -272.823505) (xy 48.16476 -272.806053) (xy 48.212979 -272.796209) (xy 48.262154 -272.794228)
			(xy 48.311009 -272.80016) (xy 48.35828 -272.813852) (xy 48.402742 -272.83495) (xy 48.443245 -272.862906)
			(xy 48.478738 -272.896998) (xy 48.508303 -272.936342) (xy 48.531174 -272.979919) (xy 48.546758 -273.0266)
			(xy 48.554653 -273.075177) (xy 48.555148 -273.099784) (xy 49.843956 -273.099784) (xy 49.847916 -273.05073)
			(xy 49.859693 -273.002946) (xy 49.878984 -272.95767) (xy 49.905287 -272.916074) (xy 49.937922 -272.879237)
			(xy 49.976043 -272.848112) (xy 50.018664 -272.823505) (xy 50.06468 -272.806053) (xy 50.112899 -272.796209)
			(xy 50.162074 -272.794228) (xy 50.210929 -272.80016) (xy 50.2582 -272.813852) (xy 50.302662 -272.83495)
			(xy 50.343165 -272.862906) (xy 50.378658 -272.896998) (xy 50.408223 -272.936342) (xy 50.431094 -272.979919)
			(xy 50.446678 -273.0266) (xy 50.454573 -273.075177) (xy 50.455068 -273.099784) (xy 51.74413 -273.099784)
			(xy 51.74809 -273.05073) (xy 51.759867 -273.002946) (xy 51.779158 -272.95767) (xy 51.805461 -272.916074)
			(xy 51.838096 -272.879237) (xy 51.876217 -272.848112) (xy 51.918838 -272.823505) (xy 51.964854 -272.806053)
			(xy 52.013073 -272.796209) (xy 52.062248 -272.794228) (xy 52.111103 -272.80016) (xy 52.158374 -272.813852)
			(xy 52.202836 -272.83495) (xy 52.243339 -272.862906) (xy 52.278832 -272.896998) (xy 52.308397 -272.936342)
			(xy 52.331268 -272.979919) (xy 52.346852 -273.0266) (xy 52.354747 -273.075177) (xy 52.355242 -273.099784)
			(xy 53.64405 -273.099784) (xy 53.64801 -273.05073) (xy 53.659787 -273.002946) (xy 53.679078 -272.95767)
			(xy 53.705381 -272.916074) (xy 53.738016 -272.879237) (xy 53.776137 -272.848112) (xy 53.818758 -272.823505)
			(xy 53.864774 -272.806053) (xy 53.912993 -272.796209) (xy 53.962168 -272.794228) (xy 54.011023 -272.80016)
			(xy 54.058294 -272.813852) (xy 54.102756 -272.83495) (xy 54.143259 -272.862906) (xy 54.178752 -272.896998)
			(xy 54.208317 -272.936342) (xy 54.231188 -272.979919) (xy 54.246772 -273.0266) (xy 54.254667 -273.075177)
			(xy 54.255162 -273.099784) (xy 55.54397 -273.099784) (xy 55.54793 -273.05073) (xy 55.559707 -273.002946)
			(xy 55.578998 -272.95767) (xy 55.605301 -272.916074) (xy 55.637936 -272.879237) (xy 55.676057 -272.848112)
			(xy 55.718678 -272.823505) (xy 55.764694 -272.806053) (xy 55.812913 -272.796209) (xy 55.862088 -272.794228)
			(xy 55.910943 -272.80016) (xy 55.958214 -272.813852) (xy 56.002676 -272.83495) (xy 56.043179 -272.862906)
			(xy 56.078672 -272.896998) (xy 56.108237 -272.936342) (xy 56.131108 -272.979919) (xy 56.146692 -273.0266)
			(xy 56.154587 -273.075177) (xy 56.155082 -273.099784) (xy 56.154587 -273.124391) (xy 56.146692 -273.172968)
			(xy 56.131108 -273.219649) (xy 56.108237 -273.263226) (xy 56.078672 -273.30257) (xy 56.043179 -273.336662)
			(xy 56.002676 -273.364618) (xy 55.958214 -273.385716) (xy 55.910943 -273.399408) (xy 55.862088 -273.40534)
			(xy 55.812913 -273.403359) (xy 55.764694 -273.393515) (xy 55.718678 -273.376063) (xy 55.676057 -273.351456)
			(xy 55.637936 -273.320331) (xy 55.605301 -273.283494) (xy 55.578998 -273.241898) (xy 55.559707 -273.196622)
			(xy 55.54793 -273.148838) (xy 55.54397 -273.099784) (xy 54.255162 -273.099784) (xy 54.254667 -273.124391)
			(xy 54.246772 -273.172968) (xy 54.231188 -273.219649) (xy 54.208317 -273.263226) (xy 54.178752 -273.30257)
			(xy 54.143259 -273.336662) (xy 54.102756 -273.364618) (xy 54.058294 -273.385716) (xy 54.011023 -273.399408)
			(xy 53.962168 -273.40534) (xy 53.912993 -273.403359) (xy 53.864774 -273.393515) (xy 53.818758 -273.376063)
			(xy 53.776137 -273.351456) (xy 53.738016 -273.320331) (xy 53.705381 -273.283494) (xy 53.679078 -273.241898)
			(xy 53.659787 -273.196622) (xy 53.64801 -273.148838) (xy 53.64405 -273.099784) (xy 52.355242 -273.099784)
			(xy 52.354747 -273.124391) (xy 52.346852 -273.172968) (xy 52.331268 -273.219649) (xy 52.308397 -273.263226)
			(xy 52.278832 -273.30257) (xy 52.243339 -273.336662) (xy 52.202836 -273.364618) (xy 52.158374 -273.385716)
			(xy 52.111103 -273.399408) (xy 52.062248 -273.40534) (xy 52.013073 -273.403359) (xy 51.964854 -273.393515)
			(xy 51.918838 -273.376063) (xy 51.876217 -273.351456) (xy 51.838096 -273.320331) (xy 51.805461 -273.283494)
			(xy 51.779158 -273.241898) (xy 51.759867 -273.196622) (xy 51.74809 -273.148838) (xy 51.74413 -273.099784)
			(xy 50.455068 -273.099784) (xy 50.454573 -273.124391) (xy 50.446678 -273.172968) (xy 50.431094 -273.219649)
			(xy 50.408223 -273.263226) (xy 50.378658 -273.30257) (xy 50.343165 -273.336662) (xy 50.302662 -273.364618)
			(xy 50.2582 -273.385716) (xy 50.210929 -273.399408) (xy 50.162074 -273.40534) (xy 50.112899 -273.403359)
			(xy 50.06468 -273.393515) (xy 50.018664 -273.376063) (xy 49.976043 -273.351456) (xy 49.937922 -273.320331)
			(xy 49.905287 -273.283494) (xy 49.878984 -273.241898) (xy 49.859693 -273.196622) (xy 49.847916 -273.148838)
			(xy 49.843956 -273.099784) (xy 48.555148 -273.099784) (xy 48.554653 -273.124391) (xy 48.546758 -273.172968)
			(xy 48.531174 -273.219649) (xy 48.508303 -273.263226) (xy 48.478738 -273.30257) (xy 48.443245 -273.336662)
			(xy 48.402742 -273.364618) (xy 48.35828 -273.385716) (xy 48.311009 -273.399408) (xy 48.262154 -273.40534)
			(xy 48.212979 -273.403359) (xy 48.16476 -273.393515) (xy 48.118744 -273.376063) (xy 48.076123 -273.351456)
			(xy 48.038002 -273.320331) (xy 48.005367 -273.283494) (xy 47.979064 -273.241898) (xy 47.959773 -273.196622)
			(xy 47.947996 -273.148838) (xy 47.944036 -273.099784) (xy 46.655228 -273.099784) (xy 46.654733 -273.124391)
			(xy 46.646838 -273.172968) (xy 46.631254 -273.219649) (xy 46.608383 -273.263226) (xy 46.578818 -273.30257)
			(xy 46.543325 -273.336662) (xy 46.502822 -273.364618) (xy 46.45836 -273.385716) (xy 46.411089 -273.399408)
			(xy 46.362234 -273.40534) (xy 46.313059 -273.403359) (xy 46.26484 -273.393515) (xy 46.218824 -273.376063)
			(xy 46.176203 -273.351456) (xy 46.138082 -273.320331) (xy 46.105447 -273.283494) (xy 46.079144 -273.241898)
			(xy 46.059853 -273.196622) (xy 46.048076 -273.148838) (xy 46.044116 -273.099784) (xy 44.755054 -273.099784)
			(xy 44.754559 -273.124391) (xy 44.746664 -273.172968) (xy 44.73108 -273.219649) (xy 44.708209 -273.263226)
			(xy 44.678644 -273.30257) (xy 44.643151 -273.336662) (xy 44.602648 -273.364618) (xy 44.558186 -273.385716)
			(xy 44.510915 -273.399408) (xy 44.46206 -273.40534) (xy 44.412885 -273.403359) (xy 44.364666 -273.393515)
			(xy 44.31865 -273.376063) (xy 44.276029 -273.351456) (xy 44.237908 -273.320331) (xy 44.205273 -273.283494)
			(xy 44.17897 -273.241898) (xy 44.159679 -273.196622) (xy 44.147902 -273.148838) (xy 44.143942 -273.099784)
			(xy 39.923212 -273.099784) (xy 39.923212 -273.196558) (xy 39.923853 -273.209068) (xy 39.935566 -273.231177)
			(xy 39.945564 -273.238722) (xy 40.01516 -273.285966) (xy 40.02577 -273.292393) (xy 40.050405 -273.295041)
			(xy 40.06215 -273.291046) (xy 40.062404 -273.291046) (xy 40.089448 -273.28101) (xy 40.146089 -273.270135)
			(xy 40.174926 -273.269456) (xy 40.200183 -273.26998) (xy 40.250007 -273.278298) (xy 40.297783 -273.294703)
			(xy 40.342207 -273.318747) (xy 40.382068 -273.349776) (xy 40.416279 -273.386941) (xy 40.443906 -273.429231)
			(xy 40.464196 -273.47549) (xy 40.476596 -273.524459) (xy 40.480764 -273.574764) (xy 41.769042 -273.574764)
			(xy 41.773002 -273.52571) (xy 41.784779 -273.477926) (xy 41.80407 -273.43265) (xy 41.830373 -273.391054)
			(xy 41.863008 -273.354217) (xy 41.901129 -273.323092) (xy 41.94375 -273.298485) (xy 41.989766 -273.281033)
			(xy 42.037985 -273.271189) (xy 42.08716 -273.269208) (xy 42.136015 -273.27514) (xy 42.183286 -273.288832)
			(xy 42.227748 -273.30993) (xy 42.268251 -273.337886) (xy 42.303744 -273.371978) (xy 42.333309 -273.411322)
			(xy 42.35618 -273.454899) (xy 42.371764 -273.50158) (xy 42.379659 -273.550157) (xy 42.380154 -273.574764)
			(xy 42.379659 -273.599371) (xy 42.371764 -273.647948) (xy 42.35618 -273.694629) (xy 42.333309 -273.738206)
			(xy 42.303744 -273.77755) (xy 42.268251 -273.811642) (xy 42.227748 -273.839598) (xy 42.183286 -273.860696)
			(xy 42.136015 -273.874388) (xy 42.08716 -273.88032) (xy 42.037985 -273.878339) (xy 41.989766 -273.868495)
			(xy 41.94375 -273.851043) (xy 41.901129 -273.826436) (xy 41.863008 -273.795311) (xy 41.830373 -273.758474)
			(xy 41.80407 -273.716878) (xy 41.784779 -273.671602) (xy 41.773002 -273.623818) (xy 41.769042 -273.574764)
			(xy 40.480764 -273.574764) (xy 40.480767 -273.5748) (xy 40.476596 -273.625141) (xy 40.464196 -273.67411)
			(xy 40.443906 -273.720369) (xy 40.416279 -273.762659) (xy 40.382068 -273.799824) (xy 40.342207 -273.830853)
			(xy 40.297783 -273.854897) (xy 40.250007 -273.871302) (xy 40.200183 -273.87962) (xy 40.174926 -273.880072)
			(xy 40.14609 -273.879379) (xy 40.08945 -273.868509) (xy 40.062404 -273.858482) (xy 40.06215 -273.858482)
			(xy 40.050384 -273.854658) (xy 40.025825 -273.857296) (xy 40.01516 -273.863562) (xy 39.945564 -273.910806)
			(xy 39.935539 -273.918332) (xy 39.923806 -273.94045) (xy 39.923212 -273.95297) (xy 39.923212 -274.049744)
			(xy 44.143942 -274.049744) (xy 44.147902 -274.00069) (xy 44.159679 -273.952906) (xy 44.17897 -273.90763)
			(xy 44.205273 -273.866034) (xy 44.237908 -273.829197) (xy 44.276029 -273.798072) (xy 44.31865 -273.773465)
			(xy 44.364666 -273.756013) (xy 44.412885 -273.746169) (xy 44.46206 -273.744188) (xy 44.510915 -273.75012)
			(xy 44.558186 -273.763812) (xy 44.602648 -273.78491) (xy 44.643151 -273.812866) (xy 44.678644 -273.846958)
			(xy 44.708209 -273.886302) (xy 44.73108 -273.929879) (xy 44.746664 -273.97656) (xy 44.754559 -274.025137)
			(xy 44.755054 -274.049744) (xy 46.044116 -274.049744) (xy 46.048076 -274.00069) (xy 46.059853 -273.952906)
			(xy 46.079144 -273.90763) (xy 46.105447 -273.866034) (xy 46.138082 -273.829197) (xy 46.176203 -273.798072)
			(xy 46.218824 -273.773465) (xy 46.26484 -273.756013) (xy 46.313059 -273.746169) (xy 46.362234 -273.744188)
			(xy 46.411089 -273.75012) (xy 46.45836 -273.763812) (xy 46.502822 -273.78491) (xy 46.543325 -273.812866)
			(xy 46.578818 -273.846958) (xy 46.608383 -273.886302) (xy 46.631254 -273.929879) (xy 46.646838 -273.97656)
			(xy 46.654733 -274.025137) (xy 46.655228 -274.049744) (xy 47.944036 -274.049744) (xy 47.947996 -274.00069)
			(xy 47.959773 -273.952906) (xy 47.979064 -273.90763) (xy 48.005367 -273.866034) (xy 48.038002 -273.829197)
			(xy 48.076123 -273.798072) (xy 48.118744 -273.773465) (xy 48.16476 -273.756013) (xy 48.212979 -273.746169)
			(xy 48.262154 -273.744188) (xy 48.311009 -273.75012) (xy 48.35828 -273.763812) (xy 48.402742 -273.78491)
			(xy 48.443245 -273.812866) (xy 48.478738 -273.846958) (xy 48.508303 -273.886302) (xy 48.531174 -273.929879)
			(xy 48.546758 -273.97656) (xy 48.554653 -274.025137) (xy 48.555148 -274.049744) (xy 49.843956 -274.049744)
			(xy 49.847916 -274.00069) (xy 49.859693 -273.952906) (xy 49.878984 -273.90763) (xy 49.905287 -273.866034)
			(xy 49.937922 -273.829197) (xy 49.976043 -273.798072) (xy 50.018664 -273.773465) (xy 50.06468 -273.756013)
			(xy 50.112899 -273.746169) (xy 50.162074 -273.744188) (xy 50.210929 -273.75012) (xy 50.2582 -273.763812)
			(xy 50.302662 -273.78491) (xy 50.343165 -273.812866) (xy 50.378658 -273.846958) (xy 50.408223 -273.886302)
			(xy 50.431094 -273.929879) (xy 50.446678 -273.97656) (xy 50.454573 -274.025137) (xy 50.455068 -274.049744)
			(xy 51.74413 -274.049744) (xy 51.74809 -274.00069) (xy 51.759867 -273.952906) (xy 51.779158 -273.90763)
			(xy 51.805461 -273.866034) (xy 51.838096 -273.829197) (xy 51.876217 -273.798072) (xy 51.918838 -273.773465)
			(xy 51.964854 -273.756013) (xy 52.013073 -273.746169) (xy 52.062248 -273.744188) (xy 52.111103 -273.75012)
			(xy 52.158374 -273.763812) (xy 52.202836 -273.78491) (xy 52.243339 -273.812866) (xy 52.278832 -273.846958)
			(xy 52.308397 -273.886302) (xy 52.331268 -273.929879) (xy 52.346852 -273.97656) (xy 52.354747 -274.025137)
			(xy 52.355242 -274.049744) (xy 53.64405 -274.049744) (xy 53.64801 -274.00069) (xy 53.659787 -273.952906)
			(xy 53.679078 -273.90763) (xy 53.705381 -273.866034) (xy 53.738016 -273.829197) (xy 53.776137 -273.798072)
			(xy 53.818758 -273.773465) (xy 53.864774 -273.756013) (xy 53.912993 -273.746169) (xy 53.962168 -273.744188)
			(xy 54.011023 -273.75012) (xy 54.058294 -273.763812) (xy 54.102756 -273.78491) (xy 54.143259 -273.812866)
			(xy 54.178752 -273.846958) (xy 54.208317 -273.886302) (xy 54.231188 -273.929879) (xy 54.246772 -273.97656)
			(xy 54.254667 -274.025137) (xy 54.255162 -274.049744) (xy 55.54397 -274.049744) (xy 55.54793 -274.00069)
			(xy 55.559707 -273.952906) (xy 55.578998 -273.90763) (xy 55.605301 -273.866034) (xy 55.637936 -273.829197)
			(xy 55.676057 -273.798072) (xy 55.718678 -273.773465) (xy 55.764694 -273.756013) (xy 55.812913 -273.746169)
			(xy 55.862088 -273.744188) (xy 55.910943 -273.75012) (xy 55.958214 -273.763812) (xy 56.002676 -273.78491)
			(xy 56.043179 -273.812866) (xy 56.078672 -273.846958) (xy 56.108237 -273.886302) (xy 56.131108 -273.929879)
			(xy 56.146692 -273.97656) (xy 56.154587 -274.025137) (xy 56.155082 -274.049744) (xy 57.444144 -274.049744)
			(xy 57.448104 -274.00069) (xy 57.459881 -273.952906) (xy 57.479172 -273.90763) (xy 57.505475 -273.866034)
			(xy 57.53811 -273.829197) (xy 57.576231 -273.798072) (xy 57.618852 -273.773465) (xy 57.664868 -273.756013)
			(xy 57.713087 -273.746169) (xy 57.762262 -273.744188) (xy 57.811117 -273.75012) (xy 57.858388 -273.763812)
			(xy 57.90285 -273.78491) (xy 57.943353 -273.812866) (xy 57.978846 -273.846958) (xy 58.008411 -273.886302)
			(xy 58.031282 -273.929879) (xy 58.046866 -273.97656) (xy 58.054761 -274.025137) (xy 58.055256 -274.049744)
			(xy 58.054761 -274.074351) (xy 58.046866 -274.122928) (xy 58.031282 -274.169609) (xy 58.008411 -274.213186)
			(xy 57.978846 -274.25253) (xy 57.943353 -274.286622) (xy 57.90285 -274.314578) (xy 57.858388 -274.335676)
			(xy 57.811117 -274.349368) (xy 57.762262 -274.3553) (xy 57.713087 -274.353319) (xy 57.664868 -274.343475)
			(xy 57.618852 -274.326023) (xy 57.576231 -274.301416) (xy 57.53811 -274.270291) (xy 57.505475 -274.233454)
			(xy 57.479172 -274.191858) (xy 57.459881 -274.146582) (xy 57.448104 -274.098798) (xy 57.444144 -274.049744)
			(xy 56.155082 -274.049744) (xy 56.154587 -274.074351) (xy 56.146692 -274.122928) (xy 56.131108 -274.169609)
			(xy 56.108237 -274.213186) (xy 56.078672 -274.25253) (xy 56.043179 -274.286622) (xy 56.002676 -274.314578)
			(xy 55.958214 -274.335676) (xy 55.910943 -274.349368) (xy 55.862088 -274.3553) (xy 55.812913 -274.353319)
			(xy 55.764694 -274.343475) (xy 55.718678 -274.326023) (xy 55.676057 -274.301416) (xy 55.637936 -274.270291)
			(xy 55.605301 -274.233454) (xy 55.578998 -274.191858) (xy 55.559707 -274.146582) (xy 55.54793 -274.098798)
			(xy 55.54397 -274.049744) (xy 54.255162 -274.049744) (xy 54.254667 -274.074351) (xy 54.246772 -274.122928)
			(xy 54.231188 -274.169609) (xy 54.208317 -274.213186) (xy 54.178752 -274.25253) (xy 54.143259 -274.286622)
			(xy 54.102756 -274.314578) (xy 54.058294 -274.335676) (xy 54.011023 -274.349368) (xy 53.962168 -274.3553)
			(xy 53.912993 -274.353319) (xy 53.864774 -274.343475) (xy 53.818758 -274.326023) (xy 53.776137 -274.301416)
			(xy 53.738016 -274.270291) (xy 53.705381 -274.233454) (xy 53.679078 -274.191858) (xy 53.659787 -274.146582)
			(xy 53.64801 -274.098798) (xy 53.64405 -274.049744) (xy 52.355242 -274.049744) (xy 52.354747 -274.074351)
			(xy 52.346852 -274.122928) (xy 52.331268 -274.169609) (xy 52.308397 -274.213186) (xy 52.278832 -274.25253)
			(xy 52.243339 -274.286622) (xy 52.202836 -274.314578) (xy 52.158374 -274.335676) (xy 52.111103 -274.349368)
			(xy 52.062248 -274.3553) (xy 52.013073 -274.353319) (xy 51.964854 -274.343475) (xy 51.918838 -274.326023)
			(xy 51.876217 -274.301416) (xy 51.838096 -274.270291) (xy 51.805461 -274.233454) (xy 51.779158 -274.191858)
			(xy 51.759867 -274.146582) (xy 51.74809 -274.098798) (xy 51.74413 -274.049744) (xy 50.455068 -274.049744)
			(xy 50.454573 -274.074351) (xy 50.446678 -274.122928) (xy 50.431094 -274.169609) (xy 50.408223 -274.213186)
			(xy 50.378658 -274.25253) (xy 50.343165 -274.286622) (xy 50.302662 -274.314578) (xy 50.2582 -274.335676)
			(xy 50.210929 -274.349368) (xy 50.162074 -274.3553) (xy 50.112899 -274.353319) (xy 50.06468 -274.343475)
			(xy 50.018664 -274.326023) (xy 49.976043 -274.301416) (xy 49.937922 -274.270291) (xy 49.905287 -274.233454)
			(xy 49.878984 -274.191858) (xy 49.859693 -274.146582) (xy 49.847916 -274.098798) (xy 49.843956 -274.049744)
			(xy 48.555148 -274.049744) (xy 48.554653 -274.074351) (xy 48.546758 -274.122928) (xy 48.531174 -274.169609)
			(xy 48.508303 -274.213186) (xy 48.478738 -274.25253) (xy 48.443245 -274.286622) (xy 48.402742 -274.314578)
			(xy 48.35828 -274.335676) (xy 48.311009 -274.349368) (xy 48.262154 -274.3553) (xy 48.212979 -274.353319)
			(xy 48.16476 -274.343475) (xy 48.118744 -274.326023) (xy 48.076123 -274.301416) (xy 48.038002 -274.270291)
			(xy 48.005367 -274.233454) (xy 47.979064 -274.191858) (xy 47.959773 -274.146582) (xy 47.947996 -274.098798)
			(xy 47.944036 -274.049744) (xy 46.655228 -274.049744) (xy 46.654733 -274.074351) (xy 46.646838 -274.122928)
			(xy 46.631254 -274.169609) (xy 46.608383 -274.213186) (xy 46.578818 -274.25253) (xy 46.543325 -274.286622)
			(xy 46.502822 -274.314578) (xy 46.45836 -274.335676) (xy 46.411089 -274.349368) (xy 46.362234 -274.3553)
			(xy 46.313059 -274.353319) (xy 46.26484 -274.343475) (xy 46.218824 -274.326023) (xy 46.176203 -274.301416)
			(xy 46.138082 -274.270291) (xy 46.105447 -274.233454) (xy 46.079144 -274.191858) (xy 46.059853 -274.146582)
			(xy 46.048076 -274.098798) (xy 46.044116 -274.049744) (xy 44.755054 -274.049744) (xy 44.754559 -274.074351)
			(xy 44.746664 -274.122928) (xy 44.73108 -274.169609) (xy 44.708209 -274.213186) (xy 44.678644 -274.25253)
			(xy 44.643151 -274.286622) (xy 44.602648 -274.314578) (xy 44.558186 -274.335676) (xy 44.510915 -274.349368)
			(xy 44.46206 -274.3553) (xy 44.412885 -274.353319) (xy 44.364666 -274.343475) (xy 44.31865 -274.326023)
			(xy 44.276029 -274.301416) (xy 44.237908 -274.270291) (xy 44.205273 -274.233454) (xy 44.17897 -274.191858)
			(xy 44.159679 -274.146582) (xy 44.147902 -274.098798) (xy 44.143942 -274.049744) (xy 39.923212 -274.049744)
			(xy 39.923212 -274.524978) (xy 40.819082 -274.524978) (xy 40.823042 -274.475924) (xy 40.834819 -274.42814)
			(xy 40.85411 -274.382864) (xy 40.880413 -274.341268) (xy 40.913048 -274.304431) (xy 40.951169 -274.273306)
			(xy 40.99379 -274.248699) (xy 41.039806 -274.231247) (xy 41.088025 -274.221403) (xy 41.1372 -274.219422)
			(xy 41.186055 -274.225354) (xy 41.233326 -274.239046) (xy 41.277788 -274.260144) (xy 41.318291 -274.2881)
			(xy 41.353784 -274.322192) (xy 41.383349 -274.361536) (xy 41.40622 -274.405113) (xy 41.421804 -274.451794)
			(xy 41.429699 -274.500371) (xy 41.430194 -274.524978) (xy 42.719002 -274.524978) (xy 42.722962 -274.475924)
			(xy 42.734739 -274.42814) (xy 42.75403 -274.382864) (xy 42.780333 -274.341268) (xy 42.812968 -274.304431)
			(xy 42.851089 -274.273306) (xy 42.89371 -274.248699) (xy 42.939726 -274.231247) (xy 42.987945 -274.221403)
			(xy 43.03712 -274.219422) (xy 43.085975 -274.225354) (xy 43.133246 -274.239046) (xy 43.177708 -274.260144)
			(xy 43.218211 -274.2881) (xy 43.253704 -274.322192) (xy 43.283269 -274.361536) (xy 43.30614 -274.405113)
			(xy 43.321724 -274.451794) (xy 43.329619 -274.500371) (xy 43.330114 -274.524978) (xy 43.329619 -274.549585)
			(xy 43.321724 -274.598162) (xy 43.30614 -274.644843) (xy 43.283269 -274.68842) (xy 43.253704 -274.727764)
			(xy 43.218211 -274.761856) (xy 43.177708 -274.789812) (xy 43.133246 -274.81091) (xy 43.085975 -274.824602)
			(xy 43.03712 -274.830534) (xy 42.987945 -274.828553) (xy 42.939726 -274.818709) (xy 42.89371 -274.801257)
			(xy 42.851089 -274.77665) (xy 42.812968 -274.745525) (xy 42.780333 -274.708688) (xy 42.75403 -274.667092)
			(xy 42.734739 -274.621816) (xy 42.722962 -274.574032) (xy 42.719002 -274.524978) (xy 41.430194 -274.524978)
			(xy 41.429699 -274.549585) (xy 41.421804 -274.598162) (xy 41.40622 -274.644843) (xy 41.383349 -274.68842)
			(xy 41.353784 -274.727764) (xy 41.318291 -274.761856) (xy 41.277788 -274.789812) (xy 41.233326 -274.81091)
			(xy 41.186055 -274.824602) (xy 41.1372 -274.830534) (xy 41.088025 -274.828553) (xy 41.039806 -274.818709)
			(xy 40.99379 -274.801257) (xy 40.951169 -274.77665) (xy 40.913048 -274.745525) (xy 40.880413 -274.708688)
			(xy 40.85411 -274.667092) (xy 40.834819 -274.621816) (xy 40.823042 -274.574032) (xy 40.819082 -274.524978)
			(xy 39.923212 -274.524978) (xy 39.923212 -274.999958) (xy 45.094156 -274.999958) (xy 45.098116 -274.950904)
			(xy 45.109893 -274.90312) (xy 45.129184 -274.857844) (xy 45.155487 -274.816248) (xy 45.188122 -274.779411)
			(xy 45.226243 -274.748286) (xy 45.268864 -274.723679) (xy 45.31488 -274.706227) (xy 45.363099 -274.696383)
			(xy 45.412274 -274.694402) (xy 45.461129 -274.700334) (xy 45.5084 -274.714026) (xy 45.552862 -274.735124)
			(xy 45.593365 -274.76308) (xy 45.628858 -274.797172) (xy 45.658423 -274.836516) (xy 45.681294 -274.880093)
			(xy 45.696878 -274.926774) (xy 45.704773 -274.975351) (xy 45.705268 -274.999958) (xy 46.994076 -274.999958)
			(xy 46.998036 -274.950904) (xy 47.009813 -274.90312) (xy 47.029104 -274.857844) (xy 47.055407 -274.816248)
			(xy 47.088042 -274.779411) (xy 47.126163 -274.748286) (xy 47.168784 -274.723679) (xy 47.2148 -274.706227)
			(xy 47.263019 -274.696383) (xy 47.312194 -274.694402) (xy 47.361049 -274.700334) (xy 47.40832 -274.714026)
			(xy 47.452782 -274.735124) (xy 47.493285 -274.76308) (xy 47.528778 -274.797172) (xy 47.558343 -274.836516)
			(xy 47.581214 -274.880093) (xy 47.596798 -274.926774) (xy 47.604693 -274.975351) (xy 47.605188 -274.999958)
			(xy 48.893996 -274.999958) (xy 48.897956 -274.950904) (xy 48.909733 -274.90312) (xy 48.929024 -274.857844)
			(xy 48.955327 -274.816248) (xy 48.987962 -274.779411) (xy 49.026083 -274.748286) (xy 49.068704 -274.723679)
			(xy 49.11472 -274.706227) (xy 49.162939 -274.696383) (xy 49.212114 -274.694402) (xy 49.260969 -274.700334)
			(xy 49.30824 -274.714026) (xy 49.352702 -274.735124) (xy 49.393205 -274.76308) (xy 49.428698 -274.797172)
			(xy 49.458263 -274.836516) (xy 49.481134 -274.880093) (xy 49.496718 -274.926774) (xy 49.504613 -274.975351)
			(xy 49.505108 -274.999958) (xy 50.79417 -274.999958) (xy 50.79813 -274.950904) (xy 50.809907 -274.90312)
			(xy 50.829198 -274.857844) (xy 50.855501 -274.816248) (xy 50.888136 -274.779411) (xy 50.926257 -274.748286)
			(xy 50.968878 -274.723679) (xy 51.014894 -274.706227) (xy 51.063113 -274.696383) (xy 51.112288 -274.694402)
			(xy 51.161143 -274.700334) (xy 51.208414 -274.714026) (xy 51.252876 -274.735124) (xy 51.293379 -274.76308)
			(xy 51.328872 -274.797172) (xy 51.358437 -274.836516) (xy 51.381308 -274.880093) (xy 51.396892 -274.926774)
			(xy 51.404787 -274.975351) (xy 51.405282 -274.999958) (xy 52.69409 -274.999958) (xy 52.69805 -274.950904)
			(xy 52.709827 -274.90312) (xy 52.729118 -274.857844) (xy 52.755421 -274.816248) (xy 52.788056 -274.779411)
			(xy 52.826177 -274.748286) (xy 52.868798 -274.723679) (xy 52.914814 -274.706227) (xy 52.963033 -274.696383)
			(xy 53.012208 -274.694402) (xy 53.061063 -274.700334) (xy 53.108334 -274.714026) (xy 53.152796 -274.735124)
			(xy 53.193299 -274.76308) (xy 53.228792 -274.797172) (xy 53.258357 -274.836516) (xy 53.281228 -274.880093)
			(xy 53.296812 -274.926774) (xy 53.304707 -274.975351) (xy 53.305202 -274.999958) (xy 54.59401 -274.999958)
			(xy 54.59797 -274.950904) (xy 54.609747 -274.90312) (xy 54.629038 -274.857844) (xy 54.655341 -274.816248)
			(xy 54.687976 -274.779411) (xy 54.726097 -274.748286) (xy 54.768718 -274.723679) (xy 54.814734 -274.706227)
			(xy 54.862953 -274.696383) (xy 54.912128 -274.694402) (xy 54.960983 -274.700334) (xy 55.008254 -274.714026)
			(xy 55.052716 -274.735124) (xy 55.093219 -274.76308) (xy 55.128712 -274.797172) (xy 55.158277 -274.836516)
			(xy 55.181148 -274.880093) (xy 55.196732 -274.926774) (xy 55.204627 -274.975351) (xy 55.205122 -274.999958)
			(xy 56.494184 -274.999958) (xy 56.498144 -274.950904) (xy 56.509921 -274.90312) (xy 56.529212 -274.857844)
			(xy 56.555515 -274.816248) (xy 56.58815 -274.779411) (xy 56.626271 -274.748286) (xy 56.668892 -274.723679)
			(xy 56.714908 -274.706227) (xy 56.763127 -274.696383) (xy 56.812302 -274.694402) (xy 56.861157 -274.700334)
			(xy 56.908428 -274.714026) (xy 56.95289 -274.735124) (xy 56.993393 -274.76308) (xy 57.028886 -274.797172)
			(xy 57.058451 -274.836516) (xy 57.081322 -274.880093) (xy 57.096906 -274.926774) (xy 57.104801 -274.975351)
			(xy 57.105296 -274.999958) (xy 57.104801 -275.024565) (xy 57.096906 -275.073142) (xy 57.081322 -275.119823)
			(xy 57.058451 -275.1634) (xy 57.028886 -275.202744) (xy 56.993393 -275.236836) (xy 56.95289 -275.264792)
			(xy 56.908428 -275.28589) (xy 56.861157 -275.299582) (xy 56.812302 -275.305514) (xy 56.763127 -275.303533)
			(xy 56.714908 -275.293689) (xy 56.668892 -275.276237) (xy 56.626271 -275.25163) (xy 56.58815 -275.220505)
			(xy 56.555515 -275.183668) (xy 56.529212 -275.142072) (xy 56.509921 -275.096796) (xy 56.498144 -275.049012)
			(xy 56.494184 -274.999958) (xy 55.205122 -274.999958) (xy 55.204627 -275.024565) (xy 55.196732 -275.073142)
			(xy 55.181148 -275.119823) (xy 55.158277 -275.1634) (xy 55.128712 -275.202744) (xy 55.093219 -275.236836)
			(xy 55.052716 -275.264792) (xy 55.008254 -275.28589) (xy 54.960983 -275.299582) (xy 54.912128 -275.305514)
			(xy 54.862953 -275.303533) (xy 54.814734 -275.293689) (xy 54.768718 -275.276237) (xy 54.726097 -275.25163)
			(xy 54.687976 -275.220505) (xy 54.655341 -275.183668) (xy 54.629038 -275.142072) (xy 54.609747 -275.096796)
			(xy 54.59797 -275.049012) (xy 54.59401 -274.999958) (xy 53.305202 -274.999958) (xy 53.304707 -275.024565)
			(xy 53.296812 -275.073142) (xy 53.281228 -275.119823) (xy 53.258357 -275.1634) (xy 53.228792 -275.202744)
			(xy 53.193299 -275.236836) (xy 53.152796 -275.264792) (xy 53.108334 -275.28589) (xy 53.061063 -275.299582)
			(xy 53.012208 -275.305514) (xy 52.963033 -275.303533) (xy 52.914814 -275.293689) (xy 52.868798 -275.276237)
			(xy 52.826177 -275.25163) (xy 52.788056 -275.220505) (xy 52.755421 -275.183668) (xy 52.729118 -275.142072)
			(xy 52.709827 -275.096796) (xy 52.69805 -275.049012) (xy 52.69409 -274.999958) (xy 51.405282 -274.999958)
			(xy 51.404787 -275.024565) (xy 51.396892 -275.073142) (xy 51.381308 -275.119823) (xy 51.358437 -275.1634)
			(xy 51.328872 -275.202744) (xy 51.293379 -275.236836) (xy 51.252876 -275.264792) (xy 51.208414 -275.28589)
			(xy 51.161143 -275.299582) (xy 51.112288 -275.305514) (xy 51.063113 -275.303533) (xy 51.014894 -275.293689)
			(xy 50.968878 -275.276237) (xy 50.926257 -275.25163) (xy 50.888136 -275.220505) (xy 50.855501 -275.183668)
			(xy 50.829198 -275.142072) (xy 50.809907 -275.096796) (xy 50.79813 -275.049012) (xy 50.79417 -274.999958)
			(xy 49.505108 -274.999958) (xy 49.504613 -275.024565) (xy 49.496718 -275.073142) (xy 49.481134 -275.119823)
			(xy 49.458263 -275.1634) (xy 49.428698 -275.202744) (xy 49.393205 -275.236836) (xy 49.352702 -275.264792)
			(xy 49.30824 -275.28589) (xy 49.260969 -275.299582) (xy 49.212114 -275.305514) (xy 49.162939 -275.303533)
			(xy 49.11472 -275.293689) (xy 49.068704 -275.276237) (xy 49.026083 -275.25163) (xy 48.987962 -275.220505)
			(xy 48.955327 -275.183668) (xy 48.929024 -275.142072) (xy 48.909733 -275.096796) (xy 48.897956 -275.049012)
			(xy 48.893996 -274.999958) (xy 47.605188 -274.999958) (xy 47.604693 -275.024565) (xy 47.596798 -275.073142)
			(xy 47.581214 -275.119823) (xy 47.558343 -275.1634) (xy 47.528778 -275.202744) (xy 47.493285 -275.236836)
			(xy 47.452782 -275.264792) (xy 47.40832 -275.28589) (xy 47.361049 -275.299582) (xy 47.312194 -275.305514)
			(xy 47.263019 -275.303533) (xy 47.2148 -275.293689) (xy 47.168784 -275.276237) (xy 47.126163 -275.25163)
			(xy 47.088042 -275.220505) (xy 47.055407 -275.183668) (xy 47.029104 -275.142072) (xy 47.009813 -275.096796)
			(xy 46.998036 -275.049012) (xy 46.994076 -274.999958) (xy 45.705268 -274.999958) (xy 45.704773 -275.024565)
			(xy 45.696878 -275.073142) (xy 45.681294 -275.119823) (xy 45.658423 -275.1634) (xy 45.628858 -275.202744)
			(xy 45.593365 -275.236836) (xy 45.552862 -275.264792) (xy 45.5084 -275.28589) (xy 45.461129 -275.299582)
			(xy 45.412274 -275.305514) (xy 45.363099 -275.303533) (xy 45.31488 -275.293689) (xy 45.268864 -275.276237)
			(xy 45.226243 -275.25163) (xy 45.188122 -275.220505) (xy 45.155487 -275.183668) (xy 45.129184 -275.142072)
			(xy 45.109893 -275.096796) (xy 45.098116 -275.049012) (xy 45.094156 -274.999958) (xy 39.923212 -274.999958)
			(xy 39.923212 -275.474938) (xy 40.819082 -275.474938) (xy 40.823042 -275.425884) (xy 40.834819 -275.3781)
			(xy 40.85411 -275.332824) (xy 40.880413 -275.291228) (xy 40.913048 -275.254391) (xy 40.951169 -275.223266)
			(xy 40.99379 -275.198659) (xy 41.039806 -275.181207) (xy 41.088025 -275.171363) (xy 41.1372 -275.169382)
			(xy 41.186055 -275.175314) (xy 41.233326 -275.189006) (xy 41.277788 -275.210104) (xy 41.318291 -275.23806)
			(xy 41.353784 -275.272152) (xy 41.383349 -275.311496) (xy 41.40622 -275.355073) (xy 41.421804 -275.401754)
			(xy 41.429699 -275.450331) (xy 41.430194 -275.474938) (xy 42.719002 -275.474938) (xy 42.722962 -275.425884)
			(xy 42.734739 -275.3781) (xy 42.75403 -275.332824) (xy 42.780333 -275.291228) (xy 42.812968 -275.254391)
			(xy 42.851089 -275.223266) (xy 42.89371 -275.198659) (xy 42.939726 -275.181207) (xy 42.987945 -275.171363)
			(xy 43.03712 -275.169382) (xy 43.085975 -275.175314) (xy 43.133246 -275.189006) (xy 43.177708 -275.210104)
			(xy 43.218211 -275.23806) (xy 43.253704 -275.272152) (xy 43.283269 -275.311496) (xy 43.30614 -275.355073)
			(xy 43.321724 -275.401754) (xy 43.329619 -275.450331) (xy 43.330114 -275.474938) (xy 43.329619 -275.499545)
			(xy 43.321724 -275.548122) (xy 43.30614 -275.594803) (xy 43.283269 -275.63838) (xy 43.253704 -275.677724)
			(xy 43.218211 -275.711816) (xy 43.177708 -275.739772) (xy 43.133246 -275.76087) (xy 43.085975 -275.774562)
			(xy 43.03712 -275.780494) (xy 42.987945 -275.778513) (xy 42.939726 -275.768669) (xy 42.89371 -275.751217)
			(xy 42.851089 -275.72661) (xy 42.812968 -275.695485) (xy 42.780333 -275.658648) (xy 42.75403 -275.617052)
			(xy 42.734739 -275.571776) (xy 42.722962 -275.523992) (xy 42.719002 -275.474938) (xy 41.430194 -275.474938)
			(xy 41.429699 -275.499545) (xy 41.421804 -275.548122) (xy 41.40622 -275.594803) (xy 41.383349 -275.63838)
			(xy 41.353784 -275.677724) (xy 41.318291 -275.711816) (xy 41.277788 -275.739772) (xy 41.233326 -275.76087)
			(xy 41.186055 -275.774562) (xy 41.1372 -275.780494) (xy 41.088025 -275.778513) (xy 41.039806 -275.768669)
			(xy 40.99379 -275.751217) (xy 40.951169 -275.72661) (xy 40.913048 -275.695485) (xy 40.880413 -275.658648)
			(xy 40.85411 -275.617052) (xy 40.834819 -275.571776) (xy 40.823042 -275.523992) (xy 40.819082 -275.474938)
			(xy 39.923212 -275.474938) (xy 39.923212 -275.949918) (xy 45.094156 -275.949918) (xy 45.098116 -275.900864)
			(xy 45.109893 -275.85308) (xy 45.129184 -275.807804) (xy 45.155487 -275.766208) (xy 45.188122 -275.729371)
			(xy 45.226243 -275.698246) (xy 45.268864 -275.673639) (xy 45.31488 -275.656187) (xy 45.363099 -275.646343)
			(xy 45.412274 -275.644362) (xy 45.461129 -275.650294) (xy 45.5084 -275.663986) (xy 45.552862 -275.685084)
			(xy 45.593365 -275.71304) (xy 45.628858 -275.747132) (xy 45.658423 -275.786476) (xy 45.681294 -275.830053)
			(xy 45.696878 -275.876734) (xy 45.704773 -275.925311) (xy 45.705268 -275.949918) (xy 46.994076 -275.949918)
			(xy 46.998036 -275.900864) (xy 47.009813 -275.85308) (xy 47.029104 -275.807804) (xy 47.055407 -275.766208)
			(xy 47.088042 -275.729371) (xy 47.126163 -275.698246) (xy 47.168784 -275.673639) (xy 47.2148 -275.656187)
			(xy 47.263019 -275.646343) (xy 47.312194 -275.644362) (xy 47.361049 -275.650294) (xy 47.40832 -275.663986)
			(xy 47.452782 -275.685084) (xy 47.493285 -275.71304) (xy 47.528778 -275.747132) (xy 47.558343 -275.786476)
			(xy 47.581214 -275.830053) (xy 47.596798 -275.876734) (xy 47.604693 -275.925311) (xy 47.605188 -275.949918)
			(xy 48.893996 -275.949918) (xy 48.897956 -275.900864) (xy 48.909733 -275.85308) (xy 48.929024 -275.807804)
			(xy 48.955327 -275.766208) (xy 48.987962 -275.729371) (xy 49.026083 -275.698246) (xy 49.068704 -275.673639)
			(xy 49.11472 -275.656187) (xy 49.162939 -275.646343) (xy 49.212114 -275.644362) (xy 49.260969 -275.650294)
			(xy 49.30824 -275.663986) (xy 49.352702 -275.685084) (xy 49.393205 -275.71304) (xy 49.428698 -275.747132)
			(xy 49.458263 -275.786476) (xy 49.481134 -275.830053) (xy 49.496718 -275.876734) (xy 49.504613 -275.925311)
			(xy 49.505108 -275.949918) (xy 50.79417 -275.949918) (xy 50.79813 -275.900864) (xy 50.809907 -275.85308)
			(xy 50.829198 -275.807804) (xy 50.855501 -275.766208) (xy 50.888136 -275.729371) (xy 50.926257 -275.698246)
			(xy 50.968878 -275.673639) (xy 51.014894 -275.656187) (xy 51.063113 -275.646343) (xy 51.112288 -275.644362)
			(xy 51.161143 -275.650294) (xy 51.208414 -275.663986) (xy 51.252876 -275.685084) (xy 51.293379 -275.71304)
			(xy 51.328872 -275.747132) (xy 51.358437 -275.786476) (xy 51.381308 -275.830053) (xy 51.396892 -275.876734)
			(xy 51.404787 -275.925311) (xy 51.405282 -275.949918) (xy 52.69409 -275.949918) (xy 52.69805 -275.900864)
			(xy 52.709827 -275.85308) (xy 52.729118 -275.807804) (xy 52.755421 -275.766208) (xy 52.788056 -275.729371)
			(xy 52.826177 -275.698246) (xy 52.868798 -275.673639) (xy 52.914814 -275.656187) (xy 52.963033 -275.646343)
			(xy 53.012208 -275.644362) (xy 53.061063 -275.650294) (xy 53.108334 -275.663986) (xy 53.152796 -275.685084)
			(xy 53.193299 -275.71304) (xy 53.228792 -275.747132) (xy 53.258357 -275.786476) (xy 53.281228 -275.830053)
			(xy 53.296812 -275.876734) (xy 53.304707 -275.925311) (xy 53.305202 -275.949918) (xy 54.59401 -275.949918)
			(xy 54.59797 -275.900864) (xy 54.609747 -275.85308) (xy 54.629038 -275.807804) (xy 54.655341 -275.766208)
			(xy 54.687976 -275.729371) (xy 54.726097 -275.698246) (xy 54.768718 -275.673639) (xy 54.814734 -275.656187)
			(xy 54.862953 -275.646343) (xy 54.912128 -275.644362) (xy 54.960983 -275.650294) (xy 55.008254 -275.663986)
			(xy 55.052716 -275.685084) (xy 55.093219 -275.71304) (xy 55.128712 -275.747132) (xy 55.158277 -275.786476)
			(xy 55.181148 -275.830053) (xy 55.196732 -275.876734) (xy 55.204627 -275.925311) (xy 55.205122 -275.949918)
			(xy 56.494184 -275.949918) (xy 56.498144 -275.900864) (xy 56.509921 -275.85308) (xy 56.529212 -275.807804)
			(xy 56.555515 -275.766208) (xy 56.58815 -275.729371) (xy 56.626271 -275.698246) (xy 56.668892 -275.673639)
			(xy 56.714908 -275.656187) (xy 56.763127 -275.646343) (xy 56.812302 -275.644362) (xy 56.861157 -275.650294)
			(xy 56.908428 -275.663986) (xy 56.95289 -275.685084) (xy 56.993393 -275.71304) (xy 57.028886 -275.747132)
			(xy 57.058451 -275.786476) (xy 57.081322 -275.830053) (xy 57.096906 -275.876734) (xy 57.104801 -275.925311)
			(xy 57.105296 -275.949918) (xy 57.104801 -275.974525) (xy 57.096906 -276.023102) (xy 57.081322 -276.069783)
			(xy 57.058451 -276.11336) (xy 57.028886 -276.152704) (xy 56.993393 -276.186796) (xy 56.95289 -276.214752)
			(xy 56.908428 -276.23585) (xy 56.861157 -276.249542) (xy 56.812302 -276.255474) (xy 56.763127 -276.253493)
			(xy 56.714908 -276.243649) (xy 56.668892 -276.226197) (xy 56.626271 -276.20159) (xy 56.58815 -276.170465)
			(xy 56.555515 -276.133628) (xy 56.529212 -276.092032) (xy 56.509921 -276.046756) (xy 56.498144 -275.998972)
			(xy 56.494184 -275.949918) (xy 55.205122 -275.949918) (xy 55.204627 -275.974525) (xy 55.196732 -276.023102)
			(xy 55.181148 -276.069783) (xy 55.158277 -276.11336) (xy 55.128712 -276.152704) (xy 55.093219 -276.186796)
			(xy 55.052716 -276.214752) (xy 55.008254 -276.23585) (xy 54.960983 -276.249542) (xy 54.912128 -276.255474)
			(xy 54.862953 -276.253493) (xy 54.814734 -276.243649) (xy 54.768718 -276.226197) (xy 54.726097 -276.20159)
			(xy 54.687976 -276.170465) (xy 54.655341 -276.133628) (xy 54.629038 -276.092032) (xy 54.609747 -276.046756)
			(xy 54.59797 -275.998972) (xy 54.59401 -275.949918) (xy 53.305202 -275.949918) (xy 53.304707 -275.974525)
			(xy 53.296812 -276.023102) (xy 53.281228 -276.069783) (xy 53.258357 -276.11336) (xy 53.228792 -276.152704)
			(xy 53.193299 -276.186796) (xy 53.152796 -276.214752) (xy 53.108334 -276.23585) (xy 53.061063 -276.249542)
			(xy 53.012208 -276.255474) (xy 52.963033 -276.253493) (xy 52.914814 -276.243649) (xy 52.868798 -276.226197)
			(xy 52.826177 -276.20159) (xy 52.788056 -276.170465) (xy 52.755421 -276.133628) (xy 52.729118 -276.092032)
			(xy 52.709827 -276.046756) (xy 52.69805 -275.998972) (xy 52.69409 -275.949918) (xy 51.405282 -275.949918)
			(xy 51.404787 -275.974525) (xy 51.396892 -276.023102) (xy 51.381308 -276.069783) (xy 51.358437 -276.11336)
			(xy 51.328872 -276.152704) (xy 51.293379 -276.186796) (xy 51.252876 -276.214752) (xy 51.208414 -276.23585)
			(xy 51.161143 -276.249542) (xy 51.112288 -276.255474) (xy 51.063113 -276.253493) (xy 51.014894 -276.243649)
			(xy 50.968878 -276.226197) (xy 50.926257 -276.20159) (xy 50.888136 -276.170465) (xy 50.855501 -276.133628)
			(xy 50.829198 -276.092032) (xy 50.809907 -276.046756) (xy 50.79813 -275.998972) (xy 50.79417 -275.949918)
			(xy 49.505108 -275.949918) (xy 49.504613 -275.974525) (xy 49.496718 -276.023102) (xy 49.481134 -276.069783)
			(xy 49.458263 -276.11336) (xy 49.428698 -276.152704) (xy 49.393205 -276.186796) (xy 49.352702 -276.214752)
			(xy 49.30824 -276.23585) (xy 49.260969 -276.249542) (xy 49.212114 -276.255474) (xy 49.162939 -276.253493)
			(xy 49.11472 -276.243649) (xy 49.068704 -276.226197) (xy 49.026083 -276.20159) (xy 48.987962 -276.170465)
			(xy 48.955327 -276.133628) (xy 48.929024 -276.092032) (xy 48.909733 -276.046756) (xy 48.897956 -275.998972)
			(xy 48.893996 -275.949918) (xy 47.605188 -275.949918) (xy 47.604693 -275.974525) (xy 47.596798 -276.023102)
			(xy 47.581214 -276.069783) (xy 47.558343 -276.11336) (xy 47.528778 -276.152704) (xy 47.493285 -276.186796)
			(xy 47.452782 -276.214752) (xy 47.40832 -276.23585) (xy 47.361049 -276.249542) (xy 47.312194 -276.255474)
			(xy 47.263019 -276.253493) (xy 47.2148 -276.243649) (xy 47.168784 -276.226197) (xy 47.126163 -276.20159)
			(xy 47.088042 -276.170465) (xy 47.055407 -276.133628) (xy 47.029104 -276.092032) (xy 47.009813 -276.046756)
			(xy 46.998036 -275.998972) (xy 46.994076 -275.949918) (xy 45.705268 -275.949918) (xy 45.704773 -275.974525)
			(xy 45.696878 -276.023102) (xy 45.681294 -276.069783) (xy 45.658423 -276.11336) (xy 45.628858 -276.152704)
			(xy 45.593365 -276.186796) (xy 45.552862 -276.214752) (xy 45.5084 -276.23585) (xy 45.461129 -276.249542)
			(xy 45.412274 -276.255474) (xy 45.363099 -276.253493) (xy 45.31488 -276.243649) (xy 45.268864 -276.226197)
			(xy 45.226243 -276.20159) (xy 45.188122 -276.170465) (xy 45.155487 -276.133628) (xy 45.129184 -276.092032)
			(xy 45.109893 -276.046756) (xy 45.098116 -275.998972) (xy 45.094156 -275.949918) (xy 39.923212 -275.949918)
			(xy 39.923212 -276.638512) (xy 39.923638 -276.648581) (xy 39.931356 -276.667181) (xy 39.938198 -276.67458)
			(xy 40.068246 -276.804628) (xy 40.075643 -276.811475) (xy 40.094243 -276.819204) (xy 40.104314 -276.819614)
			(xy 43.157648 -276.819614)
		)
		(stroke
			(width 0)
			(type solid)
		)
		(fill yes)
		(layer "In5.Cu")
		(net "GND")
	)
	(gr_poly
		(pts
			(xy 331.283818 -331.128116) (xy 331.293468 -331.132029) (xy 331.314264 -331.13254) (xy 331.333551 -331.124746)
			(xy 331.341222 -331.117702) (xy 331.473302 -330.985622) (xy 331.480136 -330.978219) (xy 331.487841 -330.959621)
			(xy 331.488288 -330.949554) (xy 331.488288 -329.921362) (xy 331.487858 -329.911295) (xy 331.480132 -329.892702)
			(xy 331.473302 -329.885294) (xy 330.955904 -329.367896) (xy 330.937874 -329.349124) (xy 330.907298 -329.307006)
			(xy 330.883676 -329.26063) (xy 330.867587 -329.211133) (xy 330.859426 -329.159731) (xy 330.858876 -329.133708)
			(xy 330.858876 -327.353168) (xy 330.858711 -327.347014) (xy 330.855765 -327.335063) (xy 330.853034 -327.329546)
			(xy 330.839202 -327.302017) (xy 330.819631 -327.243603) (xy 330.809709 -327.182802) (xy 330.809092 -327.152)
			(xy 330.809578 -327.124749) (xy 330.817334 -327.070801) (xy 330.832689 -327.018506) (xy 330.855331 -326.968929)
			(xy 330.884797 -326.923079) (xy 330.920488 -326.881888) (xy 330.961679 -326.846197) (xy 331.007529 -326.816731)
			(xy 331.057106 -326.794089) (xy 331.109401 -326.778734) (xy 331.163349 -326.770978) (xy 331.1906 -326.770492)
			(xy 331.191108 -326.770492) (xy 331.217622 -326.770962) (xy 331.270137 -326.778335) (xy 331.321124 -326.79291)
			(xy 331.34554 -326.803258) (xy 331.357478 -326.808592) (xy 331.382878 -326.80656) (xy 331.465174 -326.752966)
			(xy 331.472105 -326.748104) (xy 331.482521 -326.734767) (xy 331.487995 -326.718756) (xy 331.488288 -326.710294)
			(xy 331.488288 -281.149552) (xy 331.487791 -281.139552) (xy 331.480123 -281.121078) (xy 331.465971 -281.106943)
			(xy 331.447489 -281.099297) (xy 331.437488 -281.098752) (xy 329.17384 -281.098752) (xy 329.163776 -281.099188)
			(xy 329.145192 -281.106923) (xy 329.137772 -281.113738) (xy 324.516235 -285.735522) (xy 328.755502 -285.735522)
			(xy 328.755917 -285.708786) (xy 328.763382 -285.655838) (xy 328.778169 -285.604451) (xy 328.799988 -285.555633)
			(xy 328.828411 -285.510341) (xy 328.862881 -285.469463) (xy 328.882502 -285.451296) (xy 328.882756 -285.451042)
			(xy 328.890125 -285.443787) (xy 328.898786 -285.425034) (xy 328.89952 -285.41472) (xy 328.901806 -285.34106)
			(xy 328.901563 -285.330666) (xy 328.893839 -285.31139) (xy 328.88682 -285.303722) (xy 328.866067 -285.282129)
			(xy 328.830894 -285.23366) (xy 328.803731 -285.180287) (xy 328.785246 -285.123324) (xy 328.775895 -285.064172)
			(xy 328.775314 -285.034228) (xy 328.7758 -285.006977) (xy 328.783556 -284.953029) (xy 328.798911 -284.900734)
			(xy 328.821553 -284.851157) (xy 328.851019 -284.805307) (xy 328.88671 -284.764116) (xy 328.927901 -284.728425)
			(xy 328.973751 -284.698959) (xy 329.023328 -284.676317) (xy 329.075623 -284.660962) (xy 329.129571 -284.653206)
			(xy 329.184073 -284.653206) (xy 329.238021 -284.660962) (xy 329.290316 -284.676317) (xy 329.339893 -284.698959)
			(xy 329.385743 -284.728425) (xy 329.426934 -284.764116) (xy 329.462625 -284.805307) (xy 329.492091 -284.851157)
			(xy 329.514733 -284.900734) (xy 329.530088 -284.953029) (xy 329.537844 -285.006977) (xy 329.53833 -285.034228)
			(xy 329.537871 -285.060962) (xy 329.530414 -285.113908) (xy 329.515635 -285.165294) (xy 329.493824 -285.214111)
			(xy 329.465409 -285.259405) (xy 329.430947 -285.300285) (xy 329.41133 -285.318454) (xy 329.411076 -285.318708)
			(xy 329.403718 -285.325972) (xy 329.395053 -285.344718) (xy 329.394312 -285.35503) (xy 329.392026 -285.42869)
			(xy 329.392261 -285.439084) (xy 329.399993 -285.458359) (xy 329.407012 -285.466028) (xy 329.427747 -285.487637)
			(xy 329.462921 -285.536103) (xy 329.490087 -285.589472) (xy 329.508576 -285.646431) (xy 329.517934 -285.70558)
			(xy 329.518518 -285.735522) (xy 329.518032 -285.762773) (xy 329.510276 -285.816721) (xy 329.494921 -285.869016)
			(xy 329.472279 -285.918593) (xy 329.442813 -285.964443) (xy 329.407122 -286.005634) (xy 329.365931 -286.041325)
			(xy 329.320081 -286.070791) (xy 329.270504 -286.093433) (xy 329.218209 -286.108788) (xy 329.164261 -286.116544)
			(xy 329.109759 -286.116544) (xy 329.055811 -286.108788) (xy 329.003516 -286.093433) (xy 328.953939 -286.070791)
			(xy 328.908089 -286.041325) (xy 328.866898 -286.005634) (xy 328.831207 -285.964443) (xy 328.801741 -285.918593)
			(xy 328.779099 -285.869016) (xy 328.763744 -285.816721) (xy 328.755988 -285.762773) (xy 328.755502 -285.735522)
			(xy 324.516235 -285.735522) (xy 324.391782 -285.859982) (xy 324.369064 -285.881999) (xy 324.31887 -285.92051)
			(xy 324.264077 -285.952137) (xy 324.205624 -285.976339) (xy 324.144511 -285.992701) (xy 324.081785 -286.000943)
			(xy 324.050152 -286.00146) (xy 324.022285 -286.001047) (xy 323.966925 -285.994601) (xy 323.912673 -285.981834)
			(xy 323.886322 -285.972758) (xy 323.886068 -285.972758) (xy 323.876882 -285.969931) (xy 323.857688 -285.970579)
			(xy 323.840057 -285.978193) (xy 323.832982 -285.984696) (xy 323.812408 -286.00527) (xy 323.805011 -286.012121)
			(xy 323.786413 -286.019863) (xy 323.77634 -286.020256) (xy 322.604892 -286.020256) (xy 322.595102 -286.020696)
			(xy 322.576936 -286.028001) (xy 322.569586 -286.03448) (xy 320.626994 -287.91027) (xy 320.604833 -287.931316)
			(xy 320.558318 -287.970968) (xy 320.53403 -287.989518) (xy 320.524986 -287.997084) (xy 320.514437 -288.018142)
			(xy 320.514352 -288.041694) (xy 320.519044 -288.05251) (xy 320.532963 -288.082303) (xy 320.55148 -288.145396)
			(xy 320.555874 -288.177986) (xy 320.556382 -288.18078) (xy 320.558603 -288.190786) (xy 320.569724 -288.207981)
			(xy 320.586672 -288.219476) (xy 320.606761 -288.223449) (xy 320.626809 -288.219272) (xy 320.643639 -288.207606)
			(xy 320.654586 -288.190299) (xy 320.656712 -288.180272) (xy 320.656966 -288.177986) (xy 320.660621 -288.150418)
			(xy 320.674886 -288.096669) (xy 320.696801 -288.04556) (xy 320.725902 -287.998173) (xy 320.761573 -287.955512)
			(xy 320.803058 -287.91848) (xy 320.849479 -287.887861) (xy 320.899853 -287.864305) (xy 320.953113 -287.84831)
			(xy 321.00813 -287.840214) (xy 321.035934 -287.839658) (xy 321.063186 -287.840146) (xy 321.117135 -287.847907)
			(xy 321.16943 -287.863267) (xy 321.219008 -287.885912) (xy 321.264858 -287.915382) (xy 321.306048 -287.951076)
			(xy 321.341739 -287.992269) (xy 321.371204 -288.038122) (xy 321.393845 -288.087702) (xy 321.4092 -288.139998)
			(xy 321.416956 -288.193948) (xy 321.416956 -288.221166) (xy 321.669916 -288.221166) (xy 321.673987 -288.165544)
			(xy 321.686113 -288.111107) (xy 321.706036 -288.059016) (xy 321.733332 -288.010381) (xy 321.767418 -287.966238)
			(xy 321.807567 -287.927529) (xy 321.852925 -287.895078) (xy 321.902525 -287.869577) (xy 321.955309 -287.85157)
			(xy 322.010152 -287.84144) (xy 322.065886 -287.839403) (xy 322.121323 -287.845503) (xy 322.17528 -287.859609)
			(xy 322.226609 -287.881421) (xy 322.274215 -287.910475) (xy 322.317083 -287.94615) (xy 322.3543 -287.987687)
			(xy 322.385073 -288.0342) (xy 322.408745 -288.084697) (xy 322.424813 -288.138104) (xy 322.432933 -288.19328)
			(xy 322.433442 -288.221166) (xy 322.685916 -288.221166) (xy 322.689987 -288.165544) (xy 322.702113 -288.111107)
			(xy 322.722036 -288.059016) (xy 322.749332 -288.010381) (xy 322.783418 -287.966238) (xy 322.823567 -287.927529)
			(xy 322.868925 -287.895078) (xy 322.918525 -287.869577) (xy 322.971309 -287.85157) (xy 323.026152 -287.84144)
			(xy 323.081886 -287.839403) (xy 323.137323 -287.845503) (xy 323.19128 -287.859609) (xy 323.242609 -287.881421)
			(xy 323.290215 -287.910475) (xy 323.333083 -287.94615) (xy 323.3703 -287.987687) (xy 323.401073 -288.0342)
			(xy 323.424745 -288.084697) (xy 323.440813 -288.138104) (xy 323.448933 -288.19328) (xy 323.449442 -288.221166)
			(xy 323.669658 -288.221166) (xy 323.673729 -288.165544) (xy 323.685855 -288.111107) (xy 323.705778 -288.059016)
			(xy 323.733074 -288.010381) (xy 323.76716 -287.966238) (xy 323.807309 -287.927529) (xy 323.852667 -287.895078)
			(xy 323.902267 -287.869577) (xy 323.955051 -287.85157) (xy 324.009894 -287.84144) (xy 324.065628 -287.839403)
			(xy 324.121065 -287.845503) (xy 324.175022 -287.859609) (xy 324.226351 -287.881421) (xy 324.273957 -287.910475)
			(xy 324.316825 -287.94615) (xy 324.354042 -287.987687) (xy 324.384815 -288.0342) (xy 324.408487 -288.084697)
			(xy 324.424555 -288.138104) (xy 324.432675 -288.19328) (xy 324.433184 -288.221166) (xy 324.432675 -288.249052)
			(xy 324.424555 -288.304228) (xy 324.408487 -288.357635) (xy 324.384815 -288.408132) (xy 324.354042 -288.454645)
			(xy 324.316825 -288.496182) (xy 324.273957 -288.531857) (xy 324.226351 -288.560911) (xy 324.175022 -288.582723)
			(xy 324.121065 -288.596829) (xy 324.065628 -288.602929) (xy 324.009894 -288.600892) (xy 323.955051 -288.590762)
			(xy 323.902267 -288.572755) (xy 323.852667 -288.547254) (xy 323.807309 -288.514803) (xy 323.76716 -288.476094)
			(xy 323.733074 -288.431951) (xy 323.705778 -288.383316) (xy 323.685855 -288.331225) (xy 323.673729 -288.276788)
			(xy 323.669658 -288.221166) (xy 323.449442 -288.221166) (xy 323.448933 -288.249052) (xy 323.440813 -288.304228)
			(xy 323.424745 -288.357635) (xy 323.401073 -288.408132) (xy 323.3703 -288.454645) (xy 323.333083 -288.496182)
			(xy 323.290215 -288.531857) (xy 323.242609 -288.560911) (xy 323.19128 -288.582723) (xy 323.137323 -288.596829)
			(xy 323.081886 -288.602929) (xy 323.026152 -288.600892) (xy 322.971309 -288.590762) (xy 322.918525 -288.572755)
			(xy 322.868925 -288.547254) (xy 322.823567 -288.514803) (xy 322.783418 -288.476094) (xy 322.749332 -288.431951)
			(xy 322.722036 -288.383316) (xy 322.702113 -288.331225) (xy 322.689987 -288.276788) (xy 322.685916 -288.221166)
			(xy 322.433442 -288.221166) (xy 322.432933 -288.249052) (xy 322.424813 -288.304228) (xy 322.408745 -288.357635)
			(xy 322.385073 -288.408132) (xy 322.3543 -288.454645) (xy 322.317083 -288.496182) (xy 322.274215 -288.531857)
			(xy 322.226609 -288.560911) (xy 322.17528 -288.582723) (xy 322.121323 -288.596829) (xy 322.065886 -288.602929)
			(xy 322.010152 -288.600892) (xy 321.955309 -288.590762) (xy 321.902525 -288.572755) (xy 321.852925 -288.547254)
			(xy 321.807567 -288.514803) (xy 321.767418 -288.476094) (xy 321.733332 -288.431951) (xy 321.706036 -288.383316)
			(xy 321.686113 -288.331225) (xy 321.673987 -288.276788) (xy 321.669916 -288.221166) (xy 321.416956 -288.221166)
			(xy 321.416956 -288.248452) (xy 321.4092 -288.302402) (xy 321.393845 -288.354698) (xy 321.371204 -288.404278)
			(xy 321.341739 -288.450131) (xy 321.306048 -288.491324) (xy 321.264858 -288.527018) (xy 321.219008 -288.556488)
			(xy 321.16943 -288.579133) (xy 321.117135 -288.594493) (xy 321.063186 -288.602254) (xy 321.035934 -288.602674)
			(xy 321.009815 -288.602247) (xy 320.958065 -288.595122) (xy 320.907773 -288.581001) (xy 320.859878 -288.560147)
			(xy 320.815277 -288.532952) (xy 320.774806 -288.499924) (xy 320.739221 -288.461681) (xy 320.709189 -288.418939)
			(xy 320.696844 -288.395918) (xy 320.692226 -288.387812) (xy 320.678357 -288.375357) (xy 320.660952 -288.368682)
			(xy 320.651632 -288.368232) (xy 320.561208 -288.368232) (xy 320.551882 -288.368647) (xy 320.534467 -288.375325)
			(xy 320.520598 -288.387796) (xy 320.515996 -288.395918) (xy 320.50365 -288.418938) (xy 320.47361 -288.461672)
			(xy 320.438021 -288.49991) (xy 320.397549 -288.532935) (xy 320.35295 -288.560131) (xy 320.305059 -288.58099)
			(xy 320.25477 -288.595121) (xy 320.203024 -288.602261) (xy 320.176906 -288.602674) (xy 320.148442 -288.602149)
			(xy 320.092144 -288.593696) (xy 320.037726 -288.576977) (xy 319.986393 -288.552363) (xy 319.939285 -288.520399)
			(xy 319.897446 -288.481795) (xy 319.879218 -288.459926) (xy 319.86728 -288.44494) (xy 319.82918 -288.438336)
			(xy 319.240916 -288.80943) (xy 319.206293 -288.830766) (xy 325.352916 -288.830766) (xy 325.356987 -288.775144)
			(xy 325.369113 -288.720707) (xy 325.389036 -288.668616) (xy 325.416332 -288.619981) (xy 325.450418 -288.575838)
			(xy 325.490567 -288.537129) (xy 325.535925 -288.504678) (xy 325.585525 -288.479177) (xy 325.638309 -288.46117)
			(xy 325.693152 -288.45104) (xy 325.748886 -288.449003) (xy 325.804323 -288.455103) (xy 325.85828 -288.469209)
			(xy 325.909609 -288.491021) (xy 325.957215 -288.520075) (xy 326.000083 -288.55575) (xy 326.0373 -288.597287)
			(xy 326.068073 -288.6438) (xy 326.091745 -288.694297) (xy 326.107813 -288.747704) (xy 326.115933 -288.80288)
			(xy 326.116442 -288.830766) (xy 326.115933 -288.858652) (xy 326.107813 -288.913828) (xy 326.091745 -288.967235)
			(xy 326.068073 -289.017732) (xy 326.0373 -289.064245) (xy 326.000083 -289.105782) (xy 325.957215 -289.141457)
			(xy 325.909609 -289.170511) (xy 325.85828 -289.192323) (xy 325.804323 -289.206429) (xy 325.748886 -289.212529)
			(xy 325.693152 -289.210492) (xy 325.638309 -289.200362) (xy 325.585525 -289.182355) (xy 325.535925 -289.156854)
			(xy 325.490567 -289.124403) (xy 325.450418 -289.085694) (xy 325.416332 -289.041551) (xy 325.389036 -288.992916)
			(xy 325.369113 -288.940825) (xy 325.356987 -288.886388) (xy 325.352916 -288.830766) (xy 319.206293 -288.830766)
			(xy 319.204205 -288.832053) (xy 319.127568 -288.871599) (xy 319.0478 -288.904373) (xy 318.965497 -288.93013)
			(xy 318.881276 -288.948677) (xy 318.83858 -288.954718) (xy 318.828928 -288.955988) (xy 318.812418 -288.965132)
			(xy 318.761872 -289.026092) (xy 318.7561 -289.033772) (xy 318.75022 -289.052048) (xy 318.750442 -289.061652)
			(xy 318.751204 -289.08502) (xy 318.750718 -289.112271) (xy 318.742962 -289.166219) (xy 318.727607 -289.218514)
			(xy 318.704965 -289.268091) (xy 318.675499 -289.313941) (xy 318.639808 -289.355132) (xy 318.598617 -289.390823)
			(xy 318.552767 -289.420289) (xy 318.50319 -289.442931) (xy 318.450895 -289.458286) (xy 318.396947 -289.466042)
			(xy 318.342445 -289.466042) (xy 318.288497 -289.458286) (xy 318.236202 -289.442931) (xy 318.186625 -289.420289)
			(xy 318.140775 -289.390823) (xy 318.099584 -289.355132) (xy 318.063893 -289.313941) (xy 318.034427 -289.268091)
			(xy 318.011785 -289.218514) (xy 317.99643 -289.166219) (xy 317.988674 -289.112271) (xy 317.988188 -289.08502)
			(xy 317.988442 -289.069018) (xy 317.98895 -289.058604) (xy 317.981838 -289.0393) (xy 317.923672 -288.978848)
			(xy 317.916247 -288.971729) (xy 317.89737 -288.963606) (xy 317.887096 -288.9631) (xy 316.123828 -288.9631)
			(xy 316.061852 -288.961068) (xy 316.0495 -288.960908) (xy 316.026992 -288.971018) (xy 316.018926 -288.980372)
			(xy 316.003154 -288.999546) (xy 315.96684 -289.033399) (xy 315.925875 -289.061447) (xy 315.881179 -289.083059)
			(xy 315.833755 -289.097749) (xy 315.784669 -289.105189) (xy 315.759846 -289.105594) (xy 315.759338 -289.105594)
			(xy 315.744068 -289.105358) (xy 315.713667 -289.102433) (xy 315.698632 -289.099752) (xy 315.693298 -289.09899)
			(xy 315.68302 -289.098569) (xy 315.663487 -289.104958) (xy 315.648022 -289.118493) (xy 315.6391 -289.137006)
			(xy 315.63818 -289.14725) (xy 315.63818 -289.199828) (xy 315.641736 -289.20313) (xy 315.641736 -290.278312)
			(xy 317.353694 -290.278312) (xy 317.357765 -290.22269) (xy 317.369891 -290.168253) (xy 317.389814 -290.116162)
			(xy 317.41711 -290.067527) (xy 317.451196 -290.023384) (xy 317.491345 -289.984675) (xy 317.536703 -289.952224)
			(xy 317.586303 -289.926723) (xy 317.639087 -289.908716) (xy 317.69393 -289.898586) (xy 317.749664 -289.896549)
			(xy 317.805101 -289.902649) (xy 317.859058 -289.916755) (xy 317.910387 -289.938567) (xy 317.957993 -289.967621)
			(xy 318.000861 -290.003296) (xy 318.038078 -290.044833) (xy 318.068851 -290.091346) (xy 318.092523 -290.141843)
			(xy 318.108591 -290.19525) (xy 318.114759 -290.237164) (xy 321.364354 -290.237164) (xy 321.368425 -290.181542)
			(xy 321.380551 -290.127105) (xy 321.400474 -290.075014) (xy 321.42777 -290.026379) (xy 321.461856 -289.982236)
			(xy 321.502005 -289.943527) (xy 321.547363 -289.911076) (xy 321.596963 -289.885575) (xy 321.649747 -289.867568)
			(xy 321.70459 -289.857438) (xy 321.760324 -289.855401) (xy 321.815761 -289.861501) (xy 321.869718 -289.875607)
			(xy 321.921047 -289.897419) (xy 321.968653 -289.926473) (xy 322.011521 -289.962148) (xy 322.048738 -290.003685)
			(xy 322.079511 -290.050198) (xy 322.103183 -290.100695) (xy 322.119251 -290.154102) (xy 322.127371 -290.209278)
			(xy 322.12788 -290.237164) (xy 322.127371 -290.26505) (xy 322.119251 -290.320226) (xy 322.103183 -290.373633)
			(xy 322.079511 -290.42413) (xy 322.048738 -290.470643) (xy 322.011521 -290.51218) (xy 321.968653 -290.547855)
			(xy 321.921047 -290.576909) (xy 321.869718 -290.598721) (xy 321.815761 -290.612827) (xy 321.760324 -290.618927)
			(xy 321.70459 -290.61689) (xy 321.649747 -290.60676) (xy 321.596963 -290.588753) (xy 321.547363 -290.563252)
			(xy 321.502005 -290.530801) (xy 321.461856 -290.492092) (xy 321.42777 -290.447949) (xy 321.400474 -290.399314)
			(xy 321.380551 -290.347223) (xy 321.368425 -290.292786) (xy 321.364354 -290.237164) (xy 318.114759 -290.237164)
			(xy 318.116711 -290.250426) (xy 318.11722 -290.278312) (xy 318.116711 -290.306198) (xy 318.108591 -290.361374)
			(xy 318.092523 -290.414781) (xy 318.068851 -290.465278) (xy 318.038078 -290.511791) (xy 318.000861 -290.553328)
			(xy 317.957993 -290.589003) (xy 317.910387 -290.618057) (xy 317.859058 -290.639869) (xy 317.805101 -290.653975)
			(xy 317.749664 -290.660075) (xy 317.69393 -290.658038) (xy 317.639087 -290.647908) (xy 317.586303 -290.629901)
			(xy 317.536703 -290.6044) (xy 317.491345 -290.571949) (xy 317.451196 -290.53324) (xy 317.41711 -290.489097)
			(xy 317.389814 -290.440462) (xy 317.369891 -290.388371) (xy 317.357765 -290.333934) (xy 317.353694 -290.278312)
			(xy 315.641736 -290.278312) (xy 315.641736 -291.2364) (xy 318.184782 -291.2364) (xy 318.188853 -291.180778)
			(xy 318.200979 -291.126341) (xy 318.220902 -291.07425) (xy 318.248198 -291.025615) (xy 318.282284 -290.981472)
			(xy 318.322433 -290.942763) (xy 318.367791 -290.910312) (xy 318.417391 -290.884811) (xy 318.470175 -290.866804)
			(xy 318.525018 -290.856674) (xy 318.580752 -290.854637) (xy 318.636189 -290.860737) (xy 318.690146 -290.874843)
			(xy 318.741475 -290.896655) (xy 318.789081 -290.925709) (xy 318.831949 -290.961384) (xy 318.869166 -291.002921)
			(xy 318.899939 -291.049434) (xy 318.923611 -291.099931) (xy 318.939679 -291.153338) (xy 318.947799 -291.208514)
			(xy 318.948308 -291.2364) (xy 318.947799 -291.264286) (xy 318.939679 -291.319462) (xy 318.923611 -291.372869)
			(xy 318.899939 -291.423366) (xy 318.869166 -291.469879) (xy 318.831949 -291.511416) (xy 318.789081 -291.547091)
			(xy 318.741475 -291.576145) (xy 318.690146 -291.597957) (xy 318.636189 -291.612063) (xy 318.580752 -291.618163)
			(xy 318.525018 -291.616126) (xy 318.470175 -291.605996) (xy 318.417391 -291.587989) (xy 318.367791 -291.562488)
			(xy 318.322433 -291.530037) (xy 318.282284 -291.491328) (xy 318.248198 -291.447185) (xy 318.220902 -291.39855)
			(xy 318.200979 -291.346459) (xy 318.188853 -291.292022) (xy 318.184782 -291.2364) (xy 315.641736 -291.2364)
			(xy 315.641736 -292.122098) (xy 325.456802 -292.122098) (xy 325.460873 -292.066476) (xy 325.472999 -292.012039)
			(xy 325.492922 -291.959948) (xy 325.520218 -291.911313) (xy 325.554304 -291.86717) (xy 325.594453 -291.828461)
			(xy 325.639811 -291.79601) (xy 325.689411 -291.770509) (xy 325.742195 -291.752502) (xy 325.797038 -291.742372)
			(xy 325.852772 -291.740335) (xy 325.908209 -291.746435) (xy 325.962166 -291.760541) (xy 326.013495 -291.782353)
			(xy 326.061101 -291.811407) (xy 326.103969 -291.847082) (xy 326.141186 -291.888619) (xy 326.171959 -291.935132)
			(xy 326.195631 -291.985629) (xy 326.211699 -292.039036) (xy 326.219819 -292.094212) (xy 326.220328 -292.122098)
			(xy 326.219819 -292.149984) (xy 326.211699 -292.20516) (xy 326.195631 -292.258567) (xy 326.171959 -292.309064)
			(xy 326.141186 -292.355577) (xy 326.103969 -292.397114) (xy 326.061101 -292.432789) (xy 326.013495 -292.461843)
			(xy 325.962166 -292.483655) (xy 325.908209 -292.497761) (xy 325.852772 -292.503861) (xy 325.797038 -292.501824)
			(xy 325.742195 -292.491694) (xy 325.689411 -292.473687) (xy 325.639811 -292.448186) (xy 325.594453 -292.415735)
			(xy 325.554304 -292.377026) (xy 325.520218 -292.332883) (xy 325.492922 -292.284248) (xy 325.472999 -292.232157)
			(xy 325.460873 -292.17772) (xy 325.456802 -292.122098) (xy 315.641736 -292.122098) (xy 315.641736 -293.49573)
			(xy 315.642165 -293.505797) (xy 315.649891 -293.52439) (xy 315.656722 -293.531798) (xy 316.141051 -294.016176)
			(xy 321.840604 -294.016176) (xy 321.844675 -293.960554) (xy 321.856801 -293.906117) (xy 321.876724 -293.854026)
			(xy 321.90402 -293.805391) (xy 321.938106 -293.761248) (xy 321.978255 -293.722539) (xy 322.023613 -293.690088)
			(xy 322.073213 -293.664587) (xy 322.125997 -293.64658) (xy 322.18084 -293.63645) (xy 322.236574 -293.634413)
			(xy 322.292011 -293.640513) (xy 322.345968 -293.654619) (xy 322.397297 -293.676431) (xy 322.444903 -293.705485)
			(xy 322.487771 -293.74116) (xy 322.524988 -293.782697) (xy 322.555761 -293.82921) (xy 322.579433 -293.879707)
			(xy 322.595501 -293.933114) (xy 322.602492 -293.980616) (xy 323.480682 -293.980616) (xy 323.484753 -293.924994)
			(xy 323.496879 -293.870557) (xy 323.516802 -293.818466) (xy 323.544098 -293.769831) (xy 323.578184 -293.725688)
			(xy 323.618333 -293.686979) (xy 323.663691 -293.654528) (xy 323.713291 -293.629027) (xy 323.766075 -293.61102)
			(xy 323.820918 -293.60089) (xy 323.876652 -293.598853) (xy 323.932089 -293.604953) (xy 323.986046 -293.619059)
			(xy 324.037375 -293.640871) (xy 324.084981 -293.669925) (xy 324.127849 -293.7056) (xy 324.165066 -293.747137)
			(xy 324.195839 -293.79365) (xy 324.219511 -293.844147) (xy 324.235579 -293.897554) (xy 324.243699 -293.95273)
			(xy 324.244208 -293.980616) (xy 324.243699 -294.008502) (xy 324.235579 -294.063678) (xy 324.219511 -294.117085)
			(xy 324.195839 -294.167582) (xy 324.165066 -294.214095) (xy 324.127849 -294.255632) (xy 324.084981 -294.291307)
			(xy 324.037375 -294.320361) (xy 323.986046 -294.342173) (xy 323.932089 -294.356279) (xy 323.876652 -294.362379)
			(xy 323.820918 -294.360342) (xy 323.766075 -294.350212) (xy 323.713291 -294.332205) (xy 323.663691 -294.306704)
			(xy 323.618333 -294.274253) (xy 323.578184 -294.235544) (xy 323.544098 -294.191401) (xy 323.516802 -294.142766)
			(xy 323.496879 -294.090675) (xy 323.484753 -294.036238) (xy 323.480682 -293.980616) (xy 322.602492 -293.980616)
			(xy 322.603621 -293.98829) (xy 322.60413 -294.016176) (xy 322.603621 -294.044062) (xy 322.595501 -294.099238)
			(xy 322.579433 -294.152645) (xy 322.555761 -294.203142) (xy 322.524988 -294.249655) (xy 322.487771 -294.291192)
			(xy 322.444903 -294.326867) (xy 322.397297 -294.355921) (xy 322.345968 -294.377733) (xy 322.292011 -294.391839)
			(xy 322.236574 -294.397939) (xy 322.18084 -294.395902) (xy 322.125997 -294.385772) (xy 322.073213 -294.367765)
			(xy 322.023613 -294.342264) (xy 321.978255 -294.309813) (xy 321.938106 -294.271104) (xy 321.90402 -294.226961)
			(xy 321.876724 -294.178326) (xy 321.856801 -294.126235) (xy 321.844675 -294.071798) (xy 321.840604 -294.016176)
			(xy 316.141051 -294.016176) (xy 318.154558 -296.029888) (xy 318.737742 -296.613072) (xy 321.462398 -296.613072)
			(xy 321.466469 -296.55745) (xy 321.478595 -296.503013) (xy 321.498518 -296.450922) (xy 321.525814 -296.402287)
			(xy 321.5599 -296.358144) (xy 321.600049 -296.319435) (xy 321.645407 -296.286984) (xy 321.695007 -296.261483)
			(xy 321.747791 -296.243476) (xy 321.802634 -296.233346) (xy 321.858368 -296.231309) (xy 321.913805 -296.237409)
			(xy 321.967762 -296.251515) (xy 322.019091 -296.273327) (xy 322.066697 -296.302381) (xy 322.109565 -296.338056)
			(xy 322.146782 -296.379593) (xy 322.177555 -296.426106) (xy 322.201227 -296.476603) (xy 322.217295 -296.53001)
			(xy 322.225415 -296.585186) (xy 322.225924 -296.613072) (xy 322.737224 -296.613072) (xy 322.741295 -296.55745)
			(xy 322.753421 -296.503013) (xy 322.773344 -296.450922) (xy 322.80064 -296.402287) (xy 322.834726 -296.358144)
			(xy 322.874875 -296.319435) (xy 322.920233 -296.286984) (xy 322.969833 -296.261483) (xy 323.022617 -296.243476)
			(xy 323.07746 -296.233346) (xy 323.133194 -296.231309) (xy 323.188631 -296.237409) (xy 323.242588 -296.251515)
			(xy 323.293917 -296.273327) (xy 323.341523 -296.302381) (xy 323.384391 -296.338056) (xy 323.421608 -296.379593)
			(xy 323.452381 -296.426106) (xy 323.476053 -296.476603) (xy 323.492121 -296.53001) (xy 323.500241 -296.585186)
			(xy 323.50075 -296.613072) (xy 323.500241 -296.640958) (xy 323.492121 -296.696134) (xy 323.476053 -296.749541)
			(xy 323.452381 -296.800038) (xy 323.421608 -296.846551) (xy 323.384391 -296.888088) (xy 323.341523 -296.923763)
			(xy 323.293917 -296.952817) (xy 323.242588 -296.974629) (xy 323.188631 -296.988735) (xy 323.133194 -296.994835)
			(xy 323.07746 -296.992798) (xy 323.022617 -296.982668) (xy 322.969833 -296.964661) (xy 322.920233 -296.93916)
			(xy 322.874875 -296.906709) (xy 322.834726 -296.868) (xy 322.80064 -296.823857) (xy 322.773344 -296.775222)
			(xy 322.753421 -296.723131) (xy 322.741295 -296.668694) (xy 322.737224 -296.613072) (xy 322.225924 -296.613072)
			(xy 322.225415 -296.640958) (xy 322.217295 -296.696134) (xy 322.201227 -296.749541) (xy 322.177555 -296.800038)
			(xy 322.146782 -296.846551) (xy 322.109565 -296.888088) (xy 322.066697 -296.923763) (xy 322.019091 -296.952817)
			(xy 321.967762 -296.974629) (xy 321.913805 -296.988735) (xy 321.858368 -296.994835) (xy 321.802634 -296.992798)
			(xy 321.747791 -296.982668) (xy 321.695007 -296.964661) (xy 321.645407 -296.93916) (xy 321.600049 -296.906709)
			(xy 321.5599 -296.868) (xy 321.525814 -296.823857) (xy 321.498518 -296.775222) (xy 321.478595 -296.723131)
			(xy 321.466469 -296.668694) (xy 321.462398 -296.613072) (xy 318.737742 -296.613072) (xy 319.499488 -297.374818)
			(xy 324.815706 -297.374818) (xy 324.819777 -297.319196) (xy 324.831903 -297.264759) (xy 324.851826 -297.212668)
			(xy 324.879122 -297.164033) (xy 324.913208 -297.11989) (xy 324.953357 -297.081181) (xy 324.998715 -297.04873)
			(xy 325.048315 -297.023229) (xy 325.101099 -297.005222) (xy 325.155942 -296.995092) (xy 325.211676 -296.993055)
			(xy 325.267113 -296.999155) (xy 325.32107 -297.013261) (xy 325.372399 -297.035073) (xy 325.420005 -297.064127)
			(xy 325.462873 -297.099802) (xy 325.50009 -297.141339) (xy 325.530863 -297.187852) (xy 325.554535 -297.238349)
			(xy 325.570603 -297.291756) (xy 325.578723 -297.346932) (xy 325.579232 -297.374818) (xy 325.578723 -297.402704)
			(xy 325.570603 -297.45788) (xy 325.554535 -297.511287) (xy 325.530863 -297.561784) (xy 325.50009 -297.608297)
			(xy 325.462873 -297.649834) (xy 325.420005 -297.685509) (xy 325.372399 -297.714563) (xy 325.32107 -297.736375)
			(xy 325.267113 -297.750481) (xy 325.211676 -297.756581) (xy 325.155942 -297.754544) (xy 325.101099 -297.744414)
			(xy 325.048315 -297.726407) (xy 324.998715 -297.700906) (xy 324.953357 -297.668455) (xy 324.913208 -297.629746)
			(xy 324.879122 -297.585603) (xy 324.851826 -297.536968) (xy 324.831903 -297.484877) (xy 324.819777 -297.43044)
			(xy 324.815706 -297.374818) (xy 319.499488 -297.374818) (xy 320.652648 -298.527978) (xy 320.660048 -298.534819)
			(xy 320.678646 -298.54254) (xy 320.688716 -298.542964) (xy 320.778378 -298.542964) (xy 320.802683 -298.543168)
			(xy 320.851134 -298.547107) (xy 320.875152 -298.550838) (xy 320.87947 -298.5516) (xy 324.802246 -298.5516)
			(xy 324.812312 -298.552032) (xy 324.830905 -298.559758) (xy 324.838314 -298.566586) (xy 325.73849 -299.466762)
			(xy 325.745328 -299.474163) (xy 325.753041 -299.492762) (xy 325.753476 -299.50283) (xy 325.753476 -300.699932)
			(xy 325.753735 -300.707343) (xy 325.758005 -300.721536) (xy 325.761858 -300.727872) (xy 325.780263 -300.756637)
			(xy 325.810987 -300.817628) (xy 325.834403 -300.881781) (xy 325.850193 -300.948223) (xy 325.858142 -301.016052)
			(xy 325.858632 -301.050198) (xy 325.858632 -301.050452) (xy 325.858121 -301.08542) (xy 325.849793 -301.154859)
			(xy 325.833261 -301.222813) (xy 325.808759 -301.288318) (xy 325.776637 -301.350441) (xy 325.737351 -301.4083)
			(xy 325.691458 -301.461073) (xy 325.639612 -301.50801) (xy 325.582549 -301.548444) (xy 325.552054 -301.565564)
			(xy 325.548877 -301.567354) (xy 325.543008 -301.571682) (xy 325.54037 -301.5742) (xy 324.721982 -302.392588)
			(xy 324.714583 -302.399433) (xy 324.695985 -302.407163) (xy 324.685914 -302.407574) (xy 320.725292 -302.407574)
			(xy 320.714933 -302.408115) (xy 320.695922 -302.416369) (xy 320.688462 -302.423576) (xy 320.637662 -302.477424)
			(xy 320.630917 -302.485338) (xy 320.623848 -302.504871) (xy 320.623946 -302.51527) (xy 320.624708 -302.538384)
			(xy 320.624222 -302.565635) (xy 320.616466 -302.619583) (xy 320.601111 -302.671878) (xy 320.578469 -302.721455)
			(xy 320.549003 -302.767305) (xy 320.513312 -302.808496) (xy 320.472121 -302.844187) (xy 320.426271 -302.873653)
			(xy 320.376694 -302.896295) (xy 320.324399 -302.91165) (xy 320.270451 -302.919406) (xy 320.215949 -302.919406)
			(xy 320.162001 -302.91165) (xy 320.109706 -302.896295) (xy 320.060129 -302.873653) (xy 320.014279 -302.844187)
			(xy 319.973088 -302.808496) (xy 319.937397 -302.767305) (xy 319.907931 -302.721455) (xy 319.885289 -302.671878)
			(xy 319.869934 -302.619583) (xy 319.862178 -302.565635) (xy 319.861692 -302.538384) (xy 319.862454 -302.51527)
			(xy 319.862454 -302.515016) (xy 319.862962 -302.504602) (xy 319.856104 -302.485298) (xy 319.797938 -302.423576)
			(xy 319.790493 -302.41634) (xy 319.771477 -302.40806) (xy 319.761108 -302.407574) (xy 316.85992 -302.407574)
			(xy 316.849869 -302.40808) (xy 316.831309 -302.415801) (xy 316.823852 -302.42256) (xy 315.807344 -303.439068)
			(xy 315.799944 -303.445909) (xy 315.781345 -303.453628) (xy 315.771276 -303.454054) (xy 312.396124 -303.454054)
			(xy 312.38611 -303.454537) (xy 312.367602 -303.462191) (xy 312.35343 -303.476343) (xy 312.345751 -303.49484)
			(xy 312.345324 -303.504854) (xy 312.345324 -303.530254) (xy 312.345242 -303.536153) (xy 317.895173 -303.536153)
			(xy 317.895173 -303.481647) (xy 317.902931 -303.427697) (xy 317.918287 -303.3754) (xy 317.94093 -303.32582)
			(xy 317.970399 -303.279968) (xy 318.006094 -303.238777) (xy 318.047287 -303.203085) (xy 318.093141 -303.173619)
			(xy 318.142722 -303.150979) (xy 318.19502 -303.135625) (xy 318.248971 -303.127872) (xy 318.276224 -303.12741)
			(xy 318.304673 -303.127942) (xy 318.360943 -303.136369) (xy 318.415337 -303.153063) (xy 318.466646 -303.177652)
			(xy 318.513733 -303.209592) (xy 318.555552 -303.248173) (xy 318.591175 -303.292539) (xy 318.619812 -303.341705)
			(xy 318.630808 -303.367948) (xy 318.63411 -303.376584) (xy 318.646556 -303.3903) (xy 318.72301 -303.428908)
			(xy 318.741552 -303.43094) (xy 318.750442 -303.428654) (xy 318.773729 -303.423072) (xy 318.82124 -303.417089)
			(xy 318.845184 -303.416716) (xy 318.872439 -303.41713) (xy 318.926395 -303.424885) (xy 318.978699 -303.440241)
			(xy 319.028284 -303.462884) (xy 319.074142 -303.492354) (xy 319.115339 -303.528049) (xy 319.151037 -303.569245)
			(xy 319.180508 -303.615102) (xy 319.203153 -303.664686) (xy 319.218511 -303.716989) (xy 319.226269 -303.770945)
			(xy 319.226269 -303.825455) (xy 319.218511 -303.879411) (xy 319.203153 -303.931714) (xy 319.180508 -303.981298)
			(xy 319.151037 -304.027155) (xy 319.115339 -304.068351) (xy 319.074142 -304.104046) (xy 319.028284 -304.133516)
			(xy 318.978699 -304.156159) (xy 318.926395 -304.171515) (xy 318.872439 -304.17927) (xy 318.845184 -304.179732)
			(xy 318.816733 -304.17923) (xy 318.76046 -304.170802) (xy 318.706064 -304.154107) (xy 318.654753 -304.129514)
			(xy 318.607665 -304.097569) (xy 318.565847 -304.058983) (xy 318.530226 -304.014612) (xy 318.501594 -303.96544)
			(xy 318.4906 -303.939194) (xy 318.487298 -303.930558) (xy 318.474852 -303.916842) (xy 318.398398 -303.878234)
			(xy 318.379856 -303.876202) (xy 318.370966 -303.878488) (xy 318.347679 -303.884068) (xy 318.300167 -303.890053)
			(xy 318.276224 -303.890426) (xy 318.248971 -303.889928) (xy 318.19502 -303.882175) (xy 318.142722 -303.866821)
			(xy 318.093141 -303.844181) (xy 318.047287 -303.814715) (xy 318.006094 -303.779023) (xy 317.970399 -303.737832)
			(xy 317.94093 -303.69198) (xy 317.918287 -303.6424) (xy 317.902931 -303.590103) (xy 317.895173 -303.536153)
			(xy 312.345242 -303.536153) (xy 312.344866 -303.563109) (xy 312.337515 -303.628406) (xy 312.322899 -303.692469)
			(xy 312.301202 -303.754493) (xy 312.272698 -303.813698) (xy 312.237745 -303.86934) (xy 312.196781 -303.920718)
			(xy 312.173874 -303.944274) (xy 312.00217 -304.115978) (xy 311.995151 -304.123649) (xy 311.987406 -304.142925)
			(xy 311.987903 -304.163692) (xy 311.996562 -304.182574) (xy 312.003948 -304.189892) (xy 312.006234 -304.19167)
			(xy 312.025255 -304.207433) (xy 312.05885 -304.24365) (xy 312.086672 -304.28447) (xy 312.1081 -304.32898)
			(xy 312.122656 -304.376186) (xy 312.130013 -304.425034) (xy 312.13044 -304.449734) (xy 313.394102 -304.449734)
			(xy 313.398062 -304.40068) (xy 313.409839 -304.352896) (xy 313.42913 -304.30762) (xy 313.455433 -304.266024)
			(xy 313.488068 -304.229187) (xy 313.526189 -304.198062) (xy 313.56881 -304.173455) (xy 313.614826 -304.156003)
			(xy 313.663045 -304.146159) (xy 313.71222 -304.144178) (xy 313.761075 -304.15011) (xy 313.808346 -304.163802)
			(xy 313.852808 -304.1849) (xy 313.893311 -304.212856) (xy 313.928804 -304.246948) (xy 313.958369 -304.286292)
			(xy 313.98124 -304.329869) (xy 313.996824 -304.37655) (xy 314.004719 -304.425127) (xy 314.005214 -304.449734)
			(xy 314.344062 -304.449734) (xy 314.348022 -304.40068) (xy 314.359799 -304.352896) (xy 314.37909 -304.30762)
			(xy 314.405393 -304.266024) (xy 314.438028 -304.229187) (xy 314.476149 -304.198062) (xy 314.51877 -304.173455)
			(xy 314.564786 -304.156003) (xy 314.613005 -304.146159) (xy 314.66218 -304.144178) (xy 314.711035 -304.15011)
			(xy 314.758306 -304.163802) (xy 314.802768 -304.1849) (xy 314.843271 -304.212856) (xy 314.878764 -304.246948)
			(xy 314.908329 -304.286292) (xy 314.9312 -304.329869) (xy 314.946784 -304.37655) (xy 314.954679 -304.425127)
			(xy 314.955174 -304.449734) (xy 314.954679 -304.474341) (xy 314.946784 -304.522918) (xy 314.9312 -304.569599)
			(xy 314.908329 -304.613176) (xy 314.878764 -304.65252) (xy 314.843271 -304.686612) (xy 314.802768 -304.714568)
			(xy 314.758306 -304.735666) (xy 314.711035 -304.749358) (xy 314.66218 -304.75529) (xy 314.613005 -304.753309)
			(xy 314.564786 -304.743465) (xy 314.51877 -304.726013) (xy 314.476149 -304.701406) (xy 314.438028 -304.670281)
			(xy 314.405393 -304.633444) (xy 314.37909 -304.591848) (xy 314.359799 -304.546572) (xy 314.348022 -304.498788)
			(xy 314.344062 -304.449734) (xy 314.005214 -304.449734) (xy 314.004719 -304.474341) (xy 313.996824 -304.522918)
			(xy 313.98124 -304.569599) (xy 313.958369 -304.613176) (xy 313.928804 -304.65252) (xy 313.893311 -304.686612)
			(xy 313.852808 -304.714568) (xy 313.808346 -304.735666) (xy 313.761075 -304.749358) (xy 313.71222 -304.75529)
			(xy 313.663045 -304.753309) (xy 313.614826 -304.743465) (xy 313.56881 -304.726013) (xy 313.526189 -304.701406)
			(xy 313.488068 -304.670281) (xy 313.455433 -304.633444) (xy 313.42913 -304.591848) (xy 313.409839 -304.546572)
			(xy 313.398062 -304.498788) (xy 313.394102 -304.449734) (xy 312.13044 -304.449734) (xy 312.129993 -304.474542)
			(xy 312.122575 -304.523601) (xy 312.107909 -304.571) (xy 312.086325 -304.615676) (xy 312.058309 -304.656625)
			(xy 312.024488 -304.692929) (xy 311.985622 -304.723771) (xy 311.964324 -304.7365) (xy 311.956822 -304.741274)
			(xy 311.94539 -304.754875) (xy 311.93928 -304.771559) (xy 311.93894 -304.780052) (xy 320.049634 -304.780052)
			(xy 320.049634 -304.725548) (xy 320.05739 -304.671598) (xy 320.072744 -304.619301) (xy 320.095385 -304.569721)
			(xy 320.12485 -304.523868) (xy 320.16054 -304.482674) (xy 320.20173 -304.446979) (xy 320.247579 -304.417508)
			(xy 320.297156 -304.394861) (xy 320.349451 -304.3795) (xy 320.4034 -304.371737) (xy 320.430652 -304.371248)
			(xy 320.457798 -304.371686) (xy 320.511542 -304.379369) (xy 320.563653 -304.394598) (xy 320.613075 -304.417068)
			(xy 320.65881 -304.446323) (xy 320.699931 -304.481771) (xy 320.735606 -304.522694) (xy 320.765115 -304.568266)
			(xy 320.787858 -304.617563) (xy 320.803377 -304.669588) (xy 320.807842 -304.696368) (xy 320.810662 -304.711198)
			(xy 320.823697 -304.738407) (xy 320.844104 -304.760628) (xy 320.870107 -304.775928) (xy 320.899443 -304.782974)
			(xy 320.929558 -304.781155) (xy 320.957832 -304.770627) (xy 320.970148 -304.7619) (xy 320.990212 -304.747097)
			(xy 321.033428 -304.722226) (xy 321.079513 -304.703192) (xy 321.127683 -304.690317) (xy 321.177119 -304.683822)
			(xy 321.20205 -304.683414) (xy 321.229307 -304.683829) (xy 321.283266 -304.691581) (xy 321.335573 -304.706934)
			(xy 321.385163 -304.729575) (xy 321.431025 -304.759043) (xy 321.472226 -304.794739) (xy 321.507927 -304.835935)
			(xy 321.537401 -304.881793) (xy 321.560049 -304.93138) (xy 321.575408 -304.983685) (xy 321.583167 -305.037643)
			(xy 321.583167 -305.064922) (xy 321.835016 -305.064922) (xy 321.839087 -305.0093) (xy 321.851213 -304.954863)
			(xy 321.871136 -304.902772) (xy 321.898432 -304.854137) (xy 321.932518 -304.809994) (xy 321.972667 -304.771285)
			(xy 322.018025 -304.738834) (xy 322.067625 -304.713333) (xy 322.120409 -304.695326) (xy 322.175252 -304.685196)
			(xy 322.230986 -304.683159) (xy 322.286423 -304.689259) (xy 322.34038 -304.703365) (xy 322.391709 -304.725177)
			(xy 322.439315 -304.754231) (xy 322.482183 -304.789906) (xy 322.5194 -304.831443) (xy 322.550173 -304.877956)
			(xy 322.573845 -304.928453) (xy 322.589913 -304.98186) (xy 322.598033 -305.037036) (xy 322.598542 -305.064922)
			(xy 322.843396 -305.064922) (xy 322.847467 -305.0093) (xy 322.859593 -304.954863) (xy 322.879516 -304.902772)
			(xy 322.906812 -304.854137) (xy 322.940898 -304.809994) (xy 322.981047 -304.771285) (xy 323.026405 -304.738834)
			(xy 323.076005 -304.713333) (xy 323.128789 -304.695326) (xy 323.183632 -304.685196) (xy 323.239366 -304.683159)
			(xy 323.294803 -304.689259) (xy 323.34876 -304.703365) (xy 323.400089 -304.725177) (xy 323.447695 -304.754231)
			(xy 323.490563 -304.789906) (xy 323.52778 -304.831443) (xy 323.558553 -304.877956) (xy 323.582225 -304.928453)
			(xy 323.598293 -304.98186) (xy 323.606413 -305.037036) (xy 323.606903 -305.063906) (xy 323.868032 -305.063906)
			(xy 323.872103 -305.008284) (xy 323.884229 -304.953847) (xy 323.904152 -304.901756) (xy 323.931448 -304.853121)
			(xy 323.965534 -304.808978) (xy 324.005683 -304.770269) (xy 324.051041 -304.737818) (xy 324.100641 -304.712317)
			(xy 324.153425 -304.69431) (xy 324.208268 -304.68418) (xy 324.264002 -304.682143) (xy 324.319439 -304.688243)
			(xy 324.373396 -304.702349) (xy 324.424725 -304.724161) (xy 324.472331 -304.753215) (xy 324.515199 -304.78889)
			(xy 324.552416 -304.830427) (xy 324.583189 -304.87694) (xy 324.606861 -304.927437) (xy 324.622929 -304.980844)
			(xy 324.631049 -305.03602) (xy 324.631233 -305.046126) (xy 324.884032 -305.046126) (xy 324.888103 -304.990504)
			(xy 324.900229 -304.936067) (xy 324.920152 -304.883976) (xy 324.947448 -304.835341) (xy 324.981534 -304.791198)
			(xy 325.021683 -304.752489) (xy 325.067041 -304.720038) (xy 325.116641 -304.694537) (xy 325.169425 -304.67653)
			(xy 325.224268 -304.6664) (xy 325.280002 -304.664363) (xy 325.335439 -304.670463) (xy 325.389396 -304.684569)
			(xy 325.440725 -304.706381) (xy 325.488331 -304.735435) (xy 325.531199 -304.77111) (xy 325.568416 -304.812647)
			(xy 325.599189 -304.85916) (xy 325.622861 -304.909657) (xy 325.638929 -304.963064) (xy 325.647049 -305.01824)
			(xy 325.647558 -305.046126) (xy 325.647049 -305.074012) (xy 325.638929 -305.129188) (xy 325.622861 -305.182595)
			(xy 325.599189 -305.233092) (xy 325.568416 -305.279605) (xy 325.531199 -305.321142) (xy 325.488331 -305.356817)
			(xy 325.440725 -305.385871) (xy 325.389396 -305.407683) (xy 325.335439 -305.421789) (xy 325.280002 -305.427889)
			(xy 325.224268 -305.425852) (xy 325.169425 -305.415722) (xy 325.116641 -305.397715) (xy 325.067041 -305.372214)
			(xy 325.021683 -305.339763) (xy 324.981534 -305.301054) (xy 324.947448 -305.256911) (xy 324.920152 -305.208276)
			(xy 324.900229 -305.156185) (xy 324.888103 -305.101748) (xy 324.884032 -305.046126) (xy 324.631233 -305.046126)
			(xy 324.631558 -305.063906) (xy 324.631049 -305.091792) (xy 324.622929 -305.146968) (xy 324.606861 -305.200375)
			(xy 324.583189 -305.250872) (xy 324.552416 -305.297385) (xy 324.515199 -305.338922) (xy 324.472331 -305.374597)
			(xy 324.424725 -305.403651) (xy 324.373396 -305.425463) (xy 324.319439 -305.439569) (xy 324.264002 -305.445669)
			(xy 324.208268 -305.443632) (xy 324.153425 -305.433502) (xy 324.100641 -305.415495) (xy 324.051041 -305.389994)
			(xy 324.005683 -305.357543) (xy 323.965534 -305.318834) (xy 323.931448 -305.274691) (xy 323.904152 -305.226056)
			(xy 323.884229 -305.173965) (xy 323.872103 -305.119528) (xy 323.868032 -305.063906) (xy 323.606903 -305.063906)
			(xy 323.606922 -305.064922) (xy 323.606413 -305.092808) (xy 323.598293 -305.147984) (xy 323.582225 -305.201391)
			(xy 323.558553 -305.251888) (xy 323.52778 -305.298401) (xy 323.490563 -305.339938) (xy 323.447695 -305.375613)
			(xy 323.400089 -305.404667) (xy 323.34876 -305.426479) (xy 323.294803 -305.440585) (xy 323.239366 -305.446685)
			(xy 323.183632 -305.444648) (xy 323.128789 -305.434518) (xy 323.076005 -305.416511) (xy 323.026405 -305.39101)
			(xy 322.981047 -305.358559) (xy 322.940898 -305.31985) (xy 322.906812 -305.275707) (xy 322.879516 -305.227072)
			(xy 322.859593 -305.174981) (xy 322.847467 -305.120544) (xy 322.843396 -305.064922) (xy 322.598542 -305.064922)
			(xy 322.598033 -305.092808) (xy 322.589913 -305.147984) (xy 322.573845 -305.201391) (xy 322.550173 -305.251888)
			(xy 322.5194 -305.298401) (xy 322.482183 -305.339938) (xy 322.439315 -305.375613) (xy 322.391709 -305.404667)
			(xy 322.34038 -305.426479) (xy 322.286423 -305.440585) (xy 322.230986 -305.446685) (xy 322.175252 -305.444648)
			(xy 322.120409 -305.434518) (xy 322.067625 -305.416511) (xy 322.018025 -305.39101) (xy 321.972667 -305.358559)
			(xy 321.932518 -305.31985) (xy 321.898432 -305.275707) (xy 321.871136 -305.227072) (xy 321.851213 -305.174981)
			(xy 321.839087 -305.120544) (xy 321.835016 -305.064922) (xy 321.583167 -305.064922) (xy 321.583167 -305.092157)
			(xy 321.575408 -305.146115) (xy 321.560049 -305.19842) (xy 321.537401 -305.248007) (xy 321.507927 -305.293865)
			(xy 321.472226 -305.335061) (xy 321.431025 -305.370757) (xy 321.385163 -305.400225) (xy 321.335573 -305.422866)
			(xy 321.283266 -305.438219) (xy 321.229307 -305.445971) (xy 321.20205 -305.44643) (xy 321.174904 -305.446009)
			(xy 321.121158 -305.438326) (xy 321.069045 -305.423095) (xy 321.019622 -305.400624) (xy 320.973886 -305.371368)
			(xy 320.932765 -305.335918) (xy 320.89709 -305.294992) (xy 320.867582 -305.249418) (xy 320.84484 -305.200119)
			(xy 320.829323 -305.148091) (xy 320.82486 -305.12131) (xy 320.822048 -305.106479) (xy 320.809009 -305.079273)
			(xy 320.788599 -305.057054) (xy 320.762596 -305.041756) (xy 320.733261 -305.03471) (xy 320.703146 -305.036528)
			(xy 320.674871 -305.047052) (xy 320.662554 -305.055778) (xy 320.642497 -305.070592) (xy 320.599278 -305.095458)
			(xy 320.553191 -305.114489) (xy 320.50502 -305.127362) (xy 320.455583 -305.133857) (xy 320.430652 -305.134264)
			(xy 320.4034 -305.133863) (xy 320.349451 -305.1261) (xy 320.297156 -305.110739) (xy 320.247579 -305.088092)
			(xy 320.20173 -305.058621) (xy 320.16054 -305.022926) (xy 320.12485 -304.981732) (xy 320.095385 -304.935879)
			(xy 320.072744 -304.886299) (xy 320.05739 -304.834002) (xy 320.049634 -304.780052) (xy 311.93894 -304.780052)
			(xy 311.938924 -304.780442) (xy 311.938924 -305.098704) (xy 311.93925 -305.107252) (xy 311.944872 -305.123397)
			(xy 311.95549 -305.136796) (xy 311.962546 -305.14163) (xy 311.98398 -305.155768) (xy 312.022218 -305.19003)
			(xy 312.054187 -305.230206) (xy 312.078985 -305.275163) (xy 312.095915 -305.323634) (xy 312.104498 -305.374254)
			(xy 312.104496 -305.399948) (xy 312.443888 -305.399948) (xy 312.447848 -305.350894) (xy 312.459625 -305.30311)
			(xy 312.478916 -305.257834) (xy 312.505219 -305.216238) (xy 312.537854 -305.179401) (xy 312.575975 -305.148276)
			(xy 312.618596 -305.123669) (xy 312.664612 -305.106217) (xy 312.712831 -305.096373) (xy 312.762006 -305.094392)
			(xy 312.810861 -305.100324) (xy 312.858132 -305.114016) (xy 312.902594 -305.135114) (xy 312.943097 -305.16307)
			(xy 312.97859 -305.197162) (xy 313.008155 -305.236506) (xy 313.031026 -305.280083) (xy 313.04661 -305.326764)
			(xy 313.054505 -305.375341) (xy 313.055 -305.399948) (xy 313.054505 -305.424555) (xy 313.04661 -305.473132)
			(xy 313.031026 -305.519813) (xy 313.008155 -305.56339) (xy 312.97859 -305.602734) (xy 312.943097 -305.636826)
			(xy 312.902594 -305.664782) (xy 312.858132 -305.68588) (xy 312.810861 -305.699572) (xy 312.762006 -305.705504)
			(xy 312.712831 -305.703523) (xy 312.664612 -305.693679) (xy 312.618596 -305.676227) (xy 312.575975 -305.65162)
			(xy 312.537854 -305.620495) (xy 312.505219 -305.583658) (xy 312.478916 -305.542062) (xy 312.459625 -305.496786)
			(xy 312.447848 -305.449002) (xy 312.443888 -305.399948) (xy 312.104496 -305.399948) (xy 312.104494 -305.425597)
			(xy 312.095902 -305.476216) (xy 312.078964 -305.524684) (xy 312.054158 -305.569637) (xy 312.022183 -305.609807)
			(xy 311.983939 -305.644063) (xy 311.962546 -305.658266) (xy 311.955496 -305.663112) (xy 311.944861 -305.6765)
			(xy 311.939228 -305.692643) (xy 311.938924 -305.701192) (xy 311.938924 -306.0192) (xy 311.939264 -306.028089)
			(xy 311.945354 -306.044793) (xy 311.956796 -306.0584) (xy 311.964324 -306.063142) (xy 311.987237 -306.076887)
			(xy 312.028693 -306.110592) (xy 312.064191 -306.150525) (xy 312.092807 -306.195645) (xy 312.113795 -306.244779)
			(xy 312.12661 -306.296649) (xy 312.130919 -306.349904) (xy 312.130919 -306.349908) (xy 313.394102 -306.349908)
			(xy 313.398062 -306.300854) (xy 313.409839 -306.25307) (xy 313.42913 -306.207794) (xy 313.455433 -306.166198)
			(xy 313.488068 -306.129361) (xy 313.526189 -306.098236) (xy 313.56881 -306.073629) (xy 313.614826 -306.056177)
			(xy 313.663045 -306.046333) (xy 313.71222 -306.044352) (xy 313.761075 -306.050284) (xy 313.808346 -306.063976)
			(xy 313.852808 -306.085074) (xy 313.893311 -306.11303) (xy 313.928804 -306.147122) (xy 313.958369 -306.186466)
			(xy 313.98124 -306.230043) (xy 313.996824 -306.276724) (xy 314.004719 -306.325301) (xy 314.005214 -306.349908)
			(xy 314.344062 -306.349908) (xy 314.348022 -306.300854) (xy 314.359799 -306.25307) (xy 314.37909 -306.207794)
			(xy 314.405393 -306.166198) (xy 314.438028 -306.129361) (xy 314.476149 -306.098236) (xy 314.51877 -306.073629)
			(xy 314.564786 -306.056177) (xy 314.613005 -306.046333) (xy 314.66218 -306.044352) (xy 314.711035 -306.050284)
			(xy 314.758306 -306.063976) (xy 314.802768 -306.085074) (xy 314.843271 -306.11303) (xy 314.878764 -306.147122)
			(xy 314.908329 -306.186466) (xy 314.9312 -306.230043) (xy 314.946784 -306.276724) (xy 314.954679 -306.325301)
			(xy 314.955174 -306.349908) (xy 314.954679 -306.374515) (xy 314.946784 -306.423092) (xy 314.9312 -306.469773)
			(xy 314.908329 -306.51335) (xy 314.878764 -306.552694) (xy 314.843271 -306.586786) (xy 314.802768 -306.614742)
			(xy 314.758306 -306.63584) (xy 314.711035 -306.649532) (xy 314.66218 -306.655464) (xy 314.613005 -306.653483)
			(xy 314.564786 -306.643639) (xy 314.51877 -306.626187) (xy 314.476149 -306.60158) (xy 314.438028 -306.570455)
			(xy 314.405393 -306.533618) (xy 314.37909 -306.492022) (xy 314.359799 -306.446746) (xy 314.348022 -306.398962)
			(xy 314.344062 -306.349908) (xy 314.005214 -306.349908) (xy 314.004719 -306.374515) (xy 313.996824 -306.423092)
			(xy 313.98124 -306.469773) (xy 313.958369 -306.51335) (xy 313.928804 -306.552694) (xy 313.893311 -306.586786)
			(xy 313.852808 -306.614742) (xy 313.808346 -306.63584) (xy 313.761075 -306.649532) (xy 313.71222 -306.655464)
			(xy 313.663045 -306.653483) (xy 313.614826 -306.643639) (xy 313.56881 -306.626187) (xy 313.526189 -306.60158)
			(xy 313.488068 -306.570455) (xy 313.455433 -306.533618) (xy 313.42913 -306.492022) (xy 313.409839 -306.446746)
			(xy 313.398062 -306.398962) (xy 313.394102 -306.349908) (xy 312.130919 -306.349908) (xy 312.126609 -306.403159)
			(xy 312.113793 -306.455028) (xy 312.092803 -306.504162) (xy 312.064186 -306.549282) (xy 312.028688 -306.589213)
			(xy 311.98723 -306.622917) (xy 311.964324 -306.636674) (xy 311.956831 -306.641452) (xy 311.945418 -306.655056)
			(xy 311.939331 -306.671738) (xy 311.938924 -306.680616) (xy 311.938924 -306.998624) (xy 311.939253 -307.00717)
			(xy 311.944879 -307.02331) (xy 311.955499 -307.036704) (xy 311.962546 -307.04155) (xy 311.983987 -307.055688)
			(xy 312.022238 -307.089953) (xy 312.054219 -307.130133) (xy 312.07903 -307.175096) (xy 312.095969 -307.223576)
			(xy 312.104562 -307.274206) (xy 312.104563 -307.299868) (xy 312.443888 -307.299868) (xy 312.447848 -307.250814)
			(xy 312.459625 -307.20303) (xy 312.478916 -307.157754) (xy 312.505219 -307.116158) (xy 312.537854 -307.079321)
			(xy 312.575975 -307.048196) (xy 312.618596 -307.023589) (xy 312.664612 -307.006137) (xy 312.712831 -306.996293)
			(xy 312.762006 -306.994312) (xy 312.810861 -307.000244) (xy 312.858132 -307.013936) (xy 312.902594 -307.035034)
			(xy 312.943097 -307.06299) (xy 312.965202 -307.084222) (xy 324.914258 -307.084222) (xy 324.918329 -307.0286)
			(xy 324.930455 -306.974163) (xy 324.950378 -306.922072) (xy 324.977674 -306.873437) (xy 325.01176 -306.829294)
			(xy 325.051909 -306.790585) (xy 325.097267 -306.758134) (xy 325.146867 -306.732633) (xy 325.199651 -306.714626)
			(xy 325.254494 -306.704496) (xy 325.310228 -306.702459) (xy 325.365665 -306.708559) (xy 325.419622 -306.722665)
			(xy 325.470951 -306.744477) (xy 325.518557 -306.773531) (xy 325.561425 -306.809206) (xy 325.598642 -306.850743)
			(xy 325.629415 -306.897256) (xy 325.653087 -306.947753) (xy 325.669155 -307.00116) (xy 325.677275 -307.056336)
			(xy 325.677784 -307.084222) (xy 325.677275 -307.112108) (xy 325.669155 -307.167284) (xy 325.653087 -307.220691)
			(xy 325.629415 -307.271188) (xy 325.598642 -307.317701) (xy 325.561425 -307.359238) (xy 325.518557 -307.394913)
			(xy 325.470951 -307.423967) (xy 325.419622 -307.445779) (xy 325.365665 -307.459885) (xy 325.310228 -307.465985)
			(xy 325.254494 -307.463948) (xy 325.199651 -307.453818) (xy 325.146867 -307.435811) (xy 325.097267 -307.41031)
			(xy 325.051909 -307.377859) (xy 325.01176 -307.33915) (xy 324.977674 -307.295007) (xy 324.950378 -307.246372)
			(xy 324.930455 -307.194281) (xy 324.918329 -307.139844) (xy 324.914258 -307.084222) (xy 312.965202 -307.084222)
			(xy 312.97859 -307.097082) (xy 313.008155 -307.136426) (xy 313.031026 -307.180003) (xy 313.04661 -307.226684)
			(xy 313.054505 -307.275261) (xy 313.055 -307.299868) (xy 313.054505 -307.324475) (xy 313.04661 -307.373052)
			(xy 313.031026 -307.419733) (xy 313.008155 -307.46331) (xy 312.97859 -307.502654) (xy 312.943097 -307.536746)
			(xy 312.902594 -307.564702) (xy 312.858132 -307.5858) (xy 312.810861 -307.599492) (xy 312.762006 -307.605424)
			(xy 312.712831 -307.603443) (xy 312.664612 -307.593599) (xy 312.618596 -307.576147) (xy 312.575975 -307.55154)
			(xy 312.537854 -307.520415) (xy 312.505219 -307.483578) (xy 312.478916 -307.441982) (xy 312.459625 -307.396706)
			(xy 312.447848 -307.348922) (xy 312.443888 -307.299868) (xy 312.104563 -307.299868) (xy 312.104565 -307.32556)
			(xy 312.095978 -307.376191) (xy 312.079043 -307.424673) (xy 312.054238 -307.469639) (xy 312.022262 -307.509822)
			(xy 311.984014 -307.544091) (xy 311.962546 -307.558186) (xy 311.955498 -307.563033) (xy 311.944869 -307.576422)
			(xy 311.939242 -307.592564) (xy 311.938924 -307.601112) (xy 311.938924 -307.91912) (xy 311.939251 -307.928017)
			(xy 311.945323 -307.944741) (xy 311.95676 -307.95837) (xy 311.964324 -307.963062) (xy 311.985636 -307.975779)
			(xy 312.024528 -308.006603) (xy 312.058372 -308.042899) (xy 312.086404 -308.08385) (xy 312.107995 -308.128533)
			(xy 312.122658 -308.175944) (xy 312.130064 -308.225015) (xy 312.13044 -308.249828) (xy 313.394102 -308.249828)
			(xy 313.398062 -308.200774) (xy 313.409839 -308.15299) (xy 313.42913 -308.107714) (xy 313.455433 -308.066118)
			(xy 313.488068 -308.029281) (xy 313.526189 -307.998156) (xy 313.56881 -307.973549) (xy 313.614826 -307.956097)
			(xy 313.663045 -307.946253) (xy 313.71222 -307.944272) (xy 313.761075 -307.950204) (xy 313.808346 -307.963896)
			(xy 313.852808 -307.984994) (xy 313.893311 -308.01295) (xy 313.928804 -308.047042) (xy 313.958369 -308.086386)
			(xy 313.98124 -308.129963) (xy 313.996824 -308.176644) (xy 314.004719 -308.225221) (xy 314.005214 -308.249828)
			(xy 314.344062 -308.249828) (xy 314.348022 -308.200774) (xy 314.359799 -308.15299) (xy 314.37909 -308.107714)
			(xy 314.405393 -308.066118) (xy 314.438028 -308.029281) (xy 314.476149 -307.998156) (xy 314.51877 -307.973549)
			(xy 314.564786 -307.956097) (xy 314.613005 -307.946253) (xy 314.66218 -307.944272) (xy 314.711035 -307.950204)
			(xy 314.758306 -307.963896) (xy 314.802768 -307.984994) (xy 314.843271 -308.01295) (xy 314.878764 -308.047042)
			(xy 314.908329 -308.086386) (xy 314.9312 -308.129963) (xy 314.946784 -308.176644) (xy 314.954679 -308.225221)
			(xy 314.955174 -308.249828) (xy 314.954679 -308.274435) (xy 314.946784 -308.323012) (xy 314.9312 -308.369693)
			(xy 314.908329 -308.41327) (xy 314.878764 -308.452614) (xy 314.843271 -308.486706) (xy 314.802768 -308.514662)
			(xy 314.758306 -308.53576) (xy 314.711035 -308.549452) (xy 314.66218 -308.555384) (xy 314.613005 -308.553403)
			(xy 314.564786 -308.543559) (xy 314.51877 -308.526107) (xy 314.476149 -308.5015) (xy 314.438028 -308.470375)
			(xy 314.405393 -308.433538) (xy 314.37909 -308.391942) (xy 314.359799 -308.346666) (xy 314.348022 -308.298882)
			(xy 314.344062 -308.249828) (xy 314.005214 -308.249828) (xy 314.004719 -308.274435) (xy 313.996824 -308.323012)
			(xy 313.98124 -308.369693) (xy 313.958369 -308.41327) (xy 313.928804 -308.452614) (xy 313.893311 -308.486706)
			(xy 313.852808 -308.514662) (xy 313.808346 -308.53576) (xy 313.761075 -308.549452) (xy 313.71222 -308.555384)
			(xy 313.663045 -308.553403) (xy 313.614826 -308.543559) (xy 313.56881 -308.526107) (xy 313.526189 -308.5015)
			(xy 313.488068 -308.470375) (xy 313.455433 -308.433538) (xy 313.42913 -308.391942) (xy 313.409839 -308.346666)
			(xy 313.398062 -308.298882) (xy 313.394102 -308.249828) (xy 312.13044 -308.249828) (xy 312.129916 -308.276302)
			(xy 312.121473 -308.328573) (xy 312.104809 -308.37883) (xy 312.080348 -308.425789) (xy 312.048715 -308.468249)
			(xy 312.010721 -308.505126) (xy 311.967335 -308.535476) (xy 311.94375 -308.547516) (xy 311.934293 -308.552624)
			(xy 311.920489 -308.569072) (xy 311.91708 -308.579266) (xy 311.907921 -308.610095) (xy 311.883763 -308.669701)
			(xy 311.853215 -308.726298) (xy 311.835292 -308.753002) (xy 311.828434 -308.762908) (xy 311.825132 -308.787038)
			(xy 311.85612 -308.876192) (xy 311.860668 -308.887261) (xy 311.877905 -308.903815) (xy 311.88914 -308.907942)
			(xy 311.912245 -308.915518) (xy 311.955887 -308.936953) (xy 311.995582 -308.965032) (xy 312.030328 -308.999043)
			(xy 312.059248 -309.03813) (xy 312.081611 -309.081303) (xy 312.096853 -309.127475) (xy 312.104588 -309.175477)
			(xy 312.10504 -309.199788) (xy 312.443888 -309.199788) (xy 312.447848 -309.150734) (xy 312.459625 -309.10295)
			(xy 312.478916 -309.057674) (xy 312.505219 -309.016078) (xy 312.537854 -308.979241) (xy 312.575975 -308.948116)
			(xy 312.618596 -308.923509) (xy 312.664612 -308.906057) (xy 312.712831 -308.896213) (xy 312.762006 -308.894232)
			(xy 312.810861 -308.900164) (xy 312.858132 -308.913856) (xy 312.902594 -308.934954) (xy 312.943097 -308.96291)
			(xy 312.97859 -308.997002) (xy 313.008155 -309.036346) (xy 313.031026 -309.079923) (xy 313.04661 -309.126604)
			(xy 313.054505 -309.175181) (xy 313.05452 -309.175912) (xy 320.534028 -309.175912) (xy 320.538099 -309.12029)
			(xy 320.550225 -309.065853) (xy 320.570148 -309.013762) (xy 320.597444 -308.965127) (xy 320.63153 -308.920984)
			(xy 320.671679 -308.882275) (xy 320.717037 -308.849824) (xy 320.766637 -308.824323) (xy 320.819421 -308.806316)
			(xy 320.874264 -308.796186) (xy 320.929998 -308.794149) (xy 320.985435 -308.800249) (xy 321.039392 -308.814355)
			(xy 321.090721 -308.836167) (xy 321.138327 -308.865221) (xy 321.181195 -308.900896) (xy 321.218412 -308.942433)
			(xy 321.249185 -308.988946) (xy 321.272857 -309.039443) (xy 321.288925 -309.09285) (xy 321.297045 -309.148026)
			(xy 321.297554 -309.175912) (xy 321.297045 -309.203798) (xy 321.288925 -309.258974) (xy 321.272857 -309.312381)
			(xy 321.249185 -309.362878) (xy 321.218412 -309.409391) (xy 321.181195 -309.450928) (xy 321.138327 -309.486603)
			(xy 321.090721 -309.515657) (xy 321.039392 -309.537469) (xy 320.985435 -309.551575) (xy 320.929998 -309.557675)
			(xy 320.874264 -309.555638) (xy 320.819421 -309.545508) (xy 320.766637 -309.527501) (xy 320.717037 -309.502)
			(xy 320.671679 -309.469549) (xy 320.63153 -309.43084) (xy 320.597444 -309.386697) (xy 320.570148 -309.338062)
			(xy 320.550225 -309.285971) (xy 320.538099 -309.231534) (xy 320.534028 -309.175912) (xy 313.05452 -309.175912)
			(xy 313.055 -309.199788) (xy 313.054505 -309.224395) (xy 313.04661 -309.272972) (xy 313.031026 -309.319653)
			(xy 313.008155 -309.36323) (xy 312.97859 -309.402574) (xy 312.943097 -309.436666) (xy 312.902594 -309.464622)
			(xy 312.858132 -309.48572) (xy 312.810861 -309.499412) (xy 312.762006 -309.505344) (xy 312.712831 -309.503363)
			(xy 312.664612 -309.493519) (xy 312.618596 -309.476067) (xy 312.575975 -309.45146) (xy 312.537854 -309.420335)
			(xy 312.505219 -309.383498) (xy 312.478916 -309.341902) (xy 312.459625 -309.296626) (xy 312.447848 -309.248842)
			(xy 312.443888 -309.199788) (xy 312.10504 -309.199788) (xy 312.10457 -309.223781) (xy 312.097066 -309.271176)
			(xy 312.08224 -309.316813) (xy 312.060458 -309.35957) (xy 312.032255 -309.398393) (xy 311.998327 -309.432326)
			(xy 311.959508 -309.460535) (xy 311.916754 -309.482323) (xy 311.871119 -309.497156) (xy 311.823725 -309.504667)
			(xy 311.799732 -309.505096) (xy 311.775202 -309.504609) (xy 311.726774 -309.496766) (xy 311.680224 -309.481278)
			(xy 311.636751 -309.458542) (xy 311.597475 -309.429144) (xy 311.563408 -309.393843) (xy 311.535426 -309.353546)
			(xy 311.514251 -309.309292) (xy 311.50687 -309.285894) (xy 311.50687 -309.28564) (xy 311.502882 -309.274406)
			(xy 311.486592 -309.257044) (xy 311.475628 -309.252366) (xy 311.387998 -309.219854) (xy 311.364376 -309.222394)
			(xy 311.354216 -309.228998) (xy 311.328226 -309.245347) (xy 311.273481 -309.273157) (xy 311.216133 -309.295104)
			(xy 311.186576 -309.30342) (xy 311.175656 -309.306971) (xy 311.158231 -309.321877) (xy 311.153048 -309.332122)
			(xy 311.141579 -309.357026) (xy 311.111646 -309.402958) (xy 311.074552 -309.44333) (xy 311.031313 -309.477037)
			(xy 310.98311 -309.503156) (xy 310.931261 -309.520975) (xy 310.877185 -309.530006) (xy 310.849772 -309.530496)
			(xy 310.824268 -309.530029) (xy 310.773863 -309.522205) (xy 310.725258 -309.506732) (xy 310.679607 -309.483978)
			(xy 310.637992 -309.454481) (xy 310.619394 -309.437024) (xy 310.612014 -309.430437) (xy 310.593716 -309.422973)
			(xy 310.583834 -309.422546) (xy 310.127904 -309.422546) (xy 310.119071 -309.422926) (xy 310.102445 -309.4289)
			(xy 310.095392 -309.43423) (xy 310.076989 -309.44901) (xy 310.036526 -309.473307) (xy 309.992805 -309.491088)
			(xy 309.946869 -309.501929) (xy 309.899812 -309.505571) (xy 309.852755 -309.501929) (xy 309.806819 -309.491088)
			(xy 309.763098 -309.473307) (xy 309.722635 -309.44901) (xy 309.704232 -309.43423) (xy 309.697219 -309.428828)
			(xy 309.680568 -309.42285) (xy 309.67172 -309.422546) (xy 309.177944 -309.422546) (xy 309.169109 -309.422919)
			(xy 309.152474 -309.428883) (xy 309.145432 -309.43423) (xy 309.127029 -309.44901) (xy 309.086566 -309.473307)
			(xy 309.042845 -309.491088) (xy 308.996909 -309.501929) (xy 308.949852 -309.505571) (xy 308.902795 -309.501929)
			(xy 308.856859 -309.491088) (xy 308.813138 -309.473307) (xy 308.772675 -309.44901) (xy 308.754272 -309.43423)
			(xy 308.747261 -309.428822) (xy 308.730609 -309.422832) (xy 308.72176 -309.422546) (xy 308.26583 -309.422546)
			(xy 308.255956 -309.423014) (xy 308.237666 -309.430465) (xy 308.23027 -309.437024) (xy 308.211652 -309.454463)
			(xy 308.170048 -309.483977) (xy 308.124403 -309.506749) (xy 308.075801 -309.522238) (xy 308.025397 -309.530075)
			(xy 307.974387 -309.530075) (xy 307.923983 -309.522238) (xy 307.875381 -309.506749) (xy 307.829736 -309.483977)
			(xy 307.788132 -309.454463) (xy 307.769514 -309.437024) (xy 307.76213 -309.430449) (xy 307.743831 -309.423014)
			(xy 307.733954 -309.422546) (xy 307.31587 -309.422546) (xy 307.305993 -309.423007) (xy 307.287693 -309.430447)
			(xy 307.28031 -309.437024) (xy 307.261692 -309.454463) (xy 307.220088 -309.483977) (xy 307.174443 -309.506749)
			(xy 307.125841 -309.522238) (xy 307.075437 -309.530075) (xy 307.024427 -309.530075) (xy 306.974023 -309.522238)
			(xy 306.925421 -309.506749) (xy 306.879776 -309.483977) (xy 306.838172 -309.454463) (xy 306.819554 -309.437024)
			(xy 306.812172 -309.430443) (xy 306.793873 -309.422994) (xy 306.783994 -309.422546) (xy 306.365656 -309.422546)
			(xy 306.35578 -309.423009) (xy 306.337483 -309.430453) (xy 306.330096 -309.437024) (xy 306.311478 -309.454463)
			(xy 306.269874 -309.483977) (xy 306.224229 -309.506749) (xy 306.175627 -309.522238) (xy 306.125223 -309.530075)
			(xy 306.074213 -309.530075) (xy 306.023809 -309.522238) (xy 305.975207 -309.506749) (xy 305.929562 -309.483977)
			(xy 305.887958 -309.454463) (xy 305.86934 -309.437024) (xy 305.861957 -309.430445) (xy 305.843659 -309.423001)
			(xy 305.83378 -309.422546) (xy 305.832002 -309.422546) (xy 305.640486 -309.614062) (xy 305.616921 -309.636956)
			(xy 305.565535 -309.677903) (xy 305.509892 -309.712844) (xy 305.450688 -309.74134) (xy 305.388667 -309.763033)
			(xy 305.324609 -309.77765) (xy 305.259318 -309.785009) (xy 305.226466 -309.785512) (xy 302.46955 -309.785512)
			(xy 302.436695 -309.785055) (xy 302.371398 -309.777703) (xy 302.307335 -309.763087) (xy 302.245311 -309.741391)
			(xy 302.186106 -309.712887) (xy 302.130464 -309.677933) (xy 302.079086 -309.636969) (xy 302.05553 -309.614062)
			(xy 301.879 -309.437532) (xy 301.871603 -309.430682) (xy 301.853005 -309.422943) (xy 301.842932 -309.422546)
			(xy 296.067226 -309.422546) (xy 296.057163 -309.422984) (xy 296.038582 -309.430722) (xy 296.031158 -309.437532)
			(xy 295.867582 -309.601108) (xy 295.860728 -309.608503) (xy 295.852984 -309.627102) (xy 295.852596 -309.637176)
			(xy 295.852596 -309.864506) (xy 295.853042 -309.875316) (xy 295.861871 -309.895046) (xy 295.869614 -309.902606)
			(xy 295.888277 -309.919822) (xy 295.920617 -309.958964) (xy 295.946592 -310.002589) (xy 295.965594 -310.049673)
			(xy 295.977174 -310.099108) (xy 295.981061 -310.149732) (xy 295.98106 -310.149748) (xy 313.394102 -310.149748)
			(xy 313.398062 -310.100694) (xy 313.409839 -310.05291) (xy 313.42913 -310.007634) (xy 313.455433 -309.966038)
			(xy 313.488068 -309.929201) (xy 313.526189 -309.898076) (xy 313.56881 -309.873469) (xy 313.614826 -309.856017)
			(xy 313.663045 -309.846173) (xy 313.71222 -309.844192) (xy 313.761075 -309.850124) (xy 313.808346 -309.863816)
			(xy 313.852808 -309.884914) (xy 313.893311 -309.91287) (xy 313.928804 -309.946962) (xy 313.958369 -309.986306)
			(xy 313.98124 -310.029883) (xy 313.996824 -310.076564) (xy 314.004719 -310.125141) (xy 314.005214 -310.149748)
			(xy 314.344062 -310.149748) (xy 314.348022 -310.100694) (xy 314.359799 -310.05291) (xy 314.37909 -310.007634)
			(xy 314.405393 -309.966038) (xy 314.438028 -309.929201) (xy 314.476149 -309.898076) (xy 314.51877 -309.873469)
			(xy 314.564786 -309.856017) (xy 314.613005 -309.846173) (xy 314.66218 -309.844192) (xy 314.711035 -309.850124)
			(xy 314.722104 -309.85333) (xy 321.210684 -309.85333) (xy 321.214755 -309.797708) (xy 321.226881 -309.743271)
			(xy 321.246804 -309.69118) (xy 321.2741 -309.642545) (xy 321.308186 -309.598402) (xy 321.348335 -309.559693)
			(xy 321.393693 -309.527242) (xy 321.443293 -309.501741) (xy 321.496077 -309.483734) (xy 321.55092 -309.473604)
			(xy 321.606654 -309.471567) (xy 321.662091 -309.477667) (xy 321.716048 -309.491773) (xy 321.767377 -309.513585)
			(xy 321.814983 -309.542639) (xy 321.857851 -309.578314) (xy 321.895068 -309.619851) (xy 321.925841 -309.666364)
			(xy 321.949513 -309.716861) (xy 321.965581 -309.770268) (xy 321.973701 -309.825444) (xy 321.97421 -309.85333)
			(xy 321.973701 -309.881216) (xy 321.965581 -309.936392) (xy 321.949513 -309.989799) (xy 321.925841 -310.040296)
			(xy 321.895068 -310.086809) (xy 321.857851 -310.128346) (xy 321.814983 -310.164021) (xy 321.767377 -310.193075)
			(xy 321.716048 -310.214887) (xy 321.662091 -310.228993) (xy 321.606654 -310.235093) (xy 321.55092 -310.233056)
			(xy 321.496077 -310.222926) (xy 321.443293 -310.204919) (xy 321.393693 -310.179418) (xy 321.348335 -310.146967)
			(xy 321.308186 -310.108258) (xy 321.2741 -310.064115) (xy 321.246804 -310.01548) (xy 321.226881 -309.963389)
			(xy 321.214755 -309.908952) (xy 321.210684 -309.85333) (xy 314.722104 -309.85333) (xy 314.758306 -309.863816)
			(xy 314.802768 -309.884914) (xy 314.843271 -309.91287) (xy 314.878764 -309.946962) (xy 314.908329 -309.986306)
			(xy 314.9312 -310.029883) (xy 314.946784 -310.076564) (xy 314.954679 -310.125141) (xy 314.955174 -310.149748)
			(xy 314.954679 -310.174355) (xy 314.946784 -310.222932) (xy 314.9312 -310.269613) (xy 314.908329 -310.31319)
			(xy 314.878764 -310.352534) (xy 314.843271 -310.386626) (xy 314.802768 -310.414582) (xy 314.758306 -310.43568)
			(xy 314.711035 -310.449372) (xy 314.66218 -310.455304) (xy 314.613005 -310.453323) (xy 314.564786 -310.443479)
			(xy 314.51877 -310.426027) (xy 314.476149 -310.40142) (xy 314.438028 -310.370295) (xy 314.405393 -310.333458)
			(xy 314.37909 -310.291862) (xy 314.359799 -310.246586) (xy 314.348022 -310.198802) (xy 314.344062 -310.149748)
			(xy 314.005214 -310.149748) (xy 314.004719 -310.174355) (xy 313.996824 -310.222932) (xy 313.98124 -310.269613)
			(xy 313.958369 -310.31319) (xy 313.928804 -310.352534) (xy 313.893311 -310.386626) (xy 313.852808 -310.414582)
			(xy 313.808346 -310.43568) (xy 313.761075 -310.449372) (xy 313.71222 -310.455304) (xy 313.663045 -310.453323)
			(xy 313.614826 -310.443479) (xy 313.56881 -310.426027) (xy 313.526189 -310.40142) (xy 313.488068 -310.370295)
			(xy 313.455433 -310.333458) (xy 313.42913 -310.291862) (xy 313.409839 -310.246586) (xy 313.398062 -310.198802)
			(xy 313.394102 -310.149748) (xy 295.98106 -310.149748) (xy 295.977164 -310.200355) (xy 295.965574 -310.249788)
			(xy 295.946564 -310.296868) (xy 295.92058 -310.340489) (xy 295.888233 -310.379624) (xy 295.869614 -310.39689)
			(xy 295.861881 -310.404454) (xy 295.853055 -310.424183) (xy 295.852596 -310.43499) (xy 295.852596 -310.68518)
			(xy 322.042534 -310.68518) (xy 322.046605 -310.629558) (xy 322.058731 -310.575121) (xy 322.078654 -310.52303)
			(xy 322.10595 -310.474395) (xy 322.140036 -310.430252) (xy 322.180185 -310.391543) (xy 322.225543 -310.359092)
			(xy 322.275143 -310.333591) (xy 322.327927 -310.315584) (xy 322.38277 -310.305454) (xy 322.438504 -310.303417)
			(xy 322.493941 -310.309517) (xy 322.547898 -310.323623) (xy 322.599227 -310.345435) (xy 322.646833 -310.374489)
			(xy 322.689701 -310.410164) (xy 322.726918 -310.451701) (xy 322.757691 -310.498214) (xy 322.781363 -310.548711)
			(xy 322.797431 -310.602118) (xy 322.805551 -310.657294) (xy 322.80606 -310.68518) (xy 322.805551 -310.713066)
			(xy 322.797431 -310.768242) (xy 322.781363 -310.821649) (xy 322.757691 -310.872146) (xy 322.726918 -310.918659)
			(xy 322.689701 -310.960196) (xy 322.646833 -310.995871) (xy 322.599227 -311.024925) (xy 322.547898 -311.046737)
			(xy 322.493941 -311.060843) (xy 322.438504 -311.066943) (xy 322.38277 -311.064906) (xy 322.327927 -311.054776)
			(xy 322.275143 -311.036769) (xy 322.225543 -311.011268) (xy 322.180185 -310.978817) (xy 322.140036 -310.940108)
			(xy 322.10595 -310.895965) (xy 322.078654 -310.84733) (xy 322.058731 -310.795239) (xy 322.046605 -310.740802)
			(xy 322.042534 -310.68518) (xy 295.852596 -310.68518) (xy 295.852596 -310.81472) (xy 295.853025 -310.825538)
			(xy 295.861832 -310.845294) (xy 295.869614 -310.85282) (xy 295.888284 -310.870035) (xy 295.920637 -310.909179)
			(xy 295.946625 -310.952809) (xy 295.965638 -310.999899) (xy 295.977229 -311.049341) (xy 295.981125 -311.099962)
			(xy 296.29406 -311.099962) (xy 296.29802 -311.050908) (xy 296.309797 -311.003124) (xy 296.329088 -310.957848)
			(xy 296.355391 -310.916252) (xy 296.388026 -310.879415) (xy 296.426147 -310.84829) (xy 296.468768 -310.823683)
			(xy 296.514784 -310.806231) (xy 296.563003 -310.796387) (xy 296.612178 -310.794406) (xy 296.661033 -310.800338)
			(xy 296.708304 -310.81403) (xy 296.752766 -310.835128) (xy 296.793269 -310.863084) (xy 296.828762 -310.897176)
			(xy 296.858327 -310.93652) (xy 296.881198 -310.980097) (xy 296.896782 -311.026778) (xy 296.904677 -311.075355)
			(xy 296.905172 -311.099962) (xy 298.19398 -311.099962) (xy 298.19794 -311.050908) (xy 298.209717 -311.003124)
			(xy 298.229008 -310.957848) (xy 298.255311 -310.916252) (xy 298.287946 -310.879415) (xy 298.326067 -310.84829)
			(xy 298.368688 -310.823683) (xy 298.414704 -310.806231) (xy 298.462923 -310.796387) (xy 298.512098 -310.794406)
			(xy 298.560953 -310.800338) (xy 298.608224 -310.81403) (xy 298.652686 -310.835128) (xy 298.693189 -310.863084)
			(xy 298.728682 -310.897176) (xy 298.758247 -310.93652) (xy 298.781118 -310.980097) (xy 298.796702 -311.026778)
			(xy 298.804597 -311.075355) (xy 298.805092 -311.099962) (xy 300.0939 -311.099962) (xy 300.09786 -311.050908)
			(xy 300.109637 -311.003124) (xy 300.128928 -310.957848) (xy 300.155231 -310.916252) (xy 300.187866 -310.879415)
			(xy 300.225987 -310.84829) (xy 300.268608 -310.823683) (xy 300.314624 -310.806231) (xy 300.362843 -310.796387)
			(xy 300.412018 -310.794406) (xy 300.460873 -310.800338) (xy 300.508144 -310.81403) (xy 300.552606 -310.835128)
			(xy 300.593109 -310.863084) (xy 300.628602 -310.897176) (xy 300.658167 -310.93652) (xy 300.681038 -310.980097)
			(xy 300.696622 -311.026778) (xy 300.704517 -311.075355) (xy 300.705012 -311.099962) (xy 301.994074 -311.099962)
			(xy 301.998034 -311.050908) (xy 302.009811 -311.003124) (xy 302.029102 -310.957848) (xy 302.055405 -310.916252)
			(xy 302.08804 -310.879415) (xy 302.126161 -310.84829) (xy 302.168782 -310.823683) (xy 302.214798 -310.806231)
			(xy 302.263017 -310.796387) (xy 302.312192 -310.794406) (xy 302.361047 -310.800338) (xy 302.408318 -310.81403)
			(xy 302.45278 -310.835128) (xy 302.493283 -310.863084) (xy 302.528776 -310.897176) (xy 302.558341 -310.93652)
			(xy 302.581212 -310.980097) (xy 302.596796 -311.026778) (xy 302.604691 -311.075355) (xy 302.605186 -311.099962)
			(xy 303.893994 -311.099962) (xy 303.897954 -311.050908) (xy 303.909731 -311.003124) (xy 303.929022 -310.957848)
			(xy 303.955325 -310.916252) (xy 303.98796 -310.879415) (xy 304.026081 -310.84829) (xy 304.068702 -310.823683)
			(xy 304.114718 -310.806231) (xy 304.162937 -310.796387) (xy 304.212112 -310.794406) (xy 304.260967 -310.800338)
			(xy 304.308238 -310.81403) (xy 304.3527 -310.835128) (xy 304.393203 -310.863084) (xy 304.428696 -310.897176)
			(xy 304.458261 -310.93652) (xy 304.481132 -310.980097) (xy 304.496716 -311.026778) (xy 304.504611 -311.075355)
			(xy 304.505106 -311.099962) (xy 305.793914 -311.099962) (xy 305.797874 -311.050908) (xy 305.809651 -311.003124)
			(xy 305.828942 -310.957848) (xy 305.855245 -310.916252) (xy 305.88788 -310.879415) (xy 305.926001 -310.84829)
			(xy 305.968622 -310.823683) (xy 306.014638 -310.806231) (xy 306.062857 -310.796387) (xy 306.112032 -310.794406)
			(xy 306.160887 -310.800338) (xy 306.208158 -310.81403) (xy 306.25262 -310.835128) (xy 306.293123 -310.863084)
			(xy 306.328616 -310.897176) (xy 306.358181 -310.93652) (xy 306.381052 -310.980097) (xy 306.396636 -311.026778)
			(xy 306.404531 -311.075355) (xy 306.405026 -311.099962) (xy 307.694088 -311.099962) (xy 307.698048 -311.050908)
			(xy 307.709825 -311.003124) (xy 307.729116 -310.957848) (xy 307.755419 -310.916252) (xy 307.788054 -310.879415)
			(xy 307.826175 -310.84829) (xy 307.868796 -310.823683) (xy 307.914812 -310.806231) (xy 307.963031 -310.796387)
			(xy 308.012206 -310.794406) (xy 308.061061 -310.800338) (xy 308.108332 -310.81403) (xy 308.152794 -310.835128)
			(xy 308.193297 -310.863084) (xy 308.22879 -310.897176) (xy 308.258355 -310.93652) (xy 308.281226 -310.980097)
			(xy 308.29681 -311.026778) (xy 308.304705 -311.075355) (xy 308.3052 -311.099962) (xy 309.594008 -311.099962)
			(xy 309.597968 -311.050908) (xy 309.609745 -311.003124) (xy 309.629036 -310.957848) (xy 309.655339 -310.916252)
			(xy 309.687974 -310.879415) (xy 309.726095 -310.84829) (xy 309.768716 -310.823683) (xy 309.814732 -310.806231)
			(xy 309.862951 -310.796387) (xy 309.912126 -310.794406) (xy 309.960981 -310.800338) (xy 310.008252 -310.81403)
			(xy 310.052714 -310.835128) (xy 310.093217 -310.863084) (xy 310.12871 -310.897176) (xy 310.158275 -310.93652)
			(xy 310.181146 -310.980097) (xy 310.19673 -311.026778) (xy 310.204625 -311.075355) (xy 310.20512 -311.099962)
			(xy 311.493928 -311.099962) (xy 311.497888 -311.050908) (xy 311.509665 -311.003124) (xy 311.528956 -310.957848)
			(xy 311.555259 -310.916252) (xy 311.587894 -310.879415) (xy 311.626015 -310.84829) (xy 311.668636 -310.823683)
			(xy 311.714652 -310.806231) (xy 311.762871 -310.796387) (xy 311.812046 -310.794406) (xy 311.860901 -310.800338)
			(xy 311.908172 -310.81403) (xy 311.952634 -310.835128) (xy 311.993137 -310.863084) (xy 312.02863 -310.897176)
			(xy 312.058195 -310.93652) (xy 312.081066 -310.980097) (xy 312.09665 -311.026778) (xy 312.104545 -311.075355)
			(xy 312.10504 -311.099962) (xy 312.104545 -311.124569) (xy 312.09665 -311.173146) (xy 312.081066 -311.219827)
			(xy 312.058195 -311.263404) (xy 312.02863 -311.302748) (xy 311.993137 -311.33684) (xy 311.952634 -311.364796)
			(xy 311.918789 -311.380856) (xy 322.766688 -311.380856) (xy 322.774443 -311.326911) (xy 322.789796 -311.274618)
			(xy 322.812435 -311.225043) (xy 322.841898 -311.179194) (xy 322.877587 -311.138005) (xy 322.918773 -311.102314)
			(xy 322.96462 -311.072847) (xy 323.014194 -311.050205) (xy 323.066485 -311.034849) (xy 323.12043 -311.02709)
			(xy 323.174929 -311.027087) (xy 323.228874 -311.03484) (xy 323.281167 -311.050191) (xy 323.330743 -311.072828)
			(xy 323.376593 -311.102289) (xy 323.417784 -311.137976) (xy 323.453477 -311.179161) (xy 323.482945 -311.225007)
			(xy 323.505589 -311.274579) (xy 323.520948 -311.32687) (xy 323.528709 -311.380814) (xy 323.529198 -311.408064)
			(xy 323.529002 -311.425112) (xy 323.525947 -311.459072) (xy 323.523102 -311.475882) (xy 323.521061 -311.489765)
			(xy 323.523783 -311.517684) (xy 323.53399 -311.543811) (xy 323.550916 -311.566181) (xy 323.573284 -311.583107)
			(xy 323.599411 -311.593316) (xy 323.62733 -311.596039) (xy 323.641212 -311.593992) (xy 323.65802 -311.591128)
			(xy 323.691981 -311.588077) (xy 323.70903 -311.587896) (xy 323.709284 -311.587896) (xy 323.736538 -311.588338)
			(xy 323.790492 -311.596093) (xy 323.842793 -311.611448) (xy 323.892377 -311.634089) (xy 323.938233 -311.663557)
			(xy 323.979429 -311.699251) (xy 324.015126 -311.740444) (xy 324.044597 -311.786299) (xy 324.067243 -311.835881)
			(xy 324.082601 -311.88818) (xy 324.09036 -311.942134) (xy 324.090362 -311.996642) (xy 324.082606 -312.050596)
			(xy 324.067251 -312.102897) (xy 324.044609 -312.15248) (xy 324.015141 -312.198336) (xy 323.979446 -312.239532)
			(xy 323.938252 -312.275229) (xy 323.892398 -312.304699) (xy 323.842816 -312.327344) (xy 323.790516 -312.342702)
			(xy 323.736562 -312.350461) (xy 323.682054 -312.350462) (xy 323.6281 -312.342705) (xy 323.575799 -312.32735)
			(xy 323.526216 -312.304707) (xy 323.48036 -312.275238) (xy 323.439165 -312.239543) (xy 323.403469 -312.198349)
			(xy 323.373999 -312.152494) (xy 323.351355 -312.102912) (xy 323.335997 -312.050612) (xy 323.328239 -311.996658)
			(xy 323.327776 -311.969404) (xy 323.327981 -311.952356) (xy 323.33103 -311.918397) (xy 323.333872 -311.901586)
			(xy 323.335976 -311.88771) (xy 323.333247 -311.859783) (xy 323.323029 -311.833649) (xy 323.306093 -311.811277)
			(xy 323.283714 -311.79435) (xy 323.257576 -311.784144) (xy 323.229648 -311.781425) (xy 323.215762 -311.783476)
			(xy 323.198955 -311.786343) (xy 323.164993 -311.789392) (xy 323.147944 -311.789572) (xy 323.14769 -311.789572)
			(xy 323.12044 -311.789111) (xy 323.066496 -311.781354) (xy 323.014204 -311.765998) (xy 322.96463 -311.743358)
			(xy 322.918782 -311.713893) (xy 322.877594 -311.678203) (xy 322.841905 -311.637014) (xy 322.81244 -311.591166)
			(xy 322.7898 -311.541592) (xy 322.774445 -311.4893) (xy 322.766689 -311.435355) (xy 322.766688 -311.380856)
			(xy 311.918789 -311.380856) (xy 311.908172 -311.385894) (xy 311.860901 -311.399586) (xy 311.812046 -311.405518)
			(xy 311.762871 -311.403537) (xy 311.714652 -311.393693) (xy 311.668636 -311.376241) (xy 311.626015 -311.351634)
			(xy 311.587894 -311.320509) (xy 311.555259 -311.283672) (xy 311.528956 -311.242076) (xy 311.509665 -311.1968)
			(xy 311.497888 -311.149016) (xy 311.493928 -311.099962) (xy 310.20512 -311.099962) (xy 310.204625 -311.124569)
			(xy 310.19673 -311.173146) (xy 310.181146 -311.219827) (xy 310.158275 -311.263404) (xy 310.12871 -311.302748)
			(xy 310.093217 -311.33684) (xy 310.052714 -311.364796) (xy 310.008252 -311.385894) (xy 309.960981 -311.399586)
			(xy 309.912126 -311.405518) (xy 309.862951 -311.403537) (xy 309.814732 -311.393693) (xy 309.768716 -311.376241)
			(xy 309.726095 -311.351634) (xy 309.687974 -311.320509) (xy 309.655339 -311.283672) (xy 309.629036 -311.242076)
			(xy 309.609745 -311.1968) (xy 309.597968 -311.149016) (xy 309.594008 -311.099962) (xy 308.3052 -311.099962)
			(xy 308.304705 -311.124569) (xy 308.29681 -311.173146) (xy 308.281226 -311.219827) (xy 308.258355 -311.263404)
			(xy 308.22879 -311.302748) (xy 308.193297 -311.33684) (xy 308.152794 -311.364796) (xy 308.108332 -311.385894)
			(xy 308.061061 -311.399586) (xy 308.012206 -311.405518) (xy 307.963031 -311.403537) (xy 307.914812 -311.393693)
			(xy 307.868796 -311.376241) (xy 307.826175 -311.351634) (xy 307.788054 -311.320509) (xy 307.755419 -311.283672)
			(xy 307.729116 -311.242076) (xy 307.709825 -311.1968) (xy 307.698048 -311.149016) (xy 307.694088 -311.099962)
			(xy 306.405026 -311.099962) (xy 306.404531 -311.124569) (xy 306.396636 -311.173146) (xy 306.381052 -311.219827)
			(xy 306.358181 -311.263404) (xy 306.328616 -311.302748) (xy 306.293123 -311.33684) (xy 306.25262 -311.364796)
			(xy 306.208158 -311.385894) (xy 306.160887 -311.399586) (xy 306.112032 -311.405518) (xy 306.062857 -311.403537)
			(xy 306.014638 -311.393693) (xy 305.968622 -311.376241) (xy 305.926001 -311.351634) (xy 305.88788 -311.320509)
			(xy 305.855245 -311.283672) (xy 305.828942 -311.242076) (xy 305.809651 -311.1968) (xy 305.797874 -311.149016)
			(xy 305.793914 -311.099962) (xy 304.505106 -311.099962) (xy 304.504611 -311.124569) (xy 304.496716 -311.173146)
			(xy 304.481132 -311.219827) (xy 304.458261 -311.263404) (xy 304.428696 -311.302748) (xy 304.393203 -311.33684)
			(xy 304.3527 -311.364796) (xy 304.308238 -311.385894) (xy 304.260967 -311.399586) (xy 304.212112 -311.405518)
			(xy 304.162937 -311.403537) (xy 304.114718 -311.393693) (xy 304.068702 -311.376241) (xy 304.026081 -311.351634)
			(xy 303.98796 -311.320509) (xy 303.955325 -311.283672) (xy 303.929022 -311.242076) (xy 303.909731 -311.1968)
			(xy 303.897954 -311.149016) (xy 303.893994 -311.099962) (xy 302.605186 -311.099962) (xy 302.604691 -311.124569)
			(xy 302.596796 -311.173146) (xy 302.581212 -311.219827) (xy 302.558341 -311.263404) (xy 302.528776 -311.302748)
			(xy 302.493283 -311.33684) (xy 302.45278 -311.364796) (xy 302.408318 -311.385894) (xy 302.361047 -311.399586)
			(xy 302.312192 -311.405518) (xy 302.263017 -311.403537) (xy 302.214798 -311.393693) (xy 302.168782 -311.376241)
			(xy 302.126161 -311.351634) (xy 302.08804 -311.320509) (xy 302.055405 -311.283672) (xy 302.029102 -311.242076)
			(xy 302.009811 -311.1968) (xy 301.998034 -311.149016) (xy 301.994074 -311.099962) (xy 300.705012 -311.099962)
			(xy 300.704517 -311.124569) (xy 300.696622 -311.173146) (xy 300.681038 -311.219827) (xy 300.658167 -311.263404)
			(xy 300.628602 -311.302748) (xy 300.593109 -311.33684) (xy 300.552606 -311.364796) (xy 300.508144 -311.385894)
			(xy 300.460873 -311.399586) (xy 300.412018 -311.405518) (xy 300.362843 -311.403537) (xy 300.314624 -311.393693)
			(xy 300.268608 -311.376241) (xy 300.225987 -311.351634) (xy 300.187866 -311.320509) (xy 300.155231 -311.283672)
			(xy 300.128928 -311.242076) (xy 300.109637 -311.1968) (xy 300.09786 -311.149016) (xy 300.0939 -311.099962)
			(xy 298.805092 -311.099962) (xy 298.804597 -311.124569) (xy 298.796702 -311.173146) (xy 298.781118 -311.219827)
			(xy 298.758247 -311.263404) (xy 298.728682 -311.302748) (xy 298.693189 -311.33684) (xy 298.652686 -311.364796)
			(xy 298.608224 -311.385894) (xy 298.560953 -311.399586) (xy 298.512098 -311.405518) (xy 298.462923 -311.403537)
			(xy 298.414704 -311.393693) (xy 298.368688 -311.376241) (xy 298.326067 -311.351634) (xy 298.287946 -311.320509)
			(xy 298.255311 -311.283672) (xy 298.229008 -311.242076) (xy 298.209717 -311.1968) (xy 298.19794 -311.149016)
			(xy 298.19398 -311.099962) (xy 296.905172 -311.099962) (xy 296.904677 -311.124569) (xy 296.896782 -311.173146)
			(xy 296.881198 -311.219827) (xy 296.858327 -311.263404) (xy 296.828762 -311.302748) (xy 296.793269 -311.33684)
			(xy 296.752766 -311.364796) (xy 296.708304 -311.385894) (xy 296.661033 -311.399586) (xy 296.612178 -311.405518)
			(xy 296.563003 -311.403537) (xy 296.514784 -311.393693) (xy 296.468768 -311.376241) (xy 296.426147 -311.351634)
			(xy 296.388026 -311.320509) (xy 296.355391 -311.283672) (xy 296.329088 -311.242076) (xy 296.309797 -311.1968)
			(xy 296.29802 -311.149016) (xy 296.29406 -311.099962) (xy 295.981125 -311.099962) (xy 295.981126 -311.099975)
			(xy 295.977237 -311.150609) (xy 295.965653 -311.200053) (xy 295.946647 -311.247146) (xy 295.920666 -311.290779)
			(xy 295.888319 -311.329928) (xy 295.869614 -311.347104) (xy 295.861883 -311.354669) (xy 295.853063 -311.374398)
			(xy 295.852596 -311.385204) (xy 295.852596 -311.76468) (xy 295.853037 -311.775493) (xy 295.86186 -311.79523)
			(xy 295.869614 -311.80278) (xy 295.888279 -311.819996) (xy 295.920623 -311.859138) (xy 295.946602 -311.902765)
			(xy 295.965607 -311.94985) (xy 295.977191 -311.999288) (xy 295.981081 -312.049915) (xy 295.98108 -312.049922)
			(xy 296.29406 -312.049922) (xy 296.29802 -312.000868) (xy 296.309797 -311.953084) (xy 296.329088 -311.907808)
			(xy 296.355391 -311.866212) (xy 296.388026 -311.829375) (xy 296.426147 -311.79825) (xy 296.468768 -311.773643)
			(xy 296.514784 -311.756191) (xy 296.563003 -311.746347) (xy 296.612178 -311.744366) (xy 296.661033 -311.750298)
			(xy 296.708304 -311.76399) (xy 296.752766 -311.785088) (xy 296.793269 -311.813044) (xy 296.828762 -311.847136)
			(xy 296.858327 -311.88648) (xy 296.881198 -311.930057) (xy 296.896782 -311.976738) (xy 296.904677 -312.025315)
			(xy 296.905172 -312.049922) (xy 298.19398 -312.049922) (xy 298.19794 -312.000868) (xy 298.209717 -311.953084)
			(xy 298.229008 -311.907808) (xy 298.255311 -311.866212) (xy 298.287946 -311.829375) (xy 298.326067 -311.79825)
			(xy 298.368688 -311.773643) (xy 298.414704 -311.756191) (xy 298.462923 -311.746347) (xy 298.512098 -311.744366)
			(xy 298.560953 -311.750298) (xy 298.608224 -311.76399) (xy 298.652686 -311.785088) (xy 298.693189 -311.813044)
			(xy 298.728682 -311.847136) (xy 298.758247 -311.88648) (xy 298.781118 -311.930057) (xy 298.796702 -311.976738)
			(xy 298.804597 -312.025315) (xy 298.805092 -312.049922) (xy 300.0939 -312.049922) (xy 300.09786 -312.000868)
			(xy 300.109637 -311.953084) (xy 300.128928 -311.907808) (xy 300.155231 -311.866212) (xy 300.187866 -311.829375)
			(xy 300.225987 -311.79825) (xy 300.268608 -311.773643) (xy 300.314624 -311.756191) (xy 300.362843 -311.746347)
			(xy 300.412018 -311.744366) (xy 300.460873 -311.750298) (xy 300.508144 -311.76399) (xy 300.552606 -311.785088)
			(xy 300.593109 -311.813044) (xy 300.628602 -311.847136) (xy 300.658167 -311.88648) (xy 300.681038 -311.930057)
			(xy 300.696622 -311.976738) (xy 300.704517 -312.025315) (xy 300.705012 -312.049922) (xy 301.994074 -312.049922)
			(xy 301.998034 -312.000868) (xy 302.009811 -311.953084) (xy 302.029102 -311.907808) (xy 302.055405 -311.866212)
			(xy 302.08804 -311.829375) (xy 302.126161 -311.79825) (xy 302.168782 -311.773643) (xy 302.214798 -311.756191)
			(xy 302.263017 -311.746347) (xy 302.312192 -311.744366) (xy 302.361047 -311.750298) (xy 302.408318 -311.76399)
			(xy 302.45278 -311.785088) (xy 302.493283 -311.813044) (xy 302.528776 -311.847136) (xy 302.558341 -311.88648)
			(xy 302.581212 -311.930057) (xy 302.596796 -311.976738) (xy 302.604691 -312.025315) (xy 302.605186 -312.049922)
			(xy 303.893994 -312.049922) (xy 303.897954 -312.000868) (xy 303.909731 -311.953084) (xy 303.929022 -311.907808)
			(xy 303.955325 -311.866212) (xy 303.98796 -311.829375) (xy 304.026081 -311.79825) (xy 304.068702 -311.773643)
			(xy 304.114718 -311.756191) (xy 304.162937 -311.746347) (xy 304.212112 -311.744366) (xy 304.260967 -311.750298)
			(xy 304.308238 -311.76399) (xy 304.3527 -311.785088) (xy 304.393203 -311.813044) (xy 304.428696 -311.847136)
			(xy 304.458261 -311.88648) (xy 304.481132 -311.930057) (xy 304.496716 -311.976738) (xy 304.504611 -312.025315)
			(xy 304.505106 -312.049922) (xy 305.793914 -312.049922) (xy 305.797874 -312.000868) (xy 305.809651 -311.953084)
			(xy 305.828942 -311.907808) (xy 305.855245 -311.866212) (xy 305.88788 -311.829375) (xy 305.926001 -311.79825)
			(xy 305.968622 -311.773643) (xy 306.014638 -311.756191) (xy 306.062857 -311.746347) (xy 306.112032 -311.744366)
			(xy 306.160887 -311.750298) (xy 306.208158 -311.76399) (xy 306.25262 -311.785088) (xy 306.293123 -311.813044)
			(xy 306.328616 -311.847136) (xy 306.358181 -311.88648) (xy 306.381052 -311.930057) (xy 306.396636 -311.976738)
			(xy 306.404531 -312.025315) (xy 306.405026 -312.049922) (xy 307.694088 -312.049922) (xy 307.698048 -312.000868)
			(xy 307.709825 -311.953084) (xy 307.729116 -311.907808) (xy 307.755419 -311.866212) (xy 307.788054 -311.829375)
			(xy 307.826175 -311.79825) (xy 307.868796 -311.773643) (xy 307.914812 -311.756191) (xy 307.963031 -311.746347)
			(xy 308.012206 -311.744366) (xy 308.061061 -311.750298) (xy 308.108332 -311.76399) (xy 308.152794 -311.785088)
			(xy 308.193297 -311.813044) (xy 308.22879 -311.847136) (xy 308.258355 -311.88648) (xy 308.281226 -311.930057)
			(xy 308.29681 -311.976738) (xy 308.304705 -312.025315) (xy 308.3052 -312.049922) (xy 309.594008 -312.049922)
			(xy 309.597968 -312.000868) (xy 309.609745 -311.953084) (xy 309.629036 -311.907808) (xy 309.655339 -311.866212)
			(xy 309.687974 -311.829375) (xy 309.726095 -311.79825) (xy 309.768716 -311.773643) (xy 309.814732 -311.756191)
			(xy 309.862951 -311.746347) (xy 309.912126 -311.744366) (xy 309.960981 -311.750298) (xy 310.008252 -311.76399)
			(xy 310.052714 -311.785088) (xy 310.093217 -311.813044) (xy 310.12871 -311.847136) (xy 310.158275 -311.88648)
			(xy 310.181146 -311.930057) (xy 310.19673 -311.976738) (xy 310.204625 -312.025315) (xy 310.20512 -312.049922)
			(xy 311.493928 -312.049922) (xy 311.497888 -312.000868) (xy 311.509665 -311.953084) (xy 311.528956 -311.907808)
			(xy 311.555259 -311.866212) (xy 311.587894 -311.829375) (xy 311.626015 -311.79825) (xy 311.668636 -311.773643)
			(xy 311.714652 -311.756191) (xy 311.762871 -311.746347) (xy 311.812046 -311.744366) (xy 311.860901 -311.750298)
			(xy 311.908172 -311.76399) (xy 311.952634 -311.785088) (xy 311.993137 -311.813044) (xy 312.02863 -311.847136)
			(xy 312.058195 -311.88648) (xy 312.081066 -311.930057) (xy 312.09665 -311.976738) (xy 312.104545 -312.025315)
			(xy 312.10504 -312.049922) (xy 313.394102 -312.049922) (xy 313.398062 -312.000868) (xy 313.409839 -311.953084)
			(xy 313.42913 -311.907808) (xy 313.455433 -311.866212) (xy 313.488068 -311.829375) (xy 313.526189 -311.79825)
			(xy 313.56881 -311.773643) (xy 313.614826 -311.756191) (xy 313.663045 -311.746347) (xy 313.71222 -311.744366)
			(xy 313.761075 -311.750298) (xy 313.808346 -311.76399) (xy 313.852808 -311.785088) (xy 313.893311 -311.813044)
			(xy 313.928804 -311.847136) (xy 313.958369 -311.88648) (xy 313.98124 -311.930057) (xy 313.996824 -311.976738)
			(xy 314.004719 -312.025315) (xy 314.005214 -312.049922) (xy 314.344062 -312.049922) (xy 314.348022 -312.000868)
			(xy 314.359799 -311.953084) (xy 314.37909 -311.907808) (xy 314.405393 -311.866212) (xy 314.438028 -311.829375)
			(xy 314.476149 -311.79825) (xy 314.51877 -311.773643) (xy 314.564786 -311.756191) (xy 314.613005 -311.746347)
			(xy 314.66218 -311.744366) (xy 314.711035 -311.750298) (xy 314.758306 -311.76399) (xy 314.802768 -311.785088)
			(xy 314.843271 -311.813044) (xy 314.878764 -311.847136) (xy 314.908329 -311.88648) (xy 314.9312 -311.930057)
			(xy 314.946784 -311.976738) (xy 314.954679 -312.025315) (xy 314.955174 -312.049922) (xy 314.954679 -312.074529)
			(xy 314.946784 -312.123106) (xy 314.9312 -312.169787) (xy 314.908329 -312.213364) (xy 314.878764 -312.252708)
			(xy 314.843271 -312.2868) (xy 314.802768 -312.314756) (xy 314.758306 -312.335854) (xy 314.711035 -312.349546)
			(xy 314.66218 -312.355478) (xy 314.613005 -312.353497) (xy 314.564786 -312.343653) (xy 314.51877 -312.326201)
			(xy 314.476149 -312.301594) (xy 314.438028 -312.270469) (xy 314.405393 -312.233632) (xy 314.37909 -312.192036)
			(xy 314.359799 -312.14676) (xy 314.348022 -312.098976) (xy 314.344062 -312.049922) (xy 314.005214 -312.049922)
			(xy 314.004719 -312.074529) (xy 313.996824 -312.123106) (xy 313.98124 -312.169787) (xy 313.958369 -312.213364)
			(xy 313.928804 -312.252708) (xy 313.893311 -312.2868) (xy 313.852808 -312.314756) (xy 313.808346 -312.335854)
			(xy 313.761075 -312.349546) (xy 313.71222 -312.355478) (xy 313.663045 -312.353497) (xy 313.614826 -312.343653)
			(xy 313.56881 -312.326201) (xy 313.526189 -312.301594) (xy 313.488068 -312.270469) (xy 313.455433 -312.233632)
			(xy 313.42913 -312.192036) (xy 313.409839 -312.14676) (xy 313.398062 -312.098976) (xy 313.394102 -312.049922)
			(xy 312.10504 -312.049922) (xy 312.104545 -312.074529) (xy 312.09665 -312.123106) (xy 312.081066 -312.169787)
			(xy 312.058195 -312.213364) (xy 312.02863 -312.252708) (xy 311.993137 -312.2868) (xy 311.952634 -312.314756)
			(xy 311.908172 -312.335854) (xy 311.860901 -312.349546) (xy 311.812046 -312.355478) (xy 311.762871 -312.353497)
			(xy 311.714652 -312.343653) (xy 311.668636 -312.326201) (xy 311.626015 -312.301594) (xy 311.587894 -312.270469)
			(xy 311.555259 -312.233632) (xy 311.528956 -312.192036) (xy 311.509665 -312.14676) (xy 311.497888 -312.098976)
			(xy 311.493928 -312.049922) (xy 310.20512 -312.049922) (xy 310.204625 -312.074529) (xy 310.19673 -312.123106)
			(xy 310.181146 -312.169787) (xy 310.158275 -312.213364) (xy 310.12871 -312.252708) (xy 310.093217 -312.2868)
			(xy 310.052714 -312.314756) (xy 310.008252 -312.335854) (xy 309.960981 -312.349546) (xy 309.912126 -312.355478)
			(xy 309.862951 -312.353497) (xy 309.814732 -312.343653) (xy 309.768716 -312.326201) (xy 309.726095 -312.301594)
			(xy 309.687974 -312.270469) (xy 309.655339 -312.233632) (xy 309.629036 -312.192036) (xy 309.609745 -312.14676)
			(xy 309.597968 -312.098976) (xy 309.594008 -312.049922) (xy 308.3052 -312.049922) (xy 308.304705 -312.074529)
			(xy 308.29681 -312.123106) (xy 308.281226 -312.169787) (xy 308.258355 -312.213364) (xy 308.22879 -312.252708)
			(xy 308.193297 -312.2868) (xy 308.152794 -312.314756) (xy 308.108332 -312.335854) (xy 308.061061 -312.349546)
			(xy 308.012206 -312.355478) (xy 307.963031 -312.353497) (xy 307.914812 -312.343653) (xy 307.868796 -312.326201)
			(xy 307.826175 -312.301594) (xy 307.788054 -312.270469) (xy 307.755419 -312.233632) (xy 307.729116 -312.192036)
			(xy 307.709825 -312.14676) (xy 307.698048 -312.098976) (xy 307.694088 -312.049922) (xy 306.405026 -312.049922)
			(xy 306.404531 -312.074529) (xy 306.396636 -312.123106) (xy 306.381052 -312.169787) (xy 306.358181 -312.213364)
			(xy 306.328616 -312.252708) (xy 306.293123 -312.2868) (xy 306.25262 -312.314756) (xy 306.208158 -312.335854)
			(xy 306.160887 -312.349546) (xy 306.112032 -312.355478) (xy 306.062857 -312.353497) (xy 306.014638 -312.343653)
			(xy 305.968622 -312.326201) (xy 305.926001 -312.301594) (xy 305.88788 -312.270469) (xy 305.855245 -312.233632)
			(xy 305.828942 -312.192036) (xy 305.809651 -312.14676) (xy 305.797874 -312.098976) (xy 305.793914 -312.049922)
			(xy 304.505106 -312.049922) (xy 304.504611 -312.074529) (xy 304.496716 -312.123106) (xy 304.481132 -312.169787)
			(xy 304.458261 -312.213364) (xy 304.428696 -312.252708) (xy 304.393203 -312.2868) (xy 304.3527 -312.314756)
			(xy 304.308238 -312.335854) (xy 304.260967 -312.349546) (xy 304.212112 -312.355478) (xy 304.162937 -312.353497)
			(xy 304.114718 -312.343653) (xy 304.068702 -312.326201) (xy 304.026081 -312.301594) (xy 303.98796 -312.270469)
			(xy 303.955325 -312.233632) (xy 303.929022 -312.192036) (xy 303.909731 -312.14676) (xy 303.897954 -312.098976)
			(xy 303.893994 -312.049922) (xy 302.605186 -312.049922) (xy 302.604691 -312.074529) (xy 302.596796 -312.123106)
			(xy 302.581212 -312.169787) (xy 302.558341 -312.213364) (xy 302.528776 -312.252708) (xy 302.493283 -312.2868)
			(xy 302.45278 -312.314756) (xy 302.408318 -312.335854) (xy 302.361047 -312.349546) (xy 302.312192 -312.355478)
			(xy 302.263017 -312.353497) (xy 302.214798 -312.343653) (xy 302.168782 -312.326201) (xy 302.126161 -312.301594)
			(xy 302.08804 -312.270469) (xy 302.055405 -312.233632) (xy 302.029102 -312.192036) (xy 302.009811 -312.14676)
			(xy 301.998034 -312.098976) (xy 301.994074 -312.049922) (xy 300.705012 -312.049922) (xy 300.704517 -312.074529)
			(xy 300.696622 -312.123106) (xy 300.681038 -312.169787) (xy 300.658167 -312.213364) (xy 300.628602 -312.252708)
			(xy 300.593109 -312.2868) (xy 300.552606 -312.314756) (xy 300.508144 -312.335854) (xy 300.460873 -312.349546)
			(xy 300.412018 -312.355478) (xy 300.362843 -312.353497) (xy 300.314624 -312.343653) (xy 300.268608 -312.326201)
			(xy 300.225987 -312.301594) (xy 300.187866 -312.270469) (xy 300.155231 -312.233632) (xy 300.128928 -312.192036)
			(xy 300.109637 -312.14676) (xy 300.09786 -312.098976) (xy 300.0939 -312.049922) (xy 298.805092 -312.049922)
			(xy 298.804597 -312.074529) (xy 298.796702 -312.123106) (xy 298.781118 -312.169787) (xy 298.758247 -312.213364)
			(xy 298.728682 -312.252708) (xy 298.693189 -312.2868) (xy 298.652686 -312.314756) (xy 298.608224 -312.335854)
			(xy 298.560953 -312.349546) (xy 298.512098 -312.355478) (xy 298.462923 -312.353497) (xy 298.414704 -312.343653)
			(xy 298.368688 -312.326201) (xy 298.326067 -312.301594) (xy 298.287946 -312.270469) (xy 298.255311 -312.233632)
			(xy 298.229008 -312.192036) (xy 298.209717 -312.14676) (xy 298.19794 -312.098976) (xy 298.19398 -312.049922)
			(xy 296.905172 -312.049922) (xy 296.904677 -312.074529) (xy 296.896782 -312.123106) (xy 296.881198 -312.169787)
			(xy 296.858327 -312.213364) (xy 296.828762 -312.252708) (xy 296.793269 -312.2868) (xy 296.752766 -312.314756)
			(xy 296.708304 -312.335854) (xy 296.661033 -312.349546) (xy 296.612178 -312.355478) (xy 296.563003 -312.353497)
			(xy 296.514784 -312.343653) (xy 296.468768 -312.326201) (xy 296.426147 -312.301594) (xy 296.388026 -312.270469)
			(xy 296.355391 -312.233632) (xy 296.329088 -312.192036) (xy 296.309797 -312.14676) (xy 296.29802 -312.098976)
			(xy 296.29406 -312.049922) (xy 295.98108 -312.049922) (xy 295.977186 -312.100541) (xy 295.965598 -312.149978)
			(xy 295.946589 -312.197061) (xy 295.920606 -312.240686) (xy 295.888259 -312.279825) (xy 295.869614 -312.297064)
			(xy 295.861877 -312.304627) (xy 295.853041 -312.324356) (xy 295.852596 -312.335164) (xy 295.852596 -312.749692)
			(xy 295.853069 -312.75966) (xy 295.860637 -312.778104) (xy 295.867328 -312.785506) (xy 295.883701 -312.802757)
			(xy 295.911438 -312.841389) (xy 295.932851 -312.883854) (xy 295.947422 -312.929125) (xy 295.954797 -312.976108)
			(xy 295.954798 -312.999882) (xy 297.24402 -312.999882) (xy 297.24798 -312.950828) (xy 297.259757 -312.903044)
			(xy 297.279048 -312.857768) (xy 297.305351 -312.816172) (xy 297.337986 -312.779335) (xy 297.376107 -312.74821)
			(xy 297.418728 -312.723603) (xy 297.464744 -312.706151) (xy 297.512963 -312.696307) (xy 297.562138 -312.694326)
			(xy 297.610993 -312.700258) (xy 297.658264 -312.71395) (xy 297.702726 -312.735048) (xy 297.743229 -312.763004)
			(xy 297.778722 -312.797096) (xy 297.808287 -312.83644) (xy 297.831158 -312.880017) (xy 297.846742 -312.926698)
			(xy 297.854637 -312.975275) (xy 297.855132 -312.999882) (xy 299.14394 -312.999882) (xy 299.1479 -312.950828)
			(xy 299.159677 -312.903044) (xy 299.178968 -312.857768) (xy 299.205271 -312.816172) (xy 299.237906 -312.779335)
			(xy 299.276027 -312.74821) (xy 299.318648 -312.723603) (xy 299.364664 -312.706151) (xy 299.412883 -312.696307)
			(xy 299.462058 -312.694326) (xy 299.510913 -312.700258) (xy 299.558184 -312.71395) (xy 299.602646 -312.735048)
			(xy 299.643149 -312.763004) (xy 299.678642 -312.797096) (xy 299.708207 -312.83644) (xy 299.731078 -312.880017)
			(xy 299.746662 -312.926698) (xy 299.754557 -312.975275) (xy 299.755052 -312.999882) (xy 301.044114 -312.999882)
			(xy 301.048074 -312.950828) (xy 301.059851 -312.903044) (xy 301.079142 -312.857768) (xy 301.105445 -312.816172)
			(xy 301.13808 -312.779335) (xy 301.176201 -312.74821) (xy 301.218822 -312.723603) (xy 301.264838 -312.706151)
			(xy 301.313057 -312.696307) (xy 301.362232 -312.694326) (xy 301.411087 -312.700258) (xy 301.458358 -312.71395)
			(xy 301.50282 -312.735048) (xy 301.543323 -312.763004) (xy 301.578816 -312.797096) (xy 301.608381 -312.83644)
			(xy 301.631252 -312.880017) (xy 301.646836 -312.926698) (xy 301.654731 -312.975275) (xy 301.655226 -312.999882)
			(xy 302.944034 -312.999882) (xy 302.947994 -312.950828) (xy 302.959771 -312.903044) (xy 302.979062 -312.857768)
			(xy 303.005365 -312.816172) (xy 303.038 -312.779335) (xy 303.076121 -312.74821) (xy 303.118742 -312.723603)
			(xy 303.164758 -312.706151) (xy 303.212977 -312.696307) (xy 303.262152 -312.694326) (xy 303.311007 -312.700258)
			(xy 303.358278 -312.71395) (xy 303.40274 -312.735048) (xy 303.443243 -312.763004) (xy 303.478736 -312.797096)
			(xy 303.508301 -312.83644) (xy 303.531172 -312.880017) (xy 303.546756 -312.926698) (xy 303.554651 -312.975275)
			(xy 303.555146 -312.999882) (xy 304.843954 -312.999882) (xy 304.847914 -312.950828) (xy 304.859691 -312.903044)
			(xy 304.878982 -312.857768) (xy 304.905285 -312.816172) (xy 304.93792 -312.779335) (xy 304.976041 -312.74821)
			(xy 305.018662 -312.723603) (xy 305.064678 -312.706151) (xy 305.112897 -312.696307) (xy 305.162072 -312.694326)
			(xy 305.210927 -312.700258) (xy 305.258198 -312.71395) (xy 305.30266 -312.735048) (xy 305.343163 -312.763004)
			(xy 305.378656 -312.797096) (xy 305.408221 -312.83644) (xy 305.431092 -312.880017) (xy 305.446676 -312.926698)
			(xy 305.454571 -312.975275) (xy 305.455066 -312.999882) (xy 306.744128 -312.999882) (xy 306.748088 -312.950828)
			(xy 306.759865 -312.903044) (xy 306.779156 -312.857768) (xy 306.805459 -312.816172) (xy 306.838094 -312.779335)
			(xy 306.876215 -312.74821) (xy 306.918836 -312.723603) (xy 306.964852 -312.706151) (xy 307.013071 -312.696307)
			(xy 307.062246 -312.694326) (xy 307.111101 -312.700258) (xy 307.158372 -312.71395) (xy 307.202834 -312.735048)
			(xy 307.243337 -312.763004) (xy 307.27883 -312.797096) (xy 307.308395 -312.83644) (xy 307.331266 -312.880017)
			(xy 307.34685 -312.926698) (xy 307.354745 -312.975275) (xy 307.35524 -312.999882) (xy 308.644048 -312.999882)
			(xy 308.648008 -312.950828) (xy 308.659785 -312.903044) (xy 308.679076 -312.857768) (xy 308.705379 -312.816172)
			(xy 308.738014 -312.779335) (xy 308.776135 -312.74821) (xy 308.818756 -312.723603) (xy 308.864772 -312.706151)
			(xy 308.912991 -312.696307) (xy 308.962166 -312.694326) (xy 309.011021 -312.700258) (xy 309.058292 -312.71395)
			(xy 309.102754 -312.735048) (xy 309.143257 -312.763004) (xy 309.17875 -312.797096) (xy 309.208315 -312.83644)
			(xy 309.231186 -312.880017) (xy 309.24677 -312.926698) (xy 309.254665 -312.975275) (xy 309.25516 -312.999882)
			(xy 310.543968 -312.999882) (xy 310.547928 -312.950828) (xy 310.559705 -312.903044) (xy 310.578996 -312.857768)
			(xy 310.605299 -312.816172) (xy 310.637934 -312.779335) (xy 310.676055 -312.74821) (xy 310.718676 -312.723603)
			(xy 310.764692 -312.706151) (xy 310.812911 -312.696307) (xy 310.862086 -312.694326) (xy 310.910941 -312.700258)
			(xy 310.958212 -312.71395) (xy 311.002674 -312.735048) (xy 311.043177 -312.763004) (xy 311.07867 -312.797096)
			(xy 311.108235 -312.83644) (xy 311.131106 -312.880017) (xy 311.14669 -312.926698) (xy 311.154585 -312.975275)
			(xy 311.15508 -312.999882) (xy 312.443888 -312.999882) (xy 312.447848 -312.950828) (xy 312.459625 -312.903044)
			(xy 312.478916 -312.857768) (xy 312.505219 -312.816172) (xy 312.537854 -312.779335) (xy 312.575975 -312.74821)
			(xy 312.618596 -312.723603) (xy 312.664612 -312.706151) (xy 312.712831 -312.696307) (xy 312.762006 -312.694326)
			(xy 312.810861 -312.700258) (xy 312.858132 -312.71395) (xy 312.902594 -312.735048) (xy 312.943097 -312.763004)
			(xy 312.97859 -312.797096) (xy 313.008155 -312.83644) (xy 313.031026 -312.880017) (xy 313.04661 -312.926698)
			(xy 313.054505 -312.975275) (xy 313.055 -312.999882) (xy 313.054505 -313.024489) (xy 313.04661 -313.073066)
			(xy 313.031026 -313.119747) (xy 313.008155 -313.163324) (xy 312.97859 -313.202668) (xy 312.943097 -313.23676)
			(xy 312.902594 -313.264716) (xy 312.858132 -313.285814) (xy 312.810861 -313.299506) (xy 312.762006 -313.305438)
			(xy 312.712831 -313.303457) (xy 312.664612 -313.293613) (xy 312.618596 -313.276161) (xy 312.575975 -313.251554)
			(xy 312.537854 -313.220429) (xy 312.505219 -313.183592) (xy 312.478916 -313.141996) (xy 312.459625 -313.09672)
			(xy 312.447848 -313.048936) (xy 312.443888 -312.999882) (xy 311.15508 -312.999882) (xy 311.154585 -313.024489)
			(xy 311.14669 -313.073066) (xy 311.131106 -313.119747) (xy 311.108235 -313.163324) (xy 311.07867 -313.202668)
			(xy 311.043177 -313.23676) (xy 311.002674 -313.264716) (xy 310.958212 -313.285814) (xy 310.910941 -313.299506)
			(xy 310.862086 -313.305438) (xy 310.812911 -313.303457) (xy 310.764692 -313.293613) (xy 310.718676 -313.276161)
			(xy 310.676055 -313.251554) (xy 310.637934 -313.220429) (xy 310.605299 -313.183592) (xy 310.578996 -313.141996)
			(xy 310.559705 -313.09672) (xy 310.547928 -313.048936) (xy 310.543968 -312.999882) (xy 309.25516 -312.999882)
			(xy 309.254665 -313.024489) (xy 309.24677 -313.073066) (xy 309.231186 -313.119747) (xy 309.208315 -313.163324)
			(xy 309.17875 -313.202668) (xy 309.143257 -313.23676) (xy 309.102754 -313.264716) (xy 309.058292 -313.285814)
			(xy 309.011021 -313.299506) (xy 308.962166 -313.305438) (xy 308.912991 -313.303457) (xy 308.864772 -313.293613)
			(xy 308.818756 -313.276161) (xy 308.776135 -313.251554) (xy 308.738014 -313.220429) (xy 308.705379 -313.183592)
			(xy 308.679076 -313.141996) (xy 308.659785 -313.09672) (xy 308.648008 -313.048936) (xy 308.644048 -312.999882)
			(xy 307.35524 -312.999882) (xy 307.354745 -313.024489) (xy 307.34685 -313.073066) (xy 307.331266 -313.119747)
			(xy 307.308395 -313.163324) (xy 307.27883 -313.202668) (xy 307.243337 -313.23676) (xy 307.202834 -313.264716)
			(xy 307.158372 -313.285814) (xy 307.111101 -313.299506) (xy 307.062246 -313.305438) (xy 307.013071 -313.303457)
			(xy 306.964852 -313.293613) (xy 306.918836 -313.276161) (xy 306.876215 -313.251554) (xy 306.838094 -313.220429)
			(xy 306.805459 -313.183592) (xy 306.779156 -313.141996) (xy 306.759865 -313.09672) (xy 306.748088 -313.048936)
			(xy 306.744128 -312.999882) (xy 305.455066 -312.999882) (xy 305.454571 -313.024489) (xy 305.446676 -313.073066)
			(xy 305.431092 -313.119747) (xy 305.408221 -313.163324) (xy 305.378656 -313.202668) (xy 305.343163 -313.23676)
			(xy 305.30266 -313.264716) (xy 305.258198 -313.285814) (xy 305.210927 -313.299506) (xy 305.162072 -313.305438)
			(xy 305.112897 -313.303457) (xy 305.064678 -313.293613) (xy 305.018662 -313.276161) (xy 304.976041 -313.251554)
			(xy 304.93792 -313.220429) (xy 304.905285 -313.183592) (xy 304.878982 -313.141996) (xy 304.859691 -313.09672)
			(xy 304.847914 -313.048936) (xy 304.843954 -312.999882) (xy 303.555146 -312.999882) (xy 303.554651 -313.024489)
			(xy 303.546756 -313.073066) (xy 303.531172 -313.119747) (xy 303.508301 -313.163324) (xy 303.478736 -313.202668)
			(xy 303.443243 -313.23676) (xy 303.40274 -313.264716) (xy 303.358278 -313.285814) (xy 303.311007 -313.299506)
			(xy 303.262152 -313.305438) (xy 303.212977 -313.303457) (xy 303.164758 -313.293613) (xy 303.118742 -313.276161)
			(xy 303.076121 -313.251554) (xy 303.038 -313.220429) (xy 303.005365 -313.183592) (xy 302.979062 -313.141996)
			(xy 302.959771 -313.09672) (xy 302.947994 -313.048936) (xy 302.944034 -312.999882) (xy 301.655226 -312.999882)
			(xy 301.654731 -313.024489) (xy 301.646836 -313.073066) (xy 301.631252 -313.119747) (xy 301.608381 -313.163324)
			(xy 301.578816 -313.202668) (xy 301.543323 -313.23676) (xy 301.50282 -313.264716) (xy 301.458358 -313.285814)
			(xy 301.411087 -313.299506) (xy 301.362232 -313.305438) (xy 301.313057 -313.303457) (xy 301.264838 -313.293613)
			(xy 301.218822 -313.276161) (xy 301.176201 -313.251554) (xy 301.13808 -313.220429) (xy 301.105445 -313.183592)
			(xy 301.079142 -313.141996) (xy 301.059851 -313.09672) (xy 301.048074 -313.048936) (xy 301.044114 -312.999882)
			(xy 299.755052 -312.999882) (xy 299.754557 -313.024489) (xy 299.746662 -313.073066) (xy 299.731078 -313.119747)
			(xy 299.708207 -313.163324) (xy 299.678642 -313.202668) (xy 299.643149 -313.23676) (xy 299.602646 -313.264716)
			(xy 299.558184 -313.285814) (xy 299.510913 -313.299506) (xy 299.462058 -313.305438) (xy 299.412883 -313.303457)
			(xy 299.364664 -313.293613) (xy 299.318648 -313.276161) (xy 299.276027 -313.251554) (xy 299.237906 -313.220429)
			(xy 299.205271 -313.183592) (xy 299.178968 -313.141996) (xy 299.159677 -313.09672) (xy 299.1479 -313.048936)
			(xy 299.14394 -312.999882) (xy 297.855132 -312.999882) (xy 297.854637 -313.024489) (xy 297.846742 -313.073066)
			(xy 297.831158 -313.119747) (xy 297.808287 -313.163324) (xy 297.778722 -313.202668) (xy 297.743229 -313.23676)
			(xy 297.702726 -313.264716) (xy 297.658264 -313.285814) (xy 297.610993 -313.299506) (xy 297.562138 -313.305438)
			(xy 297.512963 -313.303457) (xy 297.464744 -313.293613) (xy 297.418728 -313.276161) (xy 297.376107 -313.251554)
			(xy 297.337986 -313.220429) (xy 297.305351 -313.183592) (xy 297.279048 -313.141996) (xy 297.259757 -313.09672)
			(xy 297.24798 -313.048936) (xy 297.24402 -312.999882) (xy 295.954798 -312.999882) (xy 295.954799 -313.023666)
			(xy 295.947428 -313.07065) (xy 295.932861 -313.115923) (xy 295.911452 -313.158389) (xy 295.883717 -313.197024)
			(xy 295.867328 -313.214258) (xy 295.860634 -313.221664) (xy 295.853033 -313.2401) (xy 295.852596 -313.250072)
			(xy 295.852596 -313.699652) (xy 295.85308 -313.709615) (xy 295.860663 -313.728044) (xy 295.867328 -313.735466)
			(xy 295.883696 -313.752717) (xy 295.911425 -313.791347) (xy 295.932829 -313.833809) (xy 295.947391 -313.879076)
			(xy 295.954758 -313.926054) (xy 295.954756 -313.949842) (xy 297.24402 -313.949842) (xy 297.24798 -313.900788)
			(xy 297.259757 -313.853004) (xy 297.279048 -313.807728) (xy 297.305351 -313.766132) (xy 297.337986 -313.729295)
			(xy 297.376107 -313.69817) (xy 297.418728 -313.673563) (xy 297.464744 -313.656111) (xy 297.512963 -313.646267)
			(xy 297.562138 -313.644286) (xy 297.610993 -313.650218) (xy 297.658264 -313.66391) (xy 297.702726 -313.685008)
			(xy 297.743229 -313.712964) (xy 297.778722 -313.747056) (xy 297.808287 -313.7864) (xy 297.831158 -313.829977)
			(xy 297.846742 -313.876658) (xy 297.854637 -313.925235) (xy 297.855132 -313.949842) (xy 299.14394 -313.949842)
			(xy 299.1479 -313.900788) (xy 299.159677 -313.853004) (xy 299.178968 -313.807728) (xy 299.205271 -313.766132)
			(xy 299.237906 -313.729295) (xy 299.276027 -313.69817) (xy 299.318648 -313.673563) (xy 299.364664 -313.656111)
			(xy 299.412883 -313.646267) (xy 299.462058 -313.644286) (xy 299.510913 -313.650218) (xy 299.558184 -313.66391)
			(xy 299.602646 -313.685008) (xy 299.643149 -313.712964) (xy 299.678642 -313.747056) (xy 299.708207 -313.7864)
			(xy 299.731078 -313.829977) (xy 299.746662 -313.876658) (xy 299.754557 -313.925235) (xy 299.755052 -313.949842)
			(xy 301.044114 -313.949842) (xy 301.048074 -313.900788) (xy 301.059851 -313.853004) (xy 301.079142 -313.807728)
			(xy 301.105445 -313.766132) (xy 301.13808 -313.729295) (xy 301.176201 -313.69817) (xy 301.218822 -313.673563)
			(xy 301.264838 -313.656111) (xy 301.313057 -313.646267) (xy 301.362232 -313.644286) (xy 301.411087 -313.650218)
			(xy 301.458358 -313.66391) (xy 301.50282 -313.685008) (xy 301.543323 -313.712964) (xy 301.578816 -313.747056)
			(xy 301.608381 -313.7864) (xy 301.631252 -313.829977) (xy 301.646836 -313.876658) (xy 301.654731 -313.925235)
			(xy 301.655226 -313.949842) (xy 302.944034 -313.949842) (xy 302.947994 -313.900788) (xy 302.959771 -313.853004)
			(xy 302.979062 -313.807728) (xy 303.005365 -313.766132) (xy 303.038 -313.729295) (xy 303.076121 -313.69817)
			(xy 303.118742 -313.673563) (xy 303.164758 -313.656111) (xy 303.212977 -313.646267) (xy 303.262152 -313.644286)
			(xy 303.311007 -313.650218) (xy 303.358278 -313.66391) (xy 303.40274 -313.685008) (xy 303.443243 -313.712964)
			(xy 303.478736 -313.747056) (xy 303.508301 -313.7864) (xy 303.531172 -313.829977) (xy 303.546756 -313.876658)
			(xy 303.554651 -313.925235) (xy 303.555146 -313.949842) (xy 304.843954 -313.949842) (xy 304.847914 -313.900788)
			(xy 304.859691 -313.853004) (xy 304.878982 -313.807728) (xy 304.905285 -313.766132) (xy 304.93792 -313.729295)
			(xy 304.976041 -313.69817) (xy 305.018662 -313.673563) (xy 305.064678 -313.656111) (xy 305.112897 -313.646267)
			(xy 305.162072 -313.644286) (xy 305.210927 -313.650218) (xy 305.258198 -313.66391) (xy 305.30266 -313.685008)
			(xy 305.343163 -313.712964) (xy 305.378656 -313.747056) (xy 305.408221 -313.7864) (xy 305.431092 -313.829977)
			(xy 305.446676 -313.876658) (xy 305.454571 -313.925235) (xy 305.455066 -313.949842) (xy 306.744128 -313.949842)
			(xy 306.748088 -313.900788) (xy 306.759865 -313.853004) (xy 306.779156 -313.807728) (xy 306.805459 -313.766132)
			(xy 306.838094 -313.729295) (xy 306.876215 -313.69817) (xy 306.918836 -313.673563) (xy 306.964852 -313.656111)
			(xy 307.013071 -313.646267) (xy 307.062246 -313.644286) (xy 307.111101 -313.650218) (xy 307.158372 -313.66391)
			(xy 307.202834 -313.685008) (xy 307.243337 -313.712964) (xy 307.27883 -313.747056) (xy 307.308395 -313.7864)
			(xy 307.331266 -313.829977) (xy 307.34685 -313.876658) (xy 307.354745 -313.925235) (xy 307.35524 -313.949842)
			(xy 308.644048 -313.949842) (xy 308.648008 -313.900788) (xy 308.659785 -313.853004) (xy 308.679076 -313.807728)
			(xy 308.705379 -313.766132) (xy 308.738014 -313.729295) (xy 308.776135 -313.69817) (xy 308.818756 -313.673563)
			(xy 308.864772 -313.656111) (xy 308.912991 -313.646267) (xy 308.962166 -313.644286) (xy 309.011021 -313.650218)
			(xy 309.058292 -313.66391) (xy 309.102754 -313.685008) (xy 309.143257 -313.712964) (xy 309.17875 -313.747056)
			(xy 309.208315 -313.7864) (xy 309.231186 -313.829977) (xy 309.24677 -313.876658) (xy 309.254665 -313.925235)
			(xy 309.25516 -313.949842) (xy 310.543968 -313.949842) (xy 310.547928 -313.900788) (xy 310.559705 -313.853004)
			(xy 310.578996 -313.807728) (xy 310.605299 -313.766132) (xy 310.637934 -313.729295) (xy 310.676055 -313.69817)
			(xy 310.718676 -313.673563) (xy 310.764692 -313.656111) (xy 310.812911 -313.646267) (xy 310.862086 -313.644286)
			(xy 310.910941 -313.650218) (xy 310.958212 -313.66391) (xy 311.002674 -313.685008) (xy 311.043177 -313.712964)
			(xy 311.07867 -313.747056) (xy 311.108235 -313.7864) (xy 311.131106 -313.829977) (xy 311.14669 -313.876658)
			(xy 311.154585 -313.925235) (xy 311.15508 -313.949842) (xy 312.443888 -313.949842) (xy 312.447848 -313.900788)
			(xy 312.459625 -313.853004) (xy 312.478916 -313.807728) (xy 312.505219 -313.766132) (xy 312.537854 -313.729295)
			(xy 312.575975 -313.69817) (xy 312.618596 -313.673563) (xy 312.664612 -313.656111) (xy 312.712831 -313.646267)
			(xy 312.762006 -313.644286) (xy 312.810861 -313.650218) (xy 312.858132 -313.66391) (xy 312.902594 -313.685008)
			(xy 312.943097 -313.712964) (xy 312.97859 -313.747056) (xy 313.008155 -313.7864) (xy 313.031026 -313.829977)
			(xy 313.04661 -313.876658) (xy 313.054505 -313.925235) (xy 313.055 -313.949842) (xy 313.054505 -313.974449)
			(xy 313.04661 -314.023026) (xy 313.031026 -314.069707) (xy 313.008155 -314.113284) (xy 312.97859 -314.152628)
			(xy 312.943097 -314.18672) (xy 312.902594 -314.214676) (xy 312.858132 -314.235774) (xy 312.810861 -314.249466)
			(xy 312.762006 -314.255398) (xy 312.712831 -314.253417) (xy 312.664612 -314.243573) (xy 312.618596 -314.226121)
			(xy 312.575975 -314.201514) (xy 312.537854 -314.170389) (xy 312.505219 -314.133552) (xy 312.478916 -314.091956)
			(xy 312.459625 -314.04668) (xy 312.447848 -313.998896) (xy 312.443888 -313.949842) (xy 311.15508 -313.949842)
			(xy 311.154585 -313.974449) (xy 311.14669 -314.023026) (xy 311.131106 -314.069707) (xy 311.108235 -314.113284)
			(xy 311.07867 -314.152628) (xy 311.043177 -314.18672) (xy 311.002674 -314.214676) (xy 310.958212 -314.235774)
			(xy 310.910941 -314.249466) (xy 310.862086 -314.255398) (xy 310.812911 -314.253417) (xy 310.764692 -314.243573)
			(xy 310.718676 -314.226121) (xy 310.676055 -314.201514) (xy 310.637934 -314.170389) (xy 310.605299 -314.133552)
			(xy 310.578996 -314.091956) (xy 310.559705 -314.04668) (xy 310.547928 -313.998896) (xy 310.543968 -313.949842)
			(xy 309.25516 -313.949842) (xy 309.254665 -313.974449) (xy 309.24677 -314.023026) (xy 309.231186 -314.069707)
			(xy 309.208315 -314.113284) (xy 309.17875 -314.152628) (xy 309.143257 -314.18672) (xy 309.102754 -314.214676)
			(xy 309.058292 -314.235774) (xy 309.011021 -314.249466) (xy 308.962166 -314.255398) (xy 308.912991 -314.253417)
			(xy 308.864772 -314.243573) (xy 308.818756 -314.226121) (xy 308.776135 -314.201514) (xy 308.738014 -314.170389)
			(xy 308.705379 -314.133552) (xy 308.679076 -314.091956) (xy 308.659785 -314.04668) (xy 308.648008 -313.998896)
			(xy 308.644048 -313.949842) (xy 307.35524 -313.949842) (xy 307.354745 -313.974449) (xy 307.34685 -314.023026)
			(xy 307.331266 -314.069707) (xy 307.308395 -314.113284) (xy 307.27883 -314.152628) (xy 307.243337 -314.18672)
			(xy 307.202834 -314.214676) (xy 307.158372 -314.235774) (xy 307.111101 -314.249466) (xy 307.062246 -314.255398)
			(xy 307.013071 -314.253417) (xy 306.964852 -314.243573) (xy 306.918836 -314.226121) (xy 306.876215 -314.201514)
			(xy 306.838094 -314.170389) (xy 306.805459 -314.133552) (xy 306.779156 -314.091956) (xy 306.759865 -314.04668)
			(xy 306.748088 -313.998896) (xy 306.744128 -313.949842) (xy 305.455066 -313.949842) (xy 305.454571 -313.974449)
			(xy 305.446676 -314.023026) (xy 305.431092 -314.069707) (xy 305.408221 -314.113284) (xy 305.378656 -314.152628)
			(xy 305.343163 -314.18672) (xy 305.30266 -314.214676) (xy 305.258198 -314.235774) (xy 305.210927 -314.249466)
			(xy 305.162072 -314.255398) (xy 305.112897 -314.253417) (xy 305.064678 -314.243573) (xy 305.018662 -314.226121)
			(xy 304.976041 -314.201514) (xy 304.93792 -314.170389) (xy 304.905285 -314.133552) (xy 304.878982 -314.091956)
			(xy 304.859691 -314.04668) (xy 304.847914 -313.998896) (xy 304.843954 -313.949842) (xy 303.555146 -313.949842)
			(xy 303.554651 -313.974449) (xy 303.546756 -314.023026) (xy 303.531172 -314.069707) (xy 303.508301 -314.113284)
			(xy 303.478736 -314.152628) (xy 303.443243 -314.18672) (xy 303.40274 -314.214676) (xy 303.358278 -314.235774)
			(xy 303.311007 -314.249466) (xy 303.262152 -314.255398) (xy 303.212977 -314.253417) (xy 303.164758 -314.243573)
			(xy 303.118742 -314.226121) (xy 303.076121 -314.201514) (xy 303.038 -314.170389) (xy 303.005365 -314.133552)
			(xy 302.979062 -314.091956) (xy 302.959771 -314.04668) (xy 302.947994 -313.998896) (xy 302.944034 -313.949842)
			(xy 301.655226 -313.949842) (xy 301.654731 -313.974449) (xy 301.646836 -314.023026) (xy 301.631252 -314.069707)
			(xy 301.608381 -314.113284) (xy 301.578816 -314.152628) (xy 301.543323 -314.18672) (xy 301.50282 -314.214676)
			(xy 301.458358 -314.235774) (xy 301.411087 -314.249466) (xy 301.362232 -314.255398) (xy 301.313057 -314.253417)
			(xy 301.264838 -314.243573) (xy 301.218822 -314.226121) (xy 301.176201 -314.201514) (xy 301.13808 -314.170389)
			(xy 301.105445 -314.133552) (xy 301.079142 -314.091956) (xy 301.059851 -314.04668) (xy 301.048074 -313.998896)
			(xy 301.044114 -313.949842) (xy 299.755052 -313.949842) (xy 299.754557 -313.974449) (xy 299.746662 -314.023026)
			(xy 299.731078 -314.069707) (xy 299.708207 -314.113284) (xy 299.678642 -314.152628) (xy 299.643149 -314.18672)
			(xy 299.602646 -314.214676) (xy 299.558184 -314.235774) (xy 299.510913 -314.249466) (xy 299.462058 -314.255398)
			(xy 299.412883 -314.253417) (xy 299.364664 -314.243573) (xy 299.318648 -314.226121) (xy 299.276027 -314.201514)
			(xy 299.237906 -314.170389) (xy 299.205271 -314.133552) (xy 299.178968 -314.091956) (xy 299.159677 -314.04668)
			(xy 299.1479 -313.998896) (xy 299.14394 -313.949842) (xy 297.855132 -313.949842) (xy 297.854637 -313.974449)
			(xy 297.846742 -314.023026) (xy 297.831158 -314.069707) (xy 297.808287 -314.113284) (xy 297.778722 -314.152628)
			(xy 297.743229 -314.18672) (xy 297.702726 -314.214676) (xy 297.658264 -314.235774) (xy 297.610993 -314.249466)
			(xy 297.562138 -314.255398) (xy 297.512963 -314.253417) (xy 297.464744 -314.243573) (xy 297.418728 -314.226121)
			(xy 297.376107 -314.201514) (xy 297.337986 -314.170389) (xy 297.305351 -314.133552) (xy 297.279048 -314.091956)
			(xy 297.259757 -314.04668) (xy 297.24798 -313.998896) (xy 297.24402 -313.949842) (xy 295.954756 -313.949842)
			(xy 295.954754 -313.973606) (xy 295.947377 -314.020582) (xy 295.932806 -314.065846) (xy 295.911393 -314.108304)
			(xy 295.883657 -314.146929) (xy 295.867328 -314.164218) (xy 295.860644 -314.171627) (xy 295.853064 -314.190064)
			(xy 295.852596 -314.200032) (xy 295.852596 -314.61456) (xy 295.853033 -314.625375) (xy 295.861851 -314.645118)
			(xy 295.869614 -314.65266) (xy 295.888281 -314.669875) (xy 295.920627 -314.709018) (xy 295.94661 -314.752646)
			(xy 295.965618 -314.799733) (xy 295.977204 -314.849172) (xy 295.981096 -314.899801) (xy 295.977203 -314.95043)
			(xy 295.965617 -314.999869) (xy 295.946609 -315.046956) (xy 295.920626 -315.090584) (xy 295.888279 -315.129727)
			(xy 295.869614 -315.146944) (xy 295.86189 -315.154511) (xy 295.853085 -315.174241) (xy 295.852596 -315.185044)
			(xy 295.852596 -315.563504) (xy 295.85302 -315.573574) (xy 295.860735 -315.592178) (xy 295.867582 -315.599572)
			(xy 296.186098 -315.918088) (xy 296.193496 -315.924936) (xy 296.212094 -315.932673) (xy 296.222166 -315.933074)
			(xy 296.24528 -315.933074) (xy 296.255302 -315.932657) (xy 296.273821 -315.92499) (xy 296.287993 -315.910816)
			(xy 296.295658 -315.892296) (xy 296.29608 -315.882274) (xy 296.29608 -315.879988) (xy 296.295826 -315.877702)
			(xy 296.294556 -315.850016) (xy 296.294556 -315.849762) (xy 296.295029 -315.825772) (xy 296.30254 -315.778382)
			(xy 296.31737 -315.732751) (xy 296.339155 -315.690001) (xy 296.367359 -315.651185) (xy 296.401286 -315.617257)
			(xy 296.440103 -315.589054) (xy 296.482853 -315.56727) (xy 296.528484 -315.55244) (xy 296.575874 -315.544929)
			(xy 296.599864 -315.544454) (xy 296.625761 -315.545005) (xy 296.676812 -315.553752) (xy 296.725657 -315.570983)
			(xy 296.770896 -315.596205) (xy 296.811232 -315.628696) (xy 296.845511 -315.667525) (xy 296.87275 -315.711578)
			(xy 296.892169 -315.759595) (xy 296.903212 -315.810199) (xy 296.904918 -315.836046) (xy 296.905172 -315.845698)
			(xy 296.9133 -315.863732) (xy 296.971212 -315.919104) (xy 296.978535 -315.925483) (xy 296.996561 -315.932664)
			(xy 297.006264 -315.933074) (xy 297.082464 -315.933074) (xy 297.094944 -315.932498) (xy 297.117043 -315.920905)
			(xy 297.124628 -315.910976) (xy 297.124628 -315.910722) (xy 297.145539 -315.880339) (xy 297.191307 -315.82249)
			(xy 297.216068 -315.795152) (xy 297.220353 -315.790259) (xy 297.226527 -315.778815) (xy 297.22826 -315.772546)
			(xy 297.234825 -315.747401) (xy 297.254719 -315.699394) (xy 297.281877 -315.655089) (xy 297.315631 -315.615578)
			(xy 297.35515 -315.581833) (xy 297.399461 -315.554685) (xy 297.447472 -315.534802) (xy 297.472608 -315.528198)
			(xy 297.478883 -315.526478) (xy 297.490334 -315.520309) (xy 297.495214 -315.516006) (xy 297.525058 -315.488969)
			(xy 297.588514 -315.439375) (xy 297.62196 -315.416946) (xy 297.627265 -315.413257) (xy 297.636008 -315.403749)
			(xy 297.639232 -315.39815) (xy 297.659557 -315.360416) (xy 297.705906 -315.288312) (xy 297.758421 -315.220568)
			(xy 297.816695 -315.157709) (xy 297.880276 -315.100224) (xy 297.948671 -315.048558) (xy 298.021347 -315.003114)
			(xy 298.097742 -314.964242) (xy 298.137326 -314.947808) (xy 298.146492 -314.943618) (xy 298.160809 -314.929454)
			(xy 298.168606 -314.910886) (xy 298.169076 -314.900818) (xy 298.169076 -314.899802) (xy 298.169586 -314.873815)
			(xy 298.177716 -314.82248) (xy 298.193777 -314.77305) (xy 298.217373 -314.72674) (xy 298.247923 -314.684692)
			(xy 298.284674 -314.647941) (xy 298.326722 -314.617391) (xy 298.373032 -314.593795) (xy 298.422462 -314.577734)
			(xy 298.473797 -314.569604) (xy 298.525771 -314.569604) (xy 298.577106 -314.577734) (xy 298.626536 -314.593795)
			(xy 298.672846 -314.617391) (xy 298.714894 -314.647941) (xy 298.751645 -314.684692) (xy 298.782195 -314.72674)
			(xy 298.805791 -314.77305) (xy 298.821852 -314.82248) (xy 298.829982 -314.873815) (xy 298.830492 -314.899802)
			(xy 298.830492 -314.900818) (xy 298.830916 -314.910898) (xy 298.838687 -314.9295) (xy 298.853051 -314.943646)
			(xy 298.862242 -314.947808) (xy 298.901482 -314.964063) (xy 298.977234 -315.002494) (xy 299.049341 -315.047392)
			(xy 299.117253 -315.098413) (xy 299.180452 -315.155169) (xy 299.238454 -315.217226) (xy 299.290817 -315.284109)
			(xy 299.337141 -315.355308) (xy 299.357542 -315.392562) (xy 299.362622 -315.402214) (xy 299.37964 -315.415422)
			(xy 299.474636 -315.438536) (xy 299.495718 -315.434726) (xy 299.504608 -315.42863) (xy 299.52188 -315.416946)
			(xy 299.527183 -315.413255) (xy 299.535923 -315.403746) (xy 299.539152 -315.39815) (xy 299.559476 -315.360414)
			(xy 299.605822 -315.288307) (xy 299.658335 -315.220559) (xy 299.716608 -315.157697) (xy 299.780187 -315.100207)
			(xy 299.848579 -315.048536) (xy 299.921254 -315.003085) (xy 299.997647 -314.964207) (xy 300.037246 -314.947808)
			(xy 300.046409 -314.943615) (xy 300.06072 -314.929451) (xy 300.068514 -314.910884) (xy 300.068996 -314.900818)
			(xy 300.068996 -314.899802) (xy 300.069506 -314.873815) (xy 300.077636 -314.82248) (xy 300.093697 -314.77305)
			(xy 300.117293 -314.72674) (xy 300.147843 -314.684692) (xy 300.184594 -314.647941) (xy 300.226642 -314.617391)
			(xy 300.272952 -314.593795) (xy 300.322382 -314.577734) (xy 300.373717 -314.569604) (xy 300.425691 -314.569604)
			(xy 300.477026 -314.577734) (xy 300.526456 -314.593795) (xy 300.572766 -314.617391) (xy 300.614814 -314.647941)
			(xy 300.651565 -314.684692) (xy 300.682115 -314.72674) (xy 300.705711 -314.77305) (xy 300.721772 -314.82248)
			(xy 300.729902 -314.873815) (xy 300.730412 -314.899802) (xy 300.730412 -314.900818) (xy 300.730836 -314.910898)
			(xy 300.738609 -314.929497) (xy 300.752975 -314.943637) (xy 300.762162 -314.947808) (xy 300.801414 -314.964069)
			(xy 300.877188 -315.002515) (xy 300.949313 -315.047434) (xy 301.017239 -315.098481) (xy 301.080447 -315.155266)
			(xy 301.138453 -315.217355) (xy 301.190813 -315.284274) (xy 301.237128 -315.355511) (xy 301.257462 -315.392816)
			(xy 301.262542 -315.402468) (xy 301.27956 -315.415676) (xy 301.363888 -315.43625) (xy 301.37447 -315.438301)
			(xy 301.395641 -315.434345) (xy 301.404782 -315.42863) (xy 301.422054 -315.416946) (xy 301.427359 -315.413257)
			(xy 301.436103 -315.40375) (xy 301.439326 -315.39815) (xy 301.459651 -315.360416) (xy 301.506 -315.288312)
			(xy 301.558515 -315.220567) (xy 301.616789 -315.157708) (xy 301.68037 -315.100223) (xy 301.748764 -315.048557)
			(xy 301.82144 -315.003111) (xy 301.897835 -314.96424) (xy 301.93742 -314.947808) (xy 301.946587 -314.943618)
			(xy 301.960906 -314.929455) (xy 301.968703 -314.910886) (xy 301.96917 -314.900818) (xy 301.96917 -314.899802)
			(xy 301.96968 -314.873815) (xy 301.97781 -314.82248) (xy 301.993871 -314.77305) (xy 302.017467 -314.72674)
			(xy 302.048017 -314.684692) (xy 302.084768 -314.647941) (xy 302.126816 -314.617391) (xy 302.173126 -314.593795)
			(xy 302.222556 -314.577734) (xy 302.273891 -314.569604) (xy 302.325865 -314.569604) (xy 302.3772 -314.577734)
			(xy 302.42663 -314.593795) (xy 302.47294 -314.617391) (xy 302.514988 -314.647941) (xy 302.551739 -314.684692)
			(xy 302.582289 -314.72674) (xy 302.605885 -314.77305) (xy 302.621946 -314.82248) (xy 302.630076 -314.873815)
			(xy 302.630586 -314.899802) (xy 302.630586 -314.900818) (xy 302.63101 -314.910899) (xy 302.63878 -314.929501)
			(xy 302.653143 -314.943649) (xy 302.662336 -314.947808) (xy 302.701576 -314.964063) (xy 302.777328 -315.002494)
			(xy 302.849436 -315.047391) (xy 302.917348 -315.098412) (xy 302.980547 -315.155168) (xy 303.03855 -315.217224)
			(xy 303.090913 -315.284107) (xy 303.137237 -315.355307) (xy 303.157636 -315.392562) (xy 303.162716 -315.402214)
			(xy 303.179734 -315.415422) (xy 303.27473 -315.438536) (xy 303.295812 -315.434726) (xy 303.304702 -315.42863)
			(xy 303.321974 -315.416946) (xy 303.327278 -315.413256) (xy 303.336019 -315.403747) (xy 303.339246 -315.39815)
			(xy 303.359572 -315.360416) (xy 303.40592 -315.288313) (xy 303.458436 -315.22057) (xy 303.516711 -315.157712)
			(xy 303.580292 -315.100227) (xy 303.648687 -315.048562) (xy 303.721364 -315.003119) (xy 303.797758 -314.964248)
			(xy 303.83734 -314.947808) (xy 303.846504 -314.943616) (xy 303.860817 -314.929452) (xy 303.868611 -314.910884)
			(xy 303.86909 -314.900818) (xy 303.86909 -314.899802) (xy 303.8696 -314.873815) (xy 303.87773 -314.82248)
			(xy 303.893791 -314.77305) (xy 303.917387 -314.72674) (xy 303.947937 -314.684692) (xy 303.984688 -314.647941)
			(xy 304.026736 -314.617391) (xy 304.073046 -314.593795) (xy 304.122476 -314.577734) (xy 304.173811 -314.569604)
			(xy 304.225785 -314.569604) (xy 304.27712 -314.577734) (xy 304.32655 -314.593795) (xy 304.37286 -314.617391)
			(xy 304.414908 -314.647941) (xy 304.451659 -314.684692) (xy 304.482209 -314.72674) (xy 304.505805 -314.77305)
			(xy 304.521866 -314.82248) (xy 304.529996 -314.873815) (xy 304.530506 -314.899802) (xy 313.394102 -314.899802)
			(xy 313.398062 -314.850748) (xy 313.409839 -314.802964) (xy 313.42913 -314.757688) (xy 313.455433 -314.716092)
			(xy 313.488068 -314.679255) (xy 313.526189 -314.64813) (xy 313.56881 -314.623523) (xy 313.614826 -314.606071)
			(xy 313.663045 -314.596227) (xy 313.71222 -314.594246) (xy 313.761075 -314.600178) (xy 313.808346 -314.61387)
			(xy 313.852808 -314.634968) (xy 313.893311 -314.662924) (xy 313.928804 -314.697016) (xy 313.958369 -314.73636)
			(xy 313.98124 -314.779937) (xy 313.996824 -314.826618) (xy 314.004719 -314.875195) (xy 314.005214 -314.899802)
			(xy 314.344062 -314.899802) (xy 314.348022 -314.850748) (xy 314.359799 -314.802964) (xy 314.37909 -314.757688)
			(xy 314.405393 -314.716092) (xy 314.438028 -314.679255) (xy 314.476149 -314.64813) (xy 314.51877 -314.623523)
			(xy 314.564786 -314.606071) (xy 314.613005 -314.596227) (xy 314.66218 -314.594246) (xy 314.711035 -314.600178)
			(xy 314.758306 -314.61387) (xy 314.802768 -314.634968) (xy 314.843271 -314.662924) (xy 314.878764 -314.697016)
			(xy 314.908329 -314.73636) (xy 314.9312 -314.779937) (xy 314.946784 -314.826618) (xy 314.954679 -314.875195)
			(xy 314.955174 -314.899802) (xy 314.954679 -314.924409) (xy 314.946784 -314.972986) (xy 314.9312 -315.019667)
			(xy 314.908329 -315.063244) (xy 314.878764 -315.102588) (xy 314.843271 -315.13668) (xy 314.802768 -315.164636)
			(xy 314.758306 -315.185734) (xy 314.711035 -315.199426) (xy 314.66218 -315.205358) (xy 314.613005 -315.203377)
			(xy 314.564786 -315.193533) (xy 314.51877 -315.176081) (xy 314.476149 -315.151474) (xy 314.438028 -315.120349)
			(xy 314.405393 -315.083512) (xy 314.37909 -315.041916) (xy 314.359799 -314.99664) (xy 314.348022 -314.948856)
			(xy 314.344062 -314.899802) (xy 314.005214 -314.899802) (xy 314.004719 -314.924409) (xy 313.996824 -314.972986)
			(xy 313.98124 -315.019667) (xy 313.958369 -315.063244) (xy 313.928804 -315.102588) (xy 313.893311 -315.13668)
			(xy 313.852808 -315.164636) (xy 313.808346 -315.185734) (xy 313.761075 -315.199426) (xy 313.71222 -315.205358)
			(xy 313.663045 -315.203377) (xy 313.614826 -315.193533) (xy 313.56881 -315.176081) (xy 313.526189 -315.151474)
			(xy 313.488068 -315.120349) (xy 313.455433 -315.083512) (xy 313.42913 -315.041916) (xy 313.409839 -314.99664)
			(xy 313.398062 -314.948856) (xy 313.394102 -314.899802) (xy 304.530506 -314.899802) (xy 304.530506 -314.900818)
			(xy 304.53093 -314.910898) (xy 304.538702 -314.929498) (xy 304.553067 -314.94364) (xy 304.562256 -314.947808)
			(xy 304.602499 -314.964503) (xy 304.680115 -315.004097) (xy 304.753876 -315.050478) (xy 304.82319 -315.103274)
			(xy 304.887501 -315.162062) (xy 304.946293 -315.22637) (xy 304.999093 -315.295681) (xy 305.045478 -315.36944)
			(xy 305.085075 -315.447054) (xy 305.101752 -315.487304) (xy 305.105938 -315.496477) (xy 305.120098 -315.510811)
			(xy 305.13867 -315.518626) (xy 305.148742 -315.519054) (xy 305.149758 -315.519054) (xy 305.175751 -315.519534)
			(xy 305.227096 -315.52766) (xy 305.276539 -315.543718) (xy 305.322861 -315.567313) (xy 305.364921 -315.597864)
			(xy 305.401684 -315.634618) (xy 305.432245 -315.676671) (xy 305.455852 -315.722987) (xy 305.471922 -315.772426)
			(xy 305.48006 -315.82377) (xy 305.480466 -315.849762) (xy 305.793914 -315.849762) (xy 305.797874 -315.800708)
			(xy 305.809651 -315.752924) (xy 305.828942 -315.707648) (xy 305.855245 -315.666052) (xy 305.88788 -315.629215)
			(xy 305.926001 -315.59809) (xy 305.968622 -315.573483) (xy 306.014638 -315.556031) (xy 306.062857 -315.546187)
			(xy 306.112032 -315.544206) (xy 306.160887 -315.550138) (xy 306.208158 -315.56383) (xy 306.25262 -315.584928)
			(xy 306.293123 -315.612884) (xy 306.328616 -315.646976) (xy 306.358181 -315.68632) (xy 306.381052 -315.729897)
			(xy 306.396636 -315.776578) (xy 306.404531 -315.825155) (xy 306.405026 -315.849762) (xy 307.694088 -315.849762)
			(xy 307.698048 -315.800708) (xy 307.709825 -315.752924) (xy 307.729116 -315.707648) (xy 307.755419 -315.666052)
			(xy 307.788054 -315.629215) (xy 307.826175 -315.59809) (xy 307.868796 -315.573483) (xy 307.914812 -315.556031)
			(xy 307.963031 -315.546187) (xy 308.012206 -315.544206) (xy 308.061061 -315.550138) (xy 308.108332 -315.56383)
			(xy 308.152794 -315.584928) (xy 308.193297 -315.612884) (xy 308.22879 -315.646976) (xy 308.258355 -315.68632)
			(xy 308.281226 -315.729897) (xy 308.29681 -315.776578) (xy 308.304705 -315.825155) (xy 308.3052 -315.849762)
			(xy 309.594008 -315.849762) (xy 309.597968 -315.800708) (xy 309.609745 -315.752924) (xy 309.629036 -315.707648)
			(xy 309.655339 -315.666052) (xy 309.687974 -315.629215) (xy 309.726095 -315.59809) (xy 309.768716 -315.573483)
			(xy 309.814732 -315.556031) (xy 309.862951 -315.546187) (xy 309.912126 -315.544206) (xy 309.960981 -315.550138)
			(xy 310.008252 -315.56383) (xy 310.052714 -315.584928) (xy 310.093217 -315.612884) (xy 310.12871 -315.646976)
			(xy 310.158275 -315.68632) (xy 310.181146 -315.729897) (xy 310.19673 -315.776578) (xy 310.204625 -315.825155)
			(xy 310.20512 -315.849762) (xy 311.493928 -315.849762) (xy 311.497888 -315.800708) (xy 311.509665 -315.752924)
			(xy 311.528956 -315.707648) (xy 311.555259 -315.666052) (xy 311.587894 -315.629215) (xy 311.626015 -315.59809)
			(xy 311.668636 -315.573483) (xy 311.714652 -315.556031) (xy 311.762871 -315.546187) (xy 311.812046 -315.544206)
			(xy 311.860901 -315.550138) (xy 311.908172 -315.56383) (xy 311.952634 -315.584928) (xy 311.993137 -315.612884)
			(xy 312.02863 -315.646976) (xy 312.058195 -315.68632) (xy 312.081066 -315.729897) (xy 312.09665 -315.776578)
			(xy 312.104545 -315.825155) (xy 312.10504 -315.849762) (xy 312.104545 -315.874369) (xy 312.09665 -315.922946)
			(xy 312.081066 -315.969627) (xy 312.058195 -316.013204) (xy 312.02863 -316.052548) (xy 311.993137 -316.08664)
			(xy 311.952634 -316.114596) (xy 311.908172 -316.135694) (xy 311.860901 -316.149386) (xy 311.812046 -316.155318)
			(xy 311.762871 -316.153337) (xy 311.714652 -316.143493) (xy 311.668636 -316.126041) (xy 311.626015 -316.101434)
			(xy 311.587894 -316.070309) (xy 311.555259 -316.033472) (xy 311.528956 -315.991876) (xy 311.509665 -315.9466)
			(xy 311.497888 -315.898816) (xy 311.493928 -315.849762) (xy 310.20512 -315.849762) (xy 310.204625 -315.874369)
			(xy 310.19673 -315.922946) (xy 310.181146 -315.969627) (xy 310.158275 -316.013204) (xy 310.12871 -316.052548)
			(xy 310.093217 -316.08664) (xy 310.052714 -316.114596) (xy 310.008252 -316.135694) (xy 309.960981 -316.149386)
			(xy 309.912126 -316.155318) (xy 309.862951 -316.153337) (xy 309.814732 -316.143493) (xy 309.768716 -316.126041)
			(xy 309.726095 -316.101434) (xy 309.687974 -316.070309) (xy 309.655339 -316.033472) (xy 309.629036 -315.991876)
			(xy 309.609745 -315.9466) (xy 309.597968 -315.898816) (xy 309.594008 -315.849762) (xy 308.3052 -315.849762)
			(xy 308.304705 -315.874369) (xy 308.29681 -315.922946) (xy 308.281226 -315.969627) (xy 308.258355 -316.013204)
			(xy 308.22879 -316.052548) (xy 308.193297 -316.08664) (xy 308.152794 -316.114596) (xy 308.108332 -316.135694)
			(xy 308.061061 -316.149386) (xy 308.012206 -316.155318) (xy 307.963031 -316.153337) (xy 307.914812 -316.143493)
			(xy 307.868796 -316.126041) (xy 307.826175 -316.101434) (xy 307.788054 -316.070309) (xy 307.755419 -316.033472)
			(xy 307.729116 -315.991876) (xy 307.709825 -315.9466) (xy 307.698048 -315.898816) (xy 307.694088 -315.849762)
			(xy 306.405026 -315.849762) (xy 306.404531 -315.874369) (xy 306.396636 -315.922946) (xy 306.381052 -315.969627)
			(xy 306.358181 -316.013204) (xy 306.328616 -316.052548) (xy 306.293123 -316.08664) (xy 306.25262 -316.114596)
			(xy 306.208158 -316.135694) (xy 306.160887 -316.149386) (xy 306.112032 -316.155318) (xy 306.062857 -316.153337)
			(xy 306.014638 -316.143493) (xy 305.968622 -316.126041) (xy 305.926001 -316.101434) (xy 305.88788 -316.070309)
			(xy 305.855245 -316.033472) (xy 305.828942 -315.991876) (xy 305.809651 -315.9466) (xy 305.797874 -315.898816)
			(xy 305.793914 -315.849762) (xy 305.480466 -315.849762) (xy 305.480128 -315.871498) (xy 305.474432 -315.914596)
			(xy 305.463121 -315.956571) (xy 305.455066 -315.976762) (xy 305.451531 -315.986206) (xy 305.451442 -316.006354)
			(xy 305.459161 -316.024965) (xy 305.465988 -316.032388) (xy 305.947572 -316.513972) (xy 305.976528 -316.520068)
			(xy 305.990752 -316.51448) (xy 306.016951 -316.505125) (xy 306.071652 -316.495029) (xy 306.099464 -316.494414)
			(xy 306.099718 -316.494414) (xy 306.12371 -316.494862) (xy 306.171102 -316.502371) (xy 306.216735 -316.517201)
			(xy 306.259487 -316.538988) (xy 306.298305 -316.567194) (xy 306.332232 -316.601126) (xy 306.360433 -316.639947)
			(xy 306.382214 -316.682702) (xy 306.397039 -316.728337) (xy 306.404542 -316.77573) (xy 306.405026 -316.799722)
			(xy 307.694088 -316.799722) (xy 307.698048 -316.750668) (xy 307.709825 -316.702884) (xy 307.729116 -316.657608)
			(xy 307.755419 -316.616012) (xy 307.788054 -316.579175) (xy 307.826175 -316.54805) (xy 307.868796 -316.523443)
			(xy 307.914812 -316.505991) (xy 307.963031 -316.496147) (xy 308.012206 -316.494166) (xy 308.061061 -316.500098)
			(xy 308.108332 -316.51379) (xy 308.152794 -316.534888) (xy 308.193297 -316.562844) (xy 308.22879 -316.596936)
			(xy 308.258355 -316.63628) (xy 308.281226 -316.679857) (xy 308.29681 -316.726538) (xy 308.304705 -316.775115)
			(xy 308.3052 -316.799722) (xy 309.594008 -316.799722) (xy 309.597968 -316.750668) (xy 309.609745 -316.702884)
			(xy 309.629036 -316.657608) (xy 309.655339 -316.616012) (xy 309.687974 -316.579175) (xy 309.726095 -316.54805)
			(xy 309.768716 -316.523443) (xy 309.814732 -316.505991) (xy 309.862951 -316.496147) (xy 309.912126 -316.494166)
			(xy 309.960981 -316.500098) (xy 310.008252 -316.51379) (xy 310.052714 -316.534888) (xy 310.093217 -316.562844)
			(xy 310.12871 -316.596936) (xy 310.158275 -316.63628) (xy 310.181146 -316.679857) (xy 310.19673 -316.726538)
			(xy 310.204625 -316.775115) (xy 310.20512 -316.799722) (xy 311.493928 -316.799722) (xy 311.497888 -316.750668)
			(xy 311.509665 -316.702884) (xy 311.528956 -316.657608) (xy 311.555259 -316.616012) (xy 311.587894 -316.579175)
			(xy 311.626015 -316.54805) (xy 311.668636 -316.523443) (xy 311.714652 -316.505991) (xy 311.762871 -316.496147)
			(xy 311.812046 -316.494166) (xy 311.860901 -316.500098) (xy 311.908172 -316.51379) (xy 311.952634 -316.534888)
			(xy 311.993137 -316.562844) (xy 312.02863 -316.596936) (xy 312.058195 -316.63628) (xy 312.081066 -316.679857)
			(xy 312.09665 -316.726538) (xy 312.104545 -316.775115) (xy 312.10504 -316.799722) (xy 313.394102 -316.799722)
			(xy 313.398062 -316.750668) (xy 313.409839 -316.702884) (xy 313.42913 -316.657608) (xy 313.455433 -316.616012)
			(xy 313.488068 -316.579175) (xy 313.526189 -316.54805) (xy 313.56881 -316.523443) (xy 313.614826 -316.505991)
			(xy 313.663045 -316.496147) (xy 313.71222 -316.494166) (xy 313.761075 -316.500098) (xy 313.808346 -316.51379)
			(xy 313.852808 -316.534888) (xy 313.893311 -316.562844) (xy 313.928804 -316.596936) (xy 313.958369 -316.63628)
			(xy 313.98124 -316.679857) (xy 313.996824 -316.726538) (xy 314.004719 -316.775115) (xy 314.005214 -316.799722)
			(xy 314.344062 -316.799722) (xy 314.348022 -316.750668) (xy 314.359799 -316.702884) (xy 314.37909 -316.657608)
			(xy 314.405393 -316.616012) (xy 314.438028 -316.579175) (xy 314.476149 -316.54805) (xy 314.51877 -316.523443)
			(xy 314.564786 -316.505991) (xy 314.613005 -316.496147) (xy 314.66218 -316.494166) (xy 314.711035 -316.500098)
			(xy 314.758306 -316.51379) (xy 314.802768 -316.534888) (xy 314.843271 -316.562844) (xy 314.878764 -316.596936)
			(xy 314.908329 -316.63628) (xy 314.9312 -316.679857) (xy 314.946784 -316.726538) (xy 314.954679 -316.775115)
			(xy 314.955174 -316.799722) (xy 314.954679 -316.824329) (xy 314.946784 -316.872906) (xy 314.9312 -316.919587)
			(xy 314.908329 -316.963164) (xy 314.878764 -317.002508) (xy 314.843271 -317.0366) (xy 314.802768 -317.064556)
			(xy 314.758306 -317.085654) (xy 314.711035 -317.099346) (xy 314.66218 -317.105278) (xy 314.613005 -317.103297)
			(xy 314.564786 -317.093453) (xy 314.51877 -317.076001) (xy 314.476149 -317.051394) (xy 314.438028 -317.020269)
			(xy 314.405393 -316.983432) (xy 314.37909 -316.941836) (xy 314.359799 -316.89656) (xy 314.348022 -316.848776)
			(xy 314.344062 -316.799722) (xy 314.005214 -316.799722) (xy 314.004719 -316.824329) (xy 313.996824 -316.872906)
			(xy 313.98124 -316.919587) (xy 313.958369 -316.963164) (xy 313.928804 -317.002508) (xy 313.893311 -317.0366)
			(xy 313.852808 -317.064556) (xy 313.808346 -317.085654) (xy 313.761075 -317.099346) (xy 313.71222 -317.105278)
			(xy 313.663045 -317.103297) (xy 313.614826 -317.093453) (xy 313.56881 -317.076001) (xy 313.526189 -317.051394)
			(xy 313.488068 -317.020269) (xy 313.455433 -316.983432) (xy 313.42913 -316.941836) (xy 313.409839 -316.89656)
			(xy 313.398062 -316.848776) (xy 313.394102 -316.799722) (xy 312.10504 -316.799722) (xy 312.104545 -316.824329)
			(xy 312.09665 -316.872906) (xy 312.081066 -316.919587) (xy 312.058195 -316.963164) (xy 312.02863 -317.002508)
			(xy 311.993137 -317.0366) (xy 311.952634 -317.064556) (xy 311.908172 -317.085654) (xy 311.860901 -317.099346)
			(xy 311.812046 -317.105278) (xy 311.762871 -317.103297) (xy 311.714652 -317.093453) (xy 311.668636 -317.076001)
			(xy 311.626015 -317.051394) (xy 311.587894 -317.020269) (xy 311.555259 -316.983432) (xy 311.528956 -316.941836)
			(xy 311.509665 -316.89656) (xy 311.497888 -316.848776) (xy 311.493928 -316.799722) (xy 310.20512 -316.799722)
			(xy 310.204625 -316.824329) (xy 310.19673 -316.872906) (xy 310.181146 -316.919587) (xy 310.158275 -316.963164)
			(xy 310.12871 -317.002508) (xy 310.093217 -317.0366) (xy 310.052714 -317.064556) (xy 310.008252 -317.085654)
			(xy 309.960981 -317.099346) (xy 309.912126 -317.105278) (xy 309.862951 -317.103297) (xy 309.814732 -317.093453)
			(xy 309.768716 -317.076001) (xy 309.726095 -317.051394) (xy 309.687974 -317.020269) (xy 309.655339 -316.983432)
			(xy 309.629036 -316.941836) (xy 309.609745 -316.89656) (xy 309.597968 -316.848776) (xy 309.594008 -316.799722)
			(xy 308.3052 -316.799722) (xy 308.304705 -316.824329) (xy 308.29681 -316.872906) (xy 308.281226 -316.919587)
			(xy 308.258355 -316.963164) (xy 308.22879 -317.002508) (xy 308.193297 -317.0366) (xy 308.152794 -317.064556)
			(xy 308.108332 -317.085654) (xy 308.061061 -317.099346) (xy 308.012206 -317.105278) (xy 307.963031 -317.103297)
			(xy 307.914812 -317.093453) (xy 307.868796 -317.076001) (xy 307.826175 -317.051394) (xy 307.788054 -317.020269)
			(xy 307.755419 -316.983432) (xy 307.729116 -316.941836) (xy 307.709825 -316.89656) (xy 307.698048 -316.848776)
			(xy 307.694088 -316.799722) (xy 306.405026 -316.799722) (xy 306.405026 -316.799976) (xy 306.404387 -316.827786)
			(xy 306.39429 -316.882482) (xy 306.38496 -316.908688) (xy 306.379372 -316.922912) (xy 306.385468 -316.951868)
			(xy 306.708048 -317.274448) (xy 306.714892 -317.281847) (xy 306.722618 -317.300445) (xy 306.723034 -317.310516)
			(xy 306.723034 -317.4111) (xy 306.723435 -317.420299) (xy 306.729923 -317.437515) (xy 306.742038 -317.451362)
			(xy 306.749958 -317.456058) (xy 306.841398 -317.504826) (xy 306.869084 -317.503302) (xy 306.880768 -317.495682)
			(xy 306.899634 -317.483625) (xy 306.940146 -317.464562) (xy 306.983004 -317.451607) (xy 307.027292 -317.445035)
			(xy 307.049678 -317.444628) (xy 307.049932 -317.444628) (xy 307.075183 -317.445152) (xy 307.124994 -317.453469)
			(xy 307.172758 -317.469871) (xy 307.217171 -317.49391) (xy 307.257022 -317.524931) (xy 307.291224 -317.562087)
			(xy 307.318843 -317.604367) (xy 307.339128 -317.650615) (xy 307.351525 -317.699571) (xy 307.355695 -317.7499)
			(xy 307.355692 -317.749936) (xy 308.644048 -317.749936) (xy 308.648008 -317.700882) (xy 308.659785 -317.653098)
			(xy 308.679076 -317.607822) (xy 308.705379 -317.566226) (xy 308.738014 -317.529389) (xy 308.776135 -317.498264)
			(xy 308.818756 -317.473657) (xy 308.864772 -317.456205) (xy 308.912991 -317.446361) (xy 308.962166 -317.44438)
			(xy 309.011021 -317.450312) (xy 309.058292 -317.464004) (xy 309.102754 -317.485102) (xy 309.143257 -317.513058)
			(xy 309.17875 -317.54715) (xy 309.208315 -317.586494) (xy 309.231186 -317.630071) (xy 309.24677 -317.676752)
			(xy 309.254665 -317.725329) (xy 309.25516 -317.749936) (xy 310.543968 -317.749936) (xy 310.547928 -317.700882)
			(xy 310.559705 -317.653098) (xy 310.578996 -317.607822) (xy 310.605299 -317.566226) (xy 310.637934 -317.529389)
			(xy 310.676055 -317.498264) (xy 310.718676 -317.473657) (xy 310.764692 -317.456205) (xy 310.812911 -317.446361)
			(xy 310.862086 -317.44438) (xy 310.910941 -317.450312) (xy 310.958212 -317.464004) (xy 311.002674 -317.485102)
			(xy 311.043177 -317.513058) (xy 311.07867 -317.54715) (xy 311.108235 -317.586494) (xy 311.131106 -317.630071)
			(xy 311.14669 -317.676752) (xy 311.154585 -317.725329) (xy 311.15508 -317.749936) (xy 312.443888 -317.749936)
			(xy 312.447848 -317.700882) (xy 312.459625 -317.653098) (xy 312.478916 -317.607822) (xy 312.505219 -317.566226)
			(xy 312.537854 -317.529389) (xy 312.575975 -317.498264) (xy 312.618596 -317.473657) (xy 312.664612 -317.456205)
			(xy 312.712831 -317.446361) (xy 312.762006 -317.44438) (xy 312.810861 -317.450312) (xy 312.858132 -317.464004)
			(xy 312.902594 -317.485102) (xy 312.943097 -317.513058) (xy 312.97859 -317.54715) (xy 313.008155 -317.586494)
			(xy 313.031026 -317.630071) (xy 313.04661 -317.676752) (xy 313.054505 -317.725329) (xy 313.055 -317.749936)
			(xy 313.054505 -317.774543) (xy 313.04661 -317.82312) (xy 313.031026 -317.869801) (xy 313.008155 -317.913378)
			(xy 312.97859 -317.952722) (xy 312.943097 -317.986814) (xy 312.902594 -318.01477) (xy 312.858132 -318.035868)
			(xy 312.810861 -318.04956) (xy 312.762006 -318.055492) (xy 312.712831 -318.053511) (xy 312.664612 -318.043667)
			(xy 312.618596 -318.026215) (xy 312.575975 -318.001608) (xy 312.537854 -317.970483) (xy 312.505219 -317.933646)
			(xy 312.478916 -317.89205) (xy 312.459625 -317.846774) (xy 312.447848 -317.79899) (xy 312.443888 -317.749936)
			(xy 311.15508 -317.749936) (xy 311.154585 -317.774543) (xy 311.14669 -317.82312) (xy 311.131106 -317.869801)
			(xy 311.108235 -317.913378) (xy 311.07867 -317.952722) (xy 311.043177 -317.986814) (xy 311.002674 -318.01477)
			(xy 310.958212 -318.035868) (xy 310.910941 -318.04956) (xy 310.862086 -318.055492) (xy 310.812911 -318.053511)
			(xy 310.764692 -318.043667) (xy 310.718676 -318.026215) (xy 310.676055 -318.001608) (xy 310.637934 -317.970483)
			(xy 310.605299 -317.933646) (xy 310.578996 -317.89205) (xy 310.559705 -317.846774) (xy 310.547928 -317.79899)
			(xy 310.543968 -317.749936) (xy 309.25516 -317.749936) (xy 309.254665 -317.774543) (xy 309.24677 -317.82312)
			(xy 309.231186 -317.869801) (xy 309.208315 -317.913378) (xy 309.17875 -317.952722) (xy 309.143257 -317.986814)
			(xy 309.102754 -318.01477) (xy 309.058292 -318.035868) (xy 309.011021 -318.04956) (xy 308.962166 -318.055492)
			(xy 308.912991 -318.053511) (xy 308.864772 -318.043667) (xy 308.818756 -318.026215) (xy 308.776135 -318.001608)
			(xy 308.738014 -317.970483) (xy 308.705379 -317.933646) (xy 308.679076 -317.89205) (xy 308.659785 -317.846774)
			(xy 308.648008 -317.79899) (xy 308.644048 -317.749936) (xy 307.355692 -317.749936) (xy 307.351525 -317.800229)
			(xy 307.339128 -317.849185) (xy 307.318843 -317.895433) (xy 307.291224 -317.937713) (xy 307.257022 -317.974869)
			(xy 307.217171 -318.00589) (xy 307.172758 -318.029929) (xy 307.124994 -318.046331) (xy 307.075183 -318.054648)
			(xy 307.049932 -318.055244) (xy 307.049678 -318.055244) (xy 307.027289 -318.054854) (xy 306.982992 -318.048311)
			(xy 306.940131 -318.035354) (xy 306.899627 -318.016262) (xy 306.880768 -318.00419) (xy 306.869084 -317.99657)
			(xy 306.841398 -317.995046) (xy 306.749958 -318.043814) (xy 306.742005 -318.048475) (xy 306.729847 -318.062309)
			(xy 306.723397 -318.079561) (xy 306.723034 -318.088772) (xy 306.723034 -318.36106) (xy 306.723429 -318.370262)
			(xy 306.729908 -318.38749) (xy 306.74202 -318.401348) (xy 306.749958 -318.406018) (xy 306.841398 -318.454786)
			(xy 306.869084 -318.453262) (xy 306.880768 -318.445642) (xy 306.899634 -318.433583) (xy 306.940145 -318.414516)
			(xy 306.983003 -318.401558) (xy 307.027291 -318.394986) (xy 307.049678 -318.394588) (xy 307.049932 -318.394588)
			(xy 307.075186 -318.395112) (xy 307.125004 -318.40343) (xy 307.172774 -318.419834) (xy 307.217193 -318.443876)
			(xy 307.257049 -318.474901) (xy 307.291255 -318.512063) (xy 307.318879 -318.554348) (xy 307.339166 -318.600602)
			(xy 307.351564 -318.649565) (xy 307.355735 -318.699896) (xy 308.644048 -318.699896) (xy 308.648008 -318.650842)
			(xy 308.659785 -318.603058) (xy 308.679076 -318.557782) (xy 308.705379 -318.516186) (xy 308.738014 -318.479349)
			(xy 308.776135 -318.448224) (xy 308.818756 -318.423617) (xy 308.864772 -318.406165) (xy 308.912991 -318.396321)
			(xy 308.962166 -318.39434) (xy 309.011021 -318.400272) (xy 309.058292 -318.413964) (xy 309.102754 -318.435062)
			(xy 309.143257 -318.463018) (xy 309.17875 -318.49711) (xy 309.208315 -318.536454) (xy 309.231186 -318.580031)
			(xy 309.24677 -318.626712) (xy 309.254665 -318.675289) (xy 309.25516 -318.699896) (xy 310.543968 -318.699896)
			(xy 310.547928 -318.650842) (xy 310.559705 -318.603058) (xy 310.578996 -318.557782) (xy 310.605299 -318.516186)
			(xy 310.637934 -318.479349) (xy 310.676055 -318.448224) (xy 310.718676 -318.423617) (xy 310.764692 -318.406165)
			(xy 310.812911 -318.396321) (xy 310.862086 -318.39434) (xy 310.910941 -318.400272) (xy 310.958212 -318.413964)
			(xy 311.002674 -318.435062) (xy 311.043177 -318.463018) (xy 311.07867 -318.49711) (xy 311.108235 -318.536454)
			(xy 311.131106 -318.580031) (xy 311.14669 -318.626712) (xy 311.154585 -318.675289) (xy 311.15508 -318.699896)
			(xy 312.443888 -318.699896) (xy 312.447848 -318.650842) (xy 312.459625 -318.603058) (xy 312.478916 -318.557782)
			(xy 312.505219 -318.516186) (xy 312.537854 -318.479349) (xy 312.575975 -318.448224) (xy 312.618596 -318.423617)
			(xy 312.664612 -318.406165) (xy 312.712831 -318.396321) (xy 312.762006 -318.39434) (xy 312.810861 -318.400272)
			(xy 312.858132 -318.413964) (xy 312.902594 -318.435062) (xy 312.943097 -318.463018) (xy 312.97859 -318.49711)
			(xy 313.008155 -318.536454) (xy 313.031026 -318.580031) (xy 313.04661 -318.626712) (xy 313.054505 -318.675289)
			(xy 313.055 -318.699896) (xy 313.054505 -318.724503) (xy 313.04661 -318.77308) (xy 313.031026 -318.819761)
			(xy 313.008155 -318.863338) (xy 312.97859 -318.902682) (xy 312.943097 -318.936774) (xy 312.902594 -318.96473)
			(xy 312.858132 -318.985828) (xy 312.810861 -318.99952) (xy 312.762006 -319.005452) (xy 312.712831 -319.003471)
			(xy 312.664612 -318.993627) (xy 312.618596 -318.976175) (xy 312.575975 -318.951568) (xy 312.537854 -318.920443)
			(xy 312.505219 -318.883606) (xy 312.478916 -318.84201) (xy 312.459625 -318.796734) (xy 312.447848 -318.74895)
			(xy 312.443888 -318.699896) (xy 311.15508 -318.699896) (xy 311.154585 -318.724503) (xy 311.14669 -318.77308)
			(xy 311.131106 -318.819761) (xy 311.108235 -318.863338) (xy 311.07867 -318.902682) (xy 311.043177 -318.936774)
			(xy 311.002674 -318.96473) (xy 310.958212 -318.985828) (xy 310.910941 -318.99952) (xy 310.862086 -319.005452)
			(xy 310.812911 -319.003471) (xy 310.764692 -318.993627) (xy 310.718676 -318.976175) (xy 310.676055 -318.951568)
			(xy 310.637934 -318.920443) (xy 310.605299 -318.883606) (xy 310.578996 -318.84201) (xy 310.559705 -318.796734)
			(xy 310.547928 -318.74895) (xy 310.543968 -318.699896) (xy 309.25516 -318.699896) (xy 309.254665 -318.724503)
			(xy 309.24677 -318.77308) (xy 309.231186 -318.819761) (xy 309.208315 -318.863338) (xy 309.17875 -318.902682)
			(xy 309.143257 -318.936774) (xy 309.102754 -318.96473) (xy 309.058292 -318.985828) (xy 309.011021 -318.99952)
			(xy 308.962166 -319.005452) (xy 308.912991 -319.003471) (xy 308.864772 -318.993627) (xy 308.818756 -318.976175)
			(xy 308.776135 -318.951568) (xy 308.738014 -318.920443) (xy 308.705379 -318.883606) (xy 308.679076 -318.84201)
			(xy 308.659785 -318.796734) (xy 308.648008 -318.74895) (xy 308.644048 -318.699896) (xy 307.355735 -318.699896)
			(xy 307.355735 -318.6999) (xy 307.351564 -318.750235) (xy 307.339166 -318.799198) (xy 307.318879 -318.845452)
			(xy 307.291255 -318.887737) (xy 307.257049 -318.924899) (xy 307.217193 -318.955924) (xy 307.172774 -318.979966)
			(xy 307.125004 -318.99637) (xy 307.075186 -319.004688) (xy 307.049932 -319.005204) (xy 307.049678 -319.005204)
			(xy 307.027289 -319.004814) (xy 306.982993 -318.99827) (xy 306.940132 -318.985312) (xy 306.89963 -318.966218)
			(xy 306.880768 -318.95415) (xy 306.869084 -318.94653) (xy 306.841398 -318.945006) (xy 306.749958 -318.993774)
			(xy 306.742001 -318.998433) (xy 306.729832 -319.012266) (xy 306.723369 -319.029519) (xy 306.723034 -319.038732)
			(xy 306.723034 -319.665096) (xy 306.723394 -319.674044) (xy 306.729561 -319.690844) (xy 306.741113 -319.704512)
			(xy 306.748688 -319.709292) (xy 306.790516 -319.733621) (xy 306.869718 -319.789222) (xy 306.943155 -319.852244)
			(xy 307.010132 -319.92209) (xy 307.040534 -319.959736) (xy 307.044412 -319.964362) (xy 307.053915 -319.9718)
			(xy 307.05933 -319.974468) (xy 309.069579 -320.900044) (xy 317.098687 -320.900044) (xy 317.102693 -320.704989)
			(xy 317.114703 -320.510263) (xy 317.134698 -320.316194) (xy 317.162643 -320.12311) (xy 317.198492 -319.931335)
			(xy 317.242184 -319.741195) (xy 317.293645 -319.553008) (xy 317.352789 -319.367093) (xy 317.419516 -319.183762)
			(xy 317.493713 -319.003326) (xy 317.575255 -318.826088) (xy 317.664006 -318.652347) (xy 317.759814 -318.482396)
			(xy 317.862519 -318.316522) (xy 317.971947 -318.155004) (xy 318.087914 -317.998115) (xy 318.210225 -317.84612)
			(xy 318.338672 -317.699274) (xy 318.47304 -317.557825) (xy 318.613102 -317.422012) (xy 318.758621 -317.292063)
			(xy 318.909353 -317.168199) (xy 319.065043 -317.050627) (xy 319.225429 -316.939547) (xy 319.39024 -316.835144)
			(xy 319.559198 -316.737596) (xy 319.732019 -316.647067) (xy 319.908411 -316.563709) (xy 320.088076 -316.487663)
			(xy 320.270711 -316.419058) (xy 320.45601 -316.358008) (xy 320.643658 -316.304618) (xy 320.83334 -316.258976)
			(xy 321.024737 -316.22116) (xy 321.217524 -316.191234) (xy 321.411377 -316.169248) (xy 321.60597 -316.155239)
			(xy 321.800973 -316.149231) (xy 321.996059 -316.151234) (xy 322.190898 -316.161245) (xy 322.385162 -316.179246)
			(xy 322.578523 -316.205208) (xy 322.770656 -316.239086) (xy 322.961235 -316.280823) (xy 323.14994 -316.33035)
			(xy 323.336453 -316.387582) (xy 323.520459 -316.452423) (xy 323.701647 -316.524764) (xy 323.879713 -316.604482)
			(xy 324.054356 -316.691444) (xy 324.225282 -316.785503) (xy 324.392201 -316.886499) (xy 324.554834 -316.994264)
			(xy 324.712905 -317.108614) (xy 324.866148 -317.229357) (xy 325.014305 -317.356291) (xy 325.157126 -317.489199)
			(xy 325.29437 -317.627859) (xy 325.425806 -317.772037) (xy 325.551211 -317.92149) (xy 325.670375 -318.075964)
			(xy 325.783096 -318.235201) (xy 325.889185 -318.398932) (xy 325.988463 -318.566879) (xy 326.080761 -318.738762)
			(xy 326.165926 -318.914288) (xy 326.243812 -319.093163) (xy 326.314289 -319.275085) (xy 326.377237 -319.459747)
			(xy 326.432552 -319.646837) (xy 326.480138 -319.836041) (xy 326.519917 -320.027038) (xy 326.551821 -320.219508)
			(xy 326.575796 -320.413126) (xy 326.591802 -320.607564) (xy 326.599811 -320.802496) (xy 326.600312 -320.900044)
			(xy 326.599811 -320.997592) (xy 326.591802 -321.192524) (xy 326.575796 -321.386962) (xy 326.551821 -321.58058)
			(xy 326.519917 -321.77305) (xy 326.480138 -321.964047) (xy 326.432552 -322.153251) (xy 326.377237 -322.340341)
			(xy 326.314289 -322.525003) (xy 326.243812 -322.706925) (xy 326.165926 -322.8858) (xy 326.080761 -323.061326)
			(xy 325.988463 -323.233209) (xy 325.889185 -323.401156) (xy 325.783096 -323.564887) (xy 325.670375 -323.724124)
			(xy 325.551211 -323.878598) (xy 325.425806 -324.028051) (xy 325.29437 -324.172229) (xy 325.157126 -324.310889)
			(xy 325.014305 -324.443797) (xy 324.866148 -324.570731) (xy 324.712905 -324.691474) (xy 324.554834 -324.805824)
			(xy 324.392201 -324.913589) (xy 324.225282 -325.014585) (xy 324.054356 -325.108644) (xy 323.879713 -325.195606)
			(xy 323.701647 -325.275324) (xy 323.520459 -325.347665) (xy 323.336453 -325.412506) (xy 323.14994 -325.469738)
			(xy 322.961235 -325.519265) (xy 322.770656 -325.561002) (xy 322.578523 -325.59488) (xy 322.385162 -325.620842)
			(xy 322.190898 -325.638843) (xy 321.996059 -325.648854) (xy 321.800973 -325.650857) (xy 321.60597 -325.644849)
			(xy 321.411377 -325.63084) (xy 321.217524 -325.608854) (xy 321.024737 -325.578928) (xy 320.83334 -325.541112)
			(xy 320.643658 -325.49547) (xy 320.45601 -325.44208) (xy 320.270711 -325.38103) (xy 320.088076 -325.312425)
			(xy 319.908411 -325.236379) (xy 319.732019 -325.153021) (xy 319.559198 -325.062492) (xy 319.39024 -324.964944)
			(xy 319.225429 -324.860541) (xy 319.065043 -324.749461) (xy 318.909353 -324.631889) (xy 318.758621 -324.508025)
			(xy 318.613102 -324.378076) (xy 318.47304 -324.242263) (xy 318.338672 -324.100814) (xy 318.210225 -323.953968)
			(xy 318.087914 -323.801973) (xy 317.971947 -323.645084) (xy 317.862519 -323.483566) (xy 317.759814 -323.317692)
			(xy 317.664006 -323.147741) (xy 317.575255 -322.974) (xy 317.493713 -322.796762) (xy 317.419516 -322.616326)
			(xy 317.352789 -322.432995) (xy 317.293645 -322.24708) (xy 317.242184 -322.058893) (xy 317.198492 -321.868753)
			(xy 317.162643 -321.676978) (xy 317.134698 -321.483894) (xy 317.114703 -321.289825) (xy 317.102693 -321.095099)
			(xy 317.098687 -320.900044) (xy 309.069579 -320.900044)
		)
		(stroke
			(width 0)
			(type solid)
		)
		(fill yes)
		(layer "In5.Cu")
		(net "GND")
	)
	(gr_poly
		(pts
			(xy 138.252454 -165.993064) (xy 138.25982 -165.999904) (xy 138.278353 -166.007646) (xy 138.298437 -166.007646)
			(xy 138.31697 -165.999904) (xy 138.324336 -165.993064) (xy 138.56589 -165.75151) (xy 138.572703 -165.744166)
			(xy 138.580441 -165.725703) (xy 138.580876 -165.715696) (xy 138.580876 -154.253438) (xy 138.580183 -154.241994)
			(xy 138.570159 -154.22141) (xy 138.561572 -154.213814) (xy 138.490198 -154.156918) (xy 138.4681 -154.151838)
			(xy 138.456416 -154.154378) (xy 138.435497 -154.158884) (xy 138.392977 -154.16372) (xy 138.37158 -154.16403)
			(xy 138.344328 -154.163543) (xy 138.290379 -154.155784) (xy 138.238084 -154.140426) (xy 138.188507 -154.117782)
			(xy 138.142656 -154.088314) (xy 138.101466 -154.05262) (xy 138.065774 -154.011428) (xy 138.036308 -153.965576)
			(xy 138.013667 -153.915997) (xy 137.998312 -153.863701) (xy 137.990556 -153.809752) (xy 137.990556 -153.755248)
			(xy 137.998312 -153.701299) (xy 138.013667 -153.649003) (xy 138.036308 -153.599424) (xy 138.065774 -153.553572)
			(xy 138.101466 -153.51238) (xy 138.142656 -153.476686) (xy 138.188507 -153.447218) (xy 138.238084 -153.424574)
			(xy 138.290379 -153.409216) (xy 138.344328 -153.401457) (xy 138.37158 -153.401014) (xy 138.392976 -153.401343)
			(xy 138.435493 -153.40618) (xy 138.456416 -153.410666) (xy 138.4681 -153.413206) (xy 138.490198 -153.408126)
			(xy 138.561572 -153.35123) (xy 138.570241 -153.3437) (xy 138.580283 -153.323074) (xy 138.580876 -153.311606)
			(xy 138.580876 -148.210524) (xy 138.580304 -148.198902) (xy 138.570115 -148.178009) (xy 138.561318 -148.170392)
			(xy 138.488928 -148.11375) (xy 138.466322 -148.108924) (xy 138.454892 -148.111718) (xy 138.432394 -148.116941)
			(xy 138.386546 -148.122541) (xy 138.363452 -148.122894) (xy 138.336204 -148.122404) (xy 138.282264 -148.114643)
			(xy 138.229977 -148.099284) (xy 138.180407 -148.076641) (xy 138.134565 -148.047175) (xy 138.093382 -148.011484)
			(xy 138.057697 -147.970297) (xy 138.028236 -147.924451) (xy 138.005599 -147.874878) (xy 137.990247 -147.822589)
			(xy 137.982492 -147.768648) (xy 137.982492 -147.714152) (xy 137.990247 -147.66021) (xy 138.005599 -147.607922)
			(xy 138.028236 -147.558349) (xy 138.057697 -147.512503) (xy 138.093382 -147.471316) (xy 138.134565 -147.435625)
			(xy 138.180407 -147.406159) (xy 138.229977 -147.383516) (xy 138.282264 -147.368157) (xy 138.336204 -147.360396)
			(xy 138.363452 -147.359878) (xy 138.386546 -147.360228) (xy 138.432394 -147.365829) (xy 138.454892 -147.371054)
			(xy 138.466322 -147.373848) (xy 138.488928 -147.369022) (xy 138.561318 -147.31238) (xy 138.570155 -147.304792)
			(xy 138.580358 -147.283883) (xy 138.580876 -147.272248) (xy 138.580876 -122.50801) (xy 138.58034 -122.498022)
			(xy 138.572626 -122.47959) (xy 138.56589 -122.472196) (xy 134.52348 -118.429786) (xy 134.516138 -118.422969)
			(xy 134.497674 -118.415231) (xy 134.487666 -118.4148) (xy 131.448048 -118.4148) (xy 131.437997 -118.415216)
			(xy 131.419427 -118.422912) (xy 131.405233 -118.437146) (xy 131.401058 -118.446296) (xy 131.395216 -118.460774)
			(xy 131.401058 -118.490492) (xy 131.631436 -118.72087) (xy 131.649524 -118.739661) (xy 131.680159 -118.781871)
			(xy 131.703809 -118.828356) (xy 131.719894 -118.877969) (xy 131.728015 -118.929488) (xy 131.728464 -118.955566)
			(xy 131.728464 -119.196358) (xy 131.731512 -119.208296) (xy 131.734306 -119.213884) (xy 131.748145 -119.241411)
			(xy 131.76773 -119.299824) (xy 131.777665 -119.360626) (xy 131.778248 -119.39143) (xy 131.777762 -119.418681)
			(xy 131.770006 -119.472629) (xy 131.754651 -119.524924) (xy 131.732009 -119.574501) (xy 131.702543 -119.620351)
			(xy 131.666852 -119.661542) (xy 131.625661 -119.697233) (xy 131.579811 -119.726699) (xy 131.530234 -119.749341)
			(xy 131.477939 -119.764696) (xy 131.423991 -119.772452) (xy 131.369489 -119.772452) (xy 131.315541 -119.764696)
			(xy 131.263246 -119.749341) (xy 131.213669 -119.726699) (xy 131.167819 -119.697233) (xy 131.126628 -119.661542)
			(xy 131.090937 -119.620351) (xy 131.061471 -119.574501) (xy 131.038829 -119.524924) (xy 131.023474 -119.472629)
			(xy 131.015718 -119.418681) (xy 131.015232 -119.39143) (xy 131.015842 -119.360627) (xy 131.025774 -119.299828)
			(xy 131.045338 -119.241411) (xy 131.059174 -119.213884) (xy 131.061968 -119.208296) (xy 131.065016 -119.196358)
			(xy 131.065016 -119.114062) (xy 131.064472 -119.104077) (xy 131.056751 -119.085654) (xy 131.05003 -119.078248)
			(xy 130.917442 -118.94566) (xy 130.910033 -118.938974) (xy 130.891597 -118.931382) (xy 130.881628 -118.930928)
			(xy 128.560068 -118.930928) (xy 128.550274 -118.931311) (xy 128.532085 -118.938562) (xy 128.517971 -118.952135)
			(xy 128.513586 -118.9609) (xy 128.469644 -119.059706) (xy 128.474216 -119.08917) (xy 128.48463 -119.100346)
			(xy 128.503004 -119.121488) (xy 128.533997 -119.168144) (xy 128.557841 -119.218828) (xy 128.574024 -119.272451)
			(xy 128.582198 -119.327864) (xy 128.582674 -119.35587) (xy 128.582213 -119.383123) (xy 128.574459 -119.437076)
			(xy 128.559105 -119.489375) (xy 128.536464 -119.538957) (xy 128.506996 -119.584811) (xy 128.471302 -119.626005)
			(xy 128.430108 -119.661699) (xy 128.384253 -119.691166) (xy 128.334671 -119.713807) (xy 128.282372 -119.72916)
			(xy 128.228419 -119.736913) (xy 128.201166 -119.737378) (xy 128.18515 -119.737227) (xy 128.15323 -119.73456)
			(xy 128.137412 -119.732044) (xy 128.126236 -119.730012) (xy 128.1049 -119.735854) (xy 128.036828 -119.793512)
			(xy 128.028803 -119.801083) (xy 128.019582 -119.8211) (xy 128.019048 -119.83212) (xy 128.019048 -120.356376)
			(xy 128.018564 -120.382464) (xy 128.0104 -120.433997) (xy 127.99427 -120.483617) (xy 127.970572 -120.530101)
			(xy 127.93989 -120.572301) (xy 127.921766 -120.591072) (xy 127.56515 -120.947688) (xy 127.558332 -120.95503)
			(xy 127.550588 -120.973493) (xy 127.550164 -120.983502) (xy 127.550164 -121.57075) (xy 129.719832 -121.57075)
			(xy 129.720262 -121.544433) (xy 129.727485 -121.492298) (xy 129.741802 -121.441649) (xy 129.762941 -121.393446)
			(xy 129.790501 -121.348605) (xy 129.823959 -121.307975) (xy 129.843022 -121.289826) (xy 129.850417 -121.2823)
			(xy 129.858945 -121.263023) (xy 129.859532 -121.252488) (xy 129.859532 -121.177812) (xy 129.859001 -121.167263)
			(xy 129.850466 -121.147968) (xy 129.843022 -121.140474) (xy 129.823934 -121.122348) (xy 129.790456 -121.081726)
			(xy 129.762886 -121.036884) (xy 129.741749 -120.988675) (xy 129.727446 -120.938015) (xy 129.720251 -120.88587)
			(xy 129.719832 -120.85955) (xy 129.720318 -120.832299) (xy 129.728074 -120.778351) (xy 129.743429 -120.726056)
			(xy 129.766071 -120.676479) (xy 129.795537 -120.630629) (xy 129.831228 -120.589438) (xy 129.872419 -120.553747)
			(xy 129.918269 -120.524281) (xy 129.967846 -120.501639) (xy 130.020141 -120.486284) (xy 130.074089 -120.478528)
			(xy 130.128591 -120.478528) (xy 130.182539 -120.486284) (xy 130.234834 -120.501639) (xy 130.284411 -120.524281)
			(xy 130.330261 -120.553747) (xy 130.371452 -120.589438) (xy 130.407143 -120.630629) (xy 130.436609 -120.676479)
			(xy 130.459251 -120.726056) (xy 130.474606 -120.778351) (xy 130.482362 -120.832299) (xy 130.482848 -120.85955)
			(xy 130.482393 -120.885866) (xy 130.475171 -120.937999) (xy 130.460857 -120.988647) (xy 130.439723 -121.036848)
			(xy 130.412169 -121.08169) (xy 130.378717 -121.122323) (xy 130.359658 -121.140474) (xy 130.352274 -121.148011)
			(xy 130.343738 -121.167279) (xy 130.343148 -121.177812) (xy 130.343148 -121.252488) (xy 130.343656 -121.263041)
			(xy 130.352204 -121.282337) (xy 130.359658 -121.289826) (xy 130.378742 -121.307956) (xy 130.412221 -121.348577)
			(xy 130.439792 -121.393418) (xy 130.46093 -121.441626) (xy 130.475233 -121.492285) (xy 130.482429 -121.54443)
			(xy 130.482848 -121.57075) (xy 130.482362 -121.598001) (xy 130.474606 -121.651949) (xy 130.459251 -121.704244)
			(xy 130.436609 -121.753821) (xy 130.407143 -121.799671) (xy 130.371452 -121.840862) (xy 130.330261 -121.876553)
			(xy 130.284411 -121.906019) (xy 130.234834 -121.928661) (xy 130.182539 -121.944016) (xy 130.128591 -121.951772)
			(xy 130.074089 -121.951772) (xy 130.020141 -121.944016) (xy 129.967846 -121.928661) (xy 129.918269 -121.906019)
			(xy 129.872419 -121.876553) (xy 129.831228 -121.840862) (xy 129.795537 -121.799671) (xy 129.766071 -121.753821)
			(xy 129.743429 -121.704244) (xy 129.728074 -121.651949) (xy 129.720318 -121.598001) (xy 129.719832 -121.57075)
			(xy 127.550164 -121.57075) (xy 127.550164 -122.09272) (xy 127.566166 -122.117612) (xy 127.579628 -122.123962)
			(xy 127.603997 -122.135811) (xy 127.649409 -122.165369) (xy 127.690183 -122.201055) (xy 127.725499 -122.242149)
			(xy 127.754647 -122.287826) (xy 127.77704 -122.337167) (xy 127.792228 -122.38918) (xy 127.799905 -122.442818)
			(xy 127.800354 -122.46991) (xy 127.799898 -122.496825) (xy 127.792341 -122.550121) (xy 127.777364 -122.601825)
			(xy 127.755265 -122.650909) (xy 127.726484 -122.696398) (xy 127.691592 -122.737388) (xy 127.651282 -122.773064)
			(xy 127.606357 -122.802716) (xy 127.557707 -122.825757) (xy 127.53213 -122.834146) (xy 127.526288 -122.836178)
			(xy 127.51562 -122.842528) (xy 127.108396 -123.249752) (xy 128.009867 -123.249752) (xy 128.009867 -123.195248)
			(xy 128.017624 -123.141298) (xy 128.03298 -123.089002) (xy 128.055622 -123.039423) (xy 128.085089 -122.993571)
			(xy 128.120782 -122.95238) (xy 128.161974 -122.916687) (xy 128.207826 -122.88722) (xy 128.257405 -122.864579)
			(xy 128.309702 -122.849223) (xy 128.363652 -122.841467) (xy 128.390904 -122.841004) (xy 128.417934 -122.841497)
			(xy 128.471452 -122.849135) (xy 128.523353 -122.864259) (xy 128.572597 -122.886563) (xy 128.618196 -122.915602)
			(xy 128.659234 -122.950791) (xy 128.677416 -122.970798) (xy 128.684782 -122.978926) (xy 128.704594 -122.98807)
			(xy 128.802638 -122.988324) (xy 128.82245 -122.979434) (xy 128.829816 -122.971306) (xy 128.847975 -122.951581)
			(xy 128.888876 -122.916917) (xy 128.934232 -122.888329) (xy 128.983148 -122.86638) (xy 129.034657 -122.851505)
			(xy 129.087743 -122.843997) (xy 129.11455 -122.843544) (xy 129.14192 -122.844029) (xy 129.196098 -122.85184)
			(xy 129.248602 -122.867324) (xy 129.298349 -122.890162) (xy 129.344316 -122.919884) (xy 129.365248 -122.937524)
			(xy 129.37236 -122.94362) (xy 129.389378 -122.94997) (xy 129.474722 -122.94997) (xy 129.49174 -122.94362)
			(xy 129.498852 -122.937524) (xy 129.519785 -122.919883) (xy 129.565753 -122.890159) (xy 129.615499 -122.867313)
			(xy 129.668001 -122.851817) (xy 129.722179 -122.843988) (xy 129.776921 -122.843988) (xy 129.831099 -122.851817)
			(xy 129.883601 -122.867313) (xy 129.933347 -122.890159) (xy 129.979315 -122.919883) (xy 130.000248 -122.937524)
			(xy 130.00736 -122.94362) (xy 130.024378 -122.94997) (xy 130.109722 -122.94997) (xy 130.12674 -122.94362)
			(xy 130.133852 -122.937524) (xy 130.146653 -122.926579) (xy 130.173869 -122.906735) (xy 130.188208 -122.8979)
			(xy 130.197352 -122.892566) (xy 130.209544 -122.875548) (xy 130.22961 -122.78233) (xy 130.225546 -122.761756)
			(xy 130.21945 -122.75312) (xy 130.203451 -122.729056) (xy 130.178109 -122.677124) (xy 130.160884 -122.621966)
			(xy 130.152168 -122.564842) (xy 130.151632 -122.53595) (xy 130.152118 -122.508699) (xy 130.159874 -122.454751)
			(xy 130.175229 -122.402456) (xy 130.197871 -122.352879) (xy 130.227337 -122.307029) (xy 130.263028 -122.265838)
			(xy 130.304219 -122.230147) (xy 130.350069 -122.200681) (xy 130.399646 -122.178039) (xy 130.451941 -122.162684)
			(xy 130.505889 -122.154928) (xy 130.560391 -122.154928) (xy 130.614339 -122.162684) (xy 130.666634 -122.178039)
			(xy 130.716211 -122.200681) (xy 130.762061 -122.230147) (xy 130.803252 -122.265838) (xy 130.838943 -122.307029)
			(xy 130.868409 -122.352879) (xy 130.891051 -122.402456) (xy 130.906406 -122.454751) (xy 130.914162 -122.508699)
			(xy 130.914648 -122.53595) (xy 130.914099 -122.564039) (xy 130.90588 -122.619613) (xy 130.889597 -122.673381)
			(xy 130.865603 -122.724177) (xy 130.834417 -122.770905) (xy 130.796714 -122.812552) (xy 130.753308 -122.848217)
			(xy 130.729482 -122.863102) (xy 130.720338 -122.868436) (xy 130.708146 -122.885454) (xy 130.68808 -122.978672)
			(xy 130.692144 -122.999246) (xy 130.69824 -123.007882) (xy 130.714239 -123.031946) (xy 130.739581 -123.083878)
			(xy 130.756807 -123.139036) (xy 130.765523 -123.19616) (xy 130.766058 -123.225052) (xy 130.7656 -123.252306)
			(xy 130.757848 -123.30626) (xy 130.742496 -123.358561) (xy 130.719855 -123.408144) (xy 130.690387 -123.454)
			(xy 130.654693 -123.495194) (xy 130.613498 -123.530889) (xy 130.567642 -123.560356) (xy 130.518059 -123.582996)
			(xy 130.465758 -123.598349) (xy 130.411804 -123.6061) (xy 130.38455 -123.60656) (xy 130.35718 -123.606074)
			(xy 130.303002 -123.598263) (xy 130.250498 -123.582779) (xy 130.200751 -123.559941) (xy 130.154784 -123.53022)
			(xy 130.133852 -123.51258) (xy 130.12674 -123.506484) (xy 130.109722 -123.500134) (xy 130.024378 -123.500134)
			(xy 130.00736 -123.506484) (xy 130.000248 -123.51258) (xy 129.979315 -123.530221) (xy 129.933347 -123.559945)
			(xy 129.883601 -123.582791) (xy 129.831099 -123.598287) (xy 129.776921 -123.606116) (xy 129.722179 -123.606116)
			(xy 129.668001 -123.598287) (xy 129.615499 -123.582791) (xy 129.565753 -123.559945) (xy 129.519785 -123.530221)
			(xy 129.498852 -123.51258) (xy 129.49174 -123.506484) (xy 129.474722 -123.500134) (xy 129.389378 -123.500134)
			(xy 129.37236 -123.506484) (xy 129.365248 -123.51258) (xy 129.344306 -123.530207) (xy 129.298336 -123.559921)
			(xy 129.248591 -123.58276) (xy 129.196093 -123.598254) (xy 129.141919 -123.606085) (xy 129.11455 -123.60656)
			(xy 129.08752 -123.606077) (xy 129.034003 -123.598433) (xy 128.982102 -123.583307) (xy 128.932859 -123.561)
			(xy 128.88726 -123.531961) (xy 128.846221 -123.496772) (xy 128.828038 -123.476766) (xy 128.820672 -123.468638)
			(xy 128.80086 -123.459494) (xy 128.702816 -123.45924) (xy 128.683004 -123.46813) (xy 128.675638 -123.476258)
			(xy 128.657465 -123.495969) (xy 128.616566 -123.530632) (xy 128.571212 -123.559221) (xy 128.522299 -123.581171)
			(xy 128.470793 -123.59605) (xy 128.41771 -123.603564) (xy 128.390904 -123.60402) (xy 128.363652 -123.603533)
			(xy 128.309702 -123.595777) (xy 128.257405 -123.580421) (xy 128.207826 -123.55778) (xy 128.161974 -123.528313)
			(xy 128.120782 -123.49262) (xy 128.085089 -123.451429) (xy 128.055622 -123.405577) (xy 128.03298 -123.355998)
			(xy 128.017624 -123.303702) (xy 128.009867 -123.249752) (xy 127.108396 -123.249752) (xy 126.635002 -123.723146)
			(xy 126.628198 -123.730494) (xy 126.620482 -123.748956) (xy 126.620016 -123.75896) (xy 126.620016 -124.9807)
			(xy 126.928878 -124.9807) (xy 126.932949 -124.925078) (xy 126.945075 -124.870641) (xy 126.964998 -124.81855)
			(xy 126.992294 -124.769915) (xy 127.02638 -124.725772) (xy 127.066529 -124.687063) (xy 127.111887 -124.654612)
			(xy 127.161487 -124.629111) (xy 127.214271 -124.611104) (xy 127.269114 -124.600974) (xy 127.324848 -124.598937)
			(xy 127.380285 -124.605037) (xy 127.434242 -124.619143) (xy 127.485571 -124.640955) (xy 127.533177 -124.670009)
			(xy 127.576045 -124.705684) (xy 127.613262 -124.747221) (xy 127.644035 -124.793734) (xy 127.667707 -124.844231)
			(xy 127.683775 -124.897638) (xy 127.691895 -124.952814) (xy 127.692404 -124.9807) (xy 127.691895 -125.008586)
			(xy 127.683775 -125.063762) (xy 127.667707 -125.117169) (xy 127.644035 -125.167666) (xy 127.613262 -125.214179)
			(xy 127.576045 -125.255716) (xy 127.533177 -125.291391) (xy 127.485571 -125.320445) (xy 127.434242 -125.342257)
			(xy 127.380285 -125.356363) (xy 127.324848 -125.362463) (xy 127.269114 -125.360426) (xy 127.214271 -125.350296)
			(xy 127.161487 -125.332289) (xy 127.111887 -125.306788) (xy 127.066529 -125.274337) (xy 127.02638 -125.235628)
			(xy 126.992294 -125.191485) (xy 126.964998 -125.14285) (xy 126.945075 -125.090759) (xy 126.932949 -125.036322)
			(xy 126.928878 -124.9807) (xy 126.620016 -124.9807) (xy 126.620016 -125.403356) (xy 131.644136 -125.403356)
			(xy 131.644626 -125.375987) (xy 131.652437 -125.321808) (xy 131.66792 -125.269305) (xy 131.690756 -125.219558)
			(xy 131.720477 -125.17359) (xy 131.738116 -125.152658) (xy 131.744212 -125.145546) (xy 131.750562 -125.128528)
			(xy 131.750562 -125.043184) (xy 131.744212 -125.026166) (xy 131.738116 -125.019054) (xy 131.720491 -124.99811)
			(xy 131.690777 -124.952141) (xy 131.667938 -124.902396) (xy 131.652443 -124.849898) (xy 131.644612 -124.795724)
			(xy 131.644136 -124.768356) (xy 131.644622 -124.741105) (xy 131.652378 -124.687157) (xy 131.667733 -124.634862)
			(xy 131.690375 -124.585285) (xy 131.719841 -124.539435) (xy 131.755532 -124.498244) (xy 131.796723 -124.462553)
			(xy 131.842573 -124.433087) (xy 131.89215 -124.410445) (xy 131.944445 -124.39509) (xy 131.998393 -124.387334)
			(xy 132.052895 -124.387334) (xy 132.106843 -124.39509) (xy 132.159138 -124.410445) (xy 132.208715 -124.433087)
			(xy 132.254565 -124.462553) (xy 132.295756 -124.498244) (xy 132.331447 -124.539435) (xy 132.360913 -124.585285)
			(xy 132.383555 -124.634862) (xy 132.39891 -124.687157) (xy 132.406666 -124.741105) (xy 132.407152 -124.768356)
			(xy 132.406672 -124.795726) (xy 132.398859 -124.849905) (xy 132.383374 -124.902408) (xy 132.360535 -124.952155)
			(xy 132.330813 -124.998122) (xy 132.313172 -125.019054) (xy 132.307076 -125.026166) (xy 132.300726 -125.043184)
			(xy 132.300726 -125.128528) (xy 132.307076 -125.145546) (xy 132.313172 -125.152658) (xy 132.330801 -125.173599)
			(xy 132.360515 -125.219569) (xy 132.383353 -125.269314) (xy 132.398847 -125.321813) (xy 132.406677 -125.375987)
			(xy 132.407152 -125.403356) (xy 132.406666 -125.430607) (xy 132.39891 -125.484555) (xy 132.383555 -125.53685)
			(xy 132.360913 -125.586427) (xy 132.331447 -125.632277) (xy 132.295756 -125.673468) (xy 132.254565 -125.709159)
			(xy 132.208715 -125.738625) (xy 132.159138 -125.761267) (xy 132.106843 -125.776622) (xy 132.052895 -125.784378)
			(xy 131.998393 -125.784378) (xy 131.944445 -125.776622) (xy 131.89215 -125.761267) (xy 131.842573 -125.738625)
			(xy 131.796723 -125.709159) (xy 131.755532 -125.673468) (xy 131.719841 -125.632277) (xy 131.690375 -125.586427)
			(xy 131.667733 -125.53685) (xy 131.652378 -125.484555) (xy 131.644622 -125.430607) (xy 131.644136 -125.403356)
			(xy 126.620016 -125.403356) (xy 126.620016 -125.962918) (xy 127.251204 -125.962918) (xy 127.255275 -125.907296)
			(xy 127.267401 -125.852859) (xy 127.287324 -125.800768) (xy 127.31462 -125.752133) (xy 127.348706 -125.70799)
			(xy 127.388855 -125.669281) (xy 127.434213 -125.63683) (xy 127.483813 -125.611329) (xy 127.536597 -125.593322)
			(xy 127.59144 -125.583192) (xy 127.647174 -125.581155) (xy 127.702611 -125.587255) (xy 127.756568 -125.601361)
			(xy 127.807897 -125.623173) (xy 127.855503 -125.652227) (xy 127.898371 -125.687902) (xy 127.935588 -125.729439)
			(xy 127.966361 -125.775952) (xy 127.990033 -125.826449) (xy 127.998231 -125.853698) (xy 132.584698 -125.853698)
			(xy 132.585163 -125.826328) (xy 132.592981 -125.772149) (xy 132.608471 -125.719646) (xy 132.631313 -125.669899)
			(xy 132.661037 -125.623932) (xy 132.678678 -125.603) (xy 132.684774 -125.595888) (xy 132.691124 -125.57887)
			(xy 132.691124 -125.493526) (xy 132.684774 -125.476508) (xy 132.678678 -125.469396) (xy 132.66102 -125.448479)
			(xy 132.631312 -125.402502) (xy 132.60848 -125.35275) (xy 132.592993 -125.300246) (xy 132.58517 -125.246068)
			(xy 132.584698 -125.218698) (xy 132.585184 -125.191447) (xy 132.59294 -125.137499) (xy 132.608295 -125.085204)
			(xy 132.630937 -125.035627) (xy 132.660403 -124.989777) (xy 132.696094 -124.948586) (xy 132.737285 -124.912895)
			(xy 132.783135 -124.883429) (xy 132.832712 -124.860787) (xy 132.885007 -124.845432) (xy 132.938955 -124.837676)
			(xy 132.993457 -124.837676) (xy 133.047405 -124.845432) (xy 133.0997 -124.860787) (xy 133.149277 -124.883429)
			(xy 133.195127 -124.912895) (xy 133.236318 -124.948586) (xy 133.272009 -124.989777) (xy 133.301475 -125.035627)
			(xy 133.324117 -125.085204) (xy 133.339472 -125.137499) (xy 133.347228 -125.191447) (xy 133.347714 -125.218698)
			(xy 133.347243 -125.246068) (xy 133.339426 -125.300247) (xy 133.323938 -125.35275) (xy 133.301097 -125.402497)
			(xy 133.271374 -125.448464) (xy 133.253734 -125.469396) (xy 133.247638 -125.476508) (xy 133.241288 -125.493526)
			(xy 133.241288 -125.57887) (xy 133.247638 -125.595888) (xy 133.253734 -125.603) (xy 133.271392 -125.623917)
			(xy 133.3011 -125.669894) (xy 133.323931 -125.719646) (xy 133.339418 -125.77215) (xy 133.347242 -125.826328)
			(xy 133.347714 -125.853698) (xy 133.347228 -125.880949) (xy 133.339472 -125.934897) (xy 133.324117 -125.987192)
			(xy 133.301475 -126.036769) (xy 133.272009 -126.082619) (xy 133.236318 -126.12381) (xy 133.195127 -126.159501)
			(xy 133.149277 -126.188967) (xy 133.0997 -126.211609) (xy 133.047405 -126.226964) (xy 132.993457 -126.23472)
			(xy 132.938955 -126.23472) (xy 132.885007 -126.226964) (xy 132.832712 -126.211609) (xy 132.783135 -126.188967)
			(xy 132.737285 -126.159501) (xy 132.696094 -126.12381) (xy 132.660403 -126.082619) (xy 132.630937 -126.036769)
			(xy 132.608295 -125.987192) (xy 132.59294 -125.934897) (xy 132.585184 -125.880949) (xy 132.584698 -125.853698)
			(xy 127.998231 -125.853698) (xy 128.006101 -125.879856) (xy 128.014221 -125.935032) (xy 128.01473 -125.962918)
			(xy 128.014221 -125.990804) (xy 128.006101 -126.04598) (xy 127.990033 -126.099387) (xy 127.966361 -126.149884)
			(xy 127.935588 -126.196397) (xy 127.898371 -126.237934) (xy 127.855503 -126.273609) (xy 127.807897 -126.302663)
			(xy 127.756568 -126.324475) (xy 127.702611 -126.338581) (xy 127.647174 -126.344681) (xy 127.59144 -126.342644)
			(xy 127.536597 -126.332514) (xy 127.483813 -126.314507) (xy 127.434213 -126.289006) (xy 127.388855 -126.256555)
			(xy 127.348706 -126.217846) (xy 127.31462 -126.173703) (xy 127.287324 -126.125068) (xy 127.267401 -126.072977)
			(xy 127.255275 -126.01854) (xy 127.251204 -125.962918) (xy 126.620016 -125.962918) (xy 126.620016 -126.530354)
			(xy 133.79323 -126.530354) (xy 133.79377 -126.50269) (xy 133.801763 -126.447941) (xy 133.817574 -126.39492)
			(xy 133.840871 -126.344735) (xy 133.871169 -126.298439) (xy 133.907831 -126.257) (xy 133.95009 -126.221287)
			(xy 133.973316 -126.20625) (xy 133.983476 -126.1999) (xy 133.995922 -126.180342) (xy 134.006336 -126.076202)
			(xy 133.998208 -126.054358) (xy 133.989318 -126.045976) (xy 133.970746 -126.027885) (xy 133.938166 -125.987556)
			(xy 133.911352 -125.943184) (xy 133.890797 -125.895587) (xy 133.876882 -125.845644) (xy 133.869863 -125.794277)
			(xy 133.86943 -125.768354) (xy 133.869835 -125.7411) (xy 133.877599 -125.687147) (xy 133.892962 -125.634849)
			(xy 133.915611 -125.585269) (xy 133.945086 -125.539417) (xy 133.980786 -125.498226) (xy 134.021984 -125.462535)
			(xy 134.067843 -125.433071) (xy 134.117428 -125.410432) (xy 134.169729 -125.395081) (xy 134.223684 -125.387329)
			(xy 134.250938 -125.386846) (xy 134.278307 -125.387337) (xy 134.332486 -125.395147) (xy 134.384989 -125.41063)
			(xy 134.434737 -125.433466) (xy 134.480704 -125.463187) (xy 134.501636 -125.480826) (xy 134.508748 -125.486922)
			(xy 134.525766 -125.493272) (xy 134.61111 -125.493272) (xy 134.628128 -125.486922) (xy 134.63524 -125.480826)
			(xy 134.656187 -125.463206) (xy 134.702155 -125.43349) (xy 134.751899 -125.41065) (xy 134.804397 -125.395155)
			(xy 134.85857 -125.387322) (xy 134.885938 -125.386846) (xy 134.913188 -125.387342) (xy 134.967133 -125.395103)
			(xy 135.019425 -125.41046) (xy 135.068999 -125.433103) (xy 135.114847 -125.462569) (xy 135.156036 -125.498259)
			(xy 135.191727 -125.539447) (xy 135.221194 -125.585294) (xy 135.243837 -125.634868) (xy 135.259195 -125.687159)
			(xy 135.266957 -125.741104) (xy 135.267446 -125.768354) (xy 135.266915 -125.797271) (xy 135.258192 -125.854442)
			(xy 135.240938 -125.909642) (xy 135.215548 -125.961604) (xy 135.182606 -126.009138) (xy 135.142865 -126.051154)
			(xy 135.12038 -126.069344) (xy 135.111599 -126.076888) (xy 135.101427 -126.09766) (xy 135.100822 -126.109222)
			(xy 135.100822 -126.189486) (xy 135.101393 -126.201054) (xy 135.111586 -126.221825) (xy 135.12038 -126.229364)
			(xy 135.142842 -126.24758) (xy 135.18258 -126.289594) (xy 135.215522 -126.337124) (xy 135.240914 -126.38908)
			(xy 135.258175 -126.444273) (xy 135.266908 -126.501439) (xy 135.267446 -126.530354) (xy 135.266902 -126.557604)
			(xy 135.259152 -126.61155) (xy 135.247051 -126.652782) (xy 135.538718 -126.652782) (xy 135.539169 -126.625411)
			(xy 135.54699 -126.571231) (xy 135.562482 -126.518728) (xy 135.585327 -126.468981) (xy 135.615055 -126.423015)
			(xy 135.632698 -126.402084) (xy 135.638794 -126.394972) (xy 135.645144 -126.377954) (xy 135.645144 -126.29261)
			(xy 135.638794 -126.275592) (xy 135.632698 -126.26848) (xy 135.615041 -126.247561) (xy 135.585319 -126.20159)
			(xy 135.562476 -126.151841) (xy 135.546983 -126.099337) (xy 135.539157 -126.045158) (xy 135.539159 -125.990415)
			(xy 135.546989 -125.936236) (xy 135.562486 -125.883733) (xy 135.585332 -125.833986) (xy 135.615057 -125.788017)
			(xy 135.632698 -125.767084) (xy 135.638794 -125.759972) (xy 135.645144 -125.742954) (xy 135.645144 -125.65761)
			(xy 135.638794 -125.640592) (xy 135.632698 -125.63348) (xy 135.615041 -125.612561) (xy 135.585319 -125.56659)
			(xy 135.562476 -125.516841) (xy 135.546983 -125.464337) (xy 135.539157 -125.410158) (xy 135.539159 -125.355415)
			(xy 135.546989 -125.301236) (xy 135.562486 -125.248733) (xy 135.585332 -125.198986) (xy 135.615057 -125.153017)
			(xy 135.632698 -125.132084) (xy 135.638794 -125.124972) (xy 135.645144 -125.107954) (xy 135.645144 -125.02261)
			(xy 135.638794 -125.005592) (xy 135.632698 -124.99848) (xy 135.615083 -124.977529) (xy 135.585367 -124.931561)
			(xy 135.562527 -124.881819) (xy 135.54703 -124.829322) (xy 135.539196 -124.77515) (xy 135.538718 -124.747782)
			(xy 135.539204 -124.720531) (xy 135.54696 -124.666583) (xy 135.562315 -124.614288) (xy 135.584957 -124.564711)
			(xy 135.614423 -124.518861) (xy 135.650114 -124.47767) (xy 135.691305 -124.441979) (xy 135.737155 -124.412513)
			(xy 135.786732 -124.389871) (xy 135.839027 -124.374516) (xy 135.892975 -124.36676) (xy 135.947477 -124.36676)
			(xy 136.001425 -124.374516) (xy 136.05372 -124.389871) (xy 136.103297 -124.412513) (xy 136.149147 -124.441979)
			(xy 136.190338 -124.47767) (xy 136.226029 -124.518861) (xy 136.255495 -124.564711) (xy 136.278137 -124.614288)
			(xy 136.293492 -124.666583) (xy 136.301248 -124.720531) (xy 136.301734 -124.747782) (xy 136.301273 -124.775153)
			(xy 136.293457 -124.829333) (xy 136.277967 -124.881836) (xy 136.255124 -124.931583) (xy 136.225397 -124.977549)
			(xy 136.207754 -124.99848) (xy 136.201658 -125.005592) (xy 136.195308 -125.02261) (xy 136.195308 -125.107954)
			(xy 136.201658 -125.124972) (xy 136.207754 -125.132084) (xy 136.225378 -125.153031) (xy 136.255105 -125.198996)
			(xy 136.277952 -125.248739) (xy 136.293451 -125.30124) (xy 136.301282 -125.355416) (xy 136.301284 -125.410156)
			(xy 136.293457 -125.464334) (xy 136.277962 -125.516835) (xy 136.255118 -125.566581) (xy 136.225394 -125.612548)
			(xy 136.207754 -125.63348) (xy 136.201658 -125.640592) (xy 136.195308 -125.65761) (xy 136.195308 -125.742954)
			(xy 136.201658 -125.759972) (xy 136.207754 -125.767084) (xy 136.225378 -125.788031) (xy 136.255105 -125.833996)
			(xy 136.277952 -125.883739) (xy 136.293451 -125.93624) (xy 136.301282 -125.990416) (xy 136.301284 -126.045156)
			(xy 136.293457 -126.099334) (xy 136.277962 -126.151835) (xy 136.255118 -126.201581) (xy 136.225394 -126.247548)
			(xy 136.207754 -126.26848) (xy 136.201658 -126.275592) (xy 136.195308 -126.29261) (xy 136.195308 -126.377954)
			(xy 136.201658 -126.394972) (xy 136.207754 -126.402084) (xy 136.225392 -126.423017) (xy 136.255105 -126.468989)
			(xy 136.277942 -126.518736) (xy 136.293434 -126.571237) (xy 136.301261 -126.625413) (xy 136.301734 -126.652782)
			(xy 136.301248 -126.680033) (xy 136.293492 -126.733981) (xy 136.278137 -126.786276) (xy 136.255495 -126.835853)
			(xy 136.226029 -126.881703) (xy 136.190338 -126.922894) (xy 136.149147 -126.958585) (xy 136.103297 -126.988051)
			(xy 136.05372 -127.010693) (xy 136.001425 -127.026048) (xy 135.947477 -127.033804) (xy 135.892975 -127.033804)
			(xy 135.839027 -127.026048) (xy 135.786732 -127.010693) (xy 135.737155 -126.988051) (xy 135.691305 -126.958585)
			(xy 135.650114 -126.922894) (xy 135.614423 -126.881703) (xy 135.584957 -126.835853) (xy 135.562315 -126.786276)
			(xy 135.54696 -126.733981) (xy 135.539204 -126.680033) (xy 135.538718 -126.652782) (xy 135.247051 -126.652782)
			(xy 135.243804 -126.663844) (xy 135.22117 -126.713422) (xy 135.19171 -126.759273) (xy 135.156025 -126.800465)
			(xy 135.11484 -126.83616) (xy 135.068995 -126.865629) (xy 135.019423 -126.888275) (xy 134.967132 -126.903634)
			(xy 134.913188 -126.911396) (xy 134.885938 -126.911862) (xy 134.859621 -126.911442) (xy 134.807485 -126.904217)
			(xy 134.756835 -126.889898) (xy 134.708633 -126.868758) (xy 134.663792 -126.841196) (xy 134.623163 -126.807736)
			(xy 134.605014 -126.788672) (xy 134.59748 -126.781285) (xy 134.57821 -126.77275) (xy 134.567676 -126.772162)
			(xy 134.493 -126.772162) (xy 134.48245 -126.772689) (xy 134.463156 -126.781227) (xy 134.455662 -126.788672)
			(xy 134.43754 -126.807764) (xy 134.396918 -126.841242) (xy 134.352075 -126.868812) (xy 134.303865 -126.889948)
			(xy 134.253205 -126.90425) (xy 134.201058 -126.911444) (xy 134.174738 -126.911862) (xy 134.147484 -126.911409)
			(xy 134.09353 -126.903656) (xy 134.041229 -126.888303) (xy 133.991646 -126.865661) (xy 133.945791 -126.836193)
			(xy 133.904597 -126.800498) (xy 133.868902 -126.759303) (xy 133.839435 -126.713447) (xy 133.816795 -126.663863)
			(xy 133.801442 -126.611562) (xy 133.79369 -126.557608) (xy 133.79323 -126.530354) (xy 126.620016 -126.530354)
			(xy 126.620016 -126.844044) (xy 126.619551 -126.870122) (xy 126.611432 -126.92164) (xy 126.595353 -126.971255)
			(xy 126.57171 -127.017743) (xy 126.547362 -127.051308) (xy 126.844042 -127.051308) (xy 126.848113 -126.995686)
			(xy 126.860239 -126.941249) (xy 126.880162 -126.889158) (xy 126.907458 -126.840523) (xy 126.941544 -126.79638)
			(xy 126.981693 -126.757671) (xy 127.027051 -126.72522) (xy 127.076651 -126.699719) (xy 127.129435 -126.681712)
			(xy 127.184278 -126.671582) (xy 127.240012 -126.669545) (xy 127.295449 -126.675645) (xy 127.349406 -126.689751)
			(xy 127.400735 -126.711563) (xy 127.448341 -126.740617) (xy 127.491209 -126.776292) (xy 127.528426 -126.817829)
			(xy 127.559199 -126.864342) (xy 127.582871 -126.914839) (xy 127.598939 -126.968246) (xy 127.607059 -127.023422)
			(xy 127.607568 -127.051308) (xy 127.607059 -127.079194) (xy 127.598939 -127.13437) (xy 127.582871 -127.187777)
			(xy 127.559199 -127.238274) (xy 127.528426 -127.284787) (xy 127.491209 -127.326324) (xy 127.448341 -127.361999)
			(xy 127.400735 -127.391053) (xy 127.349406 -127.412865) (xy 127.295449 -127.426971) (xy 127.240012 -127.433071)
			(xy 127.184278 -127.431034) (xy 127.129435 -127.420904) (xy 127.076651 -127.402897) (xy 127.027051 -127.377396)
			(xy 126.981693 -127.344945) (xy 126.941544 -127.306236) (xy 126.907458 -127.262093) (xy 126.880162 -127.213458)
			(xy 126.860239 -127.161367) (xy 126.848113 -127.10693) (xy 126.844042 -127.051308) (xy 126.547362 -127.051308)
			(xy 126.541086 -127.059959) (xy 126.522988 -127.07874) (xy 126.456186 -127.145542) (xy 126.449337 -127.152938)
			(xy 126.441604 -127.171538) (xy 126.4412 -127.18161) (xy 126.4412 -127.512318) (xy 126.440773 -127.522387)
			(xy 126.433054 -127.540986) (xy 126.426214 -127.548386) (xy 126.281942 -127.692658) (xy 126.275992 -127.699043)
			(xy 126.268457 -127.714772) (xy 126.266694 -127.732122) (xy 126.26848 -127.740664) (xy 126.292356 -127.8382)
			(xy 126.310644 -127.857504) (xy 126.323344 -127.861568) (xy 126.348303 -127.869853) (xy 126.395854 -127.892317)
			(xy 126.439879 -127.921084) (xy 126.459996 -127.938022) (xy 126.467108 -127.944118) (xy 126.484126 -127.950468)
			(xy 126.56947 -127.950468) (xy 126.586488 -127.944118) (xy 126.5936 -127.938022) (xy 126.614533 -127.920381)
			(xy 126.660501 -127.890657) (xy 126.710247 -127.867811) (xy 126.762749 -127.852315) (xy 126.816927 -127.844486)
			(xy 126.871669 -127.844486) (xy 126.925847 -127.852315) (xy 126.978349 -127.867811) (xy 127.028095 -127.890657)
			(xy 127.074063 -127.920381) (xy 127.094996 -127.938022) (xy 127.102108 -127.944118) (xy 127.119126 -127.950468)
			(xy 127.20447 -127.950468) (xy 127.221488 -127.944118) (xy 127.2286 -127.938022) (xy 127.249531 -127.920379)
			(xy 127.295497 -127.890651) (xy 127.345244 -127.867807) (xy 127.397747 -127.852316) (xy 127.451927 -127.844497)
			(xy 127.479298 -127.844042) (xy 127.506547 -127.844505) (xy 127.560491 -127.852261) (xy 127.612783 -127.867615)
			(xy 127.662357 -127.890254) (xy 127.708204 -127.919718) (xy 127.749391 -127.955407) (xy 127.785081 -127.996594)
			(xy 127.814545 -128.042442) (xy 127.837185 -128.092015) (xy 127.852539 -128.144307) (xy 127.860295 -128.198251)
			(xy 127.860295 -128.252749) (xy 127.852539 -128.306693) (xy 127.837185 -128.358985) (xy 127.814545 -128.408558)
			(xy 127.785081 -128.454406) (xy 127.749391 -128.495593) (xy 127.708204 -128.531282) (xy 127.662357 -128.560746)
			(xy 127.612783 -128.583385) (xy 127.560491 -128.598739) (xy 127.506547 -128.606495) (xy 127.479298 -128.607058)
			(xy 127.451928 -128.606586) (xy 127.397751 -128.598761) (xy 127.345248 -128.583273) (xy 127.295499 -128.560438)
			(xy 127.249524 -128.530727) (xy 127.2286 -128.513078) (xy 127.221488 -128.506982) (xy 127.20447 -128.500632)
			(xy 127.119126 -128.500632) (xy 127.102108 -128.506982) (xy 127.094996 -128.513078) (xy 127.074063 -128.530719)
			(xy 127.028095 -128.560443) (xy 126.978349 -128.583289) (xy 126.925847 -128.598785) (xy 126.871669 -128.606614)
			(xy 126.816927 -128.606614) (xy 126.762749 -128.598785) (xy 126.710247 -128.583289) (xy 126.660501 -128.560443)
			(xy 126.614533 -128.530719) (xy 126.5936 -128.513078) (xy 126.586488 -128.506982) (xy 126.56947 -128.500632)
			(xy 126.484126 -128.500632) (xy 126.467108 -128.506982) (xy 126.459996 -128.513078) (xy 126.439065 -128.530721)
			(xy 126.393099 -128.560448) (xy 126.343352 -128.583292) (xy 126.290849 -128.598783) (xy 126.236669 -128.606601)
			(xy 126.209298 -128.607058) (xy 126.182427 -128.606605) (xy 126.129217 -128.599074) (xy 126.07759 -128.584147)
			(xy 126.028571 -128.56212) (xy 125.983129 -128.53343) (xy 125.942165 -128.498643) (xy 125.906491 -128.458451)
			(xy 125.876813 -128.413648) (xy 125.853718 -128.365122) (xy 125.845316 -128.339596) (xy 125.841252 -128.326896)
			(xy 125.821948 -128.308608) (xy 125.724412 -128.284732) (xy 125.715868 -128.283042) (xy 125.698558 -128.284852)
			(xy 125.682836 -128.292318) (xy 125.676406 -128.298194) (xy 123.00458 -130.97002) (xy 122.997901 -130.977432)
			(xy 122.990329 -130.995868) (xy 122.989848 -131.005834) (xy 122.989848 -131.447157) (xy 125.813209 -131.447157)
			(xy 125.813209 -131.392643) (xy 125.820967 -131.338685) (xy 125.836326 -131.28638) (xy 125.858972 -131.236793)
			(xy 125.888445 -131.190933) (xy 125.924144 -131.149735) (xy 125.965343 -131.114037) (xy 126.011203 -131.084566)
			(xy 126.060791 -131.061922) (xy 126.113096 -131.046565) (xy 126.167055 -131.038808) (xy 126.194312 -131.038346)
			(xy 126.221683 -131.038794) (xy 126.275863 -131.046614) (xy 126.328367 -131.062107) (xy 126.378114 -131.084953)
			(xy 126.424079 -131.114682) (xy 126.44501 -131.132326) (xy 126.452122 -131.138422) (xy 126.46914 -131.144772)
			(xy 126.554484 -131.144772) (xy 126.571502 -131.138422) (xy 126.578614 -131.132326) (xy 126.599547 -131.114685)
			(xy 126.645515 -131.084961) (xy 126.695261 -131.062115) (xy 126.747763 -131.046619) (xy 126.801941 -131.03879)
			(xy 126.856683 -131.03879) (xy 126.910861 -131.046619) (xy 126.963363 -131.062115) (xy 127.013109 -131.084961)
			(xy 127.059077 -131.114685) (xy 127.08001 -131.132326) (xy 127.087122 -131.138422) (xy 127.10414 -131.144772)
			(xy 127.189484 -131.144772) (xy 127.206502 -131.138422) (xy 127.213614 -131.132326) (xy 127.234571 -131.114718)
			(xy 127.280537 -131.085) (xy 127.330278 -131.062158) (xy 127.382773 -131.04666) (xy 127.436944 -131.038824)
			(xy 127.464312 -131.038346) (xy 127.491559 -131.038925) (xy 127.545499 -131.046682) (xy 127.597786 -131.062036)
			(xy 127.647356 -131.084675) (xy 127.693199 -131.114138) (xy 127.734383 -131.149826) (xy 127.770069 -131.19101)
			(xy 127.79953 -131.236855) (xy 127.822168 -131.286425) (xy 127.837521 -131.338712) (xy 127.845276 -131.392653)
			(xy 127.845276 -131.447147) (xy 127.837521 -131.501087) (xy 127.822168 -131.553375) (xy 127.79953 -131.602945)
			(xy 127.770069 -131.64879) (xy 127.734383 -131.689974) (xy 127.693199 -131.725662) (xy 127.647356 -131.755125)
			(xy 127.597786 -131.777764) (xy 127.545499 -131.793118) (xy 127.491559 -131.800875) (xy 127.464312 -131.801362)
			(xy 127.436942 -131.800898) (xy 127.382762 -131.793081) (xy 127.330259 -131.777592) (xy 127.280512 -131.75475)
			(xy 127.234545 -131.725024) (xy 127.213614 -131.707382) (xy 127.206502 -131.701286) (xy 127.189484 -131.694936)
			(xy 127.10414 -131.694936) (xy 127.087122 -131.701286) (xy 127.08001 -131.707382) (xy 127.059077 -131.725023)
			(xy 127.013109 -131.754747) (xy 126.963363 -131.777593) (xy 126.910861 -131.793089) (xy 126.856683 -131.800918)
			(xy 126.801941 -131.800918) (xy 126.747763 -131.793089) (xy 126.695261 -131.777593) (xy 126.645515 -131.754747)
			(xy 126.599547 -131.725023) (xy 126.578614 -131.707382) (xy 126.571502 -131.701286) (xy 126.554484 -131.694936)
			(xy 126.46914 -131.694936) (xy 126.452122 -131.701286) (xy 126.44501 -131.707382) (xy 126.424083 -131.725027)
			(xy 126.378109 -131.754739) (xy 126.32836 -131.777574) (xy 126.275858 -131.793063) (xy 126.221682 -131.800889)
			(xy 126.194312 -131.801362) (xy 126.167055 -131.800992) (xy 126.113096 -131.793235) (xy 126.060791 -131.777878)
			(xy 126.011203 -131.755234) (xy 125.965343 -131.725763) (xy 125.924144 -131.690065) (xy 125.888445 -131.648867)
			(xy 125.858972 -131.603007) (xy 125.836326 -131.55342) (xy 125.820967 -131.501115) (xy 125.813209 -131.447157)
			(xy 122.989848 -131.447157) (xy 122.989848 -133.443726) (xy 127.222758 -133.443726) (xy 127.223195 -133.41741)
			(xy 127.230421 -133.365275) (xy 127.244738 -133.314628) (xy 127.265875 -133.266426) (xy 127.293432 -133.221584)
			(xy 127.326887 -133.180952) (xy 127.345948 -133.162802) (xy 127.353343 -133.155275) (xy 127.361873 -133.135999)
			(xy 127.362458 -133.125464) (xy 127.362458 -133.050788) (xy 127.361961 -133.040234) (xy 127.353405 -133.020938)
			(xy 127.345948 -133.01345) (xy 127.326854 -132.99533) (xy 127.293375 -132.954708) (xy 127.265805 -132.909864)
			(xy 127.244669 -132.861654) (xy 127.230368 -132.810993) (xy 127.223175 -132.758847) (xy 127.222758 -132.732526)
			(xy 127.223244 -132.705275) (xy 127.231 -132.651327) (xy 127.246355 -132.599032) (xy 127.268997 -132.549455)
			(xy 127.298463 -132.503605) (xy 127.334154 -132.462414) (xy 127.375345 -132.426723) (xy 127.421195 -132.397257)
			(xy 127.470772 -132.374615) (xy 127.523067 -132.35926) (xy 127.577015 -132.351504) (xy 127.631517 -132.351504)
			(xy 127.685465 -132.35926) (xy 127.73776 -132.374615) (xy 127.787337 -132.397257) (xy 127.833187 -132.426723)
			(xy 127.874378 -132.462414) (xy 127.910069 -132.503605) (xy 127.939535 -132.549455) (xy 127.962177 -132.599032)
			(xy 127.977532 -132.651327) (xy 127.985288 -132.705275) (xy 127.985774 -132.732526) (xy 127.985326 -132.758842)
			(xy 127.978106 -132.810977) (xy 127.963793 -132.861625) (xy 127.942657 -132.909828) (xy 127.915101 -132.954669)
			(xy 127.881645 -132.995301) (xy 127.862584 -133.01345) (xy 127.855156 -133.020949) (xy 127.846647 -133.040246)
			(xy 127.846074 -133.050788) (xy 127.846074 -133.125464) (xy 127.846617 -133.136012) (xy 127.855143 -133.155307)
			(xy 127.862584 -133.162802) (xy 127.881661 -133.180939) (xy 127.91514 -133.221558) (xy 127.942711 -133.266398)
			(xy 127.96385 -133.314606) (xy 127.978155 -133.365263) (xy 127.985353 -133.417407) (xy 127.985774 -133.443726)
			(xy 127.985288 -133.470977) (xy 127.977532 -133.524925) (xy 127.962177 -133.57722) (xy 127.939535 -133.626797)
			(xy 127.910069 -133.672647) (xy 127.874378 -133.713838) (xy 127.833187 -133.749529) (xy 127.787337 -133.778995)
			(xy 127.73776 -133.801637) (xy 127.685465 -133.816992) (xy 127.631517 -133.824748) (xy 127.577015 -133.824748)
			(xy 127.523067 -133.816992) (xy 127.470772 -133.801637) (xy 127.421195 -133.778995) (xy 127.375345 -133.749529)
			(xy 127.334154 -133.713838) (xy 127.298463 -133.672647) (xy 127.268997 -133.626797) (xy 127.246355 -133.57722)
			(xy 127.231 -133.524925) (xy 127.223244 -133.470977) (xy 127.222758 -133.443726) (xy 122.989848 -133.443726)
			(xy 122.989848 -133.847332) (xy 122.992642 -133.85927) (xy 122.995436 -133.864858) (xy 123.009268 -133.892387)
			(xy 123.02884 -133.9508) (xy 123.038763 -134.011601) (xy 123.039378 -134.042404) (xy 123.03881 -134.071495)
			(xy 123.029945 -134.128998) (xy 123.012467 -134.184494) (xy 122.986778 -134.236698) (xy 122.970544 -134.260844)
			(xy 122.966295 -134.267384) (xy 122.961639 -134.282259) (xy 122.9614 -134.290054) (xy 122.9614 -134.810754)
			(xy 122.961689 -134.818539) (xy 122.966351 -134.833397) (xy 122.970544 -134.839964) (xy 122.986774 -134.864116)
			(xy 123.012497 -134.916306) (xy 123.029986 -134.971802) (xy 123.038833 -135.029311) (xy 123.039378 -135.058404)
			(xy 123.03881 -135.087495) (xy 123.030399 -135.142051) (xy 125.46177 -135.142051) (xy 125.46177 -135.087549)
			(xy 125.469526 -135.033603) (xy 125.48488 -134.981309) (xy 125.50752 -134.931732) (xy 125.536985 -134.885882)
			(xy 125.572674 -134.844691) (xy 125.613862 -134.808999) (xy 125.659711 -134.779531) (xy 125.709286 -134.756888)
			(xy 125.761579 -134.741531) (xy 125.815525 -134.733771) (xy 125.842776 -134.733284) (xy 125.871694 -134.733788)
			(xy 125.928867 -134.742515) (xy 125.984068 -134.759774) (xy 126.03603 -134.785168) (xy 126.083563 -134.818116)
			(xy 126.125578 -134.857862) (xy 126.143766 -134.88035) (xy 126.151132 -134.889748) (xy 126.172976 -134.900162)
			(xy 126.278386 -134.897876) (xy 126.299722 -134.8867) (xy 126.30658 -134.876794) (xy 126.321977 -134.855883)
			(xy 126.357555 -134.818056) (xy 126.397935 -134.785404) (xy 126.442369 -134.75853) (xy 126.490038 -134.737929)
			(xy 126.54006 -134.723985) (xy 126.591511 -134.716952) (xy 126.617476 -134.71652) (xy 126.644846 -134.716995)
			(xy 126.699025 -134.72481) (xy 126.751528 -134.740297) (xy 126.801275 -134.763137) (xy 126.847242 -134.792859)
			(xy 126.868174 -134.8105) (xy 126.875286 -134.816596) (xy 126.892304 -134.822946) (xy 126.977648 -134.822946)
			(xy 126.994666 -134.816596) (xy 127.001778 -134.8105) (xy 127.022711 -134.792859) (xy 127.068679 -134.763135)
			(xy 127.118425 -134.740289) (xy 127.170927 -134.724793) (xy 127.225105 -134.716964) (xy 127.279847 -134.716964)
			(xy 127.334025 -134.724793) (xy 127.386527 -134.740289) (xy 127.436273 -134.763135) (xy 127.482241 -134.792859)
			(xy 127.503174 -134.8105) (xy 127.510286 -134.816596) (xy 127.527304 -134.822946) (xy 127.612648 -134.822946)
			(xy 127.629666 -134.816596) (xy 127.636778 -134.8105) (xy 127.649576 -134.799552) (xy 127.676794 -134.779709)
			(xy 127.691134 -134.770876) (xy 127.700278 -134.765542) (xy 127.71247 -134.748524) (xy 127.732536 -134.655306)
			(xy 127.728472 -134.634732) (xy 127.722376 -134.626096) (xy 127.706369 -134.602036) (xy 127.681029 -134.550103)
			(xy 127.663805 -134.494944) (xy 127.655092 -134.437819) (xy 127.654558 -134.408926) (xy 127.655044 -134.381675)
			(xy 127.6628 -134.327727) (xy 127.678155 -134.275432) (xy 127.700797 -134.225855) (xy 127.730263 -134.180005)
			(xy 127.765954 -134.138814) (xy 127.807145 -134.103123) (xy 127.852995 -134.073657) (xy 127.902572 -134.051015)
			(xy 127.954867 -134.03566) (xy 128.008815 -134.027904) (xy 128.063317 -134.027904) (xy 128.117265 -134.03566)
			(xy 128.16956 -134.051015) (xy 128.219137 -134.073657) (xy 128.264987 -134.103123) (xy 128.306178 -134.138814)
			(xy 128.341869 -134.180005) (xy 128.371335 -134.225855) (xy 128.393977 -134.275432) (xy 128.409332 -134.327727)
			(xy 128.417088 -134.381675) (xy 128.417574 -134.408926) (xy 128.417121 -134.437019) (xy 128.408889 -134.492599)
			(xy 128.392592 -134.54637) (xy 128.368583 -134.597169) (xy 128.337381 -134.643895) (xy 128.299662 -134.685539)
			(xy 128.256242 -134.721198) (xy 128.232408 -134.736078) (xy 128.223264 -134.741412) (xy 128.211072 -134.75843)
			(xy 128.191006 -134.851648) (xy 128.19507 -134.872222) (xy 128.201166 -134.880858) (xy 128.217146 -134.904934)
			(xy 128.242495 -134.956861) (xy 128.259726 -135.012015) (xy 128.268447 -135.069136) (xy 128.268984 -135.098028)
			(xy 128.268548 -135.125281) (xy 128.260787 -135.179232) (xy 128.245427 -135.231529) (xy 128.222781 -135.281108)
			(xy 128.19331 -135.326959) (xy 128.157613 -135.36815) (xy 128.116418 -135.403841) (xy 128.070562 -135.433306)
			(xy 128.02098 -135.455946) (xy 127.968681 -135.471298) (xy 127.914729 -135.479052) (xy 127.887476 -135.479536)
			(xy 127.860105 -135.4791) (xy 127.805924 -135.471277) (xy 127.753419 -135.455782) (xy 127.703673 -135.432933)
			(xy 127.657708 -135.403201) (xy 127.636778 -135.385556) (xy 127.629666 -135.37946) (xy 127.612648 -135.37311)
			(xy 127.527304 -135.37311) (xy 127.510286 -135.37946) (xy 127.503174 -135.385556) (xy 127.482241 -135.403197)
			(xy 127.436273 -135.432921) (xy 127.386527 -135.455767) (xy 127.334025 -135.471263) (xy 127.279847 -135.479092)
			(xy 127.225105 -135.479092) (xy 127.170927 -135.471263) (xy 127.118425 -135.455767) (xy 127.068679 -135.432921)
			(xy 127.022711 -135.403197) (xy 127.001778 -135.385556) (xy 126.994666 -135.37946) (xy 126.977648 -135.37311)
			(xy 126.892304 -135.37311) (xy 126.875286 -135.37946) (xy 126.868174 -135.385556) (xy 126.847219 -135.403167)
			(xy 126.801253 -135.432885) (xy 126.751512 -135.455727) (xy 126.699016 -135.471224) (xy 126.644844 -135.479059)
			(xy 126.617476 -135.479536) (xy 126.58856 -135.478987) (xy 126.531389 -135.470268) (xy 126.47619 -135.453018)
			(xy 126.424227 -135.427632) (xy 126.376693 -135.394692) (xy 126.334676 -135.354954) (xy 126.316486 -135.33247)
			(xy 126.30912 -135.323072) (xy 126.287276 -135.312658) (xy 126.181866 -135.314944) (xy 126.16053 -135.32612)
			(xy 126.153672 -135.336026) (xy 126.138249 -135.356917) (xy 126.102675 -135.394743) (xy 126.062299 -135.427397)
			(xy 126.017869 -135.454273) (xy 125.970205 -135.474877) (xy 125.920187 -135.488826) (xy 125.868739 -135.495864)
			(xy 125.842776 -135.4963) (xy 125.815525 -135.495829) (xy 125.761579 -135.488069) (xy 125.709286 -135.472712)
			(xy 125.659711 -135.450069) (xy 125.613862 -135.420601) (xy 125.572674 -135.384909) (xy 125.536985 -135.343718)
			(xy 125.50752 -135.297868) (xy 125.48488 -135.248291) (xy 125.469526 -135.195997) (xy 125.46177 -135.142051)
			(xy 123.030399 -135.142051) (xy 123.029945 -135.144998) (xy 123.012467 -135.200494) (xy 122.986778 -135.252698)
			(xy 122.970544 -135.276844) (xy 122.966295 -135.283384) (xy 122.961639 -135.298259) (xy 122.9614 -135.306054)
			(xy 122.9614 -135.478774) (xy 122.961615 -135.485584) (xy 122.965217 -135.498719) (xy 122.968512 -135.504682)
			(xy 122.982912 -135.530067) (xy 123.004674 -135.584217) (xy 123.017934 -135.64105) (xy 123.022385 -135.69924)
			(xy 123.017922 -135.757428) (xy 123.00465 -135.814258) (xy 122.983487 -135.866886) (xy 124.539754 -135.866886)
			(xy 124.543825 -135.811264) (xy 124.555951 -135.756827) (xy 124.575874 -135.704736) (xy 124.60317 -135.656101)
			(xy 124.637256 -135.611958) (xy 124.677405 -135.573249) (xy 124.722763 -135.540798) (xy 124.772363 -135.515297)
			(xy 124.825147 -135.49729) (xy 124.87999 -135.48716) (xy 124.935724 -135.485123) (xy 124.991161 -135.491223)
			(xy 125.045118 -135.505329) (xy 125.096447 -135.527141) (xy 125.144053 -135.556195) (xy 125.186921 -135.59187)
			(xy 125.224138 -135.633407) (xy 125.254911 -135.67992) (xy 125.278583 -135.730417) (xy 125.294651 -135.783824)
			(xy 125.302771 -135.839) (xy 125.30328 -135.866886) (xy 125.302771 -135.894772) (xy 125.294651 -135.949948)
			(xy 125.278583 -136.003355) (xy 125.254911 -136.053852) (xy 125.224138 -136.100365) (xy 125.186921 -136.141902)
			(xy 125.144053 -136.177577) (xy 125.096447 -136.206631) (xy 125.045118 -136.228443) (xy 124.991161 -136.242549)
			(xy 124.935724 -136.248649) (xy 124.87999 -136.246612) (xy 124.825147 -136.236482) (xy 124.772363 -136.218475)
			(xy 124.722763 -136.192974) (xy 124.677405 -136.160523) (xy 124.637256 -136.121814) (xy 124.60317 -136.077671)
			(xy 124.575874 -136.029036) (xy 124.555951 -135.976945) (xy 124.543825 -135.922508) (xy 124.539754 -135.866886)
			(xy 122.983487 -135.866886) (xy 122.982877 -135.868404) (xy 122.968512 -135.89381) (xy 122.965222 -135.899776)
			(xy 122.961607 -135.912908) (xy 122.9614 -135.919718) (xy 122.9614 -136.292082) (xy 122.965464 -136.30148)
			(xy 122.975334 -136.32544) (xy 122.989239 -136.375358) (xy 122.996256 -136.4267) (xy 122.996255 -136.478519)
			(xy 122.989235 -136.52986) (xy 122.975328 -136.579777) (xy 122.965464 -136.60374) (xy 122.9614 -136.613138)
			(xy 122.9614 -137.096754) (xy 122.961689 -137.104539) (xy 122.966351 -137.119397) (xy 122.970544 -137.125964)
			(xy 122.986774 -137.150116) (xy 123.012497 -137.202306) (xy 123.029986 -137.257802) (xy 123.038833 -137.315311)
			(xy 123.039378 -137.344404) (xy 123.03881 -137.373495) (xy 123.029945 -137.430998) (xy 123.024499 -137.44829)
			(xy 124.445012 -137.44829) (xy 124.449083 -137.392668) (xy 124.461209 -137.338231) (xy 124.481132 -137.28614)
			(xy 124.508428 -137.237505) (xy 124.542514 -137.193362) (xy 124.582663 -137.154653) (xy 124.628021 -137.122202)
			(xy 124.677621 -137.096701) (xy 124.730405 -137.078694) (xy 124.785248 -137.068564) (xy 124.840982 -137.066527)
			(xy 124.896419 -137.072627) (xy 124.950376 -137.086733) (xy 125.001705 -137.108545) (xy 125.049311 -137.137599)
			(xy 125.092179 -137.173274) (xy 125.129396 -137.214811) (xy 125.160169 -137.261324) (xy 125.167204 -137.276332)
			(xy 129.147062 -137.276332) (xy 129.147532 -137.248962) (xy 129.155346 -137.194782) (xy 129.170834 -137.142279)
			(xy 129.193675 -137.092532) (xy 129.2234 -137.046565) (xy 129.241042 -137.025634) (xy 129.247138 -137.018522)
			(xy 129.253488 -137.001504) (xy 129.253488 -136.91616) (xy 129.247138 -136.899142) (xy 129.241042 -136.89203)
			(xy 129.22341 -136.871092) (xy 129.193696 -136.825122) (xy 129.170858 -136.775376) (xy 129.155365 -136.722876)
			(xy 129.147536 -136.668701) (xy 129.147062 -136.641332) (xy 129.147548 -136.614081) (xy 129.155304 -136.560133)
			(xy 129.170659 -136.507838) (xy 129.193301 -136.458261) (xy 129.222767 -136.412411) (xy 129.258458 -136.37122)
			(xy 129.299649 -136.335529) (xy 129.345499 -136.306063) (xy 129.395076 -136.283421) (xy 129.447371 -136.268066)
			(xy 129.501319 -136.26031) (xy 129.555821 -136.26031) (xy 129.609769 -136.268066) (xy 129.662064 -136.283421)
			(xy 129.711641 -136.306063) (xy 129.757491 -136.335529) (xy 129.798682 -136.37122) (xy 129.834373 -136.412411)
			(xy 129.863839 -136.458261) (xy 129.886481 -136.507838) (xy 129.901836 -136.560133) (xy 129.909592 -136.614081)
			(xy 129.910078 -136.641332) (xy 129.909636 -136.668703) (xy 129.901813 -136.722883) (xy 129.886319 -136.775387)
			(xy 129.863472 -136.825134) (xy 129.833742 -136.871099) (xy 129.816098 -136.89203) (xy 129.810002 -136.899142)
			(xy 129.803652 -136.91616) (xy 129.803652 -137.001504) (xy 129.810002 -137.018522) (xy 129.816098 -137.025634)
			(xy 129.833719 -137.04658) (xy 129.863434 -137.092549) (xy 129.886273 -137.142293) (xy 129.901769 -137.194791)
			(xy 129.909601 -137.248964) (xy 129.910078 -137.276332) (xy 129.909592 -137.303583) (xy 129.901836 -137.357531)
			(xy 129.886481 -137.409826) (xy 129.863839 -137.459403) (xy 129.834373 -137.505253) (xy 129.798682 -137.546444)
			(xy 129.757491 -137.582135) (xy 129.711641 -137.611601) (xy 129.662064 -137.634243) (xy 129.609769 -137.649598)
			(xy 129.555821 -137.657354) (xy 129.501319 -137.657354) (xy 129.447371 -137.649598) (xy 129.395076 -137.634243)
			(xy 129.345499 -137.611601) (xy 129.299649 -137.582135) (xy 129.258458 -137.546444) (xy 129.222767 -137.505253)
			(xy 129.193301 -137.459403) (xy 129.170659 -137.409826) (xy 129.155304 -137.357531) (xy 129.147548 -137.303583)
			(xy 129.147062 -137.276332) (xy 125.167204 -137.276332) (xy 125.183841 -137.311821) (xy 125.199909 -137.365228)
			(xy 125.208029 -137.420404) (xy 125.208538 -137.44829) (xy 125.208029 -137.476176) (xy 125.199909 -137.531352)
			(xy 125.183841 -137.584759) (xy 125.160169 -137.635256) (xy 125.129396 -137.681769) (xy 125.092179 -137.723306)
			(xy 125.088132 -137.726674) (xy 130.087624 -137.726674) (xy 130.088069 -137.699303) (xy 130.095891 -137.645123)
			(xy 130.111385 -137.592619) (xy 130.134231 -137.542873) (xy 130.16396 -137.496907) (xy 130.181604 -137.475976)
			(xy 130.1877 -137.468864) (xy 130.19405 -137.451846) (xy 130.19405 -137.366502) (xy 130.1877 -137.349484)
			(xy 130.181604 -137.342372) (xy 130.163986 -137.321423) (xy 130.134271 -137.275455) (xy 130.111431 -137.225712)
			(xy 130.095935 -137.173215) (xy 130.088101 -137.119042) (xy 130.087624 -137.091674) (xy 130.08811 -137.064423)
			(xy 130.095866 -137.010475) (xy 130.111221 -136.95818) (xy 130.133863 -136.908603) (xy 130.163329 -136.862753)
			(xy 130.19902 -136.821562) (xy 130.240211 -136.785871) (xy 130.286061 -136.756405) (xy 130.335638 -136.733763)
			(xy 130.387933 -136.718408) (xy 130.441881 -136.710652) (xy 130.496383 -136.710652) (xy 130.550331 -136.718408)
			(xy 130.602626 -136.733763) (xy 130.652203 -136.756405) (xy 130.698053 -136.785871) (xy 130.739244 -136.821562)
			(xy 130.774935 -136.862753) (xy 130.804401 -136.908603) (xy 130.827043 -136.95818) (xy 130.842398 -137.010475)
			(xy 130.850154 -137.064423) (xy 130.85064 -137.091674) (xy 130.850173 -137.119044) (xy 130.842358 -137.173224)
			(xy 130.82687 -137.225728) (xy 130.804028 -137.275475) (xy 130.774302 -137.321441) (xy 130.75666 -137.342372)
			(xy 130.750564 -137.349484) (xy 130.744214 -137.366502) (xy 130.744214 -137.451846) (xy 130.750564 -137.468864)
			(xy 130.75666 -137.475976) (xy 130.774295 -137.496911) (xy 130.804009 -137.542883) (xy 130.826846 -137.592629)
			(xy 130.842338 -137.645129) (xy 130.850166 -137.699305) (xy 130.85064 -137.726674) (xy 130.850154 -137.753925)
			(xy 130.842398 -137.807873) (xy 130.827043 -137.860168) (xy 130.804401 -137.909745) (xy 130.774935 -137.955595)
			(xy 130.739244 -137.996786) (xy 130.698053 -138.032477) (xy 130.652203 -138.061943) (xy 130.602626 -138.084585)
			(xy 130.550331 -138.09994) (xy 130.496383 -138.107696) (xy 130.441881 -138.107696) (xy 130.387933 -138.09994)
			(xy 130.335638 -138.084585) (xy 130.286061 -138.061943) (xy 130.240211 -138.032477) (xy 130.19902 -137.996786)
			(xy 130.163329 -137.955595) (xy 130.133863 -137.909745) (xy 130.111221 -137.860168) (xy 130.095866 -137.807873)
			(xy 130.08811 -137.753925) (xy 130.087624 -137.726674) (xy 125.088132 -137.726674) (xy 125.049311 -137.758981)
			(xy 125.001705 -137.788035) (xy 124.950376 -137.809847) (xy 124.896419 -137.823953) (xy 124.840982 -137.830053)
			(xy 124.785248 -137.828016) (xy 124.730405 -137.817886) (xy 124.677621 -137.799879) (xy 124.628021 -137.774378)
			(xy 124.582663 -137.741927) (xy 124.542514 -137.703218) (xy 124.508428 -137.659075) (xy 124.481132 -137.61044)
			(xy 124.461209 -137.558349) (xy 124.449083 -137.503912) (xy 124.445012 -137.44829) (xy 123.024499 -137.44829)
			(xy 123.012467 -137.486494) (xy 122.986778 -137.538698) (xy 122.970544 -137.562844) (xy 122.966295 -137.569384)
			(xy 122.961639 -137.584259) (xy 122.9614 -137.592054) (xy 122.9614 -138.112754) (xy 122.961689 -138.120539)
			(xy 122.966351 -138.135397) (xy 122.970544 -138.141964) (xy 122.986774 -138.166116) (xy 123.012497 -138.218306)
			(xy 123.029986 -138.273802) (xy 123.038833 -138.331311) (xy 123.039378 -138.360404) (xy 123.03881 -138.389495)
			(xy 123.036677 -138.40333) (xy 131.296156 -138.40333) (xy 131.296666 -138.375664) (xy 131.304662 -138.320914)
			(xy 131.320477 -138.267891) (xy 131.34378 -138.217706) (xy 131.374082 -138.17141) (xy 131.41075 -138.129973)
			(xy 131.453014 -138.094262) (xy 131.476242 -138.079226) (xy 131.486402 -138.072876) (xy 131.498848 -138.053318)
			(xy 131.509262 -137.949178) (xy 131.501134 -137.927334) (xy 131.492244 -137.918952) (xy 131.473666 -137.900868)
			(xy 131.441085 -137.860538) (xy 131.414271 -137.816164) (xy 131.393717 -137.768566) (xy 131.379804 -137.718622)
			(xy 131.372787 -137.667253) (xy 131.372356 -137.64133) (xy 131.372906 -137.614081) (xy 131.380658 -137.560138)
			(xy 131.396007 -137.507846) (xy 131.418642 -137.458272) (xy 131.448102 -137.412423) (xy 131.483787 -137.371233)
			(xy 131.52497 -137.335541) (xy 131.570814 -137.306074) (xy 131.620384 -137.28343) (xy 131.672673 -137.268072)
			(xy 131.726615 -137.260311) (xy 131.753864 -137.259822) (xy 131.781234 -137.260304) (xy 131.835412 -137.268117)
			(xy 131.887915 -137.283602) (xy 131.937663 -137.30644) (xy 131.98363 -137.336162) (xy 132.004562 -137.353802)
			(xy 132.011674 -137.359898) (xy 132.028692 -137.366248) (xy 132.114036 -137.366248) (xy 132.131054 -137.359898)
			(xy 132.138166 -137.353802) (xy 132.1591 -137.336166) (xy 132.205072 -137.306453) (xy 132.254819 -137.283617)
			(xy 132.30732 -137.268125) (xy 132.361495 -137.260296) (xy 132.388864 -137.259822) (xy 132.416117 -137.260289)
			(xy 132.47007 -137.268042) (xy 132.522369 -137.283395) (xy 132.571951 -137.306035) (xy 132.617806 -137.335502)
			(xy 132.659 -137.371196) (xy 132.694694 -137.412389) (xy 132.724162 -137.458243) (xy 132.746803 -137.507825)
			(xy 132.762157 -137.560124) (xy 132.769911 -137.614077) (xy 132.770372 -137.64133) (xy 132.769814 -137.670246)
			(xy 132.761095 -137.727415) (xy 132.743846 -137.782614) (xy 132.718461 -137.834576) (xy 132.685524 -137.882111)
			(xy 132.645789 -137.924129) (xy 132.623306 -137.94232) (xy 132.61454 -137.949879) (xy 132.604359 -137.97064)
			(xy 132.603748 -137.982198) (xy 132.603748 -138.062462) (xy 132.604324 -138.07403) (xy 132.614513 -138.094802)
			(xy 132.623306 -138.10234) (xy 132.64581 -138.120507) (xy 132.685544 -138.162532) (xy 132.71848 -138.210072)
			(xy 132.743865 -138.262038) (xy 132.761117 -138.31724) (xy 132.76984 -138.374413) (xy 132.770372 -138.40333)
			(xy 132.769973 -138.430585) (xy 132.762211 -138.48454) (xy 132.750105 -138.525758) (xy 133.041644 -138.525758)
			(xy 133.042133 -138.498388) (xy 133.049944 -138.44421) (xy 133.065427 -138.391707) (xy 133.088264 -138.341959)
			(xy 133.117984 -138.295992) (xy 133.135624 -138.27506) (xy 133.14172 -138.267948) (xy 133.14807 -138.25093)
			(xy 133.14807 -138.165586) (xy 133.14172 -138.148568) (xy 133.135624 -138.141456) (xy 133.117942 -138.120557)
			(xy 133.088219 -138.074583) (xy 133.065377 -138.024831) (xy 133.049884 -137.972324) (xy 133.042059 -137.918141)
			(xy 133.042064 -137.863396) (xy 133.049897 -137.809214) (xy 133.065399 -137.75671) (xy 133.08825 -137.706962)
			(xy 133.11798 -137.660993) (xy 133.135624 -137.64006) (xy 133.14172 -137.632948) (xy 133.14807 -137.61593)
			(xy 133.14807 -137.530586) (xy 133.14172 -137.513568) (xy 133.135624 -137.506456) (xy 133.117942 -137.485557)
			(xy 133.088219 -137.439583) (xy 133.065377 -137.389831) (xy 133.049884 -137.337324) (xy 133.042059 -137.283141)
			(xy 133.042064 -137.228396) (xy 133.049897 -137.174214) (xy 133.065399 -137.12171) (xy 133.08825 -137.071962)
			(xy 133.11798 -137.025993) (xy 133.135624 -137.00506) (xy 133.14172 -136.997948) (xy 133.14807 -136.98093)
			(xy 133.14807 -136.895586) (xy 133.14172 -136.878568) (xy 133.135624 -136.871456) (xy 133.118001 -136.850511)
			(xy 133.088286 -136.804542) (xy 133.065447 -136.754798) (xy 133.049952 -136.7023) (xy 133.04212 -136.648126)
			(xy 133.041644 -136.620758) (xy 133.04213 -136.593507) (xy 133.049886 -136.539559) (xy 133.065241 -136.487264)
			(xy 133.087883 -136.437687) (xy 133.117349 -136.391837) (xy 133.15304 -136.350646) (xy 133.194231 -136.314955)
			(xy 133.240081 -136.285489) (xy 133.289658 -136.262847) (xy 133.341953 -136.247492) (xy 133.395901 -136.239736)
			(xy 133.450403 -136.239736) (xy 133.504351 -136.247492) (xy 133.556646 -136.262847) (xy 133.606223 -136.285489)
			(xy 133.652073 -136.314955) (xy 133.693264 -136.350646) (xy 133.728955 -136.391837) (xy 133.758421 -136.437687)
			(xy 133.781063 -136.487264) (xy 133.796418 -136.539559) (xy 133.804174 -136.593507) (xy 133.80466 -136.620758)
			(xy 133.804179 -136.648128) (xy 133.796366 -136.702307) (xy 133.780881 -136.75481) (xy 133.758043 -136.804557)
			(xy 133.72832 -136.850524) (xy 133.71068 -136.871456) (xy 133.704584 -136.878568) (xy 133.698234 -136.895586)
			(xy 133.698234 -136.98093) (xy 133.704584 -136.997948) (xy 133.71068 -137.00506) (xy 133.728279 -137.026026)
			(xy 133.758005 -137.071988) (xy 133.780853 -137.121729) (xy 133.796352 -137.174226) (xy 133.804184 -137.2284)
			(xy 133.804189 -137.283137) (xy 133.796365 -137.337312) (xy 133.780875 -137.389812) (xy 133.758036 -137.439556)
			(xy 133.728317 -137.485523) (xy 133.71068 -137.506456) (xy 133.704584 -137.513568) (xy 133.698234 -137.530586)
			(xy 133.698234 -137.61593) (xy 133.704584 -137.632948) (xy 133.71068 -137.64006) (xy 133.728279 -137.661026)
			(xy 133.758005 -137.706988) (xy 133.780853 -137.756729) (xy 133.796352 -137.809226) (xy 133.804184 -137.8634)
			(xy 133.804189 -137.918137) (xy 133.796365 -137.972312) (xy 133.780875 -138.024812) (xy 133.758036 -138.074556)
			(xy 133.728317 -138.120523) (xy 133.71068 -138.141456) (xy 133.704584 -138.148568) (xy 133.698234 -138.165586)
			(xy 133.698234 -138.25093) (xy 133.704584 -138.267948) (xy 133.71068 -138.27506) (xy 133.728311 -138.295999)
			(xy 133.758024 -138.34197) (xy 133.780862 -138.391715) (xy 133.796355 -138.444215) (xy 133.804185 -138.498389)
			(xy 133.80466 -138.525758) (xy 133.804185 -138.552387) (xy 133.796782 -138.605129) (xy 133.782114 -138.656328)
			(xy 133.760466 -138.704988) (xy 133.732259 -138.750164) (xy 133.715506 -138.770868) (xy 133.707632 -138.780266)
			(xy 133.702044 -138.80338) (xy 133.726428 -138.906504) (xy 133.741668 -138.924538) (xy 133.752844 -138.929364)
			(xy 133.779561 -138.941549) (xy 133.829186 -138.972936) (xy 133.85165 -138.991848) (xy 133.858762 -138.997944)
			(xy 133.87578 -139.004294) (xy 133.961124 -139.004294) (xy 133.978142 -138.997944) (xy 133.985254 -138.991848)
			(xy 134.006187 -138.974207) (xy 134.052155 -138.944483) (xy 134.101901 -138.921637) (xy 134.154403 -138.906141)
			(xy 134.208581 -138.898312) (xy 134.263323 -138.898312) (xy 134.317501 -138.906141) (xy 134.370003 -138.921637)
			(xy 134.419749 -138.944483) (xy 134.465717 -138.974207) (xy 134.48665 -138.991848) (xy 134.493762 -138.997944)
			(xy 134.51078 -139.004294) (xy 134.596124 -139.004294) (xy 134.613142 -138.997944) (xy 134.620254 -138.991848)
			(xy 134.641187 -138.974207) (xy 134.687155 -138.944483) (xy 134.736901 -138.921637) (xy 134.789403 -138.906141)
			(xy 134.843581 -138.898312) (xy 134.898323 -138.898312) (xy 134.952501 -138.906141) (xy 135.005003 -138.921637)
			(xy 135.054749 -138.944483) (xy 135.100717 -138.974207) (xy 135.12165 -138.991848) (xy 135.128762 -138.997944)
			(xy 135.14578 -139.004294) (xy 135.231124 -139.004294) (xy 135.248142 -138.997944) (xy 135.255254 -138.991848)
			(xy 135.276199 -138.974224) (xy 135.322167 -138.944509) (xy 135.371912 -138.921669) (xy 135.42441 -138.906174)
			(xy 135.478584 -138.898343) (xy 135.505952 -138.897868) (xy 135.533205 -138.898376) (xy 135.587158 -138.906127)
			(xy 135.639458 -138.921478) (xy 135.689041 -138.944116) (xy 135.734898 -138.973581) (xy 135.776094 -139.009272)
			(xy 135.81179 -139.050464) (xy 135.841261 -139.096316) (xy 135.863905 -139.145897) (xy 135.879263 -139.198195)
			(xy 135.887021 -139.252147) (xy 135.887021 -139.306653) (xy 135.879263 -139.360605) (xy 135.863905 -139.412903)
			(xy 135.841261 -139.462484) (xy 135.81179 -139.508336) (xy 135.776094 -139.549528) (xy 135.734898 -139.585219)
			(xy 135.689041 -139.614684) (xy 135.639458 -139.637322) (xy 135.587158 -139.652673) (xy 135.533205 -139.660424)
			(xy 135.505952 -139.660884) (xy 135.478583 -139.660391) (xy 135.424405 -139.652581) (xy 135.371902 -139.637098)
			(xy 135.322154 -139.614262) (xy 135.276186 -139.584543) (xy 135.255254 -139.566904) (xy 135.248142 -139.560808)
			(xy 135.231124 -139.554458) (xy 135.14578 -139.554458) (xy 135.128762 -139.560808) (xy 135.12165 -139.566904)
			(xy 135.100717 -139.584545) (xy 135.054749 -139.614269) (xy 135.005003 -139.637115) (xy 134.952501 -139.652611)
			(xy 134.898323 -139.66044) (xy 134.843581 -139.66044) (xy 134.789403 -139.652611) (xy 134.736901 -139.637115)
			(xy 134.687155 -139.614269) (xy 134.641187 -139.584545) (xy 134.620254 -139.566904) (xy 134.613142 -139.560808)
			(xy 134.596124 -139.554458) (xy 134.51078 -139.554458) (xy 134.493762 -139.560808) (xy 134.48665 -139.566904)
			(xy 134.465717 -139.584545) (xy 134.419749 -139.614269) (xy 134.370003 -139.637115) (xy 134.317501 -139.652611)
			(xy 134.263323 -139.66044) (xy 134.208581 -139.66044) (xy 134.154403 -139.652611) (xy 134.101901 -139.637115)
			(xy 134.052155 -139.614269) (xy 134.006187 -139.584545) (xy 133.985254 -139.566904) (xy 133.978142 -139.560808)
			(xy 133.961124 -139.554458) (xy 133.87578 -139.554458) (xy 133.858762 -139.560808) (xy 133.85165 -139.566904)
			(xy 133.83071 -139.584534) (xy 133.78474 -139.614247) (xy 133.734994 -139.637085) (xy 133.682495 -139.652578)
			(xy 133.628321 -139.660409) (xy 133.600952 -139.660884) (xy 133.573698 -139.660467) (xy 133.519747 -139.652703)
			(xy 133.46745 -139.637341) (xy 133.417871 -139.614692) (xy 133.372019 -139.585219) (xy 133.330829 -139.54952)
			(xy 133.295138 -139.508323) (xy 133.265673 -139.462466) (xy 133.243034 -139.412883) (xy 133.227682 -139.360583)
			(xy 133.219928 -139.30663) (xy 133.219444 -139.279376) (xy 133.21988 -139.252745) (xy 133.227292 -139.200002)
			(xy 133.241969 -139.148803) (xy 133.263626 -139.100143) (xy 133.291841 -139.054969) (xy 133.308598 -139.034266)
			(xy 133.316472 -139.024868) (xy 133.32206 -139.001754) (xy 133.297676 -138.89863) (xy 133.282436 -138.880596)
			(xy 133.27126 -138.87577) (xy 133.246048 -138.864275) (xy 133.198951 -138.835085) (xy 133.156571 -138.799391)
			(xy 133.119797 -138.757944) (xy 133.089403 -138.711615) (xy 133.066029 -138.661377) (xy 133.050164 -138.608288)
			(xy 133.042143 -138.553462) (xy 133.041644 -138.525758) (xy 132.750105 -138.525758) (xy 132.746849 -138.536842)
			(xy 132.724201 -138.586424) (xy 132.694726 -138.632279) (xy 132.659026 -138.673472) (xy 132.617826 -138.709166)
			(xy 132.571966 -138.738632) (xy 132.52238 -138.761272) (xy 132.470076 -138.776625) (xy 132.416119 -138.784378)
			(xy 132.388864 -138.784838) (xy 132.362548 -138.784377) (xy 132.310415 -138.777156) (xy 132.259768 -138.762844)
			(xy 132.211566 -138.741711) (xy 132.166724 -138.714158) (xy 132.126091 -138.680707) (xy 132.10794 -138.661648)
			(xy 132.100399 -138.654269) (xy 132.081134 -138.64573) (xy 132.070602 -138.645138) (xy 131.995926 -138.645138)
			(xy 131.985375 -138.645657) (xy 131.966079 -138.654198) (xy 131.958588 -138.661648) (xy 131.940449 -138.680723)
			(xy 131.899831 -138.714204) (xy 131.854991 -138.741776) (xy 131.806785 -138.762916) (xy 131.756127 -138.77722)
			(xy 131.703983 -138.784418) (xy 131.677664 -138.784838) (xy 131.650413 -138.784356) (xy 131.596467 -138.776595)
			(xy 131.544174 -138.761237) (xy 131.494599 -138.738594) (xy 131.44875 -138.709127) (xy 131.407561 -138.673435)
			(xy 131.37187 -138.632245) (xy 131.342403 -138.586396) (xy 131.319761 -138.53682) (xy 131.304404 -138.484527)
			(xy 131.296644 -138.430581) (xy 131.296156 -138.40333) (xy 123.036677 -138.40333) (xy 123.029945 -138.446998)
			(xy 123.012467 -138.502494) (xy 122.986778 -138.554698) (xy 122.970544 -138.578844) (xy 122.966295 -138.585384)
			(xy 122.961639 -138.600259) (xy 122.9614 -138.608054) (xy 122.9614 -138.824462) (xy 124.461776 -138.824462)
			(xy 124.465847 -138.76884) (xy 124.477973 -138.714403) (xy 124.497896 -138.662312) (xy 124.525192 -138.613677)
			(xy 124.559278 -138.569534) (xy 124.599427 -138.530825) (xy 124.644785 -138.498374) (xy 124.694385 -138.472873)
			(xy 124.747169 -138.454866) (xy 124.802012 -138.444736) (xy 124.857746 -138.442699) (xy 124.913183 -138.448799)
			(xy 124.96714 -138.462905) (xy 125.018469 -138.484717) (xy 125.066075 -138.513771) (xy 125.108943 -138.549446)
			(xy 125.14616 -138.590983) (xy 125.176933 -138.637496) (xy 125.200605 -138.687993) (xy 125.216673 -138.7414)
			(xy 125.224793 -138.796576) (xy 125.225302 -138.824462) (xy 125.224793 -138.852348) (xy 125.216673 -138.907524)
			(xy 125.200605 -138.960931) (xy 125.176933 -139.011428) (xy 125.14616 -139.057941) (xy 125.108943 -139.099478)
			(xy 125.066075 -139.135153) (xy 125.018469 -139.164207) (xy 124.96714 -139.186019) (xy 124.913183 -139.200125)
			(xy 124.857746 -139.206225) (xy 124.802012 -139.204188) (xy 124.747169 -139.194058) (xy 124.694385 -139.176051)
			(xy 124.644785 -139.15055) (xy 124.599427 -139.118099) (xy 124.559278 -139.07939) (xy 124.525192 -139.035247)
			(xy 124.497896 -138.986612) (xy 124.477973 -138.934521) (xy 124.465847 -138.880084) (xy 124.461776 -138.824462)
			(xy 122.9614 -138.824462) (xy 122.9614 -139.128754) (xy 122.961689 -139.136539) (xy 122.966351 -139.151397)
			(xy 122.970544 -139.157964) (xy 122.986774 -139.182116) (xy 123.012497 -139.234306) (xy 123.029986 -139.289802)
			(xy 123.038833 -139.347311) (xy 123.039378 -139.376404) (xy 123.03881 -139.405495) (xy 123.029945 -139.462998)
			(xy 123.012467 -139.518494) (xy 122.986778 -139.570698) (xy 122.970544 -139.594844) (xy 122.966295 -139.601384)
			(xy 122.961639 -139.616259) (xy 122.9614 -139.624054) (xy 122.9614 -140.144754) (xy 122.961689 -140.152539)
			(xy 122.966351 -140.167397) (xy 122.970544 -140.173964) (xy 122.986774 -140.198116) (xy 123.012497 -140.250306)
			(xy 123.029986 -140.305802) (xy 123.038833 -140.363311) (xy 123.039378 -140.392404) (xy 124.467618 -140.392404)
			(xy 124.471689 -140.336782) (xy 124.483815 -140.282345) (xy 124.503738 -140.230254) (xy 124.531034 -140.181619)
			(xy 124.56512 -140.137476) (xy 124.605269 -140.098767) (xy 124.650627 -140.066316) (xy 124.700227 -140.040815)
			(xy 124.753011 -140.022808) (xy 124.807854 -140.012678) (xy 124.863588 -140.010641) (xy 124.919025 -140.016741)
			(xy 124.972982 -140.030847) (xy 125.024311 -140.052659) (xy 125.071917 -140.081713) (xy 125.114785 -140.117388)
			(xy 125.152002 -140.158925) (xy 125.182775 -140.205438) (xy 125.206447 -140.255935) (xy 125.222515 -140.309342)
			(xy 125.230635 -140.364518) (xy 125.231144 -140.392404) (xy 125.230635 -140.42029) (xy 125.222515 -140.475466)
			(xy 125.206447 -140.528873) (xy 125.182775 -140.57937) (xy 125.152002 -140.625883) (xy 125.114785 -140.66742)
			(xy 125.071917 -140.703095) (xy 125.024311 -140.732149) (xy 124.972982 -140.753961) (xy 124.919025 -140.768067)
			(xy 124.863588 -140.774167) (xy 124.807854 -140.77213) (xy 124.753011 -140.762) (xy 124.700227 -140.743993)
			(xy 124.650627 -140.718492) (xy 124.605269 -140.686041) (xy 124.56512 -140.647332) (xy 124.531034 -140.603189)
			(xy 124.503738 -140.554554) (xy 124.483815 -140.502463) (xy 124.471689 -140.448026) (xy 124.467618 -140.392404)
			(xy 123.039378 -140.392404) (xy 123.03881 -140.421495) (xy 123.029945 -140.478998) (xy 123.012467 -140.534494)
			(xy 122.986778 -140.586698) (xy 122.970544 -140.610844) (xy 122.966295 -140.617384) (xy 122.961639 -140.632259)
			(xy 122.9614 -140.640054) (xy 122.9614 -141.046551) (xy 126.854954 -141.046551) (xy 126.854954 -140.992049)
			(xy 126.86271 -140.9381) (xy 126.878064 -140.885805) (xy 126.900704 -140.836227) (xy 126.930169 -140.790375)
			(xy 126.965859 -140.749183) (xy 127.007048 -140.71349) (xy 127.052897 -140.684021) (xy 127.102473 -140.661376)
			(xy 127.154767 -140.646017) (xy 127.208715 -140.638256) (xy 127.235966 -140.637768) (xy 127.262282 -140.638208)
			(xy 127.314417 -140.645432) (xy 127.365065 -140.659748) (xy 127.413266 -140.680885) (xy 127.458108 -140.708442)
			(xy 127.49874 -140.741897) (xy 127.51689 -140.760958) (xy 127.524419 -140.768351) (xy 127.543693 -140.776882)
			(xy 127.554228 -140.777468) (xy 127.628904 -140.777468) (xy 127.639457 -140.776964) (xy 127.658752 -140.768412)
			(xy 127.666242 -140.760958) (xy 127.684368 -140.741869) (xy 127.724989 -140.70839) (xy 127.769831 -140.680819)
			(xy 127.81804 -140.659682) (xy 127.8687 -140.64538) (xy 127.920846 -140.638186) (xy 127.947166 -140.637768)
			(xy 127.974419 -140.638277) (xy 128.02837 -140.64603) (xy 128.080669 -140.661382) (xy 128.13025 -140.684021)
			(xy 128.176104 -140.713486) (xy 128.217299 -140.749177) (xy 128.252994 -140.790368) (xy 128.282463 -140.83622)
			(xy 128.305106 -140.8858) (xy 128.320463 -140.938097) (xy 128.328221 -140.992047) (xy 128.328221 -141.046553)
			(xy 128.320463 -141.100503) (xy 128.305106 -141.1528) (xy 128.282463 -141.20238) (xy 128.252994 -141.248232)
			(xy 128.217299 -141.289423) (xy 128.176104 -141.325114) (xy 128.13025 -141.354579) (xy 128.080669 -141.377218)
			(xy 128.02837 -141.39257) (xy 127.974419 -141.400323) (xy 127.947166 -141.400784) (xy 127.92085 -141.400338)
			(xy 127.868715 -141.393118) (xy 127.818067 -141.378803) (xy 127.769865 -141.357668) (xy 127.725023 -141.330111)
			(xy 127.684392 -141.296655) (xy 127.666242 -141.277594) (xy 127.658707 -141.270208) (xy 127.639437 -141.261675)
			(xy 127.628904 -141.261084) (xy 127.554228 -141.261084) (xy 127.543679 -141.26162) (xy 127.524384 -141.270151)
			(xy 127.51689 -141.277594) (xy 127.498759 -141.296677) (xy 127.458138 -141.330155) (xy 127.413297 -141.357725)
			(xy 127.365088 -141.378863) (xy 127.31443 -141.393167) (xy 127.262286 -141.400364) (xy 127.235966 -141.400784)
			(xy 127.208715 -141.400344) (xy 127.154767 -141.392583) (xy 127.102473 -141.377224) (xy 127.052897 -141.354579)
			(xy 127.007048 -141.32511) (xy 126.965859 -141.289417) (xy 126.930169 -141.248225) (xy 126.900704 -141.202373)
			(xy 126.878064 -141.152795) (xy 126.86271 -141.1005) (xy 126.854954 -141.046551) (xy 122.9614 -141.046551)
			(xy 122.9614 -143.078551) (xy 126.854954 -143.078551) (xy 126.854954 -143.024049) (xy 126.86271 -142.9701)
			(xy 126.878064 -142.917805) (xy 126.900704 -142.868227) (xy 126.930169 -142.822375) (xy 126.965859 -142.781183)
			(xy 127.007048 -142.74549) (xy 127.052897 -142.716021) (xy 127.102473 -142.693376) (xy 127.154767 -142.678017)
			(xy 127.208715 -142.670256) (xy 127.235966 -142.669768) (xy 127.262282 -142.670208) (xy 127.314417 -142.677432)
			(xy 127.365065 -142.691748) (xy 127.413266 -142.712885) (xy 127.458108 -142.740442) (xy 127.49874 -142.773897)
			(xy 127.51689 -142.792958) (xy 127.524419 -142.800351) (xy 127.543693 -142.808882) (xy 127.554228 -142.809468)
			(xy 127.628904 -142.809468) (xy 127.639457 -142.808964) (xy 127.658752 -142.800412) (xy 127.666242 -142.792958)
			(xy 127.684368 -142.773869) (xy 127.724989 -142.74039) (xy 127.769831 -142.712819) (xy 127.81804 -142.691682)
			(xy 127.8687 -142.67738) (xy 127.920846 -142.670186) (xy 127.947166 -142.669768) (xy 127.974419 -142.670277)
			(xy 128.02837 -142.67803) (xy 128.080669 -142.693382) (xy 128.13025 -142.716021) (xy 128.176104 -142.745486)
			(xy 128.217299 -142.781177) (xy 128.252994 -142.822368) (xy 128.282463 -142.86822) (xy 128.305106 -142.9178)
			(xy 128.320463 -142.970097) (xy 128.328221 -143.024047) (xy 128.328221 -143.078553) (xy 128.320463 -143.132503)
			(xy 128.305106 -143.1848) (xy 128.282463 -143.23438) (xy 128.252994 -143.280232) (xy 128.217299 -143.321423)
			(xy 128.176104 -143.357114) (xy 128.13025 -143.386579) (xy 128.080669 -143.409218) (xy 128.02837 -143.42457)
			(xy 127.974419 -143.432323) (xy 127.947166 -143.432784) (xy 127.92085 -143.432338) (xy 127.868715 -143.425118)
			(xy 127.818067 -143.410803) (xy 127.769865 -143.389668) (xy 127.725023 -143.362111) (xy 127.684392 -143.328655)
			(xy 127.666242 -143.309594) (xy 127.658707 -143.302208) (xy 127.639437 -143.293675) (xy 127.628904 -143.293084)
			(xy 127.554228 -143.293084) (xy 127.543679 -143.29362) (xy 127.524384 -143.302151) (xy 127.51689 -143.309594)
			(xy 127.498759 -143.328677) (xy 127.458138 -143.362155) (xy 127.413297 -143.389725) (xy 127.365088 -143.410863)
			(xy 127.31443 -143.425167) (xy 127.262286 -143.432364) (xy 127.235966 -143.432784) (xy 127.208715 -143.432344)
			(xy 127.154767 -143.424583) (xy 127.102473 -143.409224) (xy 127.052897 -143.386579) (xy 127.007048 -143.35711)
			(xy 126.965859 -143.321417) (xy 126.930169 -143.280225) (xy 126.900704 -143.234373) (xy 126.878064 -143.184795)
			(xy 126.86271 -143.1325) (xy 126.854954 -143.078551) (xy 122.9614 -143.078551) (xy 122.9614 -143.966438)
			(xy 135.564118 -143.966438) (xy 135.564527 -143.940462) (xy 135.571578 -143.88899) (xy 135.585553 -143.838952)
			(xy 135.606195 -143.791276) (xy 135.63312 -143.746845) (xy 135.66583 -143.706483) (xy 135.703718 -143.670936)
			(xy 135.724646 -143.655542) (xy 135.734137 -143.64791) (xy 135.745282 -143.626298) (xy 135.745982 -143.61414)
			(xy 135.745982 -143.531336) (xy 135.745289 -143.519174) (xy 135.73415 -143.497553) (xy 135.724646 -143.489934)
			(xy 135.703727 -143.474531) (xy 135.665851 -143.438978) (xy 135.633151 -143.398613) (xy 135.606232 -143.354184)
			(xy 135.585593 -143.306511) (xy 135.571616 -143.256479) (xy 135.56456 -143.205012) (xy 135.564118 -143.179038)
			(xy 135.564626 -143.150299) (xy 135.573256 -143.093472) (xy 135.590311 -143.038582) (xy 135.615405 -142.98687)
			(xy 135.647971 -142.939507) (xy 135.667242 -142.91818) (xy 135.673846 -142.911068) (xy 135.680958 -142.893542)
			(xy 135.680958 -142.804134) (xy 135.673846 -142.786608) (xy 135.667242 -142.779496) (xy 135.648008 -142.758137)
			(xy 135.61544 -142.710781) (xy 135.590345 -142.659074) (xy 135.573292 -142.604188) (xy 135.564665 -142.547365)
			(xy 135.564661 -142.489891) (xy 135.573279 -142.433066) (xy 135.590325 -142.378177) (xy 135.615412 -142.326467)
			(xy 135.647973 -142.279106) (xy 135.667242 -142.25778) (xy 135.673846 -142.250668) (xy 135.680958 -142.233142)
			(xy 135.680958 -142.143734) (xy 135.673846 -142.126208) (xy 135.667242 -142.119096) (xy 135.648008 -142.097737)
			(xy 135.61544 -142.050381) (xy 135.590345 -141.998674) (xy 135.573292 -141.943788) (xy 135.564665 -141.886965)
			(xy 135.564661 -141.829491) (xy 135.573279 -141.772666) (xy 135.590325 -141.717777) (xy 135.615412 -141.666067)
			(xy 135.647973 -141.618706) (xy 135.667242 -141.59738) (xy 135.673846 -141.590268) (xy 135.680958 -141.572742)
			(xy 135.680958 -141.483334) (xy 135.673846 -141.465808) (xy 135.667242 -141.458696) (xy 135.648008 -141.437337)
			(xy 135.61544 -141.389981) (xy 135.590345 -141.338274) (xy 135.573292 -141.283388) (xy 135.564665 -141.226565)
			(xy 135.564661 -141.169091) (xy 135.573279 -141.112266) (xy 135.590325 -141.057377) (xy 135.615412 -141.005667)
			(xy 135.647973 -140.958306) (xy 135.667242 -140.93698) (xy 135.673846 -140.929868) (xy 135.680958 -140.912342)
			(xy 135.680958 -140.822934) (xy 135.673846 -140.805408) (xy 135.667242 -140.798296) (xy 135.64799 -140.776953)
			(xy 135.615421 -140.729595) (xy 135.590325 -140.677888) (xy 135.57327 -140.623001) (xy 135.564642 -140.566176)
			(xy 135.564118 -140.537438) (xy 135.564604 -140.510187) (xy 135.57236 -140.456239) (xy 135.587715 -140.403944)
			(xy 135.610357 -140.354367) (xy 135.639823 -140.308517) (xy 135.675514 -140.267326) (xy 135.716705 -140.231635)
			(xy 135.762555 -140.202169) (xy 135.812132 -140.179527) (xy 135.864427 -140.164172) (xy 135.918375 -140.156416)
			(xy 135.972877 -140.156416) (xy 136.026825 -140.164172) (xy 136.07912 -140.179527) (xy 136.128697 -140.202169)
			(xy 136.174547 -140.231635) (xy 136.215738 -140.267326) (xy 136.251429 -140.308517) (xy 136.280895 -140.354367)
			(xy 136.303537 -140.403944) (xy 136.318892 -140.456239) (xy 136.326648 -140.510187) (xy 136.327134 -140.537438)
			(xy 136.326624 -140.566177) (xy 136.317997 -140.623005) (xy 136.300943 -140.677895) (xy 136.275849 -140.729607)
			(xy 136.243281 -140.776969) (xy 136.22401 -140.798296) (xy 136.217406 -140.805408) (xy 136.210294 -140.822934)
			(xy 136.210294 -140.912342) (xy 136.217406 -140.929868) (xy 136.22401 -140.93698) (xy 136.243317 -140.958275)
			(xy 136.275878 -141.005644) (xy 136.300965 -141.057361) (xy 136.318011 -141.112256) (xy 136.326629 -141.169087)
			(xy 136.326625 -141.226568) (xy 136.317999 -141.283398) (xy 136.300945 -141.338291) (xy 136.27585 -141.390004)
			(xy 136.243282 -141.437368) (xy 136.22401 -141.458696) (xy 136.217406 -141.465808) (xy 136.210294 -141.483334)
			(xy 136.210294 -141.572742) (xy 136.217406 -141.590268) (xy 136.22401 -141.59738) (xy 136.243317 -141.618675)
			(xy 136.275878 -141.666044) (xy 136.300965 -141.717761) (xy 136.318011 -141.772656) (xy 136.326629 -141.829487)
			(xy 136.326625 -141.886968) (xy 136.317999 -141.943798) (xy 136.300945 -141.998691) (xy 136.27585 -142.050404)
			(xy 136.243282 -142.097768) (xy 136.22401 -142.119096) (xy 136.217406 -142.126208) (xy 136.210294 -142.143734)
			(xy 136.210294 -142.233142) (xy 136.217406 -142.250668) (xy 136.22401 -142.25778) (xy 136.243317 -142.279075)
			(xy 136.275878 -142.326444) (xy 136.300965 -142.378161) (xy 136.318011 -142.433056) (xy 136.326629 -142.489887)
			(xy 136.326625 -142.547368) (xy 136.317999 -142.604198) (xy 136.300945 -142.659091) (xy 136.27585 -142.710804)
			(xy 136.243282 -142.758168) (xy 136.22401 -142.779496) (xy 136.217406 -142.786608) (xy 136.210294 -142.804134)
			(xy 136.210294 -142.893542) (xy 136.217406 -142.911068) (xy 136.22401 -142.91818) (xy 136.24329 -142.939499)
			(xy 136.275857 -142.986863) (xy 136.300948 -143.038576) (xy 136.317996 -143.093469) (xy 136.326615 -143.150298)
			(xy 136.327134 -143.179038) (xy 136.326727 -143.205015) (xy 136.319679 -143.256488) (xy 136.305704 -143.306526)
			(xy 136.285063 -143.354203) (xy 136.258137 -143.398634) (xy 136.225426 -143.438996) (xy 136.187535 -143.474541)
			(xy 136.166606 -143.489934) (xy 136.157135 -143.497587) (xy 136.145977 -143.519183) (xy 136.14527 -143.531336)
			(xy 136.14527 -143.61414) (xy 136.145957 -143.626303) (xy 136.157098 -143.647926) (xy 136.166606 -143.655542)
			(xy 136.187525 -143.670945) (xy 136.225399 -143.706499) (xy 136.258098 -143.746865) (xy 136.285015 -143.791294)
			(xy 136.305654 -143.838966) (xy 136.319632 -143.888998) (xy 136.326691 -143.940464) (xy 136.327134 -143.966438)
			(xy 136.326648 -143.993689) (xy 136.318892 -144.047637) (xy 136.303537 -144.099932) (xy 136.280895 -144.149509)
			(xy 136.251429 -144.195359) (xy 136.215738 -144.23655) (xy 136.174547 -144.272241) (xy 136.128697 -144.301707)
			(xy 136.07912 -144.324349) (xy 136.026825 -144.339704) (xy 135.972877 -144.34746) (xy 135.918375 -144.34746)
			(xy 135.864427 -144.339704) (xy 135.812132 -144.324349) (xy 135.762555 -144.301707) (xy 135.716705 -144.272241)
			(xy 135.675514 -144.23655) (xy 135.639823 -144.195359) (xy 135.610357 -144.149509) (xy 135.587715 -144.099932)
			(xy 135.57236 -144.047637) (xy 135.564604 -143.993689) (xy 135.564118 -143.966438) (xy 122.9614 -143.966438)
			(xy 122.9614 -145.110551) (xy 126.854954 -145.110551) (xy 126.854954 -145.056049) (xy 126.86271 -145.0021)
			(xy 126.878064 -144.949805) (xy 126.900704 -144.900227) (xy 126.930169 -144.854375) (xy 126.965859 -144.813183)
			(xy 127.007048 -144.77749) (xy 127.052897 -144.748021) (xy 127.102473 -144.725376) (xy 127.154767 -144.710017)
			(xy 127.208715 -144.702256) (xy 127.235966 -144.701768) (xy 127.262282 -144.702208) (xy 127.314417 -144.709432)
			(xy 127.365065 -144.723748) (xy 127.413266 -144.744885) (xy 127.458108 -144.772442) (xy 127.49874 -144.805897)
			(xy 127.51689 -144.824958) (xy 127.524419 -144.832351) (xy 127.543693 -144.840882) (xy 127.554228 -144.841468)
			(xy 127.628904 -144.841468) (xy 127.639457 -144.840964) (xy 127.658752 -144.832412) (xy 127.666242 -144.824958)
			(xy 127.684368 -144.805869) (xy 127.724989 -144.77239) (xy 127.769831 -144.744819) (xy 127.81804 -144.723682)
			(xy 127.8687 -144.70938) (xy 127.920846 -144.702186) (xy 127.947166 -144.701768) (xy 127.974419 -144.702277)
			(xy 128.02837 -144.71003) (xy 128.080669 -144.725382) (xy 128.13025 -144.748021) (xy 128.176104 -144.777486)
			(xy 128.217299 -144.813177) (xy 128.252994 -144.854368) (xy 128.282463 -144.90022) (xy 128.305106 -144.9498)
			(xy 128.306411 -144.954244) (xy 134.038848 -144.954244) (xy 134.039419 -144.926996) (xy 134.047168 -144.873054)
			(xy 134.062516 -144.820763) (xy 134.085149 -144.771189) (xy 134.114606 -144.725341) (xy 134.150289 -144.684151)
			(xy 134.19147 -144.648459) (xy 134.237312 -144.618991) (xy 134.286881 -144.596347) (xy 134.339167 -144.580987)
			(xy 134.393108 -144.573225) (xy 134.420356 -144.572736) (xy 134.44913 -144.573257) (xy 134.506025 -144.581907)
			(xy 134.560976 -144.599004) (xy 134.612736 -144.624159) (xy 134.660132 -144.656801) (xy 134.681468 -144.676114)
			(xy 134.689596 -144.683734) (xy 134.709154 -144.690592) (xy 134.805674 -144.68348) (xy 134.823962 -144.673574)
			(xy 134.83082 -144.664938) (xy 134.849055 -144.642762) (xy 134.890987 -144.603551) (xy 134.938321 -144.571063)
			(xy 134.989987 -144.546033) (xy 135.04482 -144.529025) (xy 135.101581 -144.520423) (xy 135.130286 -144.519904)
			(xy 135.157539 -144.520368) (xy 135.211491 -144.528124) (xy 135.263789 -144.543479) (xy 135.31337 -144.56612)
			(xy 135.359224 -144.595588) (xy 135.400417 -144.631282) (xy 135.436111 -144.672475) (xy 135.465579 -144.718328)
			(xy 135.488221 -144.767909) (xy 135.503576 -144.820207) (xy 135.511331 -144.874159) (xy 135.511794 -144.901412)
			(xy 135.511345 -144.928315) (xy 135.503772 -144.981586) (xy 135.48879 -145.033265) (xy 135.466698 -145.082327)
			(xy 135.437933 -145.127799) (xy 135.403067 -145.16878) (xy 135.362789 -145.204457) (xy 135.340598 -145.219674)
			(xy 135.329676 -145.226786) (xy 135.317738 -145.249646) (xy 135.31977 -145.361914) (xy 135.332724 -145.384266)
			(xy 135.3439 -145.391124) (xy 135.367501 -145.406046) (xy 135.410453 -145.441725) (xy 135.447747 -145.483283)
			(xy 135.478584 -145.529833) (xy 135.502308 -145.58038) (xy 135.51841 -145.633846) (xy 135.526548 -145.689087)
			(xy 135.527034 -145.717006) (xy 135.526579 -145.744) (xy 135.518972 -145.797448) (xy 135.50391 -145.849292)
			(xy 135.481695 -145.898496) (xy 135.452769 -145.94408) (xy 135.435594 -145.96491) (xy 135.428482 -145.973038)
			(xy 135.422386 -145.993612) (xy 135.434578 -146.089624) (xy 135.445754 -146.107912) (xy 135.454644 -146.114262)
			(xy 135.47585 -146.129648) (xy 135.514304 -146.16523) (xy 135.547524 -146.205741) (xy 135.574886 -146.250418)
			(xy 135.595874 -146.298421) (xy 135.610092 -146.348845) (xy 135.617273 -146.400741) (xy 135.617712 -146.426936)
			(xy 135.617226 -146.454187) (xy 135.60947 -146.508135) (xy 135.594115 -146.56043) (xy 135.571473 -146.610007)
			(xy 135.542007 -146.655857) (xy 135.506316 -146.697048) (xy 135.465125 -146.732739) (xy 135.419275 -146.762205)
			(xy 135.369698 -146.784847) (xy 135.317403 -146.800202) (xy 135.263455 -146.807958) (xy 135.208953 -146.807958)
			(xy 135.155005 -146.800202) (xy 135.10271 -146.784847) (xy 135.053133 -146.762205) (xy 135.007283 -146.732739)
			(xy 134.966092 -146.697048) (xy 134.930401 -146.655857) (xy 134.900935 -146.610007) (xy 134.878293 -146.56043)
			(xy 134.862938 -146.508135) (xy 134.855182 -146.454187) (xy 134.854696 -146.426936) (xy 134.855192 -146.399944)
			(xy 134.862792 -146.346498) (xy 134.877845 -146.294656) (xy 134.90005 -146.24545) (xy 134.928966 -146.199864)
			(xy 134.946136 -146.179032) (xy 134.953248 -146.170904) (xy 134.959344 -146.15033) (xy 134.947152 -146.054318)
			(xy 134.935976 -146.03603) (xy 134.927086 -146.02968) (xy 134.902785 -146.012068) (xy 134.859526 -145.970472)
			(xy 134.84098 -145.946876) (xy 134.834884 -145.938748) (xy 134.817866 -145.928588) (xy 134.726934 -145.91538)
			(xy 134.707884 -145.920206) (xy 134.699756 -145.926048) (xy 134.675012 -145.943552) (xy 134.62116 -145.971355)
			(xy 134.563588 -145.990291) (xy 134.503745 -145.999883) (xy 134.473442 -146.00047) (xy 134.446188 -146.000006)
			(xy 134.392236 -145.992253) (xy 134.339935 -145.976901) (xy 134.290353 -145.95426) (xy 134.244498 -145.924793)
			(xy 134.203304 -145.889099) (xy 134.167609 -145.847905) (xy 134.138142 -145.802051) (xy 134.115501 -145.752468)
			(xy 134.100148 -145.700168) (xy 134.092395 -145.646216) (xy 134.091934 -145.618962) (xy 134.092369 -145.592928)
			(xy 134.09946 -145.541345) (xy 134.113493 -145.491203) (xy 134.134206 -145.443432) (xy 134.161217 -145.398918)
			(xy 134.177278 -145.378424) (xy 134.183628 -145.370804) (xy 134.189216 -145.352262) (xy 134.182104 -145.2626)
			(xy 134.173468 -145.245328) (xy 134.166102 -145.238724) (xy 134.146463 -145.220535) (xy 134.111937 -145.179632)
			(xy 134.083465 -145.134305) (xy 134.061605 -145.085444) (xy 134.046787 -145.034009) (xy 134.039302 -144.981008)
			(xy 134.038848 -144.954244) (xy 128.306411 -144.954244) (xy 128.320463 -145.002097) (xy 128.328221 -145.056047)
			(xy 128.328221 -145.110553) (xy 128.320463 -145.164503) (xy 128.305106 -145.2168) (xy 128.282463 -145.26638)
			(xy 128.252994 -145.312232) (xy 128.217299 -145.353423) (xy 128.176104 -145.389114) (xy 128.13025 -145.418579)
			(xy 128.080669 -145.441218) (xy 128.02837 -145.45657) (xy 127.974419 -145.464323) (xy 127.947166 -145.464784)
			(xy 127.92085 -145.464338) (xy 127.868715 -145.457118) (xy 127.818067 -145.442803) (xy 127.769865 -145.421668)
			(xy 127.725023 -145.394111) (xy 127.684392 -145.360655) (xy 127.666242 -145.341594) (xy 127.658707 -145.334208)
			(xy 127.639437 -145.325675) (xy 127.628904 -145.325084) (xy 127.554228 -145.325084) (xy 127.543679 -145.32562)
			(xy 127.524384 -145.334151) (xy 127.51689 -145.341594) (xy 127.498759 -145.360677) (xy 127.458138 -145.394155)
			(xy 127.413297 -145.421725) (xy 127.365088 -145.442863) (xy 127.31443 -145.457167) (xy 127.262286 -145.464364)
			(xy 127.235966 -145.464784) (xy 127.208715 -145.464344) (xy 127.154767 -145.456583) (xy 127.102473 -145.441224)
			(xy 127.052897 -145.418579) (xy 127.007048 -145.38911) (xy 126.965859 -145.353417) (xy 126.930169 -145.312225)
			(xy 126.900704 -145.266373) (xy 126.878064 -145.216795) (xy 126.86271 -145.1645) (xy 126.854954 -145.110551)
			(xy 122.9614 -145.110551) (xy 122.9614 -146.91487) (xy 135.716008 -146.91487) (xy 135.720079 -146.859248)
			(xy 135.732205 -146.804811) (xy 135.752128 -146.75272) (xy 135.779424 -146.704085) (xy 135.81351 -146.659942)
			(xy 135.853659 -146.621233) (xy 135.899017 -146.588782) (xy 135.948617 -146.563281) (xy 136.001401 -146.545274)
			(xy 136.056244 -146.535144) (xy 136.111978 -146.533107) (xy 136.167415 -146.539207) (xy 136.221372 -146.553313)
			(xy 136.272701 -146.575125) (xy 136.320307 -146.604179) (xy 136.363175 -146.639854) (xy 136.400392 -146.681391)
			(xy 136.431165 -146.727904) (xy 136.454837 -146.778401) (xy 136.470905 -146.831808) (xy 136.479025 -146.886984)
			(xy 136.479534 -146.91487) (xy 136.479025 -146.942756) (xy 136.470905 -146.997932) (xy 136.454837 -147.051339)
			(xy 136.449631 -147.062444) (xy 137.094212 -147.062444) (xy 137.098283 -147.006822) (xy 137.110409 -146.952385)
			(xy 137.130332 -146.900294) (xy 137.157628 -146.851659) (xy 137.191714 -146.807516) (xy 137.231863 -146.768807)
			(xy 137.277221 -146.736356) (xy 137.326821 -146.710855) (xy 137.379605 -146.692848) (xy 137.434448 -146.682718)
			(xy 137.490182 -146.680681) (xy 137.545619 -146.686781) (xy 137.599576 -146.700887) (xy 137.650905 -146.722699)
			(xy 137.698511 -146.751753) (xy 137.741379 -146.787428) (xy 137.778596 -146.828965) (xy 137.809369 -146.875478)
			(xy 137.833041 -146.925975) (xy 137.849109 -146.979382) (xy 137.857229 -147.034558) (xy 137.857738 -147.062444)
			(xy 137.857229 -147.09033) (xy 137.849109 -147.145506) (xy 137.833041 -147.198913) (xy 137.809369 -147.24941)
			(xy 137.778596 -147.295923) (xy 137.741379 -147.33746) (xy 137.698511 -147.373135) (xy 137.650905 -147.402189)
			(xy 137.599576 -147.424001) (xy 137.545619 -147.438107) (xy 137.490182 -147.444207) (xy 137.434448 -147.44217)
			(xy 137.379605 -147.43204) (xy 137.326821 -147.414033) (xy 137.277221 -147.388532) (xy 137.231863 -147.356081)
			(xy 137.191714 -147.317372) (xy 137.157628 -147.273229) (xy 137.130332 -147.224594) (xy 137.110409 -147.172503)
			(xy 137.098283 -147.118066) (xy 137.094212 -147.062444) (xy 136.449631 -147.062444) (xy 136.431165 -147.101836)
			(xy 136.400392 -147.148349) (xy 136.363175 -147.189886) (xy 136.320307 -147.225561) (xy 136.272701 -147.254615)
			(xy 136.221372 -147.276427) (xy 136.167415 -147.290533) (xy 136.111978 -147.296633) (xy 136.056244 -147.294596)
			(xy 136.001401 -147.284466) (xy 135.948617 -147.266459) (xy 135.899017 -147.240958) (xy 135.853659 -147.208507)
			(xy 135.81351 -147.169798) (xy 135.779424 -147.125655) (xy 135.752128 -147.07702) (xy 135.732205 -147.024929)
			(xy 135.720079 -146.970492) (xy 135.716008 -146.91487) (xy 122.9614 -146.91487) (xy 122.9614 -147.657656)
			(xy 127.250343 -147.657656) (xy 127.250343 -147.603144) (xy 127.258101 -147.549188) (xy 127.27346 -147.496885)
			(xy 127.296107 -147.4473) (xy 127.32558 -147.401443) (xy 127.361279 -147.360248) (xy 127.402478 -147.324553)
			(xy 127.448339 -147.295085) (xy 127.497926 -147.272445) (xy 127.550231 -147.257092) (xy 127.604188 -147.24934)
			(xy 127.631444 -147.24888) (xy 127.65776 -147.24933) (xy 127.709894 -147.256552) (xy 127.760542 -147.270866)
			(xy 127.808744 -147.292001) (xy 127.853586 -147.319556) (xy 127.894218 -147.35301) (xy 127.912368 -147.37207)
			(xy 127.919904 -147.379455) (xy 127.939173 -147.38799) (xy 127.949706 -147.38858) (xy 128.024382 -147.38858)
			(xy 128.034933 -147.388061) (xy 128.054229 -147.379519) (xy 128.06172 -147.37207) (xy 128.079859 -147.352994)
			(xy 128.120477 -147.319513) (xy 128.165316 -147.291941) (xy 128.213523 -147.270801) (xy 128.26418 -147.256496)
			(xy 128.316324 -147.249299) (xy 128.342644 -147.24888) (xy 128.36896 -147.24933) (xy 128.421094 -147.256552)
			(xy 128.471742 -147.270866) (xy 128.519944 -147.292001) (xy 128.564786 -147.319556) (xy 128.605418 -147.35301)
			(xy 128.623568 -147.37207) (xy 128.631104 -147.379455) (xy 128.650373 -147.38799) (xy 128.660906 -147.38858)
			(xy 128.735582 -147.38858) (xy 128.746133 -147.388061) (xy 128.765429 -147.379519) (xy 128.77292 -147.37207)
			(xy 128.791059 -147.352994) (xy 128.831677 -147.319513) (xy 128.876516 -147.291941) (xy 128.924723 -147.270801)
			(xy 128.97538 -147.256496) (xy 129.027524 -147.249299) (xy 129.053844 -147.24888) (xy 129.081092 -147.249393)
			(xy 129.135034 -147.257155) (xy 129.187321 -147.272513) (xy 129.236891 -147.295156) (xy 129.282735 -147.324622)
			(xy 129.323918 -147.360313) (xy 129.359604 -147.401501) (xy 129.389065 -147.447347) (xy 129.411702 -147.49692)
			(xy 129.427055 -147.54921) (xy 129.43481 -147.603152) (xy 129.43481 -147.657648) (xy 129.427055 -147.71159)
			(xy 129.411702 -147.76388) (xy 129.389065 -147.813453) (xy 129.359604 -147.859299) (xy 129.323918 -147.900487)
			(xy 129.282735 -147.936178) (xy 129.236891 -147.965644) (xy 129.187321 -147.988287) (xy 129.135034 -148.003645)
			(xy 129.081092 -148.011407) (xy 129.053844 -148.011896) (xy 129.027527 -148.011461) (xy 128.975392 -148.004238)
			(xy 128.924744 -147.989921) (xy 128.876542 -147.968783) (xy 128.8317 -147.941225) (xy 128.791069 -147.907768)
			(xy 128.77292 -147.888706) (xy 128.765392 -147.881312) (xy 128.746117 -147.872783) (xy 128.735582 -147.872196)
			(xy 128.660906 -147.872196) (xy 128.650355 -147.872716) (xy 128.63106 -147.881258) (xy 128.623568 -147.888706)
			(xy 128.60545 -147.907802) (xy 128.564826 -147.941278) (xy 128.519982 -147.968846) (xy 128.471771 -147.989982)
			(xy 128.421111 -148.004283) (xy 128.368965 -148.011477) (xy 128.342644 -148.011896) (xy 128.316327 -148.011461)
			(xy 128.264192 -148.004238) (xy 128.213544 -147.989921) (xy 128.165342 -147.968783) (xy 128.1205 -147.941225)
			(xy 128.079869 -147.907768) (xy 128.06172 -147.888706) (xy 128.054192 -147.881312) (xy 128.034917 -147.872783)
			(xy 128.024382 -147.872196) (xy 127.949706 -147.872196) (xy 127.939155 -147.872716) (xy 127.91986 -147.881258)
			(xy 127.912368 -147.888706) (xy 127.89425 -147.907802) (xy 127.853626 -147.941278) (xy 127.808782 -147.968846)
			(xy 127.760571 -147.989982) (xy 127.709911 -148.004283) (xy 127.657765 -148.011477) (xy 127.631444 -148.011896)
			(xy 127.604188 -148.01146) (xy 127.550231 -148.003708) (xy 127.497926 -147.988355) (xy 127.448339 -147.965715)
			(xy 127.402478 -147.936247) (xy 127.361279 -147.900552) (xy 127.32558 -147.859357) (xy 127.296107 -147.8135)
			(xy 127.27346 -147.763915) (xy 127.258101 -147.711612) (xy 127.250343 -147.657656) (xy 122.9614 -147.657656)
			(xy 122.9614 -148.017738) (xy 132.077458 -148.017738) (xy 132.081529 -147.962116) (xy 132.093655 -147.907679)
			(xy 132.113578 -147.855588) (xy 132.140874 -147.806953) (xy 132.17496 -147.76281) (xy 132.215109 -147.724101)
			(xy 132.260467 -147.69165) (xy 132.310067 -147.666149) (xy 132.362851 -147.648142) (xy 132.417694 -147.638012)
			(xy 132.473428 -147.635975) (xy 132.528865 -147.642075) (xy 132.582822 -147.656181) (xy 132.634151 -147.677993)
			(xy 132.681757 -147.707047) (xy 132.724625 -147.742722) (xy 132.761842 -147.784259) (xy 132.792615 -147.830772)
			(xy 132.816287 -147.881269) (xy 132.832355 -147.934676) (xy 132.840475 -147.989852) (xy 132.840984 -148.017738)
			(xy 132.840475 -148.045624) (xy 132.832355 -148.1008) (xy 132.816287 -148.154207) (xy 132.792615 -148.204704)
			(xy 132.761842 -148.251217) (xy 132.724625 -148.292754) (xy 132.681757 -148.328429) (xy 132.634151 -148.357483)
			(xy 132.582822 -148.379295) (xy 132.528865 -148.393401) (xy 132.473428 -148.399501) (xy 132.417694 -148.397464)
			(xy 132.362851 -148.387334) (xy 132.310067 -148.369327) (xy 132.260467 -148.343826) (xy 132.215109 -148.311375)
			(xy 132.17496 -148.272666) (xy 132.140874 -148.228523) (xy 132.113578 -148.179888) (xy 132.093655 -148.127797)
			(xy 132.081529 -148.07336) (xy 132.077458 -148.017738) (xy 122.9614 -148.017738) (xy 122.9614 -150.195854)
			(xy 127.250365 -150.195854) (xy 127.250365 -150.141346) (xy 127.258123 -150.087392) (xy 127.273481 -150.035093)
			(xy 127.296126 -149.985511) (xy 127.325598 -149.939657) (xy 127.361295 -149.898464) (xy 127.402492 -149.862771)
			(xy 127.448349 -149.833305) (xy 127.497934 -149.810666) (xy 127.550236 -149.795314) (xy 127.60419 -149.787562)
			(xy 127.631444 -149.787102) (xy 127.65776 -149.787545) (xy 127.709895 -149.794767) (xy 127.760543 -149.809082)
			(xy 127.808745 -149.830219) (xy 127.853587 -149.857776) (xy 127.894218 -149.891231) (xy 127.912368 -149.910292)
			(xy 127.919901 -149.91768) (xy 127.939172 -149.926212) (xy 127.949706 -149.926802) (xy 128.024382 -149.926802)
			(xy 128.034932 -149.926276) (xy 128.054227 -149.917738) (xy 128.06172 -149.910292) (xy 128.079843 -149.891201)
			(xy 128.120466 -149.857725) (xy 128.165309 -149.830156) (xy 128.213519 -149.809019) (xy 128.264178 -149.794717)
			(xy 128.316324 -149.787521) (xy 128.342644 -149.787102) (xy 128.36896 -149.787545) (xy 128.421095 -149.794767)
			(xy 128.471743 -149.809082) (xy 128.519945 -149.830219) (xy 128.564787 -149.857776) (xy 128.605418 -149.891231)
			(xy 128.623568 -149.910292) (xy 128.631101 -149.91768) (xy 128.650372 -149.926212) (xy 128.660906 -149.926802)
			(xy 128.735582 -149.926802) (xy 128.746132 -149.926276) (xy 128.765427 -149.917738) (xy 128.77292 -149.910292)
			(xy 128.791043 -149.891201) (xy 128.831666 -149.857725) (xy 128.876509 -149.830156) (xy 128.924719 -149.809019)
			(xy 128.975378 -149.794717) (xy 129.027524 -149.787521) (xy 129.053844 -149.787102) (xy 129.081094 -149.787571)
			(xy 129.135038 -149.795333) (xy 129.187329 -149.810692) (xy 129.236902 -149.833336) (xy 129.282748 -149.862804)
			(xy 129.323934 -149.898497) (xy 129.359622 -149.939687) (xy 129.389085 -149.985537) (xy 129.411723 -150.035112)
			(xy 129.420045 -150.063454) (xy 131.938012 -150.063454) (xy 131.942083 -150.007832) (xy 131.954209 -149.953395)
			(xy 131.974132 -149.901304) (xy 132.001428 -149.852669) (xy 132.035514 -149.808526) (xy 132.075663 -149.769817)
			(xy 132.121021 -149.737366) (xy 132.170621 -149.711865) (xy 132.223405 -149.693858) (xy 132.278248 -149.683728)
			(xy 132.333982 -149.681691) (xy 132.389419 -149.687791) (xy 132.443376 -149.701897) (xy 132.494705 -149.723709)
			(xy 132.542311 -149.752763) (xy 132.585179 -149.788438) (xy 132.622396 -149.829975) (xy 132.653169 -149.876488)
			(xy 132.676841 -149.926985) (xy 132.692909 -149.980392) (xy 132.701029 -150.035568) (xy 132.701538 -150.063454)
			(xy 132.701029 -150.09134) (xy 132.692909 -150.146516) (xy 132.676841 -150.199923) (xy 132.653169 -150.25042)
			(xy 132.622396 -150.296933) (xy 132.585179 -150.33847) (xy 132.542311 -150.374145) (xy 132.494705 -150.403199)
			(xy 132.443376 -150.425011) (xy 132.389419 -150.439117) (xy 132.333982 -150.445217) (xy 132.278248 -150.44318)
			(xy 132.223405 -150.43305) (xy 132.170621 -150.415043) (xy 132.121021 -150.389542) (xy 132.075663 -150.357091)
			(xy 132.035514 -150.318382) (xy 132.001428 -150.274239) (xy 131.974132 -150.225604) (xy 131.954209 -150.173513)
			(xy 131.942083 -150.119076) (xy 131.938012 -150.063454) (xy 129.420045 -150.063454) (xy 129.427077 -150.087405)
			(xy 129.434832 -150.14135) (xy 129.434832 -150.19585) (xy 129.427077 -150.249795) (xy 129.411723 -150.302088)
			(xy 129.389085 -150.351663) (xy 129.359622 -150.397513) (xy 129.323934 -150.438703) (xy 129.282748 -150.474396)
			(xy 129.236902 -150.503864) (xy 129.187329 -150.526508) (xy 129.135038 -150.541867) (xy 129.081094 -150.549629)
			(xy 129.053844 -150.550118) (xy 129.027528 -150.549676) (xy 128.975393 -150.542453) (xy 128.924745 -150.528137)
			(xy 128.876543 -150.507001) (xy 128.831702 -150.479444) (xy 128.79107 -150.445989) (xy 128.77292 -150.426928)
			(xy 128.765389 -150.419537) (xy 128.746116 -150.411006) (xy 128.735582 -150.410418) (xy 128.660906 -150.410418)
			(xy 128.650354 -150.410932) (xy 128.631059 -150.419477) (xy 128.623568 -150.426928) (xy 128.605435 -150.446009)
			(xy 128.564816 -150.47949) (xy 128.519975 -150.507062) (xy 128.471767 -150.528201) (xy 128.421109 -150.542504)
			(xy 128.368964 -150.549699) (xy 128.342644 -150.550118) (xy 128.316328 -150.549676) (xy 128.264193 -150.542453)
			(xy 128.213545 -150.528137) (xy 128.165343 -150.507001) (xy 128.120502 -150.479444) (xy 128.07987 -150.445989)
			(xy 128.06172 -150.426928) (xy 128.054189 -150.419537) (xy 128.034916 -150.411006) (xy 128.024382 -150.410418)
			(xy 127.949706 -150.410418) (xy 127.939154 -150.410932) (xy 127.919859 -150.419477) (xy 127.912368 -150.426928)
			(xy 127.894235 -150.446009) (xy 127.853616 -150.47949) (xy 127.808775 -150.507062) (xy 127.760567 -150.528201)
			(xy 127.709909 -150.542504) (xy 127.657764 -150.549699) (xy 127.631444 -150.550118) (xy 127.60419 -150.549638)
			(xy 127.550236 -150.541886) (xy 127.497934 -150.526534) (xy 127.448349 -150.503895) (xy 127.402492 -150.474429)
			(xy 127.361295 -150.438736) (xy 127.325598 -150.397543) (xy 127.296126 -150.351689) (xy 127.273481 -150.302107)
			(xy 127.258123 -150.249808) (xy 127.250365 -150.195854) (xy 122.9614 -150.195854) (xy 122.9614 -151.67102)
			(xy 131.893562 -151.67102) (xy 131.897633 -151.615398) (xy 131.909759 -151.560961) (xy 131.929682 -151.50887)
			(xy 131.956978 -151.460235) (xy 131.991064 -151.416092) (xy 132.031213 -151.377383) (xy 132.076571 -151.344932)
			(xy 132.126171 -151.319431) (xy 132.178955 -151.301424) (xy 132.233798 -151.291294) (xy 132.289532 -151.289257)
			(xy 132.344969 -151.295357) (xy 132.398926 -151.309463) (xy 132.450255 -151.331275) (xy 132.497861 -151.360329)
			(xy 132.540729 -151.396004) (xy 132.577946 -151.437541) (xy 132.608719 -151.484054) (xy 132.632391 -151.534551)
			(xy 132.648459 -151.587958) (xy 132.656579 -151.643134) (xy 132.657088 -151.67102) (xy 132.656615 -151.696928)
			(xy 132.909562 -151.696928) (xy 132.913633 -151.641306) (xy 132.925759 -151.586869) (xy 132.945682 -151.534778)
			(xy 132.972978 -151.486143) (xy 133.007064 -151.442) (xy 133.047213 -151.403291) (xy 133.092571 -151.37084)
			(xy 133.142171 -151.345339) (xy 133.194955 -151.327332) (xy 133.249798 -151.317202) (xy 133.305532 -151.315165)
			(xy 133.360969 -151.321265) (xy 133.414926 -151.335371) (xy 133.466255 -151.357183) (xy 133.513861 -151.386237)
			(xy 133.538337 -151.406606) (xy 134.136636 -151.406606) (xy 134.140707 -151.350984) (xy 134.152833 -151.296547)
			(xy 134.172756 -151.244456) (xy 134.200052 -151.195821) (xy 134.234138 -151.151678) (xy 134.274287 -151.112969)
			(xy 134.319645 -151.080518) (xy 134.369245 -151.055017) (xy 134.422029 -151.03701) (xy 134.476872 -151.02688)
			(xy 134.532606 -151.024843) (xy 134.588043 -151.030943) (xy 134.642 -151.045049) (xy 134.693329 -151.066861)
			(xy 134.740935 -151.095915) (xy 134.783803 -151.13159) (xy 134.82102 -151.173127) (xy 134.851793 -151.21964)
			(xy 134.875465 -151.270137) (xy 134.891533 -151.323544) (xy 134.899653 -151.37872) (xy 134.900162 -151.406606)
			(xy 134.899653 -151.434492) (xy 134.891533 -151.489668) (xy 134.875465 -151.543075) (xy 134.856923 -151.582628)
			(xy 135.462262 -151.582628) (xy 135.466333 -151.527006) (xy 135.478459 -151.472569) (xy 135.498382 -151.420478)
			(xy 135.525678 -151.371843) (xy 135.559764 -151.3277) (xy 135.599913 -151.288991) (xy 135.645271 -151.25654)
			(xy 135.694871 -151.231039) (xy 135.747655 -151.213032) (xy 135.802498 -151.202902) (xy 135.858232 -151.200865)
			(xy 135.913669 -151.206965) (xy 135.967626 -151.221071) (xy 136.018955 -151.242883) (xy 136.066561 -151.271937)
			(xy 136.109429 -151.307612) (xy 136.146646 -151.349149) (xy 136.177419 -151.395662) (xy 136.201091 -151.446159)
			(xy 136.217159 -151.499566) (xy 136.225279 -151.554742) (xy 136.225542 -151.569166) (xy 136.973562 -151.569166)
			(xy 136.977633 -151.513544) (xy 136.989759 -151.459107) (xy 137.009682 -151.407016) (xy 137.036978 -151.358381)
			(xy 137.071064 -151.314238) (xy 137.111213 -151.275529) (xy 137.156571 -151.243078) (xy 137.206171 -151.217577)
			(xy 137.258955 -151.19957) (xy 137.313798 -151.18944) (xy 137.369532 -151.187403) (xy 137.424969 -151.193503)
			(xy 137.478926 -151.207609) (xy 137.530255 -151.229421) (xy 137.577861 -151.258475) (xy 137.620729 -151.29415)
			(xy 137.657946 -151.335687) (xy 137.688719 -151.3822) (xy 137.712391 -151.432697) (xy 137.728459 -151.486104)
			(xy 137.736579 -151.54128) (xy 137.737088 -151.569166) (xy 137.736579 -151.597052) (xy 137.728459 -151.652228)
			(xy 137.712391 -151.705635) (xy 137.688719 -151.756132) (xy 137.657946 -151.802645) (xy 137.620729 -151.844182)
			(xy 137.577861 -151.879857) (xy 137.530255 -151.908911) (xy 137.478926 -151.930723) (xy 137.424969 -151.944829)
			(xy 137.369532 -151.950929) (xy 137.313798 -151.948892) (xy 137.258955 -151.938762) (xy 137.206171 -151.920755)
			(xy 137.156571 -151.895254) (xy 137.111213 -151.862803) (xy 137.071064 -151.824094) (xy 137.036978 -151.779951)
			(xy 137.009682 -151.731316) (xy 136.989759 -151.679225) (xy 136.977633 -151.624788) (xy 136.973562 -151.569166)
			(xy 136.225542 -151.569166) (xy 136.225788 -151.582628) (xy 136.225279 -151.610514) (xy 136.217159 -151.66569)
			(xy 136.201091 -151.719097) (xy 136.177419 -151.769594) (xy 136.146646 -151.816107) (xy 136.109429 -151.857644)
			(xy 136.066561 -151.893319) (xy 136.018955 -151.922373) (xy 135.967626 -151.944185) (xy 135.913669 -151.958291)
			(xy 135.858232 -151.964391) (xy 135.802498 -151.962354) (xy 135.747655 -151.952224) (xy 135.694871 -151.934217)
			(xy 135.645271 -151.908716) (xy 135.599913 -151.876265) (xy 135.559764 -151.837556) (xy 135.525678 -151.793413)
			(xy 135.498382 -151.744778) (xy 135.478459 -151.692687) (xy 135.466333 -151.63825) (xy 135.462262 -151.582628)
			(xy 134.856923 -151.582628) (xy 134.851793 -151.593572) (xy 134.82102 -151.640085) (xy 134.783803 -151.681622)
			(xy 134.740935 -151.717297) (xy 134.693329 -151.746351) (xy 134.642 -151.768163) (xy 134.588043 -151.782269)
			(xy 134.532606 -151.788369) (xy 134.476872 -151.786332) (xy 134.422029 -151.776202) (xy 134.369245 -151.758195)
			(xy 134.319645 -151.732694) (xy 134.274287 -151.700243) (xy 134.234138 -151.661534) (xy 134.200052 -151.617391)
			(xy 134.172756 -151.568756) (xy 134.152833 -151.516665) (xy 134.140707 -151.462228) (xy 134.136636 -151.406606)
			(xy 133.538337 -151.406606) (xy 133.556729 -151.421912) (xy 133.593946 -151.463449) (xy 133.624719 -151.509962)
			(xy 133.648391 -151.560459) (xy 133.664459 -151.613866) (xy 133.672579 -151.669042) (xy 133.673088 -151.696928)
			(xy 133.672579 -151.724814) (xy 133.664459 -151.77999) (xy 133.648391 -151.833397) (xy 133.624719 -151.883894)
			(xy 133.593946 -151.930407) (xy 133.556729 -151.971944) (xy 133.513861 -152.007619) (xy 133.466255 -152.036673)
			(xy 133.414926 -152.058485) (xy 133.360969 -152.072591) (xy 133.305532 -152.078691) (xy 133.249798 -152.076654)
			(xy 133.194955 -152.066524) (xy 133.142171 -152.048517) (xy 133.092571 -152.023016) (xy 133.047213 -151.990565)
			(xy 133.007064 -151.951856) (xy 132.972978 -151.907713) (xy 132.945682 -151.859078) (xy 132.925759 -151.806987)
			(xy 132.913633 -151.75255) (xy 132.909562 -151.696928) (xy 132.656615 -151.696928) (xy 132.656579 -151.698906)
			(xy 132.648459 -151.754082) (xy 132.632391 -151.807489) (xy 132.608719 -151.857986) (xy 132.577946 -151.904499)
			(xy 132.540729 -151.946036) (xy 132.497861 -151.981711) (xy 132.450255 -152.010765) (xy 132.398926 -152.032577)
			(xy 132.344969 -152.046683) (xy 132.289532 -152.052783) (xy 132.233798 -152.050746) (xy 132.178955 -152.040616)
			(xy 132.126171 -152.022609) (xy 132.076571 -151.997108) (xy 132.031213 -151.964657) (xy 131.991064 -151.925948)
			(xy 131.956978 -151.881805) (xy 131.929682 -151.83317) (xy 131.909759 -151.781079) (xy 131.897633 -151.726642)
			(xy 131.893562 -151.67102) (xy 122.9614 -151.67102) (xy 122.9614 -153.782522) (xy 130.877562 -153.782522)
			(xy 130.881633 -153.7269) (xy 130.893759 -153.672463) (xy 130.913682 -153.620372) (xy 130.940978 -153.571737)
			(xy 130.975064 -153.527594) (xy 131.015213 -153.488885) (xy 131.060571 -153.456434) (xy 131.110171 -153.430933)
			(xy 131.162955 -153.412926) (xy 131.217798 -153.402796) (xy 131.273532 -153.400759) (xy 131.328969 -153.406859)
			(xy 131.382926 -153.420965) (xy 131.434255 -153.442777) (xy 131.481861 -153.471831) (xy 131.524729 -153.507506)
			(xy 131.561946 -153.549043) (xy 131.592719 -153.595556) (xy 131.616391 -153.646053) (xy 131.632459 -153.69946)
			(xy 131.640579 -153.754636) (xy 131.641088 -153.782522) (xy 131.893562 -153.782522) (xy 131.897633 -153.7269)
			(xy 131.909759 -153.672463) (xy 131.929682 -153.620372) (xy 131.956978 -153.571737) (xy 131.991064 -153.527594)
			(xy 132.031213 -153.488885) (xy 132.076571 -153.456434) (xy 132.126171 -153.430933) (xy 132.178955 -153.412926)
			(xy 132.233798 -153.402796) (xy 132.289532 -153.400759) (xy 132.344969 -153.406859) (xy 132.398926 -153.420965)
			(xy 132.450255 -153.442777) (xy 132.497861 -153.471831) (xy 132.540729 -153.507506) (xy 132.577946 -153.549043)
			(xy 132.608719 -153.595556) (xy 132.632391 -153.646053) (xy 132.648459 -153.69946) (xy 132.656579 -153.754636)
			(xy 132.657088 -153.782522) (xy 132.656579 -153.810408) (xy 132.653431 -153.831798) (xy 132.909562 -153.831798)
			(xy 132.913633 -153.776176) (xy 132.925759 -153.721739) (xy 132.945682 -153.669648) (xy 132.972978 -153.621013)
			(xy 133.007064 -153.57687) (xy 133.047213 -153.538161) (xy 133.092571 -153.50571) (xy 133.142171 -153.480209)
			(xy 133.194955 -153.462202) (xy 133.249798 -153.452072) (xy 133.305532 -153.450035) (xy 133.360969 -153.456135)
			(xy 133.414926 -153.470241) (xy 133.466255 -153.492053) (xy 133.513861 -153.521107) (xy 133.556729 -153.556782)
			(xy 133.593946 -153.598319) (xy 133.624719 -153.644832) (xy 133.648391 -153.695329) (xy 133.664459 -153.748736)
			(xy 133.669431 -153.782522) (xy 135.957562 -153.782522) (xy 135.961633 -153.7269) (xy 135.973759 -153.672463)
			(xy 135.993682 -153.620372) (xy 136.020978 -153.571737) (xy 136.055064 -153.527594) (xy 136.095213 -153.488885)
			(xy 136.140571 -153.456434) (xy 136.190171 -153.430933) (xy 136.242955 -153.412926) (xy 136.297798 -153.402796)
			(xy 136.353532 -153.400759) (xy 136.408969 -153.406859) (xy 136.462926 -153.420965) (xy 136.514255 -153.442777)
			(xy 136.561861 -153.471831) (xy 136.604729 -153.507506) (xy 136.641946 -153.549043) (xy 136.672719 -153.595556)
			(xy 136.696391 -153.646053) (xy 136.712459 -153.69946) (xy 136.720579 -153.754636) (xy 136.721088 -153.782522)
			(xy 136.720579 -153.810408) (xy 136.712459 -153.865584) (xy 136.696391 -153.918991) (xy 136.672719 -153.969488)
			(xy 136.641946 -154.016001) (xy 136.604729 -154.057538) (xy 136.561861 -154.093213) (xy 136.514255 -154.122267)
			(xy 136.462926 -154.144079) (xy 136.408969 -154.158185) (xy 136.353532 -154.164285) (xy 136.297798 -154.162248)
			(xy 136.242955 -154.152118) (xy 136.190171 -154.134111) (xy 136.140571 -154.10861) (xy 136.095213 -154.076159)
			(xy 136.055064 -154.03745) (xy 136.020978 -153.993307) (xy 135.993682 -153.944672) (xy 135.973759 -153.892581)
			(xy 135.961633 -153.838144) (xy 135.957562 -153.782522) (xy 133.669431 -153.782522) (xy 133.672579 -153.803912)
			(xy 133.673088 -153.831798) (xy 133.672579 -153.859684) (xy 133.664459 -153.91486) (xy 133.648391 -153.968267)
			(xy 133.624719 -154.018764) (xy 133.593946 -154.065277) (xy 133.556729 -154.106814) (xy 133.513861 -154.142489)
			(xy 133.466255 -154.171543) (xy 133.414926 -154.193355) (xy 133.360969 -154.207461) (xy 133.305532 -154.213561)
			(xy 133.249798 -154.211524) (xy 133.194955 -154.201394) (xy 133.142171 -154.183387) (xy 133.092571 -154.157886)
			(xy 133.047213 -154.125435) (xy 133.007064 -154.086726) (xy 132.972978 -154.042583) (xy 132.945682 -153.993948)
			(xy 132.925759 -153.941857) (xy 132.913633 -153.88742) (xy 132.909562 -153.831798) (xy 132.653431 -153.831798)
			(xy 132.648459 -153.865584) (xy 132.632391 -153.918991) (xy 132.608719 -153.969488) (xy 132.577946 -154.016001)
			(xy 132.540729 -154.057538) (xy 132.497861 -154.093213) (xy 132.450255 -154.122267) (xy 132.398926 -154.144079)
			(xy 132.344969 -154.158185) (xy 132.289532 -154.164285) (xy 132.233798 -154.162248) (xy 132.178955 -154.152118)
			(xy 132.126171 -154.134111) (xy 132.076571 -154.10861) (xy 132.031213 -154.076159) (xy 131.991064 -154.03745)
			(xy 131.956978 -153.993307) (xy 131.929682 -153.944672) (xy 131.909759 -153.892581) (xy 131.897633 -153.838144)
			(xy 131.893562 -153.782522) (xy 131.641088 -153.782522) (xy 131.640579 -153.810408) (xy 131.632459 -153.865584)
			(xy 131.616391 -153.918991) (xy 131.592719 -153.969488) (xy 131.561946 -154.016001) (xy 131.524729 -154.057538)
			(xy 131.481861 -154.093213) (xy 131.434255 -154.122267) (xy 131.382926 -154.144079) (xy 131.328969 -154.158185)
			(xy 131.273532 -154.164285) (xy 131.217798 -154.162248) (xy 131.162955 -154.152118) (xy 131.110171 -154.134111)
			(xy 131.060571 -154.10861) (xy 131.015213 -154.076159) (xy 130.975064 -154.03745) (xy 130.940978 -153.993307)
			(xy 130.913682 -153.944672) (xy 130.893759 -153.892581) (xy 130.881633 -153.838144) (xy 130.877562 -153.782522)
			(xy 122.9614 -153.782522) (xy 122.9614 -155.212034) (xy 123.369068 -155.212034) (xy 123.373139 -155.156412)
			(xy 123.385265 -155.101975) (xy 123.405188 -155.049884) (xy 123.432484 -155.001249) (xy 123.46657 -154.957106)
			(xy 123.506719 -154.918397) (xy 123.552077 -154.885946) (xy 123.601677 -154.860445) (xy 123.654461 -154.842438)
			(xy 123.709304 -154.832308) (xy 123.765038 -154.830271) (xy 123.820475 -154.836371) (xy 123.874432 -154.850477)
			(xy 123.925761 -154.872289) (xy 123.973367 -154.901343) (xy 124.016235 -154.937018) (xy 124.053452 -154.978555)
			(xy 124.084225 -155.025068) (xy 124.107897 -155.075565) (xy 124.108988 -155.079192) (xy 125.969774 -155.079192)
			(xy 125.973845 -155.02357) (xy 125.985971 -154.969133) (xy 126.005894 -154.917042) (xy 126.03319 -154.868407)
			(xy 126.067276 -154.824264) (xy 126.107425 -154.785555) (xy 126.152783 -154.753104) (xy 126.202383 -154.727603)
			(xy 126.255167 -154.709596) (xy 126.31001 -154.699466) (xy 126.365744 -154.697429) (xy 126.421181 -154.703529)
			(xy 126.475138 -154.717635) (xy 126.526467 -154.739447) (xy 126.574073 -154.768501) (xy 126.616941 -154.804176)
			(xy 126.654158 -154.845713) (xy 126.684931 -154.892226) (xy 126.708603 -154.942723) (xy 126.724671 -154.99613)
			(xy 126.732791 -155.051306) (xy 126.7333 -155.079192) (xy 126.733235 -155.082748) (xy 127.293624 -155.082748)
			(xy 127.294055 -155.056431) (xy 127.301279 -155.004296) (xy 127.315595 -154.953647) (xy 127.336734 -154.905445)
			(xy 127.364294 -154.860604) (xy 127.397752 -154.819973) (xy 127.416814 -154.801824) (xy 127.424209 -154.794297)
			(xy 127.432737 -154.775021) (xy 127.433324 -154.764486) (xy 127.433324 -154.68981) (xy 127.432796 -154.67926)
			(xy 127.424259 -154.659965) (xy 127.416814 -154.652472) (xy 127.397724 -154.634348) (xy 127.364246 -154.593726)
			(xy 127.336677 -154.548883) (xy 127.31554 -154.500673) (xy 127.301238 -154.450014) (xy 127.294043 -154.397868)
			(xy 127.293624 -154.371548) (xy 127.2941 -154.344295) (xy 127.301851 -154.290343) (xy 127.317203 -154.238043)
			(xy 127.339842 -154.188461) (xy 127.369308 -154.142606) (xy 127.405001 -154.101412) (xy 127.446193 -154.065718)
			(xy 127.492047 -154.03625) (xy 127.541628 -154.013608) (xy 127.593927 -153.998255) (xy 127.647879 -153.990501)
			(xy 127.675132 -153.99004) (xy 127.701449 -153.990479) (xy 127.753584 -153.9977) (xy 127.804233 -154.012015)
			(xy 127.852435 -154.033152) (xy 127.897276 -154.060711) (xy 127.937907 -154.094168) (xy 127.956056 -154.11323)
			(xy 127.963601 -154.120604) (xy 127.982863 -154.129147) (xy 127.993394 -154.12974) (xy 128.06807 -154.12974)
			(xy 128.078618 -154.129197) (xy 128.097913 -154.12067) (xy 128.105408 -154.11323) (xy 128.123545 -154.094152)
			(xy 128.164164 -154.060673) (xy 128.209004 -154.033102) (xy 128.257211 -154.011963) (xy 128.307869 -153.997658)
			(xy 128.360012 -153.99046) (xy 128.386332 -153.99004) (xy 128.412649 -153.990479) (xy 128.464784 -153.9977)
			(xy 128.515433 -154.012015) (xy 128.563635 -154.033152) (xy 128.608476 -154.060711) (xy 128.649107 -154.094168)
			(xy 128.667256 -154.11323) (xy 128.674801 -154.120604) (xy 128.694063 -154.129147) (xy 128.704594 -154.12974)
			(xy 128.77927 -154.12974) (xy 128.789818 -154.129197) (xy 128.809113 -154.12067) (xy 128.816608 -154.11323)
			(xy 128.834745 -154.094152) (xy 128.875364 -154.060673) (xy 128.920204 -154.033102) (xy 128.968411 -154.011963)
			(xy 129.019069 -153.997658) (xy 129.071212 -153.99046) (xy 129.097532 -153.99004) (xy 129.123849 -153.990479)
			(xy 129.175984 -153.9977) (xy 129.226633 -154.012015) (xy 129.274835 -154.033152) (xy 129.319676 -154.060711)
			(xy 129.360307 -154.094168) (xy 129.378456 -154.11323) (xy 129.386001 -154.120604) (xy 129.405263 -154.129147)
			(xy 129.415794 -154.12974) (xy 129.49047 -154.12974) (xy 129.501018 -154.129197) (xy 129.520313 -154.12067)
			(xy 129.527808 -154.11323) (xy 129.545945 -154.094152) (xy 129.586564 -154.060673) (xy 129.631404 -154.033102)
			(xy 129.679611 -154.011963) (xy 129.730269 -153.997658) (xy 129.782412 -153.99046) (xy 129.808732 -153.99004)
			(xy 129.835988 -153.990425) (xy 129.889944 -153.998188) (xy 129.942246 -154.01355) (xy 129.99183 -154.0362)
			(xy 130.037685 -154.065676) (xy 130.078879 -154.101378) (xy 130.114572 -154.142579) (xy 130.144038 -154.18844)
			(xy 130.166678 -154.238029) (xy 130.182029 -154.290334) (xy 130.18978 -154.344292) (xy 130.19024 -154.371548)
			(xy 130.189786 -154.397864) (xy 130.182564 -154.449997) (xy 130.168251 -154.500645) (xy 130.147116 -154.548847)
			(xy 130.119562 -154.593689) (xy 130.086109 -154.634321) (xy 130.06705 -154.652472) (xy 130.059666 -154.660009)
			(xy 130.05113 -154.679277) (xy 130.05054 -154.68981) (xy 130.05054 -154.764486) (xy 130.051051 -154.775038)
			(xy 130.059598 -154.794334) (xy 130.06705 -154.801824) (xy 130.086132 -154.819957) (xy 130.119611 -154.860577)
			(xy 130.147183 -154.905417) (xy 130.168321 -154.953625) (xy 130.182625 -155.004283) (xy 130.189821 -155.056428)
			(xy 130.19024 -155.082748) (xy 130.189767 -155.109999) (xy 130.182005 -155.163945) (xy 130.166645 -155.216238)
			(xy 130.144001 -155.265814) (xy 130.114532 -155.311662) (xy 130.07884 -155.352851) (xy 130.03765 -155.388542)
			(xy 129.9918 -155.418008) (xy 129.942223 -155.440651) (xy 129.88993 -155.456008) (xy 129.835983 -155.463768)
			(xy 129.808732 -155.464256) (xy 129.782415 -155.463842) (xy 129.730278 -155.456616) (xy 129.679629 -155.442296)
			(xy 129.631427 -155.421154) (xy 129.586586 -155.393592) (xy 129.545956 -155.36013) (xy 129.527808 -155.341066)
			(xy 129.520277 -155.333676) (xy 129.501004 -155.325143) (xy 129.49047 -155.324556) (xy 129.415794 -155.324556)
			(xy 129.405244 -155.325082) (xy 129.38595 -155.333621) (xy 129.378456 -155.341066) (xy 129.360336 -155.36016)
			(xy 129.319713 -155.393638) (xy 129.27487 -155.421208) (xy 129.226659 -155.442344) (xy 129.175999 -155.456645)
			(xy 129.123853 -155.463838) (xy 129.097532 -155.464256) (xy 129.071215 -155.463842) (xy 129.019078 -155.456616)
			(xy 128.968429 -155.442296) (xy 128.920227 -155.421154) (xy 128.875386 -155.393592) (xy 128.834756 -155.36013)
			(xy 128.816608 -155.341066) (xy 128.809077 -155.333676) (xy 128.789804 -155.325143) (xy 128.77927 -155.324556)
			(xy 128.704594 -155.324556) (xy 128.694044 -155.325082) (xy 128.67475 -155.333621) (xy 128.667256 -155.341066)
			(xy 128.649136 -155.36016) (xy 128.608513 -155.393638) (xy 128.56367 -155.421208) (xy 128.515459 -155.442344)
			(xy 128.464799 -155.456645) (xy 128.412653 -155.463838) (xy 128.386332 -155.464256) (xy 128.360015 -155.463842)
			(xy 128.307878 -155.456616) (xy 128.257229 -155.442296) (xy 128.209027 -155.421154) (xy 128.164186 -155.393592)
			(xy 128.123556 -155.36013) (xy 128.105408 -155.341066) (xy 128.097877 -155.333676) (xy 128.078604 -155.325143)
			(xy 128.06807 -155.324556) (xy 127.993394 -155.324556) (xy 127.982844 -155.325082) (xy 127.96355 -155.333621)
			(xy 127.956056 -155.341066) (xy 127.937936 -155.36016) (xy 127.897313 -155.393638) (xy 127.85247 -155.421208)
			(xy 127.804259 -155.442344) (xy 127.753599 -155.456645) (xy 127.701453 -155.463838) (xy 127.675132 -155.464256)
			(xy 127.647884 -155.463692) (xy 127.593941 -155.455941) (xy 127.541651 -155.440593) (xy 127.492077 -155.417959)
			(xy 127.446229 -155.3885) (xy 127.40504 -155.352817) (xy 127.369348 -155.311635) (xy 127.33988 -155.265793)
			(xy 127.317235 -155.216224) (xy 127.301876 -155.163937) (xy 127.294114 -155.109996) (xy 127.293624 -155.082748)
			(xy 126.733235 -155.082748) (xy 126.732791 -155.107078) (xy 126.724671 -155.162254) (xy 126.708603 -155.215661)
			(xy 126.684931 -155.266158) (xy 126.654158 -155.312671) (xy 126.616941 -155.354208) (xy 126.574073 -155.389883)
			(xy 126.526467 -155.418937) (xy 126.475138 -155.440749) (xy 126.421181 -155.454855) (xy 126.365744 -155.460955)
			(xy 126.31001 -155.458918) (xy 126.255167 -155.448788) (xy 126.202383 -155.430781) (xy 126.152783 -155.40528)
			(xy 126.107425 -155.372829) (xy 126.067276 -155.33412) (xy 126.03319 -155.289977) (xy 126.005894 -155.241342)
			(xy 125.985971 -155.189251) (xy 125.973845 -155.134814) (xy 125.969774 -155.079192) (xy 124.108988 -155.079192)
			(xy 124.123965 -155.128972) (xy 124.132085 -155.184148) (xy 124.132594 -155.212034) (xy 124.132085 -155.23992)
			(xy 124.123965 -155.295096) (xy 124.107897 -155.348503) (xy 124.084225 -155.399) (xy 124.053452 -155.445513)
			(xy 124.016235 -155.48705) (xy 123.973367 -155.522725) (xy 123.925761 -155.551779) (xy 123.874432 -155.573591)
			(xy 123.820475 -155.587697) (xy 123.765038 -155.593797) (xy 123.709304 -155.59176) (xy 123.654461 -155.58163)
			(xy 123.601677 -155.563623) (xy 123.552077 -155.538122) (xy 123.506719 -155.505671) (xy 123.46657 -155.466962)
			(xy 123.432484 -155.422819) (xy 123.405188 -155.374184) (xy 123.385265 -155.322093) (xy 123.373139 -155.267656)
			(xy 123.369068 -155.212034) (xy 122.9614 -155.212034) (xy 122.9614 -156.69387) (xy 124.987302 -156.69387)
			(xy 124.991373 -156.638248) (xy 125.003499 -156.583811) (xy 125.023422 -156.53172) (xy 125.050718 -156.483085)
			(xy 125.084804 -156.438942) (xy 125.124953 -156.400233) (xy 125.170311 -156.367782) (xy 125.219911 -156.342281)
			(xy 125.272695 -156.324274) (xy 125.327538 -156.314144) (xy 125.383272 -156.312107) (xy 125.438709 -156.318207)
			(xy 125.492666 -156.332313) (xy 125.543995 -156.354125) (xy 125.591601 -156.383179) (xy 125.634469 -156.418854)
			(xy 125.671686 -156.460391) (xy 125.702459 -156.506904) (xy 125.726131 -156.557401) (xy 125.742199 -156.610808)
			(xy 125.750319 -156.665984) (xy 125.750828 -156.69387) (xy 125.750319 -156.721756) (xy 125.742199 -156.776932)
			(xy 125.726131 -156.830339) (xy 125.702459 -156.880836) (xy 125.671686 -156.927349) (xy 125.634469 -156.968886)
			(xy 125.591601 -157.004561) (xy 125.543995 -157.033615) (xy 125.492666 -157.055427) (xy 125.438709 -157.069533)
			(xy 125.383272 -157.075633) (xy 125.327538 -157.073596) (xy 125.272695 -157.063466) (xy 125.219911 -157.045459)
			(xy 125.170311 -157.019958) (xy 125.124953 -156.987507) (xy 125.084804 -156.948798) (xy 125.050718 -156.904655)
			(xy 125.023422 -156.85602) (xy 125.003499 -156.803929) (xy 124.991373 -156.749492) (xy 124.987302 -156.69387)
			(xy 122.9614 -156.69387) (xy 122.9614 -157.334966) (xy 122.961917 -157.345896) (xy 122.970996 -157.365781)
			(xy 122.978926 -157.37332) (xy 123.045474 -157.430978) (xy 123.066302 -157.437074) (xy 123.077478 -157.435296)
			(xy 123.091057 -157.43348) (xy 123.118389 -157.43157) (xy 123.132088 -157.431486) (xy 123.159342 -157.431949)
			(xy 123.213294 -157.439704) (xy 123.265594 -157.455059) (xy 123.315176 -157.477701) (xy 123.361031 -157.507168)
			(xy 123.402225 -157.542862) (xy 123.437921 -157.584055) (xy 123.467391 -157.629908) (xy 123.475605 -157.647894)
			(xy 127.113792 -157.647894) (xy 127.114327 -157.621251) (xy 127.12285 -157.568653) (xy 127.139707 -157.518105)
			(xy 127.164461 -157.470918) (xy 127.196468 -157.428318) (xy 127.2349 -157.391409) (xy 127.25654 -157.37586)
			(xy 127.267829 -157.367502) (xy 127.28568 -157.345826) (xy 127.296959 -157.320111) (xy 127.300815 -157.292297)
			(xy 127.296957 -157.264483) (xy 127.285677 -157.238768) (xy 127.267824 -157.217094) (xy 127.25654 -157.208728)
			(xy 127.234939 -157.193131) (xy 127.196524 -157.156217) (xy 127.164523 -157.113623) (xy 127.139765 -157.066449)
			(xy 127.12289 -157.015916) (xy 127.114334 -156.963332) (xy 127.113792 -156.936694) (xy 127.114302 -156.910707)
			(xy 127.122432 -156.859372) (xy 127.138493 -156.809942) (xy 127.162089 -156.763632) (xy 127.192639 -156.721584)
			(xy 127.22939 -156.684833) (xy 127.271438 -156.654283) (xy 127.317748 -156.630687) (xy 127.367178 -156.614626)
			(xy 127.418513 -156.606496) (xy 127.470487 -156.606496) (xy 127.521822 -156.614626) (xy 127.571252 -156.630687)
			(xy 127.617562 -156.654283) (xy 127.65961 -156.684833) (xy 127.696361 -156.721584) (xy 127.726911 -156.763632)
			(xy 127.750507 -156.809942) (xy 127.766568 -156.859372) (xy 127.774698 -156.910707) (xy 127.775208 -156.936694)
			(xy 127.774664 -156.963336) (xy 127.766143 -157.015935) (xy 127.749288 -157.066482) (xy 127.724536 -157.113669)
			(xy 127.69253 -157.156269) (xy 127.6541 -157.193179) (xy 127.63246 -157.208728) (xy 127.621182 -157.217101)
			(xy 127.603332 -157.238773) (xy 127.592052 -157.264485) (xy 127.588195 -157.292297) (xy 127.59205 -157.320108)
			(xy 127.603328 -157.345821) (xy 127.621177 -157.367494) (xy 127.63246 -157.37586) (xy 127.654056 -157.391465)
			(xy 127.692471 -157.428377) (xy 127.724472 -157.47097) (xy 127.749231 -157.518142) (xy 127.766107 -157.568673)
			(xy 127.774665 -157.621257) (xy 127.775208 -157.647894) (xy 128.013714 -157.647894) (xy 128.014239 -157.621251)
			(xy 128.022763 -157.568651) (xy 128.039622 -157.518103) (xy 128.064377 -157.470916) (xy 128.096387 -157.428316)
			(xy 128.13482 -157.391408) (xy 128.156462 -157.37586) (xy 128.167749 -157.3675) (xy 128.185596 -157.345824)
			(xy 128.196873 -157.320109) (xy 128.200728 -157.292297) (xy 128.196871 -157.264484) (xy 128.185593 -157.238771)
			(xy 128.167744 -157.217095) (xy 128.156462 -157.208728) (xy 128.134866 -157.193124) (xy 128.096449 -157.156213)
			(xy 128.064448 -157.11362) (xy 128.039689 -157.066447) (xy 128.022813 -157.015915) (xy 128.014256 -156.963332)
			(xy 128.013714 -156.936694) (xy 128.014224 -156.910707) (xy 128.022354 -156.859372) (xy 128.038415 -156.809942)
			(xy 128.062011 -156.763632) (xy 128.092561 -156.721584) (xy 128.129312 -156.684833) (xy 128.17136 -156.654283)
			(xy 128.21767 -156.630687) (xy 128.2671 -156.614626) (xy 128.318435 -156.606496) (xy 128.370409 -156.606496)
			(xy 128.421744 -156.614626) (xy 128.471174 -156.630687) (xy 128.517484 -156.654283) (xy 128.559532 -156.684833)
			(xy 128.596283 -156.721584) (xy 128.626833 -156.763632) (xy 128.650429 -156.809942) (xy 128.66649 -156.859372)
			(xy 128.67462 -156.910707) (xy 128.67513 -156.936694) (xy 128.67462 -156.963338) (xy 128.666096 -157.01594)
			(xy 128.649236 -157.06649) (xy 128.624478 -157.113677) (xy 128.592465 -157.156276) (xy 128.554026 -157.193182)
			(xy 128.532382 -157.208728) (xy 128.521103 -157.2171) (xy 128.503248 -157.238771) (xy 128.491966 -157.264484)
			(xy 128.488108 -157.292297) (xy 128.491964 -157.320109) (xy 128.503245 -157.345823) (xy 128.521098 -157.367495)
			(xy 128.532382 -157.37586) (xy 128.553982 -157.391458) (xy 128.592396 -157.428372) (xy 128.624396 -157.470967)
			(xy 128.649154 -157.51814) (xy 128.66603 -157.568673) (xy 128.674587 -157.621256) (xy 128.67513 -157.647894)
			(xy 128.913636 -157.647894) (xy 128.914152 -157.62125) (xy 128.922677 -157.56865) (xy 128.939536 -157.5181)
			(xy 128.964293 -157.470914) (xy 128.996305 -157.428314) (xy 129.034741 -157.391407) (xy 129.056384 -157.37586)
			(xy 129.067678 -157.367505) (xy 129.085539 -157.345831) (xy 129.096824 -157.320115) (xy 129.100683 -157.292297)
			(xy 129.096823 -157.264479) (xy 129.085535 -157.238763) (xy 129.067673 -157.217091) (xy 129.056384 -157.208728)
			(xy 129.034792 -157.193118) (xy 128.996375 -157.156208) (xy 128.964372 -157.113617) (xy 128.939612 -157.066446)
			(xy 128.922735 -157.015914) (xy 128.914178 -156.963331) (xy 128.913636 -156.936694) (xy 128.914146 -156.910707)
			(xy 128.922276 -156.859372) (xy 128.938337 -156.809942) (xy 128.961933 -156.763632) (xy 128.992483 -156.721584)
			(xy 129.029234 -156.684833) (xy 129.071282 -156.654283) (xy 129.117592 -156.630687) (xy 129.167022 -156.614626)
			(xy 129.218357 -156.606496) (xy 129.270331 -156.606496) (xy 129.321666 -156.614626) (xy 129.371096 -156.630687)
			(xy 129.417406 -156.654283) (xy 129.459454 -156.684833) (xy 129.496205 -156.721584) (xy 129.526755 -156.763632)
			(xy 129.550351 -156.809942) (xy 129.566412 -156.859372) (xy 129.574542 -156.910707) (xy 129.575052 -156.936694)
			(xy 129.574532 -156.963338) (xy 129.566009 -157.015938) (xy 129.549151 -157.066488) (xy 129.524395 -157.113674)
			(xy 129.492383 -157.156274) (xy 129.453947 -157.193181) (xy 129.432304 -157.208728) (xy 129.421023 -157.217099)
			(xy 129.403164 -157.238769) (xy 129.39188 -157.264482) (xy 129.38802 -157.292297) (xy 129.391878 -157.320111)
			(xy 129.403161 -157.345825) (xy 129.421018 -157.367497) (xy 129.432304 -157.37586) (xy 129.453887 -157.391481)
			(xy 129.492306 -157.428388) (xy 129.52431 -157.470977) (xy 129.549072 -157.518146) (xy 129.56595 -157.568676)
			(xy 129.574509 -157.621257) (xy 129.575052 -157.647894) (xy 129.813812 -157.647894) (xy 129.814338 -157.621251)
			(xy 129.822862 -157.568651) (xy 129.83972 -157.518103) (xy 129.864475 -157.470916) (xy 129.896485 -157.428316)
			(xy 129.934919 -157.391408) (xy 129.95656 -157.37586) (xy 129.967847 -157.3675) (xy 129.985695 -157.345824)
			(xy 129.996971 -157.320109) (xy 130.000827 -157.292297) (xy 129.99697 -157.264484) (xy 129.985691 -157.23877)
			(xy 129.967842 -157.217095) (xy 129.95656 -157.208728) (xy 129.934963 -157.193125) (xy 129.896547 -157.156213)
			(xy 129.864545 -157.11362) (xy 129.839786 -157.066447) (xy 129.822911 -157.015915) (xy 129.814354 -156.963332)
			(xy 129.813812 -156.936694) (xy 129.814322 -156.910707) (xy 129.822452 -156.859372) (xy 129.838513 -156.809942)
			(xy 129.862109 -156.763632) (xy 129.892659 -156.721584) (xy 129.92941 -156.684833) (xy 129.971458 -156.654283)
			(xy 130.017768 -156.630687) (xy 130.067198 -156.614626) (xy 130.118533 -156.606496) (xy 130.170507 -156.606496)
			(xy 130.221842 -156.614626) (xy 130.271272 -156.630687) (xy 130.317582 -156.654283) (xy 130.35963 -156.684833)
			(xy 130.396381 -156.721584) (xy 130.426931 -156.763632) (xy 130.450527 -156.809942) (xy 130.466588 -156.859372)
			(xy 130.474718 -156.910707) (xy 130.475228 -156.936694) (xy 130.474719 -156.963338) (xy 130.466195 -157.01594)
			(xy 130.449335 -157.06649) (xy 130.424577 -157.113677) (xy 130.392563 -157.156276) (xy 130.354124 -157.193182)
			(xy 130.33248 -157.208728) (xy 130.321201 -157.2171) (xy 130.303346 -157.238771) (xy 130.292064 -157.264484)
			(xy 130.288206 -157.292297) (xy 130.292063 -157.320109) (xy 130.303343 -157.345823) (xy 130.321196 -157.367495)
			(xy 130.33248 -157.37586) (xy 130.35408 -157.391459) (xy 130.392494 -157.428373) (xy 130.424494 -157.470967)
			(xy 130.449252 -157.518141) (xy 130.466128 -157.568673) (xy 130.474685 -157.621256) (xy 130.475187 -157.645862)
			(xy 131.429252 -157.645862) (xy 131.429715 -157.619547) (xy 131.436936 -157.567414) (xy 131.451248 -157.516766)
			(xy 131.47238 -157.468565) (xy 131.499933 -157.423722) (xy 131.533383 -157.383089) (xy 131.552442 -157.364938)
			(xy 131.55982 -157.357396) (xy 131.56836 -157.338132) (xy 131.568952 -157.3276) (xy 131.568952 -157.252924)
			(xy 131.568437 -157.242372) (xy 131.559893 -157.223076) (xy 131.552442 -157.215586) (xy 131.533364 -157.19745)
			(xy 131.499884 -157.156831) (xy 131.472312 -157.111991) (xy 131.451173 -157.063783) (xy 131.436869 -157.013126)
			(xy 131.429672 -156.960982) (xy 131.429252 -156.934662) (xy 131.429738 -156.907411) (xy 131.437494 -156.853463)
			(xy 131.452849 -156.801168) (xy 131.475491 -156.751591) (xy 131.504957 -156.705741) (xy 131.540648 -156.66455)
			(xy 131.581839 -156.628859) (xy 131.627689 -156.599393) (xy 131.677266 -156.576751) (xy 131.729561 -156.561396)
			(xy 131.783509 -156.55364) (xy 131.838011 -156.55364) (xy 131.891959 -156.561396) (xy 131.944254 -156.576751)
			(xy 131.993831 -156.599393) (xy 132.039681 -156.628859) (xy 132.080872 -156.66455) (xy 132.116563 -156.705741)
			(xy 132.146029 -156.751591) (xy 132.168671 -156.801168) (xy 132.184026 -156.853463) (xy 132.191782 -156.907411)
			(xy 132.192268 -156.934662) (xy 132.191846 -156.960979) (xy 132.184621 -157.013115) (xy 132.170303 -157.063764)
			(xy 132.149162 -157.111966) (xy 132.121601 -157.156807) (xy 132.088141 -157.197437) (xy 132.069078 -157.215586)
			(xy 132.061677 -157.223108) (xy 132.053153 -157.242388) (xy 132.052568 -157.252924) (xy 132.052568 -157.3276)
			(xy 132.053093 -157.33815) (xy 132.061126 -157.356302) (xy 133.414516 -157.356302) (xy 133.414919 -157.329984)
			(xy 133.422148 -157.277848) (xy 133.436471 -157.227198) (xy 133.457615 -157.178997) (xy 133.485179 -157.134156)
			(xy 133.518642 -157.093526) (xy 133.537706 -157.075378) (xy 133.54512 -157.067867) (xy 133.553637 -157.048579)
			(xy 133.554216 -157.03804) (xy 133.554216 -156.963364) (xy 133.553661 -156.952817) (xy 133.545144 -156.933522)
			(xy 133.537706 -156.926026) (xy 133.51864 -156.907877) (xy 133.485161 -156.86726) (xy 133.457588 -156.822423)
			(xy 133.436447 -156.774218) (xy 133.42214 -156.723563) (xy 133.414938 -156.671421) (xy 133.414516 -156.645102)
			(xy 133.414919 -156.618784) (xy 133.422148 -156.566648) (xy 133.436471 -156.515998) (xy 133.457615 -156.467797)
			(xy 133.485179 -156.422956) (xy 133.518642 -156.382326) (xy 133.537706 -156.364178) (xy 133.54512 -156.356667)
			(xy 133.553637 -156.337379) (xy 133.554216 -156.32684) (xy 133.554216 -156.252164) (xy 133.553661 -156.241617)
			(xy 133.545144 -156.222322) (xy 133.537706 -156.214826) (xy 133.51864 -156.196677) (xy 133.485161 -156.15606)
			(xy 133.457588 -156.111223) (xy 133.436447 -156.063018) (xy 133.42214 -156.012363) (xy 133.414938 -155.960221)
			(xy 133.414516 -155.933902) (xy 133.415002 -155.906651) (xy 133.422758 -155.852703) (xy 133.438113 -155.800408)
			(xy 133.460755 -155.750831) (xy 133.490221 -155.704981) (xy 133.525912 -155.66379) (xy 133.567103 -155.628099)
			(xy 133.612953 -155.598633) (xy 133.66253 -155.575991) (xy 133.714825 -155.560636) (xy 133.768773 -155.55288)
			(xy 133.823275 -155.55288) (xy 133.877223 -155.560636) (xy 133.929518 -155.575991) (xy 133.979095 -155.598633)
			(xy 134.024945 -155.628099) (xy 134.066136 -155.66379) (xy 134.101827 -155.704981) (xy 134.131293 -155.750831)
			(xy 134.153935 -155.800408) (xy 134.16929 -155.852703) (xy 134.177046 -155.906651) (xy 134.177532 -155.933902)
			(xy 134.177116 -155.960219) (xy 134.169887 -156.012354) (xy 134.155566 -156.063003) (xy 134.134425 -156.111204)
			(xy 134.106863 -156.156046) (xy 134.073404 -156.196676) (xy 134.054342 -156.214826) (xy 134.046933 -156.222342)
			(xy 134.038412 -156.241626) (xy 134.037832 -156.252164) (xy 134.037832 -156.32684) (xy 134.038371 -156.337389)
			(xy 134.046898 -156.356685) (xy 134.054342 -156.364178) (xy 134.0734 -156.382335) (xy 134.106882 -156.422949)
			(xy 134.134457 -156.467785) (xy 134.155599 -156.515988) (xy 134.169908 -156.566642) (xy 134.17711 -156.618784)
			(xy 134.177532 -156.645102) (xy 134.177116 -156.671419) (xy 134.169887 -156.723554) (xy 134.155566 -156.774203)
			(xy 134.134425 -156.822404) (xy 134.106863 -156.867246) (xy 134.073404 -156.907876) (xy 134.054342 -156.926026)
			(xy 134.046933 -156.933542) (xy 134.038412 -156.952826) (xy 134.037832 -156.963364) (xy 134.037832 -157.03804)
			(xy 134.038371 -157.048589) (xy 134.046898 -157.067885) (xy 134.054342 -157.075378) (xy 134.0734 -157.093535)
			(xy 134.106882 -157.134149) (xy 134.134457 -157.178985) (xy 134.155599 -157.227188) (xy 134.169908 -157.277842)
			(xy 134.17711 -157.329984) (xy 134.177532 -157.356302) (xy 134.177046 -157.383553) (xy 134.172017 -157.418532)
			(xy 136.480296 -157.418532) (xy 136.480725 -157.392215) (xy 136.48795 -157.34008) (xy 136.502268 -157.289432)
			(xy 136.523407 -157.24123) (xy 136.550967 -157.196388) (xy 136.584424 -157.155757) (xy 136.603486 -157.137608)
			(xy 136.610884 -157.130083) (xy 136.619411 -157.110806) (xy 136.619996 -157.10027) (xy 136.619996 -157.025594)
			(xy 136.619485 -157.015042) (xy 136.610937 -156.995747) (xy 136.603486 -156.988256) (xy 136.584383 -156.970146)
			(xy 136.550907 -156.92952) (xy 136.52334 -156.884674) (xy 136.502206 -156.836462) (xy 136.487906 -156.7858)
			(xy 136.480714 -156.733653) (xy 136.480296 -156.707332) (xy 136.480725 -156.681015) (xy 136.48795 -156.62888)
			(xy 136.502268 -156.578232) (xy 136.523407 -156.53003) (xy 136.550967 -156.485188) (xy 136.584424 -156.444557)
			(xy 136.603486 -156.426408) (xy 136.610884 -156.418883) (xy 136.619411 -156.399606) (xy 136.619996 -156.38907)
			(xy 136.619996 -156.314394) (xy 136.619485 -156.303842) (xy 136.610937 -156.284547) (xy 136.603486 -156.277056)
			(xy 136.584383 -156.258946) (xy 136.550907 -156.21832) (xy 136.52334 -156.173474) (xy 136.502206 -156.125262)
			(xy 136.487906 -156.0746) (xy 136.480714 -156.022453) (xy 136.480296 -155.996132) (xy 136.480782 -155.968881)
			(xy 136.488538 -155.914933) (xy 136.503893 -155.862638) (xy 136.526535 -155.813061) (xy 136.556001 -155.767211)
			(xy 136.591692 -155.72602) (xy 136.632883 -155.690329) (xy 136.678733 -155.660863) (xy 136.72831 -155.638221)
			(xy 136.780605 -155.622866) (xy 136.834553 -155.61511) (xy 136.889055 -155.61511) (xy 136.943003 -155.622866)
			(xy 136.995298 -155.638221) (xy 137.044875 -155.660863) (xy 137.090725 -155.690329) (xy 137.131916 -155.72602)
			(xy 137.167607 -155.767211) (xy 137.197073 -155.813061) (xy 137.219715 -155.862638) (xy 137.23507 -155.914933)
			(xy 137.242826 -155.968881) (xy 137.243312 -155.996132) (xy 137.242856 -156.022448) (xy 137.235636 -156.074582)
			(xy 137.221323 -156.12523) (xy 137.200189 -156.173431) (xy 137.172635 -156.218274) (xy 137.139182 -156.258906)
			(xy 137.120122 -156.277056) (xy 137.112741 -156.284595) (xy 137.104204 -156.303862) (xy 137.103612 -156.314394)
			(xy 137.103612 -156.38907) (xy 137.10414 -156.39962) (xy 137.112676 -156.418915) (xy 137.120122 -156.426408)
			(xy 137.13919 -156.444554) (xy 137.172672 -156.48517) (xy 137.200246 -156.530008) (xy 137.221387 -156.578213)
			(xy 137.235693 -156.62887) (xy 137.242892 -156.681013) (xy 137.243312 -156.707332) (xy 137.242856 -156.733648)
			(xy 137.235636 -156.785782) (xy 137.221323 -156.83643) (xy 137.200189 -156.884631) (xy 137.172635 -156.929474)
			(xy 137.139182 -156.970106) (xy 137.120122 -156.988256) (xy 137.112741 -156.995795) (xy 137.104204 -157.015062)
			(xy 137.103612 -157.025594) (xy 137.103612 -157.10027) (xy 137.10414 -157.11082) (xy 137.112676 -157.130115)
			(xy 137.120122 -157.137608) (xy 137.13919 -157.155754) (xy 137.172672 -157.19637) (xy 137.200246 -157.241208)
			(xy 137.221387 -157.289413) (xy 137.235693 -157.34007) (xy 137.242892 -157.392213) (xy 137.243312 -157.418532)
			(xy 137.242826 -157.445783) (xy 137.23507 -157.499731) (xy 137.219715 -157.552026) (xy 137.197073 -157.601603)
			(xy 137.167607 -157.647453) (xy 137.131916 -157.688644) (xy 137.090725 -157.724335) (xy 137.044875 -157.753801)
			(xy 136.995298 -157.776443) (xy 136.943003 -157.791798) (xy 136.889055 -157.799554) (xy 136.834553 -157.799554)
			(xy 136.780605 -157.791798) (xy 136.72831 -157.776443) (xy 136.678733 -157.753801) (xy 136.632883 -157.724335)
			(xy 136.591692 -157.688644) (xy 136.556001 -157.647453) (xy 136.526535 -157.601603) (xy 136.503893 -157.552026)
			(xy 136.488538 -157.499731) (xy 136.480782 -157.445783) (xy 136.480296 -157.418532) (xy 134.172017 -157.418532)
			(xy 134.16929 -157.437501) (xy 134.153935 -157.489796) (xy 134.131293 -157.539373) (xy 134.101827 -157.585223)
			(xy 134.066136 -157.626414) (xy 134.024945 -157.662105) (xy 133.979095 -157.691571) (xy 133.929518 -157.714213)
			(xy 133.877223 -157.729568) (xy 133.823275 -157.737324) (xy 133.768773 -157.737324) (xy 133.714825 -157.729568)
			(xy 133.66253 -157.714213) (xy 133.612953 -157.691571) (xy 133.567103 -157.662105) (xy 133.525912 -157.626414)
			(xy 133.490221 -157.585223) (xy 133.460755 -157.539373) (xy 133.438113 -157.489796) (xy 133.422758 -157.437501)
			(xy 133.415002 -157.383553) (xy 133.414516 -157.356302) (xy 132.061126 -157.356302) (xy 132.061632 -157.357445)
			(xy 132.069078 -157.364938) (xy 132.088172 -157.383058) (xy 132.121649 -157.423681) (xy 132.149218 -157.468525)
			(xy 132.170355 -157.516735) (xy 132.184656 -157.567395) (xy 132.19185 -157.619542) (xy 132.192268 -157.645862)
			(xy 132.191782 -157.673113) (xy 132.184026 -157.727061) (xy 132.168671 -157.779356) (xy 132.146029 -157.828933)
			(xy 132.116563 -157.874783) (xy 132.080872 -157.915974) (xy 132.039681 -157.951665) (xy 131.993831 -157.981131)
			(xy 131.944254 -158.003773) (xy 131.891959 -158.019128) (xy 131.838011 -158.026884) (xy 131.783509 -158.026884)
			(xy 131.729561 -158.019128) (xy 131.677266 -158.003773) (xy 131.627689 -157.981131) (xy 131.581839 -157.951665)
			(xy 131.540648 -157.915974) (xy 131.504957 -157.874783) (xy 131.475491 -157.828933) (xy 131.452849 -157.779356)
			(xy 131.437494 -157.727061) (xy 131.429738 -157.673113) (xy 131.429252 -157.645862) (xy 130.475187 -157.645862)
			(xy 130.475228 -157.647894) (xy 130.474718 -157.673881) (xy 130.466588 -157.725216) (xy 130.450527 -157.774646)
			(xy 130.426931 -157.820956) (xy 130.396381 -157.863004) (xy 130.35963 -157.899755) (xy 130.317582 -157.930305)
			(xy 130.271272 -157.953901) (xy 130.221842 -157.969962) (xy 130.170507 -157.978092) (xy 130.118533 -157.978092)
			(xy 130.067198 -157.969962) (xy 130.017768 -157.953901) (xy 129.971458 -157.930305) (xy 129.92941 -157.899755)
			(xy 129.892659 -157.863004) (xy 129.862109 -157.820956) (xy 129.838513 -157.774646) (xy 129.822452 -157.725216)
			(xy 129.814322 -157.673881) (xy 129.813812 -157.647894) (xy 129.575052 -157.647894) (xy 129.574542 -157.673881)
			(xy 129.566412 -157.725216) (xy 129.550351 -157.774646) (xy 129.526755 -157.820956) (xy 129.496205 -157.863004)
			(xy 129.459454 -157.899755) (xy 129.417406 -157.930305) (xy 129.371096 -157.953901) (xy 129.321666 -157.969962)
			(xy 129.270331 -157.978092) (xy 129.218357 -157.978092) (xy 129.167022 -157.969962) (xy 129.117592 -157.953901)
			(xy 129.071282 -157.930305) (xy 129.029234 -157.899755) (xy 128.992483 -157.863004) (xy 128.961933 -157.820956)
			(xy 128.938337 -157.774646) (xy 128.922276 -157.725216) (xy 128.914146 -157.673881) (xy 128.913636 -157.647894)
			(xy 128.67513 -157.647894) (xy 128.67462 -157.673881) (xy 128.66649 -157.725216) (xy 128.650429 -157.774646)
			(xy 128.626833 -157.820956) (xy 128.596283 -157.863004) (xy 128.559532 -157.899755) (xy 128.517484 -157.930305)
			(xy 128.471174 -157.953901) (xy 128.421744 -157.969962) (xy 128.370409 -157.978092) (xy 128.318435 -157.978092)
			(xy 128.2671 -157.969962) (xy 128.21767 -157.953901) (xy 128.17136 -157.930305) (xy 128.129312 -157.899755)
			(xy 128.092561 -157.863004) (xy 128.062011 -157.820956) (xy 128.038415 -157.774646) (xy 128.022354 -157.725216)
			(xy 128.014224 -157.673881) (xy 128.013714 -157.647894) (xy 127.775208 -157.647894) (xy 127.774698 -157.673881)
			(xy 127.766568 -157.725216) (xy 127.750507 -157.774646) (xy 127.726911 -157.820956) (xy 127.696361 -157.863004)
			(xy 127.65961 -157.899755) (xy 127.617562 -157.930305) (xy 127.571252 -157.953901) (xy 127.521822 -157.969962)
			(xy 127.470487 -157.978092) (xy 127.418513 -157.978092) (xy 127.367178 -157.969962) (xy 127.317748 -157.953901)
			(xy 127.271438 -157.930305) (xy 127.22939 -157.899755) (xy 127.192639 -157.863004) (xy 127.162089 -157.820956)
			(xy 127.138493 -157.774646) (xy 127.122432 -157.725216) (xy 127.114302 -157.673881) (xy 127.113792 -157.647894)
			(xy 123.475605 -157.647894) (xy 123.490035 -157.679489) (xy 123.505392 -157.731788) (xy 123.51315 -157.78574)
			(xy 123.513596 -157.812994) (xy 123.513126 -157.840022) (xy 123.505494 -157.893536) (xy 123.490383 -157.945436)
			(xy 123.468096 -157.994683) (xy 123.439078 -158.040289) (xy 123.421859 -158.06039) (xy 124.93955 -158.06039)
			(xy 124.943621 -158.004768) (xy 124.955747 -157.950331) (xy 124.97567 -157.89824) (xy 125.002966 -157.849605)
			(xy 125.037052 -157.805462) (xy 125.077201 -157.766753) (xy 125.122559 -157.734302) (xy 125.172159 -157.708801)
			(xy 125.224943 -157.690794) (xy 125.279786 -157.680664) (xy 125.33552 -157.678627) (xy 125.390957 -157.684727)
			(xy 125.444914 -157.698833) (xy 125.496243 -157.720645) (xy 125.543849 -157.749699) (xy 125.586717 -157.785374)
			(xy 125.623934 -157.826911) (xy 125.654707 -157.873424) (xy 125.678379 -157.923921) (xy 125.694447 -157.977328)
			(xy 125.702567 -158.032504) (xy 125.703076 -158.06039) (xy 125.702567 -158.088276) (xy 125.694447 -158.143452)
			(xy 125.678379 -158.196859) (xy 125.654707 -158.247356) (xy 125.623934 -158.293869) (xy 125.586717 -158.335406)
			(xy 125.543849 -158.371081) (xy 125.496243 -158.400135) (xy 125.444914 -158.421947) (xy 125.390957 -158.436053)
			(xy 125.33552 -158.442153) (xy 125.279786 -158.440116) (xy 125.224943 -158.429986) (xy 125.172159 -158.411979)
			(xy 125.122559 -158.386478) (xy 125.077201 -158.354027) (xy 125.037052 -158.315318) (xy 125.002966 -158.271175)
			(xy 124.97567 -158.22254) (xy 124.955747 -158.170449) (xy 124.943621 -158.116012) (xy 124.93955 -158.06039)
			(xy 123.421859 -158.06039) (xy 123.403912 -158.081342) (xy 123.363302 -158.117018) (xy 123.318061 -158.146602)
			(xy 123.269096 -158.169503) (xy 123.217388 -158.18526) (xy 123.190762 -158.18993) (xy 123.176538 -158.192216)
			(xy 123.154694 -158.210758) (xy 123.122182 -158.31058) (xy 123.11974 -158.319587) (xy 123.120767 -158.338204)
			(xy 123.128348 -158.35524) (xy 123.134628 -158.362142) (xy 123.228862 -158.456376) (xy 123.23953 -158.462726)
			(xy 123.245372 -158.464758) (xy 123.270929 -158.473194) (xy 123.319562 -158.496247) (xy 123.364472 -158.525905)
			(xy 123.404769 -158.561579) (xy 123.439654 -158.602562) (xy 123.468434 -158.64804) (xy 123.490538 -158.697111)
			(xy 123.505527 -158.748801) (xy 123.506167 -158.753302) (xy 132.616446 -158.753302) (xy 132.620517 -158.69768)
			(xy 132.632643 -158.643243) (xy 132.652566 -158.591152) (xy 132.679862 -158.542517) (xy 132.713948 -158.498374)
			(xy 132.754097 -158.459665) (xy 132.799455 -158.427214) (xy 132.849055 -158.401713) (xy 132.901839 -158.383706)
			(xy 132.956682 -158.373576) (xy 133.012416 -158.371539) (xy 133.067853 -158.377639) (xy 133.12181 -158.391745)
			(xy 133.173139 -158.413557) (xy 133.220745 -158.442611) (xy 133.263613 -158.478286) (xy 133.30083 -158.519823)
			(xy 133.331603 -158.566336) (xy 133.355275 -158.616833) (xy 133.371343 -158.67024) (xy 133.379463 -158.725416)
			(xy 133.379972 -158.753302) (xy 133.379463 -158.781188) (xy 133.371343 -158.836364) (xy 133.355275 -158.889771)
			(xy 133.331603 -158.940268) (xy 133.30083 -158.986781) (xy 133.263613 -159.028318) (xy 133.220745 -159.063993)
			(xy 133.173139 -159.093047) (xy 133.12181 -159.114859) (xy 133.067853 -159.128965) (xy 133.012416 -159.135065)
			(xy 132.956682 -159.133028) (xy 132.901839 -159.122898) (xy 132.849055 -159.104891) (xy 132.799455 -159.07939)
			(xy 132.754097 -159.046939) (xy 132.713948 -159.00823) (xy 132.679862 -158.964087) (xy 132.652566 -158.915452)
			(xy 132.632643 -158.863361) (xy 132.620517 -158.808924) (xy 132.616446 -158.753302) (xy 123.506167 -158.753302)
			(xy 123.513105 -158.802084) (xy 123.513596 -158.828994) (xy 123.513133 -158.856247) (xy 123.505377 -158.910198)
			(xy 123.490021 -158.962496) (xy 123.467379 -159.012076) (xy 123.437911 -159.057929) (xy 123.402217 -159.099121)
			(xy 123.361024 -159.134814) (xy 123.31517 -159.164282) (xy 123.26559 -159.186923) (xy 123.213292 -159.202278)
			(xy 123.159341 -159.210033) (xy 123.132088 -159.210502) (xy 123.118389 -159.210407) (xy 123.091058 -159.208498)
			(xy 123.077478 -159.206692) (xy 123.066302 -159.204914) (xy 123.045474 -159.21101) (xy 122.978926 -159.268668)
			(xy 122.971015 -159.276222) (xy 122.961933 -159.296097) (xy 122.9614 -159.307022) (xy 122.9614 -159.366966)
			(xy 122.961917 -159.377896) (xy 122.970996 -159.397781) (xy 122.978926 -159.40532) (xy 123.017917 -159.439102)
			(xy 125.007876 -159.439102) (xy 125.011947 -159.38348) (xy 125.024073 -159.329043) (xy 125.043996 -159.276952)
			(xy 125.071292 -159.228317) (xy 125.105378 -159.184174) (xy 125.145527 -159.145465) (xy 125.190885 -159.113014)
			(xy 125.240485 -159.087513) (xy 125.293269 -159.069506) (xy 125.348112 -159.059376) (xy 125.403846 -159.057339)
			(xy 125.459283 -159.063439) (xy 125.51324 -159.077545) (xy 125.564569 -159.099357) (xy 125.612175 -159.128411)
			(xy 125.655043 -159.164086) (xy 125.69226 -159.205623) (xy 125.723033 -159.252136) (xy 125.746705 -159.302633)
			(xy 125.762773 -159.35604) (xy 125.770893 -159.411216) (xy 125.771402 -159.439102) (xy 125.770893 -159.466988)
			(xy 125.762773 -159.522164) (xy 125.75987 -159.531812) (xy 128.212594 -159.531812) (xy 128.216665 -159.47619)
			(xy 128.228791 -159.421753) (xy 128.248714 -159.369662) (xy 128.27601 -159.321027) (xy 128.310096 -159.276884)
			(xy 128.350245 -159.238175) (xy 128.395603 -159.205724) (xy 128.445203 -159.180223) (xy 128.497987 -159.162216)
			(xy 128.55283 -159.152086) (xy 128.608564 -159.150049) (xy 128.664001 -159.156149) (xy 128.717958 -159.170255)
			(xy 128.769287 -159.192067) (xy 128.816893 -159.221121) (xy 128.859761 -159.256796) (xy 128.896978 -159.298333)
			(xy 128.927751 -159.344846) (xy 128.951423 -159.395343) (xy 128.967491 -159.44875) (xy 128.97336 -159.488632)
			(xy 130.4958 -159.488632) (xy 130.499871 -159.43301) (xy 130.511997 -159.378573) (xy 130.53192 -159.326482)
			(xy 130.559216 -159.277847) (xy 130.593302 -159.233704) (xy 130.633451 -159.194995) (xy 130.678809 -159.162544)
			(xy 130.728409 -159.137043) (xy 130.781193 -159.119036) (xy 130.836036 -159.108906) (xy 130.89177 -159.106869)
			(xy 130.947207 -159.112969) (xy 131.001164 -159.127075) (xy 131.052493 -159.148887) (xy 131.100099 -159.177941)
			(xy 131.142967 -159.213616) (xy 131.180184 -159.255153) (xy 131.210957 -159.301666) (xy 131.234629 -159.352163)
			(xy 131.250697 -159.40557) (xy 131.258817 -159.460746) (xy 131.259326 -159.488632) (xy 131.258817 -159.516518)
			(xy 131.250697 -159.571694) (xy 131.234629 -159.625101) (xy 131.210957 -159.675598) (xy 131.180184 -159.722111)
			(xy 131.142967 -159.763648) (xy 131.100099 -159.799323) (xy 131.052493 -159.828377) (xy 131.001164 -159.850189)
			(xy 130.947207 -159.864295) (xy 130.89177 -159.870395) (xy 130.836036 -159.868358) (xy 130.781193 -159.858228)
			(xy 130.728409 -159.840221) (xy 130.678809 -159.81472) (xy 130.633451 -159.782269) (xy 130.593302 -159.74356)
			(xy 130.559216 -159.699417) (xy 130.53192 -159.650782) (xy 130.511997 -159.598691) (xy 130.499871 -159.544254)
			(xy 130.4958 -159.488632) (xy 128.97336 -159.488632) (xy 128.975611 -159.503926) (xy 128.97612 -159.531812)
			(xy 128.975611 -159.559698) (xy 128.967491 -159.614874) (xy 128.951423 -159.668281) (xy 128.927751 -159.718778)
			(xy 128.896978 -159.765291) (xy 128.859761 -159.806828) (xy 128.816893 -159.842503) (xy 128.769287 -159.871557)
			(xy 128.717958 -159.893369) (xy 128.664001 -159.907475) (xy 128.608564 -159.913575) (xy 128.55283 -159.911538)
			(xy 128.497987 -159.901408) (xy 128.445203 -159.883401) (xy 128.395603 -159.8579) (xy 128.350245 -159.825449)
			(xy 128.310096 -159.78674) (xy 128.27601 -159.742597) (xy 128.248714 -159.693962) (xy 128.228791 -159.641871)
			(xy 128.216665 -159.587434) (xy 128.212594 -159.531812) (xy 125.75987 -159.531812) (xy 125.746705 -159.575571)
			(xy 125.723033 -159.626068) (xy 125.69226 -159.672581) (xy 125.655043 -159.714118) (xy 125.612175 -159.749793)
			(xy 125.564569 -159.778847) (xy 125.51324 -159.800659) (xy 125.459283 -159.814765) (xy 125.403846 -159.820865)
			(xy 125.348112 -159.818828) (xy 125.293269 -159.808698) (xy 125.240485 -159.790691) (xy 125.190885 -159.76519)
			(xy 125.145527 -159.732739) (xy 125.105378 -159.69403) (xy 125.071292 -159.649887) (xy 125.043996 -159.601252)
			(xy 125.024073 -159.549161) (xy 125.011947 -159.494724) (xy 125.007876 -159.439102) (xy 123.017917 -159.439102)
			(xy 123.045474 -159.462978) (xy 123.066302 -159.469074) (xy 123.077478 -159.467296) (xy 123.091057 -159.46548)
			(xy 123.118389 -159.46357) (xy 123.132088 -159.463486) (xy 123.159342 -159.463949) (xy 123.213295 -159.471704)
			(xy 123.265595 -159.487059) (xy 123.315177 -159.509702) (xy 123.361033 -159.53917) (xy 123.402228 -159.574864)
			(xy 123.437923 -159.616058) (xy 123.467393 -159.661912) (xy 123.490036 -159.711494) (xy 123.505393 -159.763793)
			(xy 123.513151 -159.817746) (xy 123.513151 -159.872254) (xy 123.505393 -159.926207) (xy 123.490036 -159.978506)
			(xy 123.467393 -160.028088) (xy 123.437923 -160.073942) (xy 123.402228 -160.115136) (xy 123.361033 -160.15083)
			(xy 123.315177 -160.180298) (xy 123.265595 -160.202941) (xy 123.213295 -160.218296) (xy 123.159342 -160.226051)
			(xy 123.132088 -160.226502) (xy 123.118389 -160.226407) (xy 123.091058 -160.224498) (xy 123.077478 -160.222692)
			(xy 123.066302 -160.220914) (xy 123.045474 -160.22701) (xy 122.978926 -160.284668) (xy 122.971015 -160.292222)
			(xy 122.961933 -160.312097) (xy 122.9614 -160.323022) (xy 122.9614 -160.965896) (xy 125.037594 -160.965896)
			(xy 125.041665 -160.910274) (xy 125.053791 -160.855837) (xy 125.073714 -160.803746) (xy 125.10101 -160.755111)
			(xy 125.135096 -160.710968) (xy 125.175245 -160.672259) (xy 125.220603 -160.639808) (xy 125.270203 -160.614307)
			(xy 125.322987 -160.5963) (xy 125.37783 -160.58617) (xy 125.433564 -160.584133) (xy 125.489001 -160.590233)
			(xy 125.542958 -160.604339) (xy 125.594287 -160.626151) (xy 125.641893 -160.655205) (xy 125.684761 -160.69088)
			(xy 125.721978 -160.732417) (xy 125.752751 -160.77893) (xy 125.776423 -160.829427) (xy 125.792491 -160.882834)
			(xy 125.800611 -160.93801) (xy 125.801083 -160.963864) (xy 126.429514 -160.963864) (xy 126.433585 -160.908242)
			(xy 126.445711 -160.853805) (xy 126.465634 -160.801714) (xy 126.49293 -160.753079) (xy 126.527016 -160.708936)
			(xy 126.567165 -160.670227) (xy 126.612523 -160.637776) (xy 126.662123 -160.612275) (xy 126.714907 -160.594268)
			(xy 126.76975 -160.584138) (xy 126.825484 -160.582101) (xy 126.880921 -160.588201) (xy 126.934878 -160.602307)
			(xy 126.986207 -160.624119) (xy 127.033813 -160.653173) (xy 127.076681 -160.688848) (xy 127.113898 -160.730385)
			(xy 127.144671 -160.776898) (xy 127.168343 -160.827395) (xy 127.184411 -160.880802) (xy 127.192531 -160.935978)
			(xy 127.19304 -160.963864) (xy 127.192947 -160.968944) (xy 127.701292 -160.968944) (xy 127.705363 -160.913322)
			(xy 127.717489 -160.858885) (xy 127.737412 -160.806794) (xy 127.764708 -160.758159) (xy 127.798794 -160.714016)
			(xy 127.838943 -160.675307) (xy 127.884301 -160.642856) (xy 127.933901 -160.617355) (xy 127.986685 -160.599348)
			(xy 128.041528 -160.589218) (xy 128.097262 -160.587181) (xy 128.152699 -160.593281) (xy 128.206656 -160.607387)
			(xy 128.257985 -160.629199) (xy 128.305591 -160.658253) (xy 128.348459 -160.693928) (xy 128.385676 -160.735465)
			(xy 128.416449 -160.781978) (xy 128.440121 -160.832475) (xy 128.456189 -160.885882) (xy 128.458582 -160.902142)
			(xy 129.482594 -160.902142) (xy 129.486665 -160.84652) (xy 129.498791 -160.792083) (xy 129.518714 -160.739992)
			(xy 129.54601 -160.691357) (xy 129.580096 -160.647214) (xy 129.620245 -160.608505) (xy 129.665603 -160.576054)
			(xy 129.715203 -160.550553) (xy 129.767987 -160.532546) (xy 129.82283 -160.522416) (xy 129.878564 -160.520379)
			(xy 129.934001 -160.526479) (xy 129.987958 -160.540585) (xy 130.039287 -160.562397) (xy 130.086893 -160.591451)
			(xy 130.129761 -160.627126) (xy 130.166978 -160.668663) (xy 130.197751 -160.715176) (xy 130.221423 -160.765673)
			(xy 130.237491 -160.81908) (xy 130.245611 -160.874256) (xy 130.24612 -160.902142) (xy 130.245611 -160.930028)
			(xy 130.237491 -160.985204) (xy 130.221423 -161.038611) (xy 130.197751 -161.089108) (xy 130.166978 -161.135621)
			(xy 130.129761 -161.177158) (xy 130.086893 -161.212833) (xy 130.039287 -161.241887) (xy 129.987958 -161.263699)
			(xy 129.934001 -161.277805) (xy 129.878564 -161.283905) (xy 129.82283 -161.281868) (xy 129.767987 -161.271738)
			(xy 129.715203 -161.253731) (xy 129.665603 -161.22823) (xy 129.620245 -161.195779) (xy 129.580096 -161.15707)
			(xy 129.54601 -161.112927) (xy 129.518714 -161.064292) (xy 129.498791 -161.012201) (xy 129.486665 -160.957764)
			(xy 129.482594 -160.902142) (xy 128.458582 -160.902142) (xy 128.464309 -160.941058) (xy 128.464818 -160.968944)
			(xy 128.464309 -160.99683) (xy 128.456189 -161.052006) (xy 128.440121 -161.105413) (xy 128.416449 -161.15591)
			(xy 128.385676 -161.202423) (xy 128.348459 -161.24396) (xy 128.305591 -161.279635) (xy 128.257985 -161.308689)
			(xy 128.206656 -161.330501) (xy 128.152699 -161.344607) (xy 128.097262 -161.350707) (xy 128.041528 -161.34867)
			(xy 127.986685 -161.33854) (xy 127.933901 -161.320533) (xy 127.884301 -161.295032) (xy 127.838943 -161.262581)
			(xy 127.798794 -161.223872) (xy 127.764708 -161.179729) (xy 127.737412 -161.131094) (xy 127.717489 -161.079003)
			(xy 127.705363 -161.024566) (xy 127.701292 -160.968944) (xy 127.192947 -160.968944) (xy 127.192531 -160.99175)
			(xy 127.184411 -161.046926) (xy 127.168343 -161.100333) (xy 127.144671 -161.15083) (xy 127.113898 -161.197343)
			(xy 127.076681 -161.23888) (xy 127.033813 -161.274555) (xy 126.986207 -161.303609) (xy 126.934878 -161.325421)
			(xy 126.880921 -161.339527) (xy 126.825484 -161.345627) (xy 126.76975 -161.34359) (xy 126.714907 -161.33346)
			(xy 126.662123 -161.315453) (xy 126.612523 -161.289952) (xy 126.567165 -161.257501) (xy 126.527016 -161.218792)
			(xy 126.49293 -161.174649) (xy 126.465634 -161.126014) (xy 126.445711 -161.073923) (xy 126.433585 -161.019486)
			(xy 126.429514 -160.963864) (xy 125.801083 -160.963864) (xy 125.80112 -160.965896) (xy 125.800611 -160.993782)
			(xy 125.792491 -161.048958) (xy 125.776423 -161.102365) (xy 125.752751 -161.152862) (xy 125.721978 -161.199375)
			(xy 125.684761 -161.240912) (xy 125.641893 -161.276587) (xy 125.594287 -161.305641) (xy 125.542958 -161.327453)
			(xy 125.489001 -161.341559) (xy 125.433564 -161.347659) (xy 125.37783 -161.345622) (xy 125.322987 -161.335492)
			(xy 125.270203 -161.317485) (xy 125.220603 -161.291984) (xy 125.175245 -161.259533) (xy 125.135096 -161.220824)
			(xy 125.10101 -161.176681) (xy 125.073714 -161.128046) (xy 125.053791 -161.075955) (xy 125.041665 -161.021518)
			(xy 125.037594 -160.965896) (xy 122.9614 -160.965896) (xy 122.9614 -161.354008) (xy 122.961825 -161.364078)
			(xy 122.969541 -161.38268) (xy 122.976386 -161.390076) (xy 124.701046 -163.114736) (xy 132.149594 -163.114736)
			(xy 132.153665 -163.059114) (xy 132.165791 -163.004677) (xy 132.185714 -162.952586) (xy 132.21301 -162.903951)
			(xy 132.247096 -162.859808) (xy 132.287245 -162.821099) (xy 132.332603 -162.788648) (xy 132.382203 -162.763147)
			(xy 132.434987 -162.74514) (xy 132.48983 -162.73501) (xy 132.545564 -162.732973) (xy 132.601001 -162.739073)
			(xy 132.654958 -162.753179) (xy 132.706287 -162.774991) (xy 132.753893 -162.804045) (xy 132.796761 -162.83972)
			(xy 132.833978 -162.881257) (xy 132.864751 -162.92777) (xy 132.888423 -162.978267) (xy 132.904491 -163.031674)
			(xy 132.912611 -163.08685) (xy 132.91312 -163.114736) (xy 132.912611 -163.142622) (xy 132.904491 -163.197798)
			(xy 132.888423 -163.251205) (xy 132.864751 -163.301702) (xy 132.833978 -163.348215) (xy 132.796761 -163.389752)
			(xy 132.753893 -163.425427) (xy 132.706287 -163.454481) (xy 132.654958 -163.476293) (xy 132.601001 -163.490399)
			(xy 132.545564 -163.496499) (xy 132.48983 -163.494462) (xy 132.434987 -163.484332) (xy 132.382203 -163.466325)
			(xy 132.332603 -163.440824) (xy 132.287245 -163.408373) (xy 132.247096 -163.369664) (xy 132.21301 -163.325521)
			(xy 132.185714 -163.276886) (xy 132.165791 -163.224795) (xy 132.153665 -163.170358) (xy 132.149594 -163.114736)
			(xy 124.701046 -163.114736) (xy 125.476254 -163.889944) (xy 125.483663 -163.896631) (xy 125.502099 -163.904222)
			(xy 125.512068 -163.904676) (xy 136.026652 -163.904676) (xy 136.052737 -163.905166) (xy 136.104264 -163.913341)
			(xy 136.153876 -163.92948) (xy 136.20035 -163.953186) (xy 136.24254 -163.983875) (xy 136.261348 -164.001958)
		)
		(stroke
			(width 0)
			(type solid)
		)
		(fill yes)
		(layer "In5.Cu")
		(net "GND")
	)
	(gr_poly
		(pts
			(xy 200.096882 -417.143692) (xy 200.106945 -417.143254) (xy 200.125527 -417.135517) (xy 200.13295 -417.128706)
			(xy 201.56551 -415.696146) (xy 201.572907 -415.689296) (xy 201.591505 -415.681558) (xy 201.601578 -415.68116)
			(xy 273.555714 -415.68116) (xy 273.565782 -415.681587) (xy 273.584377 -415.689312) (xy 273.591782 -415.696146)
			(xy 273.71802 -415.822384) (xy 274.001808 -416.106102) (xy 276.344378 -416.106102) (xy 276.348449 -416.05048)
			(xy 276.360575 -415.996043) (xy 276.380498 -415.943952) (xy 276.407794 -415.895317) (xy 276.44188 -415.851174)
			(xy 276.482029 -415.812465) (xy 276.527387 -415.780014) (xy 276.576987 -415.754513) (xy 276.629771 -415.736506)
			(xy 276.684614 -415.726376) (xy 276.740348 -415.724339) (xy 276.795785 -415.730439) (xy 276.849742 -415.744545)
			(xy 276.901071 -415.766357) (xy 276.948677 -415.795411) (xy 276.991545 -415.831086) (xy 277.028762 -415.872623)
			(xy 277.059535 -415.919136) (xy 277.083207 -415.969633) (xy 277.099275 -416.02304) (xy 277.107395 -416.078216)
			(xy 277.107904 -416.106102) (xy 277.360378 -416.106102) (xy 277.364449 -416.05048) (xy 277.376575 -415.996043)
			(xy 277.396498 -415.943952) (xy 277.423794 -415.895317) (xy 277.45788 -415.851174) (xy 277.498029 -415.812465)
			(xy 277.543387 -415.780014) (xy 277.592987 -415.754513) (xy 277.645771 -415.736506) (xy 277.700614 -415.726376)
			(xy 277.756348 -415.724339) (xy 277.811785 -415.730439) (xy 277.865742 -415.744545) (xy 277.917071 -415.766357)
			(xy 277.964677 -415.795411) (xy 278.007545 -415.831086) (xy 278.044762 -415.872623) (xy 278.075535 -415.919136)
			(xy 278.099207 -415.969633) (xy 278.105113 -415.989262) (xy 278.376378 -415.989262) (xy 278.380449 -415.93364)
			(xy 278.392575 -415.879203) (xy 278.412498 -415.827112) (xy 278.439794 -415.778477) (xy 278.47388 -415.734334)
			(xy 278.514029 -415.695625) (xy 278.559387 -415.663174) (xy 278.608987 -415.637673) (xy 278.661771 -415.619666)
			(xy 278.716614 -415.609536) (xy 278.772348 -415.607499) (xy 278.827785 -415.613599) (xy 278.881742 -415.627705)
			(xy 278.933071 -415.649517) (xy 278.980677 -415.678571) (xy 279.023545 -415.714246) (xy 279.060762 -415.755783)
			(xy 279.091535 -415.802296) (xy 279.115207 -415.852793) (xy 279.131275 -415.9062) (xy 279.139395 -415.961376)
			(xy 279.139904 -415.989262) (xy 279.139593 -416.00628) (xy 279.392378 -416.00628) (xy 279.396449 -415.950658)
			(xy 279.408575 -415.896221) (xy 279.428498 -415.84413) (xy 279.455794 -415.795495) (xy 279.48988 -415.751352)
			(xy 279.530029 -415.712643) (xy 279.575387 -415.680192) (xy 279.624987 -415.654691) (xy 279.677771 -415.636684)
			(xy 279.732614 -415.626554) (xy 279.788348 -415.624517) (xy 279.843785 -415.630617) (xy 279.897742 -415.644723)
			(xy 279.949071 -415.666535) (xy 279.996677 -415.695589) (xy 280.039545 -415.731264) (xy 280.076762 -415.772801)
			(xy 280.107535 -415.819314) (xy 280.131207 -415.869811) (xy 280.147275 -415.923218) (xy 280.155395 -415.978394)
			(xy 280.155904 -416.00628) (xy 280.155395 -416.034166) (xy 280.147275 -416.089342) (xy 280.131207 -416.142749)
			(xy 280.123024 -416.160204) (xy 280.408378 -416.160204) (xy 280.412449 -416.104582) (xy 280.424575 -416.050145)
			(xy 280.444498 -415.998054) (xy 280.471794 -415.949419) (xy 280.50588 -415.905276) (xy 280.546029 -415.866567)
			(xy 280.591387 -415.834116) (xy 280.640987 -415.808615) (xy 280.693771 -415.790608) (xy 280.748614 -415.780478)
			(xy 280.804348 -415.778441) (xy 280.859785 -415.784541) (xy 280.913742 -415.798647) (xy 280.965071 -415.820459)
			(xy 281.012677 -415.849513) (xy 281.055545 -415.885188) (xy 281.092762 -415.926725) (xy 281.123535 -415.973238)
			(xy 281.147207 -416.023735) (xy 281.163275 -416.077142) (xy 281.171395 -416.132318) (xy 281.171904 -416.160204)
			(xy 281.171395 -416.18809) (xy 281.163275 -416.243266) (xy 281.147207 -416.296673) (xy 281.123535 -416.34717)
			(xy 281.092762 -416.393683) (xy 281.055545 -416.43522) (xy 281.012677 -416.470895) (xy 280.965071 -416.499949)
			(xy 280.913742 -416.521761) (xy 280.859785 -416.535867) (xy 280.804348 -416.541967) (xy 280.748614 -416.53993)
			(xy 280.693771 -416.5298) (xy 280.640987 -416.511793) (xy 280.591387 -416.486292) (xy 280.546029 -416.453841)
			(xy 280.50588 -416.415132) (xy 280.471794 -416.370989) (xy 280.444498 -416.322354) (xy 280.424575 -416.270263)
			(xy 280.412449 -416.215826) (xy 280.408378 -416.160204) (xy 280.123024 -416.160204) (xy 280.107535 -416.193246)
			(xy 280.076762 -416.239759) (xy 280.039545 -416.281296) (xy 279.996677 -416.316971) (xy 279.949071 -416.346025)
			(xy 279.897742 -416.367837) (xy 279.843785 -416.381943) (xy 279.788348 -416.388043) (xy 279.732614 -416.386006)
			(xy 279.677771 -416.375876) (xy 279.624987 -416.357869) (xy 279.575387 -416.332368) (xy 279.530029 -416.299917)
			(xy 279.48988 -416.261208) (xy 279.455794 -416.217065) (xy 279.428498 -416.16843) (xy 279.408575 -416.116339)
			(xy 279.396449 -416.061902) (xy 279.392378 -416.00628) (xy 279.139593 -416.00628) (xy 279.139395 -416.017148)
			(xy 279.131275 -416.072324) (xy 279.115207 -416.125731) (xy 279.091535 -416.176228) (xy 279.060762 -416.222741)
			(xy 279.023545 -416.264278) (xy 278.980677 -416.299953) (xy 278.933071 -416.329007) (xy 278.881742 -416.350819)
			(xy 278.827785 -416.364925) (xy 278.772348 -416.371025) (xy 278.716614 -416.368988) (xy 278.661771 -416.358858)
			(xy 278.608987 -416.340851) (xy 278.559387 -416.31535) (xy 278.514029 -416.282899) (xy 278.47388 -416.24419)
			(xy 278.439794 -416.200047) (xy 278.412498 -416.151412) (xy 278.392575 -416.099321) (xy 278.380449 -416.044884)
			(xy 278.376378 -415.989262) (xy 278.105113 -415.989262) (xy 278.115275 -416.02304) (xy 278.123395 -416.078216)
			(xy 278.123904 -416.106102) (xy 278.123395 -416.133988) (xy 278.115275 -416.189164) (xy 278.099207 -416.242571)
			(xy 278.075535 -416.293068) (xy 278.044762 -416.339581) (xy 278.007545 -416.381118) (xy 277.964677 -416.416793)
			(xy 277.917071 -416.445847) (xy 277.865742 -416.467659) (xy 277.811785 -416.481765) (xy 277.756348 -416.487865)
			(xy 277.700614 -416.485828) (xy 277.645771 -416.475698) (xy 277.592987 -416.457691) (xy 277.543387 -416.43219)
			(xy 277.498029 -416.399739) (xy 277.45788 -416.36103) (xy 277.423794 -416.316887) (xy 277.396498 -416.268252)
			(xy 277.376575 -416.216161) (xy 277.364449 -416.161724) (xy 277.360378 -416.106102) (xy 277.107904 -416.106102)
			(xy 277.107395 -416.133988) (xy 277.099275 -416.189164) (xy 277.083207 -416.242571) (xy 277.059535 -416.293068)
			(xy 277.028762 -416.339581) (xy 276.991545 -416.381118) (xy 276.948677 -416.416793) (xy 276.901071 -416.445847)
			(xy 276.849742 -416.467659) (xy 276.795785 -416.481765) (xy 276.740348 -416.487865) (xy 276.684614 -416.485828)
			(xy 276.629771 -416.475698) (xy 276.576987 -416.457691) (xy 276.527387 -416.43219) (xy 276.482029 -416.399739)
			(xy 276.44188 -416.36103) (xy 276.407794 -416.316887) (xy 276.380498 -416.268252) (xy 276.360575 -416.216161)
			(xy 276.348449 -416.161724) (xy 276.344378 -416.106102) (xy 274.001808 -416.106102) (xy 274.740624 -416.844734)
			(xy 274.748021 -416.851584) (xy 274.766619 -416.85932) (xy 274.776692 -416.85972) (xy 282.672282 -416.85972)
			(xy 282.682332 -416.859214) (xy 282.700892 -416.851491) (xy 282.70835 -416.844734) (xy 283.300424 -416.25266)
			(xy 283.307272 -416.245263) (xy 283.315004 -416.226664) (xy 283.31541 -416.216592) (xy 283.31541 -392.954256)
			(xy 283.31505 -392.945459) (xy 283.309114 -392.928899) (xy 283.297923 -392.915325) (xy 283.290518 -392.910568)
			(xy 283.226764 -392.872468) (xy 283.186278 -392.847825) (xy 283.109691 -392.791981) (xy 283.073856 -392.760962)
			(xy 280.137108 -390.152382) (xy 280.106797 -390.124885) (xy 280.050289 -390.065678) (xy 279.998825 -390.002038)
			(xy 279.952751 -389.934394) (xy 279.912377 -389.8632) (xy 279.894792 -389.826246) (xy 279.717754 -389.444738)
			(xy 279.698196 -389.429498) (xy 279.686258 -389.427466) (xy 279.660318 -389.422181) (xy 279.610113 -389.405396)
			(xy 279.56271 -389.381829) (xy 279.519023 -389.351934) (xy 279.479889 -389.316283) (xy 279.446062 -389.275564)
			(xy 279.418192 -389.230557) (xy 279.396813 -389.182129) (xy 279.382338 -389.131209) (xy 279.375043 -389.078777)
			(xy 279.3746 -389.052308) (xy 279.374989 -389.027587) (xy 279.381367 -388.978559) (xy 279.394018 -388.930763)
			(xy 279.412729 -388.884998) (xy 279.424638 -388.863332) (xy 279.430734 -388.852664) (xy 279.43175 -388.82828)
			(xy 279.06091 -388.028688) (xy 279.056904 -388.020853) (xy 279.04458 -388.00831) (xy 279.028729 -388.000697)
			(xy 279.020016 -387.999478) (xy 278.91994 -387.989064) (xy 278.895556 -387.999732) (xy 278.887428 -388.0104)
			(xy 278.869307 -388.033711) (xy 278.827083 -388.074981) (xy 278.779002 -388.109248) (xy 278.726212 -388.135692)
			(xy 278.669977 -388.153682) (xy 278.611641 -388.162788) (xy 278.58212 -388.163308) (xy 278.554866 -388.162846)
			(xy 278.500913 -388.155091) (xy 278.448613 -388.139737) (xy 278.39903 -388.117096) (xy 278.353175 -388.087628)
			(xy 278.31198 -388.051935) (xy 278.276284 -388.010741) (xy 278.246814 -387.964887) (xy 278.22417 -387.915306)
			(xy 278.208813 -387.863006) (xy 278.201055 -387.809054) (xy 278.201055 -387.754546) (xy 278.208813 -387.700594)
			(xy 278.22417 -387.648294) (xy 278.246814 -387.598713) (xy 278.276284 -387.552859) (xy 278.31198 -387.511665)
			(xy 278.353175 -387.475972) (xy 278.39903 -387.446504) (xy 278.448613 -387.423863) (xy 278.500913 -387.408509)
			(xy 278.554866 -387.400754) (xy 278.58212 -387.400292) (xy 278.604472 -387.401054) (xy 278.60498 -387.401054)
			(xy 278.618188 -387.401816) (xy 278.642064 -387.389878) (xy 278.698706 -387.30682) (xy 278.703367 -387.299371)
			(xy 278.707784 -387.282378) (xy 278.706146 -387.264896) (xy 278.70277 -387.256782) (xy 278.248872 -386.277866)
			(xy 278.228875 -386.233334) (xy 278.19665 -386.141183) (xy 278.173574 -386.046327) (xy 278.159866 -385.949671)
			(xy 278.157178 -385.90093) (xy 278.110188 -384.80619) (xy 278.087836 -384.779774) (xy 278.070818 -384.776218)
			(xy 278.042703 -384.769687) (xy 277.988709 -384.749296) (xy 277.938402 -384.721003) (xy 277.892931 -384.685455)
			(xy 277.853334 -384.643464) (xy 277.820515 -384.595986) (xy 277.795222 -384.544106) (xy 277.778033 -384.489009)
			(xy 277.76934 -384.43195) (xy 277.768812 -384.403092) (xy 277.769289 -384.376059) (xy 277.776934 -384.322536)
			(xy 277.792055 -384.270628) (xy 277.81435 -384.221372) (xy 277.843372 -384.175756) (xy 277.878542 -384.134692)
			(xy 277.919154 -384.099001) (xy 277.964396 -384.069399) (xy 278.013362 -384.046477) (xy 278.039068 -384.038094)
			(xy 278.055832 -384.033014) (xy 278.075644 -384.00482) (xy 278.01189 -382.520444) (xy 278.011022 -382.510743)
			(xy 278.00297 -382.493027) (xy 277.988893 -382.479591) (xy 277.970821 -382.472374) (xy 277.96109 -382.47193)
			(xy 275.578824 -382.47193) (xy 275.569039 -382.472381) (xy 275.550888 -382.479701) (xy 275.543518 -382.486154)
			(xy 275.467145 -382.558927) (xy 275.309377 -382.69901) (xy 275.146114 -382.832648) (xy 274.977619 -382.959625)
			(xy 274.804163 -383.079737) (xy 274.626026 -383.19279) (xy 274.443495 -383.298602) (xy 274.256863 -383.397002)
			(xy 274.066433 -383.487832) (xy 273.87251 -383.570946) (xy 273.774154 -383.609088) (xy 273.763994 -383.612898)
			(xy 273.650964 -383.725928) (xy 273.644115 -383.733325) (xy 273.636381 -383.751924) (xy 273.635978 -383.761996)
			(xy 273.635978 -387.752082) (xy 274.772374 -387.752082) (xy 274.77286 -387.724831) (xy 274.780616 -387.670883)
			(xy 274.795971 -387.618588) (xy 274.818613 -387.569011) (xy 274.848079 -387.523161) (xy 274.88377 -387.48197)
			(xy 274.924961 -387.446279) (xy 274.970811 -387.416813) (xy 275.020388 -387.394171) (xy 275.072683 -387.378816)
			(xy 275.126631 -387.37106) (xy 275.181133 -387.37106) (xy 275.235081 -387.378816) (xy 275.287376 -387.394171)
			(xy 275.336953 -387.416813) (xy 275.382803 -387.446279) (xy 275.423994 -387.48197) (xy 275.459685 -387.523161)
			(xy 275.489151 -387.569011) (xy 275.511793 -387.618588) (xy 275.527148 -387.670883) (xy 275.534904 -387.724831)
			(xy 275.53539 -387.752082) (xy 275.534896 -387.779556) (xy 275.527006 -387.833936) (xy 275.511388 -387.886618)
			(xy 275.488365 -387.936511) (xy 275.458415 -387.98258) (xy 275.440648 -388.003542) (xy 275.431935 -388.014333)
			(xy 275.419948 -388.039323) (xy 275.41512 -388.066616) (xy 275.417806 -388.094202) (xy 275.427809 -388.120051)
			(xy 275.444392 -388.14226) (xy 275.466334 -388.159194) (xy 275.479002 -388.164832) (xy 275.505069 -388.175866)
			(xy 275.553838 -388.2046) (xy 275.597824 -388.240227) (xy 275.636062 -388.281963) (xy 275.644431 -388.294372)
			(xy 276.866348 -388.294372) (xy 276.870419 -388.23875) (xy 276.882545 -388.184313) (xy 276.902468 -388.132222)
			(xy 276.929764 -388.083587) (xy 276.96385 -388.039444) (xy 277.003999 -388.000735) (xy 277.049357 -387.968284)
			(xy 277.098957 -387.942783) (xy 277.151741 -387.924776) (xy 277.206584 -387.914646) (xy 277.262318 -387.912609)
			(xy 277.317755 -387.918709) (xy 277.371712 -387.932815) (xy 277.423041 -387.954627) (xy 277.470647 -387.983681)
			(xy 277.513515 -388.019356) (xy 277.550732 -388.060893) (xy 277.581505 -388.107406) (xy 277.605177 -388.157903)
			(xy 277.621245 -388.21131) (xy 277.629365 -388.266486) (xy 277.629874 -388.294372) (xy 277.629365 -388.322258)
			(xy 277.621245 -388.377434) (xy 277.605177 -388.430841) (xy 277.581505 -388.481338) (xy 277.550732 -388.527851)
			(xy 277.513515 -388.569388) (xy 277.470647 -388.605063) (xy 277.423041 -388.634117) (xy 277.371712 -388.655929)
			(xy 277.317755 -388.670035) (xy 277.262318 -388.676135) (xy 277.206584 -388.674098) (xy 277.151741 -388.663968)
			(xy 277.098957 -388.645961) (xy 277.049357 -388.62046) (xy 277.003999 -388.588009) (xy 276.96385 -388.5493)
			(xy 276.929764 -388.505157) (xy 276.902468 -388.456522) (xy 276.882545 -388.404431) (xy 276.870419 -388.349994)
			(xy 276.866348 -388.294372) (xy 275.644431 -388.294372) (xy 275.667712 -388.328892) (xy 275.692079 -388.379983)
			(xy 275.708627 -388.434115) (xy 275.716992 -388.490098) (xy 275.717508 -388.5184) (xy 275.717022 -388.545651)
			(xy 275.709266 -388.599599) (xy 275.693911 -388.651894) (xy 275.671269 -388.701471) (xy 275.641803 -388.747321)
			(xy 275.606112 -388.788512) (xy 275.564921 -388.824203) (xy 275.519071 -388.853669) (xy 275.469494 -388.876311)
			(xy 275.417199 -388.891666) (xy 275.363251 -388.899422) (xy 275.308749 -388.899422) (xy 275.254801 -388.891666)
			(xy 275.202506 -388.876311) (xy 275.152929 -388.853669) (xy 275.107079 -388.824203) (xy 275.065888 -388.788512)
			(xy 275.030197 -388.747321) (xy 275.000731 -388.701471) (xy 274.978089 -388.651894) (xy 274.962734 -388.599599)
			(xy 274.954978 -388.545651) (xy 274.954492 -388.5184) (xy 274.95498 -388.490925) (xy 274.962872 -388.436546)
			(xy 274.978492 -388.383864) (xy 275.001516 -388.333971) (xy 275.031467 -388.287902) (xy 275.049234 -388.26694)
			(xy 275.057975 -388.25617) (xy 275.069963 -388.231174) (xy 275.07479 -388.203875) (xy 275.0721 -388.176283)
			(xy 275.062092 -388.15043) (xy 275.045502 -388.12822) (xy 275.023552 -388.111287) (xy 275.01088 -388.10565)
			(xy 274.984839 -388.094559) (xy 274.936074 -388.06583) (xy 274.892089 -388.030211) (xy 274.85385 -387.988483)
			(xy 274.822198 -387.941563) (xy 274.797826 -387.89048) (xy 274.781271 -387.836357) (xy 274.772895 -387.780381)
			(xy 274.772374 -387.752082) (xy 273.635978 -387.752082) (xy 273.635978 -389.0264) (xy 277.811482 -389.0264)
			(xy 277.815553 -388.970778) (xy 277.827679 -388.916341) (xy 277.847602 -388.86425) (xy 277.874898 -388.815615)
			(xy 277.908984 -388.771472) (xy 277.949133 -388.732763) (xy 277.994491 -388.700312) (xy 278.044091 -388.674811)
			(xy 278.096875 -388.656804) (xy 278.151718 -388.646674) (xy 278.207452 -388.644637) (xy 278.262889 -388.650737)
			(xy 278.316846 -388.664843) (xy 278.368175 -388.686655) (xy 278.415781 -388.715709) (xy 278.458649 -388.751384)
			(xy 278.495866 -388.792921) (xy 278.526639 -388.839434) (xy 278.550311 -388.889931) (xy 278.566379 -388.943338)
			(xy 278.574499 -388.998514) (xy 278.575008 -389.0264) (xy 278.574499 -389.054286) (xy 278.566379 -389.109462)
			(xy 278.550311 -389.162869) (xy 278.526639 -389.213366) (xy 278.495866 -389.259879) (xy 278.458649 -389.301416)
			(xy 278.415781 -389.337091) (xy 278.368175 -389.366145) (xy 278.316846 -389.387957) (xy 278.262889 -389.402063)
			(xy 278.207452 -389.408163) (xy 278.151718 -389.406126) (xy 278.096875 -389.395996) (xy 278.044091 -389.377989)
			(xy 277.994491 -389.352488) (xy 277.949133 -389.320037) (xy 277.908984 -389.281328) (xy 277.874898 -389.237185)
			(xy 277.847602 -389.18855) (xy 277.827679 -389.136459) (xy 277.815553 -389.082022) (xy 277.811482 -389.0264)
			(xy 273.635978 -389.0264) (xy 273.635978 -389.9916) (xy 278.200102 -389.9916) (xy 278.204173 -389.935978)
			(xy 278.216299 -389.881541) (xy 278.236222 -389.82945) (xy 278.263518 -389.780815) (xy 278.297604 -389.736672)
			(xy 278.337753 -389.697963) (xy 278.383111 -389.665512) (xy 278.432711 -389.640011) (xy 278.485495 -389.622004)
			(xy 278.540338 -389.611874) (xy 278.596072 -389.609837) (xy 278.651509 -389.615937) (xy 278.705466 -389.630043)
			(xy 278.756795 -389.651855) (xy 278.804401 -389.680909) (xy 278.847269 -389.716584) (xy 278.884486 -389.758121)
			(xy 278.915259 -389.804634) (xy 278.938931 -389.855131) (xy 278.954999 -389.908538) (xy 278.963119 -389.963714)
			(xy 278.963628 -389.9916) (xy 278.963119 -390.019486) (xy 278.954999 -390.074662) (xy 278.938931 -390.128069)
			(xy 278.915259 -390.178566) (xy 278.884486 -390.225079) (xy 278.847269 -390.266616) (xy 278.804401 -390.302291)
			(xy 278.756795 -390.331345) (xy 278.705466 -390.353157) (xy 278.651509 -390.367263) (xy 278.596072 -390.373363)
			(xy 278.540338 -390.371326) (xy 278.485495 -390.361196) (xy 278.432711 -390.343189) (xy 278.383111 -390.317688)
			(xy 278.337753 -390.285237) (xy 278.297604 -390.246528) (xy 278.263518 -390.202385) (xy 278.236222 -390.15375)
			(xy 278.216299 -390.101659) (xy 278.204173 -390.047222) (xy 278.200102 -389.9916) (xy 273.635978 -389.9916)
			(xy 273.635978 -392.7602) (xy 276.865332 -392.7602) (xy 276.869403 -392.704578) (xy 276.881529 -392.650141)
			(xy 276.901452 -392.59805) (xy 276.928748 -392.549415) (xy 276.962834 -392.505272) (xy 277.002983 -392.466563)
			(xy 277.048341 -392.434112) (xy 277.097941 -392.408611) (xy 277.150725 -392.390604) (xy 277.205568 -392.380474)
			(xy 277.261302 -392.378437) (xy 277.316739 -392.384537) (xy 277.370696 -392.398643) (xy 277.422025 -392.420455)
			(xy 277.469631 -392.449509) (xy 277.512499 -392.485184) (xy 277.549716 -392.526721) (xy 277.580489 -392.573234)
			(xy 277.604161 -392.623731) (xy 277.620229 -392.677138) (xy 277.628079 -392.730482) (xy 278.6667 -392.730482)
			(xy 278.670771 -392.67486) (xy 278.682897 -392.620423) (xy 278.70282 -392.568332) (xy 278.730116 -392.519697)
			(xy 278.764202 -392.475554) (xy 278.804351 -392.436845) (xy 278.849709 -392.404394) (xy 278.899309 -392.378893)
			(xy 278.952093 -392.360886) (xy 279.006936 -392.350756) (xy 279.06267 -392.348719) (xy 279.118107 -392.354819)
			(xy 279.172064 -392.368925) (xy 279.223393 -392.390737) (xy 279.270999 -392.419791) (xy 279.313867 -392.455466)
			(xy 279.351084 -392.497003) (xy 279.381857 -392.543516) (xy 279.405529 -392.594013) (xy 279.421597 -392.64742)
			(xy 279.429717 -392.702596) (xy 279.430226 -392.730482) (xy 279.429717 -392.758368) (xy 279.421597 -392.813544)
			(xy 279.405529 -392.866951) (xy 279.381857 -392.917448) (xy 279.351084 -392.963961) (xy 279.313867 -393.005498)
			(xy 279.270999 -393.041173) (xy 279.223393 -393.070227) (xy 279.172064 -393.092039) (xy 279.118107 -393.106145)
			(xy 279.06267 -393.112245) (xy 279.006936 -393.110208) (xy 278.952093 -393.100078) (xy 278.899309 -393.082071)
			(xy 278.849709 -393.05657) (xy 278.804351 -393.024119) (xy 278.764202 -392.98541) (xy 278.730116 -392.941267)
			(xy 278.70282 -392.892632) (xy 278.682897 -392.840541) (xy 278.670771 -392.786104) (xy 278.6667 -392.730482)
			(xy 277.628079 -392.730482) (xy 277.628349 -392.732314) (xy 277.628858 -392.7602) (xy 277.628349 -392.788086)
			(xy 277.620229 -392.843262) (xy 277.604161 -392.896669) (xy 277.580489 -392.947166) (xy 277.549716 -392.993679)
			(xy 277.512499 -393.035216) (xy 277.469631 -393.070891) (xy 277.422025 -393.099945) (xy 277.370696 -393.121757)
			(xy 277.316739 -393.135863) (xy 277.261302 -393.141963) (xy 277.205568 -393.139926) (xy 277.150725 -393.129796)
			(xy 277.097941 -393.111789) (xy 277.048341 -393.086288) (xy 277.002983 -393.053837) (xy 276.962834 -393.015128)
			(xy 276.928748 -392.970985) (xy 276.901452 -392.92235) (xy 276.881529 -392.870259) (xy 276.869403 -392.815822)
			(xy 276.865332 -392.7602) (xy 273.635978 -392.7602) (xy 273.635978 -394.762482) (xy 276.700486 -394.762482)
			(xy 276.704557 -394.70686) (xy 276.716683 -394.652423) (xy 276.736606 -394.600332) (xy 276.763902 -394.551697)
			(xy 276.797988 -394.507554) (xy 276.838137 -394.468845) (xy 276.883495 -394.436394) (xy 276.933095 -394.410893)
			(xy 276.985879 -394.392886) (xy 277.040722 -394.382756) (xy 277.096456 -394.380719) (xy 277.151893 -394.386819)
			(xy 277.20585 -394.400925) (xy 277.257179 -394.422737) (xy 277.304785 -394.451791) (xy 277.347653 -394.487466)
			(xy 277.38487 -394.529003) (xy 277.415643 -394.575516) (xy 277.439315 -394.626013) (xy 277.455383 -394.67942)
			(xy 277.463503 -394.734596) (xy 277.464012 -394.762482) (xy 279.240486 -394.762482) (xy 279.244557 -394.70686)
			(xy 279.256683 -394.652423) (xy 279.276606 -394.600332) (xy 279.303902 -394.551697) (xy 279.337988 -394.507554)
			(xy 279.378137 -394.468845) (xy 279.423495 -394.436394) (xy 279.473095 -394.410893) (xy 279.525879 -394.392886)
			(xy 279.580722 -394.382756) (xy 279.636456 -394.380719) (xy 279.691893 -394.386819) (xy 279.74585 -394.400925)
			(xy 279.797179 -394.422737) (xy 279.844785 -394.451791) (xy 279.887653 -394.487466) (xy 279.92487 -394.529003)
			(xy 279.955643 -394.575516) (xy 279.979315 -394.626013) (xy 279.995383 -394.67942) (xy 280.003503 -394.734596)
			(xy 280.004012 -394.762482) (xy 280.003503 -394.790368) (xy 279.995383 -394.845544) (xy 279.979315 -394.898951)
			(xy 279.955643 -394.949448) (xy 279.92487 -394.995961) (xy 279.887653 -395.037498) (xy 279.844785 -395.073173)
			(xy 279.797179 -395.102227) (xy 279.74585 -395.124039) (xy 279.691893 -395.138145) (xy 279.636456 -395.144245)
			(xy 279.580722 -395.142208) (xy 279.525879 -395.132078) (xy 279.473095 -395.114071) (xy 279.423495 -395.08857)
			(xy 279.378137 -395.056119) (xy 279.337988 -395.01741) (xy 279.303902 -394.973267) (xy 279.276606 -394.924632)
			(xy 279.256683 -394.872541) (xy 279.244557 -394.818104) (xy 279.240486 -394.762482) (xy 277.464012 -394.762482)
			(xy 277.463503 -394.790368) (xy 277.455383 -394.845544) (xy 277.439315 -394.898951) (xy 277.415643 -394.949448)
			(xy 277.38487 -394.995961) (xy 277.347653 -395.037498) (xy 277.304785 -395.073173) (xy 277.257179 -395.102227)
			(xy 277.20585 -395.124039) (xy 277.151893 -395.138145) (xy 277.096456 -395.144245) (xy 277.040722 -395.142208)
			(xy 276.985879 -395.132078) (xy 276.933095 -395.114071) (xy 276.883495 -395.08857) (xy 276.838137 -395.056119)
			(xy 276.797988 -395.01741) (xy 276.763902 -394.973267) (xy 276.736606 -394.924632) (xy 276.716683 -394.872541)
			(xy 276.704557 -394.818104) (xy 276.700486 -394.762482) (xy 273.635978 -394.762482) (xy 273.635978 -395.638274)
			(xy 273.635541 -395.648338) (xy 273.627805 -395.666921) (xy 273.620992 -395.674342) (xy 272.725134 -396.5702)
			(xy 276.876508 -396.5702) (xy 276.880579 -396.514578) (xy 276.892705 -396.460141) (xy 276.912628 -396.40805)
			(xy 276.939924 -396.359415) (xy 276.97401 -396.315272) (xy 277.014159 -396.276563) (xy 277.059517 -396.244112)
			(xy 277.109117 -396.218611) (xy 277.161901 -396.200604) (xy 277.216744 -396.190474) (xy 277.272478 -396.188437)
			(xy 277.327915 -396.194537) (xy 277.381872 -396.208643) (xy 277.433201 -396.230455) (xy 277.480807 -396.259509)
			(xy 277.523675 -396.295184) (xy 277.560892 -396.336721) (xy 277.591665 -396.383234) (xy 277.615337 -396.433731)
			(xy 277.631405 -396.487138) (xy 277.638134 -396.532862) (xy 278.858216 -396.532862) (xy 278.862287 -396.47724)
			(xy 278.874413 -396.422803) (xy 278.894336 -396.370712) (xy 278.921632 -396.322077) (xy 278.955718 -396.277934)
			(xy 278.995867 -396.239225) (xy 279.041225 -396.206774) (xy 279.090825 -396.181273) (xy 279.143609 -396.163266)
			(xy 279.198452 -396.153136) (xy 279.254186 -396.151099) (xy 279.309623 -396.157199) (xy 279.36358 -396.171305)
			(xy 279.414909 -396.193117) (xy 279.462515 -396.222171) (xy 279.505383 -396.257846) (xy 279.5426 -396.299383)
			(xy 279.573373 -396.345896) (xy 279.597045 -396.396393) (xy 279.613113 -396.4498) (xy 279.621233 -396.504976)
			(xy 279.621742 -396.532862) (xy 279.621233 -396.560748) (xy 279.613113 -396.615924) (xy 279.597045 -396.669331)
			(xy 279.573373 -396.719828) (xy 279.5426 -396.766341) (xy 279.505383 -396.807878) (xy 279.462515 -396.843553)
			(xy 279.414909 -396.872607) (xy 279.36358 -396.894419) (xy 279.309623 -396.908525) (xy 279.254186 -396.914625)
			(xy 279.198452 -396.912588) (xy 279.143609 -396.902458) (xy 279.090825 -396.884451) (xy 279.041225 -396.85895)
			(xy 278.995867 -396.826499) (xy 278.955718 -396.78779) (xy 278.921632 -396.743647) (xy 278.894336 -396.695012)
			(xy 278.874413 -396.642921) (xy 278.862287 -396.588484) (xy 278.858216 -396.532862) (xy 277.638134 -396.532862)
			(xy 277.639525 -396.542314) (xy 277.640034 -396.5702) (xy 277.639525 -396.598086) (xy 277.631405 -396.653262)
			(xy 277.615337 -396.706669) (xy 277.591665 -396.757166) (xy 277.560892 -396.803679) (xy 277.523675 -396.845216)
			(xy 277.480807 -396.880891) (xy 277.433201 -396.909945) (xy 277.381872 -396.931757) (xy 277.327915 -396.945863)
			(xy 277.272478 -396.951963) (xy 277.216744 -396.949926) (xy 277.161901 -396.939796) (xy 277.109117 -396.921789)
			(xy 277.059517 -396.896288) (xy 277.014159 -396.863837) (xy 276.97401 -396.825128) (xy 276.939924 -396.780985)
			(xy 276.912628 -396.73235) (xy 276.892705 -396.680259) (xy 276.880579 -396.625822) (xy 276.876508 -396.5702)
			(xy 272.725134 -396.5702) (xy 271.361662 -397.933672) (xy 279.755598 -397.933672) (xy 279.759669 -397.87805)
			(xy 279.771795 -397.823613) (xy 279.791718 -397.771522) (xy 279.819014 -397.722887) (xy 279.8531 -397.678744)
			(xy 279.893249 -397.640035) (xy 279.938607 -397.607584) (xy 279.988207 -397.582083) (xy 280.040991 -397.564076)
			(xy 280.095834 -397.553946) (xy 280.151568 -397.551909) (xy 280.207005 -397.558009) (xy 280.260962 -397.572115)
			(xy 280.312291 -397.593927) (xy 280.359897 -397.622981) (xy 280.402765 -397.658656) (xy 280.439982 -397.700193)
			(xy 280.470755 -397.746706) (xy 280.494427 -397.797203) (xy 280.510495 -397.85061) (xy 280.518615 -397.905786)
			(xy 280.519124 -397.933672) (xy 280.518615 -397.961558) (xy 280.510495 -398.016734) (xy 280.494427 -398.070141)
			(xy 280.470755 -398.120638) (xy 280.439982 -398.167151) (xy 280.402765 -398.208688) (xy 280.359897 -398.244363)
			(xy 280.312291 -398.273417) (xy 280.260962 -398.295229) (xy 280.207005 -398.309335) (xy 280.151568 -398.315435)
			(xy 280.095834 -398.313398) (xy 280.040991 -398.303268) (xy 279.988207 -398.285261) (xy 279.938607 -398.25976)
			(xy 279.893249 -398.227309) (xy 279.8531 -398.1886) (xy 279.819014 -398.144457) (xy 279.791718 -398.095822)
			(xy 279.771795 -398.043731) (xy 279.759669 -397.989294) (xy 279.755598 -397.933672) (xy 271.361662 -397.933672)
			(xy 270.640048 -398.655286) (xy 270.632647 -398.662126) (xy 270.614049 -398.669844) (xy 270.60398 -398.670272)
			(xy 266.489688 -398.670272) (xy 266.479619 -398.669846) (xy 266.461021 -398.662125) (xy 266.45362 -398.655286)
			(xy 265.257026 -397.458692) (xy 265.24966 -397.452596) (xy 265.167329 -397.396226) (xy 265.006507 -397.278077)
			(xy 264.850282 -397.153912) (xy 264.698881 -397.023909) (xy 264.552522 -396.888255) (xy 264.411414 -396.747146)
			(xy 264.275762 -396.600786) (xy 264.14576 -396.449383) (xy 264.021596 -396.293158) (xy 263.903449 -396.132335)
			(xy 263.847072 -396.050008) (xy 263.840976 -396.042642) (xy 260.175756 -392.377422) (xy 260.168356 -392.37058)
			(xy 260.149758 -392.362858) (xy 260.139688 -392.362436) (xy 254.997712 -392.362436) (xy 254.987642 -392.362858)
			(xy 254.969037 -392.370573) (xy 254.961644 -392.377422) (xy 254.616204 -392.722862) (xy 254.609367 -392.730264)
			(xy 254.601654 -392.748862) (xy 254.601218 -392.75893) (xy 254.601218 -398.357852) (xy 254.600786 -398.367918)
			(xy 254.59306 -398.386511) (xy 254.586232 -398.39392) (xy 253.639574 -399.340578) (xy 253.632175 -399.347423)
			(xy 253.613577 -399.355151) (xy 253.603506 -399.355564) (xy 245.76278 -399.355564) (xy 245.752713 -399.355992)
			(xy 245.73412 -399.363719) (xy 245.726712 -399.37055) (xy 245.35892 -399.738342) (xy 245.352078 -399.745742)
			(xy 245.344356 -399.76434) (xy 245.343934 -399.77441) (xy 245.343934 -400.82851) (xy 245.343507 -400.838578)
			(xy 245.335783 -400.857174) (xy 245.328948 -400.864578) (xy 245.020338 -401.173188) (xy 277.12035 -401.173188)
			(xy 277.120836 -401.145937) (xy 277.128592 -401.091989) (xy 277.143947 -401.039694) (xy 277.166589 -400.990117)
			(xy 277.196055 -400.944267) (xy 277.231746 -400.903076) (xy 277.272937 -400.867385) (xy 277.318787 -400.837919)
			(xy 277.368364 -400.815277) (xy 277.420659 -400.799922) (xy 277.474607 -400.792166) (xy 277.529109 -400.792166)
			(xy 277.583057 -400.799922) (xy 277.635352 -400.815277) (xy 277.684929 -400.837919) (xy 277.730779 -400.867385)
			(xy 277.77197 -400.903076) (xy 277.807661 -400.944267) (xy 277.837127 -400.990117) (xy 277.859769 -401.039694)
			(xy 277.875124 -401.091989) (xy 277.88288 -401.145937) (xy 277.882895 -401.146772) (xy 279.138886 -401.146772)
			(xy 279.142957 -401.09115) (xy 279.155083 -401.036713) (xy 279.175006 -400.984622) (xy 279.202302 -400.935987)
			(xy 279.236388 -400.891844) (xy 279.276537 -400.853135) (xy 279.321895 -400.820684) (xy 279.371495 -400.795183)
			(xy 279.424279 -400.777176) (xy 279.479122 -400.767046) (xy 279.534856 -400.765009) (xy 279.590293 -400.771109)
			(xy 279.64425 -400.785215) (xy 279.695579 -400.807027) (xy 279.743185 -400.836081) (xy 279.786053 -400.871756)
			(xy 279.82327 -400.913293) (xy 279.854043 -400.959806) (xy 279.877715 -401.010303) (xy 279.893783 -401.06371)
			(xy 279.901903 -401.118886) (xy 279.902412 -401.146772) (xy 279.901903 -401.174658) (xy 279.893783 -401.229834)
			(xy 279.877715 -401.283241) (xy 279.854043 -401.333738) (xy 279.82327 -401.380251) (xy 279.786053 -401.421788)
			(xy 279.743185 -401.457463) (xy 279.695579 -401.486517) (xy 279.64425 -401.508329) (xy 279.590293 -401.522435)
			(xy 279.534856 -401.528535) (xy 279.479122 -401.526498) (xy 279.424279 -401.516368) (xy 279.371495 -401.498361)
			(xy 279.321895 -401.47286) (xy 279.276537 -401.440409) (xy 279.236388 -401.4017) (xy 279.202302 -401.357557)
			(xy 279.175006 -401.308922) (xy 279.155083 -401.256831) (xy 279.142957 -401.202394) (xy 279.138886 -401.146772)
			(xy 277.882895 -401.146772) (xy 277.883366 -401.173188) (xy 277.883366 -401.173442) (xy 277.882731 -401.204219)
			(xy 277.872821 -401.26497) (xy 277.853297 -401.323347) (xy 277.824664 -401.377836) (xy 277.806658 -401.402804)
			(xy 277.79821 -401.41486) (xy 277.787947 -401.442437) (xy 277.785972 -401.471796) (xy 277.79245 -401.5005)
			(xy 277.806842 -401.526165) (xy 277.827953 -401.546663) (xy 277.854033 -401.56029) (xy 277.86838 -401.563586)
			(xy 277.894092 -401.569098) (xy 277.943829 -401.586165) (xy 277.990751 -401.609903) (xy 278.033966 -401.63986)
			(xy 278.072657 -401.675471) (xy 278.10609 -401.716058) (xy 278.133631 -401.760853) (xy 278.154757 -401.809006)
			(xy 278.169069 -401.859605) (xy 278.176294 -401.91169) (xy 278.176736 -401.937982) (xy 278.17625 -401.965233)
			(xy 278.168494 -402.019181) (xy 278.153139 -402.071476) (xy 278.130497 -402.121053) (xy 278.101031 -402.166903)
			(xy 278.06534 -402.208094) (xy 278.024149 -402.243785) (xy 277.978299 -402.273251) (xy 277.928722 -402.295893)
			(xy 277.876427 -402.311248) (xy 277.822479 -402.319004) (xy 277.767977 -402.319004) (xy 277.714029 -402.311248)
			(xy 277.661734 -402.295893) (xy 277.612157 -402.273251) (xy 277.566307 -402.243785) (xy 277.525116 -402.208094)
			(xy 277.489425 -402.166903) (xy 277.459959 -402.121053) (xy 277.437317 -402.071476) (xy 277.421962 -402.019181)
			(xy 277.414206 -401.965233) (xy 277.41372 -401.937982) (xy 277.41372 -401.937728) (xy 277.414342 -401.906951)
			(xy 277.424256 -401.846199) (xy 277.443784 -401.787823) (xy 277.47242 -401.733334) (xy 277.490428 -401.708366)
			(xy 277.498921 -401.696339) (xy 277.509183 -401.668752) (xy 277.511153 -401.639385) (xy 277.504669 -401.610674)
			(xy 277.490269 -401.585004) (xy 277.469147 -401.564505) (xy 277.443058 -401.550878) (xy 277.428706 -401.547584)
			(xy 277.402985 -401.542111) (xy 277.353246 -401.52504) (xy 277.306323 -401.501298) (xy 277.263107 -401.471336)
			(xy 277.224416 -401.435721) (xy 277.190984 -401.39513) (xy 277.163445 -401.35033) (xy 277.142321 -401.302173)
			(xy 277.128012 -401.25157) (xy 277.12079 -401.199481) (xy 277.12035 -401.173188) (xy 245.020338 -401.173188)
			(xy 244.002052 -402.191474) (xy 243.994652 -402.198315) (xy 243.976054 -402.206037) (xy 243.965984 -402.20646)
			(xy 239.48898 -402.20646) (xy 239.478913 -402.206888) (xy 239.460319 -402.214615) (xy 239.452912 -402.221446)
			(xy 238.291878 -403.38248) (xy 238.285036 -403.389879) (xy 238.277318 -403.408478) (xy 238.276892 -403.418548)
			(xy 238.276892 -403.46249) (xy 275.581108 -403.46249) (xy 275.585179 -403.406868) (xy 275.597305 -403.352431)
			(xy 275.617228 -403.30034) (xy 275.644524 -403.251705) (xy 275.67861 -403.207562) (xy 275.718759 -403.168853)
			(xy 275.764117 -403.136402) (xy 275.813717 -403.110901) (xy 275.866501 -403.092894) (xy 275.921344 -403.082764)
			(xy 275.977078 -403.080727) (xy 276.032515 -403.086827) (xy 276.086472 -403.100933) (xy 276.137801 -403.122745)
			(xy 276.185407 -403.151799) (xy 276.228275 -403.187474) (xy 276.265492 -403.229011) (xy 276.296265 -403.275524)
			(xy 276.319937 -403.326021) (xy 276.336005 -403.379428) (xy 276.344125 -403.434604) (xy 276.344634 -403.46249)
			(xy 276.597108 -403.46249) (xy 276.601179 -403.406868) (xy 276.613305 -403.352431) (xy 276.633228 -403.30034)
			(xy 276.660524 -403.251705) (xy 276.69461 -403.207562) (xy 276.734759 -403.168853) (xy 276.780117 -403.136402)
			(xy 276.829717 -403.110901) (xy 276.882501 -403.092894) (xy 276.937344 -403.082764) (xy 276.993078 -403.080727)
			(xy 277.048515 -403.086827) (xy 277.102472 -403.100933) (xy 277.153801 -403.122745) (xy 277.201407 -403.151799)
			(xy 277.244275 -403.187474) (xy 277.281492 -403.229011) (xy 277.312265 -403.275524) (xy 277.335937 -403.326021)
			(xy 277.352005 -403.379428) (xy 277.360125 -403.434604) (xy 277.360634 -403.46249) (xy 277.360125 -403.490376)
			(xy 277.352005 -403.545552) (xy 277.335937 -403.598959) (xy 277.312265 -403.649456) (xy 277.281492 -403.695969)
			(xy 277.244275 -403.737506) (xy 277.201407 -403.773181) (xy 277.153801 -403.802235) (xy 277.102472 -403.824047)
			(xy 277.048515 -403.838153) (xy 276.993078 -403.844253) (xy 276.937344 -403.842216) (xy 276.882501 -403.832086)
			(xy 276.829717 -403.814079) (xy 276.780117 -403.788578) (xy 276.734759 -403.756127) (xy 276.69461 -403.717418)
			(xy 276.660524 -403.673275) (xy 276.633228 -403.62464) (xy 276.613305 -403.572549) (xy 276.601179 -403.518112)
			(xy 276.597108 -403.46249) (xy 276.344634 -403.46249) (xy 276.344125 -403.490376) (xy 276.336005 -403.545552)
			(xy 276.319937 -403.598959) (xy 276.296265 -403.649456) (xy 276.265492 -403.695969) (xy 276.228275 -403.737506)
			(xy 276.185407 -403.773181) (xy 276.137801 -403.802235) (xy 276.086472 -403.824047) (xy 276.032515 -403.838153)
			(xy 275.977078 -403.844253) (xy 275.921344 -403.842216) (xy 275.866501 -403.832086) (xy 275.813717 -403.814079)
			(xy 275.764117 -403.788578) (xy 275.718759 -403.756127) (xy 275.67861 -403.717418) (xy 275.644524 -403.673275)
			(xy 275.617228 -403.62464) (xy 275.597305 -403.572549) (xy 275.585179 -403.518112) (xy 275.581108 -403.46249)
			(xy 238.276892 -403.46249) (xy 238.276892 -403.97049) (xy 278.636984 -403.97049) (xy 278.637515 -403.944067)
			(xy 278.644823 -403.891728) (xy 278.659285 -403.840899) (xy 278.680623 -403.792552) (xy 278.708429 -403.747612)
			(xy 278.74217 -403.70694) (xy 278.781203 -403.671314) (xy 278.824778 -403.641415) (xy 278.872062 -403.617816)
			(xy 278.922151 -403.600969) (xy 278.974086 -403.591195) (xy 279.000458 -403.58949) (xy 279.015759 -403.588239)
			(xy 279.04459 -403.577725) (xy 279.069008 -403.559138) (xy 279.08682 -403.534149) (xy 279.096425 -403.505003)
			(xy 279.096959 -403.474319) (xy 279.093168 -403.459442) (xy 279.085948 -403.43317) (xy 279.078177 -403.379242)
			(xy 279.077674 -403.352) (xy 279.07816 -403.324749) (xy 279.085916 -403.270801) (xy 279.101271 -403.218506)
			(xy 279.123913 -403.168929) (xy 279.153379 -403.123079) (xy 279.18907 -403.081888) (xy 279.230261 -403.046197)
			(xy 279.276111 -403.016731) (xy 279.325688 -402.994089) (xy 279.377983 -402.978734) (xy 279.431931 -402.970978)
			(xy 279.486433 -402.970978) (xy 279.540381 -402.978734) (xy 279.592676 -402.994089) (xy 279.642253 -403.016731)
			(xy 279.688103 -403.046197) (xy 279.729294 -403.081888) (xy 279.764985 -403.123079) (xy 279.794451 -403.168929)
			(xy 279.817093 -403.218506) (xy 279.832448 -403.270801) (xy 279.840204 -403.324749) (xy 279.840613 -403.347682)
			(xy 280.093164 -403.347682) (xy 280.097235 -403.29206) (xy 280.109361 -403.237623) (xy 280.129284 -403.185532)
			(xy 280.15658 -403.136897) (xy 280.190666 -403.092754) (xy 280.230815 -403.054045) (xy 280.276173 -403.021594)
			(xy 280.325773 -402.996093) (xy 280.378557 -402.978086) (xy 280.4334 -402.967956) (xy 280.489134 -402.965919)
			(xy 280.544571 -402.972019) (xy 280.598528 -402.986125) (xy 280.649857 -403.007937) (xy 280.697463 -403.036991)
			(xy 280.740331 -403.072666) (xy 280.777548 -403.114203) (xy 280.808321 -403.160716) (xy 280.831993 -403.211213)
			(xy 280.848061 -403.26462) (xy 280.856181 -403.319796) (xy 280.85669 -403.347682) (xy 280.856181 -403.375568)
			(xy 280.848061 -403.430744) (xy 280.831993 -403.484151) (xy 280.808321 -403.534648) (xy 280.777548 -403.581161)
			(xy 280.740331 -403.622698) (xy 280.697463 -403.658373) (xy 280.649857 -403.687427) (xy 280.598528 -403.709239)
			(xy 280.544571 -403.723345) (xy 280.489134 -403.729445) (xy 280.4334 -403.727408) (xy 280.378557 -403.717278)
			(xy 280.325773 -403.699271) (xy 280.276173 -403.67377) (xy 280.230815 -403.641319) (xy 280.190666 -403.60261)
			(xy 280.15658 -403.558467) (xy 280.129284 -403.509832) (xy 280.109361 -403.457741) (xy 280.097235 -403.403304)
			(xy 280.093164 -403.347682) (xy 279.840613 -403.347682) (xy 279.84069 -403.352) (xy 279.840174 -403.378424)
			(xy 279.832867 -403.430764) (xy 279.818405 -403.481595) (xy 279.797067 -403.529944) (xy 279.76926 -403.574885)
			(xy 279.735516 -403.615558) (xy 279.696482 -403.651184) (xy 279.652904 -403.681082) (xy 279.605617 -403.70468)
			(xy 279.555526 -403.721526) (xy 279.503589 -403.731297) (xy 279.477216 -403.733) (xy 279.461915 -403.734244)
			(xy 279.433087 -403.744763) (xy 279.40867 -403.763352) (xy 279.39086 -403.788342) (xy 279.381255 -403.817488)
			(xy 279.380718 -403.84817) (xy 279.384506 -403.863048) (xy 279.391723 -403.889321) (xy 279.399497 -403.943248)
			(xy 279.4 -403.97049) (xy 279.399514 -403.997741) (xy 279.391758 -404.051689) (xy 279.376403 -404.103984)
			(xy 279.353761 -404.153561) (xy 279.324295 -404.199411) (xy 279.288604 -404.240602) (xy 279.247413 -404.276293)
			(xy 279.201563 -404.305759) (xy 279.151986 -404.328401) (xy 279.099691 -404.343756) (xy 279.045743 -404.351512)
			(xy 278.991241 -404.351512) (xy 278.937293 -404.343756) (xy 278.884998 -404.328401) (xy 278.835421 -404.305759)
			(xy 278.789571 -404.276293) (xy 278.74838 -404.240602) (xy 278.712689 -404.199411) (xy 278.683223 -404.153561)
			(xy 278.660581 -404.103984) (xy 278.645226 -404.051689) (xy 278.63747 -403.997741) (xy 278.636984 -403.97049)
			(xy 238.276892 -403.97049) (xy 238.276892 -404.674324) (xy 274.928582 -404.674324) (xy 274.932653 -404.618702)
			(xy 274.944779 -404.564265) (xy 274.964702 -404.512174) (xy 274.991998 -404.463539) (xy 275.026084 -404.419396)
			(xy 275.066233 -404.380687) (xy 275.111591 -404.348236) (xy 275.161191 -404.322735) (xy 275.213975 -404.304728)
			(xy 275.268818 -404.294598) (xy 275.324552 -404.292561) (xy 275.379989 -404.298661) (xy 275.433946 -404.312767)
			(xy 275.485275 -404.334579) (xy 275.532881 -404.363633) (xy 275.575749 -404.399308) (xy 275.612966 -404.440845)
			(xy 275.643739 -404.487358) (xy 275.667411 -404.537855) (xy 275.683479 -404.591262) (xy 275.691599 -404.646438)
			(xy 275.692108 -404.674324) (xy 275.691599 -404.70221) (xy 275.683479 -404.757386) (xy 275.667411 -404.810793)
			(xy 275.643739 -404.86129) (xy 275.612966 -404.907803) (xy 275.575749 -404.94934) (xy 275.532881 -404.985015)
			(xy 275.485275 -405.014069) (xy 275.433946 -405.035881) (xy 275.379989 -405.049987) (xy 275.324552 -405.056087)
			(xy 275.268818 -405.05405) (xy 275.213975 -405.04392) (xy 275.161191 -405.025913) (xy 275.111591 -405.000412)
			(xy 275.066233 -404.967961) (xy 275.026084 -404.929252) (xy 274.991998 -404.885109) (xy 274.964702 -404.836474)
			(xy 274.944779 -404.784383) (xy 274.932653 -404.729946) (xy 274.928582 -404.674324) (xy 238.276892 -404.674324)
			(xy 238.276892 -406.147016) (xy 275.691598 -406.147016) (xy 275.695669 -406.091394) (xy 275.707795 -406.036957)
			(xy 275.727718 -405.984866) (xy 275.755014 -405.936231) (xy 275.7891 -405.892088) (xy 275.829249 -405.853379)
			(xy 275.874607 -405.820928) (xy 275.924207 -405.795427) (xy 275.976991 -405.77742) (xy 276.031834 -405.76729)
			(xy 276.087568 -405.765253) (xy 276.143005 -405.771353) (xy 276.196962 -405.785459) (xy 276.248291 -405.807271)
			(xy 276.295897 -405.836325) (xy 276.338765 -405.872) (xy 276.375982 -405.913537) (xy 276.406755 -405.96005)
			(xy 276.430427 -406.010547) (xy 276.446495 -406.063954) (xy 276.454615 -406.11913) (xy 276.455124 -406.147016)
			(xy 276.454615 -406.174902) (xy 276.453107 -406.185151) (xy 276.708593 -406.185151) (xy 276.708593 -406.130649)
			(xy 276.71635 -406.076702) (xy 276.731705 -406.024408) (xy 276.754347 -405.974832) (xy 276.783813 -405.928983)
			(xy 276.819505 -405.887794) (xy 276.860695 -405.852104) (xy 276.906546 -405.822639) (xy 276.956123 -405.8)
			(xy 277.008418 -405.784646) (xy 277.062365 -405.776892) (xy 277.089616 -405.77643) (xy 277.118436 -405.776938)
			(xy 277.175418 -405.785624) (xy 277.230446 -405.802782) (xy 277.282267 -405.828021) (xy 277.329703 -405.860766)
			(xy 277.371675 -405.900274) (xy 277.407227 -405.945644) (xy 277.421848 -405.970486) (xy 277.427835 -405.979953)
			(xy 277.446013 -405.992998) (xy 277.4569 -405.995632) (xy 277.533862 -406.009602) (xy 277.544953 -406.011034)
			(xy 277.566561 -406.005374) (xy 277.575518 -405.99868) (xy 277.596164 -405.982058) (xy 277.641186 -405.954089)
			(xy 277.689649 -405.932626) (xy 277.740618 -405.918084) (xy 277.793111 -405.910743) (xy 277.819612 -405.910288)
			(xy 277.846862 -405.910783) (xy 277.900808 -405.91854) (xy 277.953101 -405.933896) (xy 278.002676 -405.956538)
			(xy 278.048525 -405.986004) (xy 278.089713 -406.021695) (xy 278.125403 -406.062885) (xy 278.154868 -406.108734)
			(xy 278.177508 -406.15831) (xy 278.192862 -406.210603) (xy 278.200618 -406.26455) (xy 278.200618 -406.31905)
			(xy 278.192862 -406.372997) (xy 278.177508 -406.42529) (xy 278.154868 -406.474866) (xy 278.125403 -406.520715)
			(xy 278.089713 -406.561905) (xy 278.048525 -406.597596) (xy 278.002676 -406.627062) (xy 277.953101 -406.649704)
			(xy 277.900808 -406.66506) (xy 277.846862 -406.672817) (xy 277.819612 -406.673304) (xy 277.790794 -406.672757)
			(xy 277.733814 -406.664075) (xy 277.678788 -406.646923) (xy 277.626967 -406.621691) (xy 277.579531 -406.588952)
			(xy 277.537558 -406.549451) (xy 277.502003 -406.504087) (xy 277.48738 -406.479248) (xy 277.481415 -406.469763)
			(xy 277.463222 -406.456726) (xy 277.452328 -406.454102) (xy 277.375366 -406.440132) (xy 277.364274 -406.43871)
			(xy 277.342667 -406.444361) (xy 277.33371 -406.451054) (xy 277.313058 -406.467668) (xy 277.268037 -406.495637)
			(xy 277.219575 -406.517101) (xy 277.168608 -406.531645) (xy 277.116117 -406.538989) (xy 277.089616 -406.539446)
			(xy 277.062365 -406.538908) (xy 277.008418 -406.531154) (xy 276.956123 -406.5158) (xy 276.906546 -406.493161)
			(xy 276.860695 -406.463696) (xy 276.819505 -406.428006) (xy 276.783813 -406.386817) (xy 276.754347 -406.340968)
			(xy 276.731705 -406.291392) (xy 276.71635 -406.239098) (xy 276.708593 -406.185151) (xy 276.453107 -406.185151)
			(xy 276.446495 -406.230078) (xy 276.430427 -406.283485) (xy 276.406755 -406.333982) (xy 276.375982 -406.380495)
			(xy 276.338765 -406.422032) (xy 276.295897 -406.457707) (xy 276.248291 -406.486761) (xy 276.196962 -406.508573)
			(xy 276.143005 -406.522679) (xy 276.087568 -406.528779) (xy 276.031834 -406.526742) (xy 275.976991 -406.516612)
			(xy 275.924207 -406.498605) (xy 275.874607 -406.473104) (xy 275.829249 -406.440653) (xy 275.7891 -406.401944)
			(xy 275.755014 -406.357801) (xy 275.727718 -406.309166) (xy 275.707795 -406.257075) (xy 275.695669 -406.202638)
			(xy 275.691598 -406.147016) (xy 238.276892 -406.147016) (xy 238.276892 -406.551892) (xy 274.490686 -406.551892)
			(xy 274.494757 -406.49627) (xy 274.506883 -406.441833) (xy 274.526806 -406.389742) (xy 274.554102 -406.341107)
			(xy 274.588188 -406.296964) (xy 274.628337 -406.258255) (xy 274.673695 -406.225804) (xy 274.723295 -406.200303)
			(xy 274.776079 -406.182296) (xy 274.830922 -406.172166) (xy 274.886656 -406.170129) (xy 274.942093 -406.176229)
			(xy 274.99605 -406.190335) (xy 275.047379 -406.212147) (xy 275.094985 -406.241201) (xy 275.137853 -406.276876)
			(xy 275.17507 -406.318413) (xy 275.205843 -406.364926) (xy 275.229515 -406.415423) (xy 275.245583 -406.46883)
			(xy 275.253703 -406.524006) (xy 275.254212 -406.551892) (xy 275.253703 -406.579778) (xy 275.245583 -406.634954)
			(xy 275.229515 -406.688361) (xy 275.205843 -406.738858) (xy 275.17507 -406.785371) (xy 275.137853 -406.826908)
			(xy 275.094985 -406.862583) (xy 275.047379 -406.891637) (xy 274.99605 -406.913449) (xy 274.942093 -406.927555)
			(xy 274.886656 -406.933655) (xy 274.830922 -406.931618) (xy 274.776079 -406.921488) (xy 274.723295 -406.903481)
			(xy 274.673695 -406.87798) (xy 274.628337 -406.845529) (xy 274.588188 -406.80682) (xy 274.554102 -406.762677)
			(xy 274.526806 -406.714042) (xy 274.506883 -406.661951) (xy 274.494757 -406.607514) (xy 274.490686 -406.551892)
			(xy 238.276892 -406.551892) (xy 238.276892 -406.943052) (xy 278.739598 -406.943052) (xy 278.743669 -406.88743)
			(xy 278.755795 -406.832993) (xy 278.775718 -406.780902) (xy 278.803014 -406.732267) (xy 278.8371 -406.688124)
			(xy 278.877249 -406.649415) (xy 278.922607 -406.616964) (xy 278.972207 -406.591463) (xy 279.024991 -406.573456)
			(xy 279.079834 -406.563326) (xy 279.135568 -406.561289) (xy 279.191005 -406.567389) (xy 279.244962 -406.581495)
			(xy 279.296291 -406.603307) (xy 279.343897 -406.632361) (xy 279.386765 -406.668036) (xy 279.423982 -406.709573)
			(xy 279.454755 -406.756086) (xy 279.478427 -406.806583) (xy 279.494495 -406.85999) (xy 279.502615 -406.915166)
			(xy 279.503124 -406.943052) (xy 279.502615 -406.970938) (xy 279.494495 -407.026114) (xy 279.478427 -407.079521)
			(xy 279.454755 -407.130018) (xy 279.423982 -407.176531) (xy 279.386765 -407.218068) (xy 279.343897 -407.253743)
			(xy 279.296291 -407.282797) (xy 279.244962 -407.304609) (xy 279.205567 -407.314908) (xy 280.953462 -407.314908)
			(xy 280.957533 -407.259286) (xy 280.969659 -407.204849) (xy 280.989582 -407.152758) (xy 281.016878 -407.104123)
			(xy 281.050964 -407.05998) (xy 281.091113 -407.021271) (xy 281.136471 -406.98882) (xy 281.186071 -406.963319)
			(xy 281.238855 -406.945312) (xy 281.293698 -406.935182) (xy 281.349432 -406.933145) (xy 281.404869 -406.939245)
			(xy 281.458826 -406.953351) (xy 281.510155 -406.975163) (xy 281.557761 -407.004217) (xy 281.600629 -407.039892)
			(xy 281.637846 -407.081429) (xy 281.668619 -407.127942) (xy 281.692291 -407.178439) (xy 281.708359 -407.231846)
			(xy 281.716479 -407.287022) (xy 281.716988 -407.314908) (xy 281.716479 -407.342794) (xy 281.708359 -407.39797)
			(xy 281.692291 -407.451377) (xy 281.668619 -407.501874) (xy 281.637846 -407.548387) (xy 281.600629 -407.589924)
			(xy 281.557761 -407.625599) (xy 281.510155 -407.654653) (xy 281.458826 -407.676465) (xy 281.404869 -407.690571)
			(xy 281.349432 -407.696671) (xy 281.293698 -407.694634) (xy 281.238855 -407.684504) (xy 281.186071 -407.666497)
			(xy 281.136471 -407.640996) (xy 281.091113 -407.608545) (xy 281.050964 -407.569836) (xy 281.016878 -407.525693)
			(xy 280.989582 -407.477058) (xy 280.969659 -407.424967) (xy 280.957533 -407.37053) (xy 280.953462 -407.314908)
			(xy 279.205567 -407.314908) (xy 279.191005 -407.318715) (xy 279.135568 -407.324815) (xy 279.079834 -407.322778)
			(xy 279.024991 -407.312648) (xy 278.972207 -407.294641) (xy 278.922607 -407.26914) (xy 278.877249 -407.236689)
			(xy 278.8371 -407.19798) (xy 278.803014 -407.153837) (xy 278.775718 -407.105202) (xy 278.755795 -407.053111)
			(xy 278.743669 -406.998674) (xy 278.739598 -406.943052) (xy 238.276892 -406.943052) (xy 238.276892 -408.165046)
			(xy 275.975316 -408.165046) (xy 275.979387 -408.109424) (xy 275.991513 -408.054987) (xy 276.011436 -408.002896)
			(xy 276.038732 -407.954261) (xy 276.072818 -407.910118) (xy 276.112967 -407.871409) (xy 276.158325 -407.838958)
			(xy 276.207925 -407.813457) (xy 276.260709 -407.79545) (xy 276.315552 -407.78532) (xy 276.371286 -407.783283)
			(xy 276.426723 -407.789383) (xy 276.48068 -407.803489) (xy 276.532009 -407.825301) (xy 276.579615 -407.854355)
			(xy 276.622483 -407.89003) (xy 276.6597 -407.931567) (xy 276.690473 -407.97808) (xy 276.714145 -408.028577)
			(xy 276.730213 -408.081984) (xy 276.738333 -408.13716) (xy 276.738842 -408.165046) (xy 276.738333 -408.192932)
			(xy 276.730213 -408.248108) (xy 276.714145 -408.301515) (xy 276.690473 -408.352012) (xy 276.6597 -408.398525)
			(xy 276.622483 -408.440062) (xy 276.579615 -408.475737) (xy 276.532009 -408.504791) (xy 276.48068 -408.526603)
			(xy 276.426723 -408.540709) (xy 276.371286 -408.546809) (xy 276.315552 -408.544772) (xy 276.260709 -408.534642)
			(xy 276.207925 -408.516635) (xy 276.158325 -408.491134) (xy 276.112967 -408.458683) (xy 276.072818 -408.419974)
			(xy 276.038732 -408.375831) (xy 276.011436 -408.327196) (xy 275.991513 -408.275105) (xy 275.979387 -408.220668)
			(xy 275.975316 -408.165046) (xy 238.276892 -408.165046) (xy 238.276892 -410.136086) (xy 279.512266 -410.136086)
			(xy 279.516337 -410.080464) (xy 279.528463 -410.026027) (xy 279.548386 -409.973936) (xy 279.575682 -409.925301)
			(xy 279.609768 -409.881158) (xy 279.649917 -409.842449) (xy 279.695275 -409.809998) (xy 279.744875 -409.784497)
			(xy 279.797659 -409.76649) (xy 279.852502 -409.75636) (xy 279.908236 -409.754323) (xy 279.963673 -409.760423)
			(xy 280.01763 -409.774529) (xy 280.068959 -409.796341) (xy 280.116565 -409.825395) (xy 280.159433 -409.86107)
			(xy 280.19665 -409.902607) (xy 280.227423 -409.94912) (xy 280.251095 -409.999617) (xy 280.267163 -410.053024)
			(xy 280.275283 -410.1082) (xy 280.275792 -410.136086) (xy 280.275283 -410.163972) (xy 280.267163 -410.219148)
			(xy 280.251095 -410.272555) (xy 280.227423 -410.323052) (xy 280.19665 -410.369565) (xy 280.159433 -410.411102)
			(xy 280.116565 -410.446777) (xy 280.068959 -410.475831) (xy 280.01763 -410.497643) (xy 279.963673 -410.511749)
			(xy 279.908236 -410.517849) (xy 279.852502 -410.515812) (xy 279.797659 -410.505682) (xy 279.744875 -410.487675)
			(xy 279.695275 -410.462174) (xy 279.649917 -410.429723) (xy 279.609768 -410.391014) (xy 279.575682 -410.346871)
			(xy 279.548386 -410.298236) (xy 279.528463 -410.246145) (xy 279.516337 -410.191708) (xy 279.512266 -410.136086)
			(xy 238.276892 -410.136086) (xy 238.276892 -412.688278) (xy 238.276454 -412.698342) (xy 238.268719 -412.716925)
			(xy 238.261906 -412.724346) (xy 237.21314 -413.773112) (xy 275.328378 -413.773112) (xy 275.332449 -413.71749)
			(xy 275.344575 -413.663053) (xy 275.364498 -413.610962) (xy 275.391794 -413.562327) (xy 275.42588 -413.518184)
			(xy 275.466029 -413.479475) (xy 275.511387 -413.447024) (xy 275.560987 -413.421523) (xy 275.613771 -413.403516)
			(xy 275.668614 -413.393386) (xy 275.724348 -413.391349) (xy 275.779785 -413.397449) (xy 275.833742 -413.411555)
			(xy 275.885071 -413.433367) (xy 275.932677 -413.462421) (xy 275.975545 -413.498096) (xy 276.012762 -413.539633)
			(xy 276.043535 -413.586146) (xy 276.044141 -413.587438) (xy 276.501604 -413.587438) (xy 276.505675 -413.531816)
			(xy 276.517801 -413.477379) (xy 276.537724 -413.425288) (xy 276.56502 -413.376653) (xy 276.599106 -413.33251)
			(xy 276.639255 -413.293801) (xy 276.684613 -413.26135) (xy 276.734213 -413.235849) (xy 276.786997 -413.217842)
			(xy 276.84184 -413.207712) (xy 276.897574 -413.205675) (xy 276.953011 -413.211775) (xy 277.006968 -413.225881)
			(xy 277.058297 -413.247693) (xy 277.105903 -413.276747) (xy 277.148771 -413.312422) (xy 277.185988 -413.353959)
			(xy 277.216761 -413.400472) (xy 277.240433 -413.450969) (xy 277.251535 -413.48787) (xy 278.240996 -413.48787)
			(xy 278.245067 -413.432248) (xy 278.257193 -413.377811) (xy 278.277116 -413.32572) (xy 278.304412 -413.277085)
			(xy 278.338498 -413.232942) (xy 278.378647 -413.194233) (xy 278.424005 -413.161782) (xy 278.473605 -413.136281)
			(xy 278.526389 -413.118274) (xy 278.581232 -413.108144) (xy 278.636966 -413.106107) (xy 278.692403 -413.112207)
			(xy 278.74636 -413.126313) (xy 278.797689 -413.148125) (xy 278.845295 -413.177179) (xy 278.888163 -413.212854)
			(xy 278.92538 -413.254391) (xy 278.956153 -413.300904) (xy 278.979825 -413.351401) (xy 278.995893 -413.404808)
			(xy 279.004013 -413.459984) (xy 279.004522 -413.48787) (xy 279.004013 -413.515756) (xy 278.995893 -413.570932)
			(xy 278.979825 -413.624339) (xy 278.956153 -413.674836) (xy 278.92538 -413.721349) (xy 278.888163 -413.762886)
			(xy 278.845295 -413.798561) (xy 278.797689 -413.827615) (xy 278.74636 -413.849427) (xy 278.692403 -413.863533)
			(xy 278.636966 -413.869633) (xy 278.581232 -413.867596) (xy 278.526389 -413.857466) (xy 278.473605 -413.839459)
			(xy 278.424005 -413.813958) (xy 278.378647 -413.781507) (xy 278.338498 -413.742798) (xy 278.304412 -413.698655)
			(xy 278.277116 -413.65002) (xy 278.257193 -413.597929) (xy 278.245067 -413.543492) (xy 278.240996 -413.48787)
			(xy 277.251535 -413.48787) (xy 277.256501 -413.504376) (xy 277.264621 -413.559552) (xy 277.26513 -413.587438)
			(xy 277.264621 -413.615324) (xy 277.256501 -413.6705) (xy 277.240433 -413.723907) (xy 277.216761 -413.774404)
			(xy 277.185988 -413.820917) (xy 277.148771 -413.862454) (xy 277.127327 -413.8803) (xy 280.408378 -413.8803)
			(xy 280.412449 -413.824678) (xy 280.424575 -413.770241) (xy 280.444498 -413.71815) (xy 280.471794 -413.669515)
			(xy 280.50588 -413.625372) (xy 280.546029 -413.586663) (xy 280.591387 -413.554212) (xy 280.640987 -413.528711)
			(xy 280.693771 -413.510704) (xy 280.748614 -413.500574) (xy 280.804348 -413.498537) (xy 280.859785 -413.504637)
			(xy 280.913742 -413.518743) (xy 280.965071 -413.540555) (xy 281.012677 -413.569609) (xy 281.055545 -413.605284)
			(xy 281.092762 -413.646821) (xy 281.123535 -413.693334) (xy 281.147207 -413.743831) (xy 281.163275 -413.797238)
			(xy 281.171395 -413.852414) (xy 281.171904 -413.8803) (xy 281.171395 -413.908186) (xy 281.163275 -413.963362)
			(xy 281.147207 -414.016769) (xy 281.123535 -414.067266) (xy 281.092762 -414.113779) (xy 281.055545 -414.155316)
			(xy 281.012677 -414.190991) (xy 280.965071 -414.220045) (xy 280.913742 -414.241857) (xy 280.859785 -414.255963)
			(xy 280.804348 -414.262063) (xy 280.748614 -414.260026) (xy 280.693771 -414.249896) (xy 280.640987 -414.231889)
			(xy 280.591387 -414.206388) (xy 280.546029 -414.173937) (xy 280.50588 -414.135228) (xy 280.471794 -414.091085)
			(xy 280.444498 -414.04245) (xy 280.424575 -413.990359) (xy 280.412449 -413.935922) (xy 280.408378 -413.8803)
			(xy 277.127327 -413.8803) (xy 277.105903 -413.898129) (xy 277.058297 -413.927183) (xy 277.006968 -413.948995)
			(xy 276.953011 -413.963101) (xy 276.897574 -413.969201) (xy 276.84184 -413.967164) (xy 276.786997 -413.957034)
			(xy 276.734213 -413.939027) (xy 276.684613 -413.913526) (xy 276.639255 -413.881075) (xy 276.599106 -413.842366)
			(xy 276.56502 -413.798223) (xy 276.537724 -413.749588) (xy 276.517801 -413.697497) (xy 276.505675 -413.64306)
			(xy 276.501604 -413.587438) (xy 276.044141 -413.587438) (xy 276.067207 -413.636643) (xy 276.083275 -413.69005)
			(xy 276.091395 -413.745226) (xy 276.091904 -413.773112) (xy 276.091395 -413.800998) (xy 276.083275 -413.856174)
			(xy 276.067207 -413.909581) (xy 276.043535 -413.960078) (xy 276.012762 -414.006591) (xy 275.975545 -414.048128)
			(xy 275.932677 -414.083803) (xy 275.885071 -414.112857) (xy 275.833742 -414.134669) (xy 275.779785 -414.148775)
			(xy 275.724348 -414.154875) (xy 275.668614 -414.152838) (xy 275.613771 -414.142708) (xy 275.560987 -414.124701)
			(xy 275.511387 -414.0992) (xy 275.466029 -414.066749) (xy 275.42588 -414.02804) (xy 275.391794 -413.983897)
			(xy 275.364498 -413.935262) (xy 275.344575 -413.883171) (xy 275.332449 -413.828734) (xy 275.328378 -413.773112)
			(xy 237.21314 -413.773112) (xy 236.607858 -414.378394) (xy 236.600457 -414.385235) (xy 236.581859 -414.392955)
			(xy 236.57179 -414.39338) (xy 207.459072 -414.39338) (xy 207.449004 -414.392951) (xy 207.430409 -414.385227)
			(xy 207.423004 -414.378394) (xy 203.85532 -410.81071) (xy 203.84847 -410.803313) (xy 203.840728 -410.784715)
			(xy 203.840334 -410.774642) (xy 203.840334 -384.558032) (xy 203.839897 -384.547969) (xy 203.832158 -384.529388)
			(xy 203.825348 -384.521964) (xy 202.860148 -383.556764) (xy 202.85275 -383.549919) (xy 202.834151 -383.542193)
			(xy 202.82408 -383.541778) (xy 197.751954 -383.541778) (xy 197.746922 -383.541918) (xy 197.737067 -383.543965)
			(xy 197.732396 -383.545842) (xy 197.635966 -383.585721) (xy 197.440453 -383.658727) (xy 197.242196 -383.723914)
			(xy 197.041507 -383.781181) (xy 196.838703 -383.830435) (xy 196.634105 -383.8716) (xy 196.428033 -383.904611)
			(xy 196.220813 -383.929416) (xy 196.012772 -383.945976) (xy 195.804238 -383.954264) (xy 195.699888 -383.954782)
			(xy 195.699634 -383.954782) (xy 195.595296 -383.954268) (xy 195.386786 -383.945987) (xy 195.178769 -383.929433)
			(xy 194.971573 -383.904632) (xy 194.765525 -383.871623) (xy 194.56095 -383.830458) (xy 194.358172 -383.781202)
			(xy 194.157509 -383.723933) (xy 193.959279 -383.658741) (xy 193.763794 -383.585729) (xy 193.66738 -383.545842)
			(xy 193.657728 -383.541778) (xy 190.997586 -383.541778) (xy 190.987516 -383.542203) (xy 190.968914 -383.549919)
			(xy 190.961518 -383.556764) (xy 190.181992 -384.33629) (xy 190.175145 -384.343688) (xy 190.167408 -384.362286)
			(xy 190.167006 -384.372358) (xy 190.167006 -394.85189) (xy 190.167428 -394.861961) (xy 190.17514 -394.880567)
			(xy 190.181992 -394.887958) (xy 196.620638 -401.326858) (xy 196.628037 -401.333703) (xy 196.646635 -401.34143)
			(xy 196.656706 -401.341844) (xy 198.84644 -401.341844) (xy 198.872464 -401.342371) (xy 198.923868 -401.350536)
			(xy 198.973367 -401.366629) (xy 199.019745 -401.390254) (xy 199.061864 -401.420832) (xy 199.080628 -401.438872)
			(xy 200.819766 -403.17801) (xy 200.837882 -403.196789) (xy 200.868574 -403.238984) (xy 200.892281 -403.285465)
			(xy 200.908418 -403.335084) (xy 200.916587 -403.386617) (xy 200.917048 -403.412706) (xy 200.917048 -407.6319)
			(xy 200.916562 -407.657987) (xy 200.908395 -407.709518) (xy 200.892262 -407.759136) (xy 200.868562 -407.805617)
			(xy 200.837878 -407.847815) (xy 200.819766 -407.866596) (xy 199.770238 -408.916124) (xy 199.751469 -408.93416)
			(xy 199.709354 -408.964747) (xy 199.662978 -408.988381) (xy 199.61348 -409.00448) (xy 199.562075 -409.012649)
			(xy 199.53605 -409.013152) (xy 197.574154 -409.013152) (xy 197.568 -409.013319) (xy 197.556052 -409.016269)
			(xy 197.550532 -409.018994) (xy 197.523003 -409.032824) (xy 197.464589 -409.052391) (xy 197.403788 -409.062311)
			(xy 197.372986 -409.062936) (xy 197.345733 -409.062449) (xy 197.291783 -409.05469) (xy 197.239486 -409.039333)
			(xy 197.189907 -409.016689) (xy 197.144055 -408.987221) (xy 197.102864 -408.951526) (xy 197.067171 -408.910334)
			(xy 197.037704 -408.86448) (xy 197.015062 -408.814901) (xy 196.999707 -408.762603) (xy 196.99195 -408.708653)
			(xy 196.99195 -408.654147) (xy 196.999707 -408.600197) (xy 197.015062 -408.547899) (xy 197.037704 -408.49832)
			(xy 197.067171 -408.452466) (xy 197.102864 -408.411274) (xy 197.144055 -408.375579) (xy 197.189907 -408.346111)
			(xy 197.239486 -408.323467) (xy 197.291783 -408.30811) (xy 197.345733 -408.300351) (xy 197.372986 -408.29992)
			(xy 197.403788 -408.300531) (xy 197.464587 -408.310465) (xy 197.523003 -408.330031) (xy 197.550532 -408.343862)
			(xy 197.556064 -408.346554) (xy 197.568005 -408.349499) (xy 197.574154 -408.349704) (xy 199.377046 -408.349704)
			(xy 199.387113 -408.349272) (xy 199.405705 -408.341547) (xy 199.413114 -408.334718) (xy 200.238106 -407.509472)
			(xy 200.244947 -407.502072) (xy 200.252671 -407.483474) (xy 200.253092 -407.473404) (xy 200.253092 -403.571202)
			(xy 200.252669 -403.561132) (xy 200.244954 -403.542528) (xy 200.238106 -403.535134) (xy 198.95058 -402.247354)
			(xy 198.943855 -402.241216) (xy 198.927277 -402.233718) (xy 198.909126 -402.23246) (xy 198.900288 -402.234654)
			(xy 198.80072 -402.264626) (xy 198.781924 -402.2852) (xy 198.77913 -402.298916) (xy 198.7728 -402.327252)
			(xy 198.752715 -402.381727) (xy 198.724601 -402.432525) (xy 198.689109 -402.478473) (xy 198.64706 -402.518508)
			(xy 198.599427 -402.551704) (xy 198.54731 -402.577292) (xy 198.491916 -402.594682) (xy 198.434526 -402.60347)
			(xy 198.405496 -402.60397) (xy 198.374792 -402.603332) (xy 198.314183 -402.593451) (xy 198.255938 -402.573993)
			(xy 198.228458 -402.560282) (xy 198.227442 -402.559774) (xy 198.222108 -402.55698) (xy 198.210932 -402.55444)
			(xy 196.540374 -402.55444) (xy 196.514288 -402.553952) (xy 196.462759 -402.545781) (xy 196.413144 -402.529645)
			(xy 196.366666 -402.505942) (xy 196.324472 -402.475256) (xy 196.305678 -402.457158) (xy 194.358006 -400.509486)
			(xy 194.350605 -400.502803) (xy 194.332191 -400.495201) (xy 194.31227 -400.495188) (xy 194.302888 -400.498564)
			(xy 194.28841 -400.504406) (xy 194.271392 -400.53006) (xy 194.271392 -403.706076) (xy 194.271562 -403.712229)
			(xy 194.274515 -403.724176) (xy 194.277234 -403.729698) (xy 194.291071 -403.757226) (xy 194.310652 -403.815639)
			(xy 194.320584 -403.87644) (xy 194.321176 -403.907244) (xy 194.32069 -403.934495) (xy 194.312934 -403.988443)
			(xy 194.297579 -404.040738) (xy 194.274937 -404.090315) (xy 194.245471 -404.136165) (xy 194.20978 -404.177356)
			(xy 194.168589 -404.213047) (xy 194.122739 -404.242513) (xy 194.073162 -404.265155) (xy 194.020867 -404.28051)
			(xy 193.966919 -404.288266) (xy 193.912417 -404.288266) (xy 193.858469 -404.28051) (xy 193.806174 -404.265155)
			(xy 193.756597 -404.242513) (xy 193.710747 -404.213047) (xy 193.669556 -404.177356) (xy 193.633865 -404.136165)
			(xy 193.604399 -404.090315) (xy 193.581757 -404.040738) (xy 193.566402 -403.988443) (xy 193.558646 -403.934495)
			(xy 193.55816 -403.907244) (xy 193.558768 -403.876441) (xy 193.5687 -403.815641) (xy 193.588263 -403.757223)
			(xy 193.602102 -403.729698) (xy 193.604795 -403.724166) (xy 193.607745 -403.712226) (xy 193.607944 -403.706076)
			(xy 193.607944 -400.286982) (xy 193.607516 -400.276914) (xy 193.599791 -400.25832) (xy 193.592958 -400.250914)
			(xy 193.408046 -400.066256) (xy 193.400646 -400.059576) (xy 193.382236 -400.051984) (xy 193.362321 -400.051993)
			(xy 193.352928 -400.055334) (xy 193.343795 -400.059542) (xy 193.329558 -400.07372) (xy 193.321855 -400.092277)
			(xy 193.321432 -400.102324) (xy 193.321432 -403.878288) (xy 193.321604 -403.884441) (xy 193.324561 -403.896385)
			(xy 193.327274 -403.90191) (xy 193.341109 -403.929438) (xy 193.360686 -403.987851) (xy 193.370616 -404.048653)
			(xy 193.371216 -404.079456) (xy 193.37073 -404.106707) (xy 193.362974 -404.160655) (xy 193.347619 -404.21295)
			(xy 193.324977 -404.262527) (xy 193.295511 -404.308377) (xy 193.25982 -404.349568) (xy 193.218629 -404.385259)
			(xy 193.172779 -404.414725) (xy 193.123202 -404.437367) (xy 193.070907 -404.452722) (xy 193.016959 -404.460478)
			(xy 192.962457 -404.460478) (xy 192.908509 -404.452722) (xy 192.856214 -404.437367) (xy 192.806637 -404.414725)
			(xy 192.760787 -404.385259) (xy 192.719596 -404.349568) (xy 192.683905 -404.308377) (xy 192.654439 -404.262527)
			(xy 192.631797 -404.21295) (xy 192.616442 -404.160655) (xy 192.608686 -404.106707) (xy 192.6082 -404.079456)
			(xy 192.608808 -404.048653) (xy 192.618738 -403.987852) (xy 192.638302 -403.929435) (xy 192.652142 -403.90191)
			(xy 192.654835 -403.896378) (xy 192.657785 -403.884437) (xy 192.657984 -403.878288) (xy 192.657984 -399.844006)
			(xy 192.657562 -399.833936) (xy 192.649847 -399.815331) (xy 192.642998 -399.807938) (xy 189.258194 -396.423388)
			(xy 189.250799 -396.416533) (xy 189.2322 -396.408787) (xy 189.222126 -396.408402) (xy 188.16066 -396.408402)
			(xy 188.142118 -396.400782) (xy 188.138308 -396.396972) (xy 187.196476 -396.396972) (xy 187.186469 -396.397464)
			(xy 187.167981 -396.405127) (xy 187.153829 -396.419278) (xy 187.146164 -396.437765) (xy 187.145676 -396.447772)
			(xy 187.145676 -401.65909) (xy 189.391542 -401.65909) (xy 189.395613 -401.603468) (xy 189.407739 -401.549031)
			(xy 189.427662 -401.49694) (xy 189.454958 -401.448305) (xy 189.489044 -401.404162) (xy 189.529193 -401.365453)
			(xy 189.574551 -401.333002) (xy 189.624151 -401.307501) (xy 189.676935 -401.289494) (xy 189.731778 -401.279364)
			(xy 189.787512 -401.277327) (xy 189.842949 -401.283427) (xy 189.896906 -401.297533) (xy 189.948235 -401.319345)
			(xy 189.995841 -401.348399) (xy 190.038709 -401.384074) (xy 190.075926 -401.425611) (xy 190.106699 -401.472124)
			(xy 190.130371 -401.522621) (xy 190.13215 -401.528534) (xy 191.43548 -401.528534) (xy 191.439551 -401.472912)
			(xy 191.451677 -401.418475) (xy 191.4716 -401.366384) (xy 191.498896 -401.317749) (xy 191.532982 -401.273606)
			(xy 191.573131 -401.234897) (xy 191.618489 -401.202446) (xy 191.668089 -401.176945) (xy 191.720873 -401.158938)
			(xy 191.775716 -401.148808) (xy 191.83145 -401.146771) (xy 191.886887 -401.152871) (xy 191.940844 -401.166977)
			(xy 191.992173 -401.188789) (xy 192.039779 -401.217843) (xy 192.082647 -401.253518) (xy 192.119864 -401.295055)
			(xy 192.150637 -401.341568) (xy 192.174309 -401.392065) (xy 192.190377 -401.445472) (xy 192.198497 -401.500648)
			(xy 192.199006 -401.528534) (xy 192.198497 -401.55642) (xy 192.190377 -401.611596) (xy 192.174309 -401.665003)
			(xy 192.150637 -401.7155) (xy 192.119864 -401.762013) (xy 192.082647 -401.80355) (xy 192.039779 -401.839225)
			(xy 191.992173 -401.868279) (xy 191.940844 -401.890091) (xy 191.886887 -401.904197) (xy 191.83145 -401.910297)
			(xy 191.775716 -401.90826) (xy 191.720873 -401.89813) (xy 191.668089 -401.880123) (xy 191.618489 -401.854622)
			(xy 191.573131 -401.822171) (xy 191.532982 -401.783462) (xy 191.498896 -401.739319) (xy 191.4716 -401.690684)
			(xy 191.451677 -401.638593) (xy 191.439551 -401.584156) (xy 191.43548 -401.528534) (xy 190.13215 -401.528534)
			(xy 190.146439 -401.576028) (xy 190.154559 -401.631204) (xy 190.155068 -401.65909) (xy 190.154559 -401.686976)
			(xy 190.146439 -401.742152) (xy 190.130371 -401.795559) (xy 190.106699 -401.846056) (xy 190.075926 -401.892569)
			(xy 190.038709 -401.934106) (xy 189.995841 -401.969781) (xy 189.948235 -401.998835) (xy 189.896906 -402.020647)
			(xy 189.842949 -402.034753) (xy 189.787512 -402.040853) (xy 189.731778 -402.038816) (xy 189.676935 -402.028686)
			(xy 189.624151 -402.010679) (xy 189.574551 -401.985178) (xy 189.529193 -401.952727) (xy 189.489044 -401.914018)
			(xy 189.454958 -401.869875) (xy 189.427662 -401.82124) (xy 189.407739 -401.769149) (xy 189.395613 -401.714712)
			(xy 189.391542 -401.65909) (xy 187.145676 -401.65909) (xy 187.145676 -402.352256) (xy 187.146109 -402.362322)
			(xy 187.153835 -402.380914) (xy 187.160662 -402.388324) (xy 188.763797 -403.991318) (xy 190.063626 -403.991318)
			(xy 190.067697 -403.935696) (xy 190.079823 -403.881259) (xy 190.099746 -403.829168) (xy 190.127042 -403.780533)
			(xy 190.161128 -403.73639) (xy 190.201277 -403.697681) (xy 190.246635 -403.66523) (xy 190.296235 -403.639729)
			(xy 190.349019 -403.621722) (xy 190.403862 -403.611592) (xy 190.459596 -403.609555) (xy 190.515033 -403.615655)
			(xy 190.56899 -403.629761) (xy 190.620319 -403.651573) (xy 190.667925 -403.680627) (xy 190.710793 -403.716302)
			(xy 190.74801 -403.757839) (xy 190.778783 -403.804352) (xy 190.802455 -403.854849) (xy 190.818523 -403.908256)
			(xy 190.826643 -403.963432) (xy 190.827152 -403.991318) (xy 190.826643 -404.019204) (xy 190.818523 -404.07438)
			(xy 190.802455 -404.127787) (xy 190.778783 -404.178284) (xy 190.74801 -404.224797) (xy 190.710793 -404.266334)
			(xy 190.667925 -404.302009) (xy 190.620319 -404.331063) (xy 190.56899 -404.352875) (xy 190.515033 -404.366981)
			(xy 190.459596 -404.373081) (xy 190.403862 -404.371044) (xy 190.349019 -404.360914) (xy 190.296235 -404.342907)
			(xy 190.246635 -404.317406) (xy 190.201277 -404.284955) (xy 190.161128 -404.246246) (xy 190.127042 -404.202103)
			(xy 190.099746 -404.153468) (xy 190.079823 -404.101377) (xy 190.067697 -404.04694) (xy 190.063626 -403.991318)
			(xy 188.763797 -403.991318) (xy 189.9671 -405.194516) (xy 198.019922 -405.194516) (xy 198.023993 -405.138894)
			(xy 198.036119 -405.084457) (xy 198.056042 -405.032366) (xy 198.083338 -404.983731) (xy 198.117424 -404.939588)
			(xy 198.157573 -404.900879) (xy 198.202931 -404.868428) (xy 198.252531 -404.842927) (xy 198.305315 -404.82492)
			(xy 198.360158 -404.81479) (xy 198.415892 -404.812753) (xy 198.471329 -404.818853) (xy 198.525286 -404.832959)
			(xy 198.576615 -404.854771) (xy 198.624221 -404.883825) (xy 198.667089 -404.9195) (xy 198.704306 -404.961037)
			(xy 198.735079 -405.00755) (xy 198.758751 -405.058047) (xy 198.774819 -405.111454) (xy 198.782939 -405.16663)
			(xy 198.783448 -405.194516) (xy 198.782939 -405.222402) (xy 198.774819 -405.277578) (xy 198.758751 -405.330985)
			(xy 198.735079 -405.381482) (xy 198.704306 -405.427995) (xy 198.667089 -405.469532) (xy 198.624221 -405.505207)
			(xy 198.576615 -405.534261) (xy 198.525286 -405.556073) (xy 198.471329 -405.570179) (xy 198.415892 -405.576279)
			(xy 198.360158 -405.574242) (xy 198.305315 -405.564112) (xy 198.252531 -405.546105) (xy 198.202931 -405.520604)
			(xy 198.157573 -405.488153) (xy 198.117424 -405.449444) (xy 198.083338 -405.405301) (xy 198.056042 -405.356666)
			(xy 198.036119 -405.304575) (xy 198.023993 -405.250138) (xy 198.019922 -405.194516) (xy 189.9671 -405.194516)
			(xy 190.057786 -405.285194) (xy 190.065189 -405.292027) (xy 190.083787 -405.299731) (xy 190.093854 -405.30018)
			(xy 196.743574 -405.30018) (xy 196.769662 -405.300664) (xy 196.821195 -405.308828) (xy 196.870814 -405.324959)
			(xy 196.917297 -405.348658) (xy 196.959496 -405.379342) (xy 196.97827 -405.397462) (xy 197.745096 -406.164542)
			(xy 197.752491 -406.171395) (xy 197.77109 -406.179141) (xy 197.781164 -406.179528) (xy 198.946516 -406.179528)
			(xy 198.952667 -406.179353) (xy 198.964608 -406.176387) (xy 198.970138 -406.173686) (xy 198.997666 -406.159851)
			(xy 199.05608 -406.140275) (xy 199.116881 -406.130349) (xy 199.147684 -406.129744) (xy 199.174941 -406.130206)
			(xy 199.228901 -406.137962) (xy 199.281207 -406.153319) (xy 199.330795 -406.175963) (xy 199.376656 -406.205434)
			(xy 199.417856 -406.241133) (xy 199.453556 -406.282331) (xy 199.483029 -406.328191) (xy 199.505676 -406.377778)
			(xy 199.521035 -406.430084) (xy 199.528793 -406.484043) (xy 199.528793 -406.538557) (xy 199.521035 -406.592516)
			(xy 199.505676 -406.644822) (xy 199.483029 -406.694409) (xy 199.453556 -406.740269) (xy 199.417856 -406.781467)
			(xy 199.376656 -406.817166) (xy 199.330795 -406.846637) (xy 199.281207 -406.869281) (xy 199.228901 -406.884638)
			(xy 199.174941 -406.892394) (xy 199.147684 -406.89276) (xy 199.116882 -406.892147) (xy 199.056085 -406.882207)
			(xy 198.997673 -406.862637) (xy 198.970138 -406.848818) (xy 198.964607 -406.846119) (xy 198.952667 -406.843159)
			(xy 198.946516 -406.842976) (xy 197.62216 -406.842976) (xy 197.596136 -406.842449) (xy 197.544731 -406.834284)
			(xy 197.495232 -406.818192) (xy 197.448853 -406.794568) (xy 197.406732 -406.763991) (xy 197.387972 -406.745948)
			(xy 196.621146 -405.979122) (xy 196.613745 -405.972282) (xy 196.595147 -405.964564) (xy 196.585078 -405.964136)
			(xy 190.274956 -405.964136) (xy 190.264956 -405.964624) (xy 190.246466 -405.97225) (xy 190.232269 -405.986339)
			(xy 190.227966 -405.995378) (xy 190.222124 -406.009602) (xy 190.227966 -406.039574) (xy 193.149474 -408.961082)
			(xy 194.781676 -408.961082) (xy 194.785747 -408.90546) (xy 194.797873 -408.851023) (xy 194.817796 -408.798932)
			(xy 194.845092 -408.750297) (xy 194.879178 -408.706154) (xy 194.919327 -408.667445) (xy 194.964685 -408.634994)
			(xy 195.014285 -408.609493) (xy 195.067069 -408.591486) (xy 195.121912 -408.581356) (xy 195.177646 -408.579319)
			(xy 195.233083 -408.585419) (xy 195.28704 -408.599525) (xy 195.338369 -408.621337) (xy 195.385975 -408.650391)
			(xy 195.428843 -408.686066) (xy 195.46606 -408.727603) (xy 195.496833 -408.774116) (xy 195.520505 -408.824613)
			(xy 195.536573 -408.87802) (xy 195.544693 -408.933196) (xy 195.545202 -408.961082) (xy 195.544693 -408.988968)
			(xy 195.536573 -409.044144) (xy 195.520505 -409.097551) (xy 195.496833 -409.148048) (xy 195.46606 -409.194561)
			(xy 195.428843 -409.236098) (xy 195.385975 -409.271773) (xy 195.338369 -409.300827) (xy 195.28704 -409.322639)
			(xy 195.233083 -409.336745) (xy 195.177646 -409.342845) (xy 195.121912 -409.340808) (xy 195.067069 -409.330678)
			(xy 195.014285 -409.312671) (xy 194.964685 -409.28717) (xy 194.919327 -409.254719) (xy 194.879178 -409.21601)
			(xy 194.845092 -409.171867) (xy 194.817796 -409.123232) (xy 194.797873 -409.071141) (xy 194.785747 -409.016704)
			(xy 194.781676 -408.961082) (xy 193.149474 -408.961082) (xy 194.538346 -410.349954) (xy 194.545745 -410.356798)
			(xy 194.564343 -410.364523) (xy 194.574414 -410.36494) (xy 195.730622 -410.36494) (xy 195.736491 -410.364792)
			(xy 195.747915 -410.362102) (xy 195.753228 -410.359606) (xy 195.753736 -410.359352) (xy 195.781264 -410.345518)
			(xy 195.839678 -410.325944) (xy 195.900479 -410.316018) (xy 195.931282 -410.31541) (xy 195.958534 -410.315872)
			(xy 196.012485 -410.323627) (xy 196.064782 -410.33898) (xy 196.114362 -410.361621) (xy 196.160216 -410.391087)
			(xy 196.201408 -410.426779) (xy 196.237102 -410.46797) (xy 196.266571 -410.513822) (xy 196.289213 -410.563401)
			(xy 196.30457 -410.615698) (xy 196.312327 -410.669648) (xy 196.312327 -410.724152) (xy 196.30457 -410.778102)
			(xy 196.289213 -410.830399) (xy 196.266571 -410.879978) (xy 196.237102 -410.92583) (xy 196.201408 -410.967021)
			(xy 196.160216 -411.002713) (xy 196.114362 -411.032179) (xy 196.064782 -411.05482) (xy 196.012485 -411.070173)
			(xy 195.958534 -411.077928) (xy 195.931282 -411.078426) (xy 195.900578 -411.077786) (xy 195.839971 -411.067902)
			(xy 195.781728 -411.048441) (xy 195.754244 -411.034738) (xy 195.753228 -411.03423) (xy 195.747894 -411.031436)
			(xy 195.736718 -411.028896) (xy 194.415918 -411.028896) (xy 194.38983 -411.028411) (xy 194.338296 -411.020248)
			(xy 194.288675 -411.004119) (xy 194.24219 -410.980423) (xy 194.199987 -410.949743) (xy 194.181222 -410.931614)
			(xy 188.82741 -405.577802) (xy 188.820047 -405.570977) (xy 188.801537 -405.56324) (xy 188.781475 -405.563198)
			(xy 188.772038 -405.566626) (xy 188.757814 -405.572468) (xy 188.740796 -405.597868) (xy 188.740796 -408.592274)
			(xy 190.042798 -408.592274) (xy 190.046869 -408.536652) (xy 190.058995 -408.482215) (xy 190.078918 -408.430124)
			(xy 190.106214 -408.381489) (xy 190.1403 -408.337346) (xy 190.180449 -408.298637) (xy 190.225807 -408.266186)
			(xy 190.275407 -408.240685) (xy 190.328191 -408.222678) (xy 190.383034 -408.212548) (xy 190.438768 -408.210511)
			(xy 190.494205 -408.216611) (xy 190.548162 -408.230717) (xy 190.599491 -408.252529) (xy 190.647097 -408.281583)
			(xy 190.689965 -408.317258) (xy 190.727182 -408.358795) (xy 190.757955 -408.405308) (xy 190.781627 -408.455805)
			(xy 190.797695 -408.509212) (xy 190.805815 -408.564388) (xy 190.806324 -408.592274) (xy 190.805815 -408.62016)
			(xy 190.797695 -408.675336) (xy 190.781627 -408.728743) (xy 190.757955 -408.77924) (xy 190.727182 -408.825753)
			(xy 190.689965 -408.86729) (xy 190.647097 -408.902965) (xy 190.599491 -408.932019) (xy 190.548162 -408.953831)
			(xy 190.494205 -408.967937) (xy 190.438768 -408.974037) (xy 190.383034 -408.972) (xy 190.328191 -408.96187)
			(xy 190.275407 -408.943863) (xy 190.225807 -408.918362) (xy 190.180449 -408.885911) (xy 190.1403 -408.847202)
			(xy 190.106214 -408.803059) (xy 190.078918 -408.754424) (xy 190.058995 -408.702333) (xy 190.046869 -408.647896)
			(xy 190.042798 -408.592274) (xy 188.740796 -408.592274) (xy 188.740796 -409.896818) (xy 191.732914 -409.896818)
			(xy 191.736985 -409.841196) (xy 191.749111 -409.786759) (xy 191.769034 -409.734668) (xy 191.79633 -409.686033)
			(xy 191.830416 -409.64189) (xy 191.870565 -409.603181) (xy 191.915923 -409.57073) (xy 191.965523 -409.545229)
			(xy 192.018307 -409.527222) (xy 192.07315 -409.517092) (xy 192.128884 -409.515055) (xy 192.184321 -409.521155)
			(xy 192.238278 -409.535261) (xy 192.289607 -409.557073) (xy 192.337213 -409.586127) (xy 192.380081 -409.621802)
			(xy 192.417298 -409.663339) (xy 192.448071 -409.709852) (xy 192.471743 -409.760349) (xy 192.487811 -409.813756)
			(xy 192.495931 -409.868932) (xy 192.49644 -409.896818) (xy 192.495931 -409.924704) (xy 192.487811 -409.97988)
			(xy 192.471743 -410.033287) (xy 192.448071 -410.083784) (xy 192.417298 -410.130297) (xy 192.380081 -410.171834)
			(xy 192.337213 -410.207509) (xy 192.289607 -410.236563) (xy 192.238278 -410.258375) (xy 192.184321 -410.272481)
			(xy 192.128884 -410.278581) (xy 192.07315 -410.276544) (xy 192.018307 -410.266414) (xy 191.965523 -410.248407)
			(xy 191.915923 -410.222906) (xy 191.870565 -410.190455) (xy 191.830416 -410.151746) (xy 191.79633 -410.107603)
			(xy 191.769034 -410.058968) (xy 191.749111 -410.006877) (xy 191.736985 -409.95244) (xy 191.732914 -409.896818)
			(xy 188.740796 -409.896818) (xy 188.740796 -410.585412) (xy 188.741283 -410.595785) (xy 188.749463 -410.614852)
			(xy 188.764494 -410.629152) (xy 188.77407 -410.633164) (xy 188.863478 -410.666184) (xy 188.873352 -410.6693)
			(xy 188.894008 -410.668197) (xy 188.912547 -410.659021) (xy 188.919612 -410.651452) (xy 188.919866 -410.651198)
			(xy 188.938082 -410.630492) (xy 188.979454 -410.594026) (xy 189.025644 -410.563895) (xy 189.07569 -410.540726)
			(xy 189.128549 -410.525001) (xy 189.183122 -410.517049) (xy 189.210696 -410.516578) (xy 189.23795 -410.517041)
			(xy 189.291903 -410.524797) (xy 189.344204 -410.540154) (xy 189.393786 -410.562797) (xy 189.439642 -410.592266)
			(xy 189.480836 -410.627961) (xy 189.516532 -410.669155) (xy 189.546001 -410.71501) (xy 189.568645 -410.764592)
			(xy 189.584002 -410.816893) (xy 189.591759 -410.870846) (xy 189.591759 -410.925354) (xy 189.584002 -410.979307)
			(xy 189.568645 -411.031608) (xy 189.546001 -411.08119) (xy 189.516532 -411.127045) (xy 189.480836 -411.168239)
			(xy 189.439642 -411.203934) (xy 189.393786 -411.233403) (xy 189.344204 -411.256046) (xy 189.291903 -411.271403)
			(xy 189.23795 -411.279159) (xy 189.210696 -411.279594) (xy 189.182613 -411.279103) (xy 189.127052 -411.270884)
			(xy 189.073297 -411.25461) (xy 189.022507 -411.230631) (xy 188.975781 -411.199467) (xy 188.934127 -411.161791)
			(xy 188.898447 -411.118415) (xy 188.869509 -411.070278) (xy 188.847941 -411.018419) (xy 188.840618 -410.991304)
			(xy 188.840618 -410.99105) (xy 188.837281 -410.980283) (xy 188.822966 -410.962908) (xy 188.802599 -410.953313)
			(xy 188.791342 -410.952696) (xy 188.770514 -410.952696) (xy 188.740796 -410.982414) (xy 188.740796 -411.086808)
			(xy 188.740309 -411.112895) (xy 188.732142 -411.164427) (xy 188.716011 -411.214045) (xy 188.692312 -411.260527)
			(xy 188.661631 -411.302727) (xy 188.64572 -411.319218) (xy 193.336416 -411.319218) (xy 193.340487 -411.263596)
			(xy 193.352613 -411.209159) (xy 193.372536 -411.157068) (xy 193.399832 -411.108433) (xy 193.433918 -411.06429)
			(xy 193.474067 -411.025581) (xy 193.519425 -410.99313) (xy 193.569025 -410.967629) (xy 193.621809 -410.949622)
			(xy 193.676652 -410.939492) (xy 193.732386 -410.937455) (xy 193.787823 -410.943555) (xy 193.84178 -410.957661)
			(xy 193.893109 -410.979473) (xy 193.940715 -411.008527) (xy 193.983583 -411.044202) (xy 194.0208 -411.085739)
			(xy 194.051573 -411.132252) (xy 194.075245 -411.182749) (xy 194.091313 -411.236156) (xy 194.099433 -411.291332)
			(xy 194.099942 -411.319218) (xy 194.099812 -411.32633) (xy 197.241412 -411.32633) (xy 197.245483 -411.270708)
			(xy 197.257609 -411.216271) (xy 197.277532 -411.16418) (xy 197.304828 -411.115545) (xy 197.338914 -411.071402)
			(xy 197.379063 -411.032693) (xy 197.424421 -411.000242) (xy 197.474021 -410.974741) (xy 197.526805 -410.956734)
			(xy 197.581648 -410.946604) (xy 197.637382 -410.944567) (xy 197.692819 -410.950667) (xy 197.746776 -410.964773)
			(xy 197.798105 -410.986585) (xy 197.845711 -411.015639) (xy 197.888579 -411.051314) (xy 197.925796 -411.092851)
			(xy 197.956569 -411.139364) (xy 197.980241 -411.189861) (xy 197.996309 -411.243268) (xy 198.004429 -411.298444)
			(xy 198.004938 -411.32633) (xy 198.004429 -411.354216) (xy 197.996309 -411.409392) (xy 197.980241 -411.462799)
			(xy 197.956569 -411.513296) (xy 197.925796 -411.559809) (xy 197.888579 -411.601346) (xy 197.845711 -411.637021)
			(xy 197.798105 -411.666075) (xy 197.746776 -411.687887) (xy 197.692819 -411.701993) (xy 197.637382 -411.708093)
			(xy 197.581648 -411.706056) (xy 197.526805 -411.695926) (xy 197.474021 -411.677919) (xy 197.424421 -411.652418)
			(xy 197.379063 -411.619967) (xy 197.338914 -411.581258) (xy 197.304828 -411.537115) (xy 197.277532 -411.48848)
			(xy 197.257609 -411.436389) (xy 197.245483 -411.381952) (xy 197.241412 -411.32633) (xy 194.099812 -411.32633)
			(xy 194.099433 -411.347104) (xy 194.091313 -411.40228) (xy 194.075245 -411.455687) (xy 194.051573 -411.506184)
			(xy 194.0208 -411.552697) (xy 193.983583 -411.594234) (xy 193.940715 -411.629909) (xy 193.893109 -411.658963)
			(xy 193.84178 -411.680775) (xy 193.787823 -411.694881) (xy 193.732386 -411.700981) (xy 193.676652 -411.698944)
			(xy 193.621809 -411.688814) (xy 193.569025 -411.670807) (xy 193.519425 -411.645306) (xy 193.474067 -411.612855)
			(xy 193.433918 -411.574146) (xy 193.399832 -411.530003) (xy 193.372536 -411.481368) (xy 193.352613 -411.429277)
			(xy 193.340487 -411.37484) (xy 193.336416 -411.319218) (xy 188.64572 -411.319218) (xy 188.643514 -411.321504)
			(xy 188.495686 -411.469332) (xy 188.4899 -411.475512) (xy 188.482419 -411.490689) (xy 188.480275 -411.507473)
			(xy 188.481716 -411.515814) (xy 188.502036 -411.611826) (xy 188.518546 -411.631384) (xy 188.530738 -411.635956)
			(xy 188.557295 -411.646777) (xy 188.607082 -411.67523) (xy 188.652049 -411.710816) (xy 188.691182 -411.752733)
			(xy 188.723599 -411.800035) (xy 188.748569 -411.851658) (xy 188.765529 -411.906437) (xy 188.774098 -411.963138)
			(xy 188.774578 -411.99181) (xy 188.774114 -412.019062) (xy 188.766356 -412.07301) (xy 188.750998 -412.125305)
			(xy 188.728355 -412.174882) (xy 188.698886 -412.220731) (xy 188.663192 -412.26192) (xy 188.621999 -412.29761)
			(xy 188.576147 -412.327074) (xy 188.526567 -412.349712) (xy 188.474271 -412.365064) (xy 188.420322 -412.372817)
			(xy 188.39307 -412.373318) (xy 188.364401 -412.3728) (xy 188.30771 -412.364218) (xy 188.252941 -412.347251)
			(xy 188.201326 -412.322281) (xy 188.154028 -412.289871) (xy 188.112111 -412.250749) (xy 188.076518 -412.205797)
			(xy 188.048052 -412.156025) (xy 188.037216 -412.129478) (xy 188.032644 -412.117286) (xy 188.013086 -412.100776)
			(xy 187.917074 -412.080456) (xy 187.908732 -412.079033) (xy 187.891953 -412.081167) (xy 187.876789 -412.08866)
			(xy 187.870592 -412.094426) (xy 186.938412 -413.026606) (xy 186.919633 -413.044722) (xy 186.877437 -413.075413)
			(xy 186.830956 -413.09912) (xy 186.781338 -413.115258) (xy 186.729804 -413.123429) (xy 186.703716 -413.123888)
			(xy 185.51906 -413.123888) (xy 185.513192 -413.124038) (xy 185.50177 -413.126733) (xy 185.496454 -413.129222)
			(xy 185.495946 -413.129476) (xy 185.468417 -413.143307) (xy 185.410003 -413.162878) (xy 185.349202 -413.1728)
			(xy 185.3184 -413.173418) (xy 185.291148 -413.172932) (xy 185.237199 -413.165175) (xy 185.184903 -413.14982)
			(xy 185.135324 -413.127178) (xy 185.089473 -413.097711) (xy 185.048281 -413.062019) (xy 185.012589 -413.020827)
			(xy 184.983122 -412.974976) (xy 184.96048 -412.925397) (xy 184.945125 -412.873101) (xy 184.937368 -412.819152)
			(xy 184.937368 -412.764648) (xy 184.945125 -412.710699) (xy 184.96048 -412.658403) (xy 184.983122 -412.608824)
			(xy 185.012589 -412.562973) (xy 185.048281 -412.521781) (xy 185.089473 -412.486089) (xy 185.135324 -412.456622)
			(xy 185.184903 -412.43398) (xy 185.237199 -412.418625) (xy 185.291148 -412.410868) (xy 185.3184 -412.410402)
			(xy 185.349104 -412.411041) (xy 185.409712 -412.420923) (xy 185.467956 -412.440383) (xy 185.495438 -412.45409)
			(xy 185.496454 -412.454598) (xy 185.501788 -412.457392) (xy 185.512964 -412.459932) (xy 186.54522 -412.459932)
			(xy 186.555289 -412.459506) (xy 186.573891 -412.45179) (xy 186.581288 -412.444946) (xy 188.061854 -410.96438)
			(xy 188.068702 -410.956983) (xy 188.076437 -410.938384) (xy 188.07684 -410.928312) (xy 188.07684 -406.214072)
			(xy 188.076423 -406.204192) (xy 188.069019 -406.185877) (xy 188.055215 -406.171746) (xy 188.04636 -406.167336)
			(xy 187.9473 -406.123902) (xy 187.917836 -406.128728) (xy 187.90666 -406.139142) (xy 187.885435 -406.157903)
			(xy 187.838482 -406.189595) (xy 187.787362 -406.214) (xy 187.733195 -406.230581) (xy 187.677173 -406.238975)
			(xy 187.64885 -406.239472) (xy 187.621604 -406.238982) (xy 187.567667 -406.231221) (xy 187.515383 -406.215863)
			(xy 187.465817 -406.193221) (xy 187.419977 -406.163756) (xy 187.378796 -406.128068) (xy 187.343114 -406.086883)
			(xy 187.313655 -406.041039) (xy 187.29102 -405.99147) (xy 187.275669 -405.939185) (xy 187.267914 -405.885246)
			(xy 187.267914 -405.830754) (xy 187.275669 -405.776815) (xy 187.29102 -405.72453) (xy 187.313655 -405.674961)
			(xy 187.343114 -405.629117) (xy 187.378797 -405.587932) (xy 187.419977 -405.552244) (xy 187.465817 -405.522779)
			(xy 187.515383 -405.500137) (xy 187.567667 -405.484779) (xy 187.621604 -405.477018) (xy 187.64885 -405.476456)
			(xy 187.67778 -405.476987) (xy 187.734976 -405.485716) (xy 187.7902 -405.50298) (xy 187.842183 -405.528385)
			(xy 187.889735 -405.561347) (xy 187.931765 -405.601111) (xy 187.967309 -405.646765) (xy 187.981844 -405.671782)
			(xy 187.988448 -405.68372) (xy 188.012324 -405.69769) (xy 188.02604 -405.69769) (xy 188.036042 -405.697195)
			(xy 188.054518 -405.689528) (xy 188.068656 -405.675376) (xy 188.076305 -405.656892) (xy 188.07684 -405.64689)
			(xy 188.07684 -405.508714) (xy 188.0764 -405.498652) (xy 188.068656 -405.480076) (xy 188.061854 -405.472646)
			(xy 185.862976 -403.273768) (xy 185.844945 -403.254997) (xy 185.814366 -403.212881) (xy 185.790742 -403.166504)
			(xy 185.774654 -403.117006) (xy 185.766495 -403.065603) (xy 185.765948 -403.03958) (xy 185.765948 -396.447772)
			(xy 185.765456 -396.437765) (xy 185.757793 -396.419274) (xy 185.743643 -396.405118) (xy 185.725155 -396.397448)
			(xy 185.715148 -396.396972) (xy 185.681874 -396.396972) (xy 185.671858 -396.396547) (xy 185.653355 -396.388872)
			(xy 185.639198 -396.3747) (xy 185.631542 -396.356188) (xy 185.631074 -396.346172) (xy 185.631074 -376.449844)
			(xy 185.631507 -376.439778) (xy 185.639232 -376.421186) (xy 185.64606 -376.413776) (xy 185.750962 -376.308874)
			(xy 185.757809 -376.301476) (xy 185.76554 -376.282877) (xy 185.765948 -376.272806) (xy 185.765948 -375.60631)
			(xy 185.766478 -375.580288) (xy 185.774651 -375.528887) (xy 185.790749 -375.479394) (xy 185.814379 -375.433022)
			(xy 185.844961 -375.390908) (xy 185.862976 -375.372122) (xy 188.875162 -372.36019) (xy 188.882011 -372.352793)
			(xy 188.889748 -372.334194) (xy 188.890148 -372.324122) (xy 188.890148 -368.44859) (xy 188.889671 -368.438624)
			(xy 188.882092 -368.42019) (xy 188.875416 -368.412776) (xy 188.824616 -368.361722) (xy 188.817214 -368.354886)
			(xy 188.798615 -368.347179) (xy 188.788548 -368.346736) (xy 183.371998 -368.346736) (xy 183.361838 -368.347752)
			(xy 180.21808 -368.983514) (xy 180.195728 -369.009168) (xy 180.194458 -369.026186) (xy 180.191749 -369.056365)
			(xy 180.179776 -369.115763) (xy 180.160505 -369.17321) (xy 180.134237 -369.227813) (xy 180.101379 -369.278724)
			(xy 180.062443 -369.325151) (xy 180.018033 -369.366373) (xy 179.968839 -369.401749) (xy 179.915627 -369.430731)
			(xy 179.859221 -369.452866) (xy 179.800501 -369.467812) (xy 179.740377 -369.475336) (xy 179.71008 -369.475766)
			(xy 179.68046 -369.475329) (xy 179.621659 -369.468135) (xy 179.564169 -369.453843) (xy 179.508843 -369.432666)
			(xy 179.456504 -369.404918) (xy 179.407927 -369.371011) (xy 179.363835 -369.331448) (xy 179.324881 -369.286817)
			(xy 179.291643 -369.23778) (xy 179.277772 -369.211606) (xy 179.269898 -369.196366) (xy 179.239418 -369.181634)
			(xy 178.32705 -369.366292) (xy 178.315728 -369.369188) (xy 178.29725 -369.383454) (xy 178.286951 -369.404404)
			(xy 178.28641 -369.416076) (xy 178.28641 -371.590062) (xy 179.223932 -371.590062) (xy 179.227923 -371.527895)
			(xy 179.239832 -371.466748) (xy 179.259461 -371.407627) (xy 179.28649 -371.351501) (xy 179.320474 -371.299292)
			(xy 179.360856 -371.251857) (xy 179.406972 -371.209976) (xy 179.458064 -371.174336) (xy 179.513295 -371.145522)
			(xy 179.571757 -371.124008) (xy 179.632491 -371.110146) (xy 179.694498 -371.104164) (xy 179.756761 -371.10616)
			(xy 179.818258 -371.116103) (xy 179.877979 -371.133827) (xy 179.934942 -371.159044) (xy 179.988213 -371.191337)
			(xy 180.036918 -371.230177) (xy 180.080255 -371.274927) (xy 180.117515 -371.324851) (xy 180.148084 -371.37913)
			(xy 180.171462 -371.436873) (xy 180.187263 -371.497131) (xy 180.195229 -371.558914) (xy 180.195728 -371.590062)
			(xy 180.195229 -371.62121) (xy 180.187263 -371.682993) (xy 180.171462 -371.743251) (xy 180.148084 -371.800994)
			(xy 180.117515 -371.855273) (xy 180.080255 -371.905197) (xy 180.036918 -371.949947) (xy 179.988213 -371.988787)
			(xy 179.934942 -372.02108) (xy 179.877979 -372.046297) (xy 179.818258 -372.064021) (xy 179.756761 -372.073964)
			(xy 179.694498 -372.07596) (xy 179.632491 -372.069978) (xy 179.571757 -372.056116) (xy 179.513295 -372.034602)
			(xy 179.458064 -372.005788) (xy 179.406972 -371.970148) (xy 179.360856 -371.928267) (xy 179.320474 -371.880832)
			(xy 179.28649 -371.828623) (xy 179.259461 -371.772497) (xy 179.239832 -371.713376) (xy 179.227923 -371.652229)
			(xy 179.223932 -371.590062) (xy 178.28641 -371.590062) (xy 178.28641 -372.890034) (xy 179.223932 -372.890034)
			(xy 179.227923 -372.827867) (xy 179.239832 -372.76672) (xy 179.259461 -372.707599) (xy 179.28649 -372.651473)
			(xy 179.320474 -372.599264) (xy 179.360856 -372.551829) (xy 179.406972 -372.509948) (xy 179.458064 -372.474308)
			(xy 179.513295 -372.445494) (xy 179.571757 -372.42398) (xy 179.632491 -372.410118) (xy 179.694498 -372.404136)
			(xy 179.756761 -372.406132) (xy 179.818258 -372.416075) (xy 179.877979 -372.433799) (xy 179.934942 -372.459016)
			(xy 179.988213 -372.491309) (xy 180.036918 -372.530149) (xy 180.080255 -372.574899) (xy 180.117515 -372.624823)
			(xy 180.148084 -372.679102) (xy 180.171462 -372.736845) (xy 180.187263 -372.797103) (xy 180.195229 -372.858886)
			(xy 180.195728 -372.890034) (xy 180.195229 -372.921182) (xy 180.187263 -372.982965) (xy 180.171462 -373.043223)
			(xy 180.148084 -373.100966) (xy 180.117515 -373.155245) (xy 180.080255 -373.205169) (xy 180.036918 -373.249919)
			(xy 179.988213 -373.288759) (xy 179.934942 -373.321052) (xy 179.877979 -373.346269) (xy 179.818258 -373.363993)
			(xy 179.756761 -373.373936) (xy 179.694498 -373.375932) (xy 179.632491 -373.36995) (xy 179.571757 -373.356088)
			(xy 179.513295 -373.334574) (xy 179.458064 -373.30576) (xy 179.406972 -373.27012) (xy 179.360856 -373.228239)
			(xy 179.320474 -373.180804) (xy 179.28649 -373.128595) (xy 179.259461 -373.072469) (xy 179.239832 -373.013348)
			(xy 179.227923 -372.952201) (xy 179.223932 -372.890034) (xy 178.28641 -372.890034) (xy 178.28641 -375.490232)
			(xy 179.223932 -375.490232) (xy 179.227923 -375.428065) (xy 179.239832 -375.366918) (xy 179.259461 -375.307797)
			(xy 179.28649 -375.251671) (xy 179.320474 -375.199462) (xy 179.360856 -375.152027) (xy 179.406972 -375.110146)
			(xy 179.458064 -375.074506) (xy 179.513295 -375.045692) (xy 179.571757 -375.024178) (xy 179.632491 -375.010316)
			(xy 179.694498 -375.004334) (xy 179.756761 -375.00633) (xy 179.818258 -375.016273) (xy 179.877979 -375.033997)
			(xy 179.934942 -375.059214) (xy 179.988213 -375.091507) (xy 180.036918 -375.130347) (xy 180.080255 -375.175097)
			(xy 180.117515 -375.225021) (xy 180.148084 -375.2793) (xy 180.171462 -375.337043) (xy 180.187263 -375.397301)
			(xy 180.195229 -375.459084) (xy 180.195728 -375.490232) (xy 180.195229 -375.52138) (xy 180.187263 -375.583163)
			(xy 180.171462 -375.643421) (xy 180.148084 -375.701164) (xy 180.117515 -375.755443) (xy 180.080255 -375.805367)
			(xy 180.036918 -375.850117) (xy 179.988213 -375.888957) (xy 179.934942 -375.92125) (xy 179.877979 -375.946467)
			(xy 179.818258 -375.964191) (xy 179.756761 -375.974134) (xy 179.694498 -375.97613) (xy 179.632491 -375.970148)
			(xy 179.571757 -375.956286) (xy 179.513295 -375.934772) (xy 179.458064 -375.905958) (xy 179.406972 -375.870318)
			(xy 179.360856 -375.828437) (xy 179.320474 -375.781002) (xy 179.28649 -375.728793) (xy 179.259461 -375.672667)
			(xy 179.239832 -375.613546) (xy 179.227923 -375.552399) (xy 179.223932 -375.490232) (xy 178.28641 -375.490232)
			(xy 178.28641 -376.790204) (xy 179.223932 -376.790204) (xy 179.227923 -376.728037) (xy 179.239832 -376.66689)
			(xy 179.259461 -376.607769) (xy 179.28649 -376.551643) (xy 179.320474 -376.499434) (xy 179.360856 -376.451999)
			(xy 179.406972 -376.410118) (xy 179.458064 -376.374478) (xy 179.513295 -376.345664) (xy 179.571757 -376.32415)
			(xy 179.632491 -376.310288) (xy 179.694498 -376.304306) (xy 179.756761 -376.306302) (xy 179.818258 -376.316245)
			(xy 179.877979 -376.333969) (xy 179.934942 -376.359186) (xy 179.988213 -376.391479) (xy 180.036918 -376.430319)
			(xy 180.080255 -376.475069) (xy 180.117515 -376.524993) (xy 180.148084 -376.579272) (xy 180.171462 -376.637015)
			(xy 180.187263 -376.697273) (xy 180.195229 -376.759056) (xy 180.195728 -376.790204) (xy 180.195229 -376.821352)
			(xy 180.187263 -376.883135) (xy 180.171462 -376.943393) (xy 180.148084 -377.001136) (xy 180.117515 -377.055415)
			(xy 180.080255 -377.105339) (xy 180.036918 -377.150089) (xy 179.988213 -377.188929) (xy 179.934942 -377.221222)
			(xy 179.877979 -377.246439) (xy 179.818258 -377.264163) (xy 179.756761 -377.274106) (xy 179.694498 -377.276102)
			(xy 179.632491 -377.27012) (xy 179.571757 -377.256258) (xy 179.513295 -377.234744) (xy 179.458064 -377.20593)
			(xy 179.406972 -377.17029) (xy 179.360856 -377.128409) (xy 179.320474 -377.080974) (xy 179.28649 -377.028765)
			(xy 179.259461 -376.972639) (xy 179.239832 -376.913518) (xy 179.227923 -376.852371) (xy 179.223932 -376.790204)
			(xy 178.28641 -376.790204) (xy 178.28641 -379.390148) (xy 179.223932 -379.390148) (xy 179.227923 -379.327981)
			(xy 179.239832 -379.266834) (xy 179.259461 -379.207713) (xy 179.28649 -379.151587) (xy 179.320474 -379.099378)
			(xy 179.360856 -379.051943) (xy 179.406972 -379.010062) (xy 179.458064 -378.974422) (xy 179.513295 -378.945608)
			(xy 179.571757 -378.924094) (xy 179.632491 -378.910232) (xy 179.694498 -378.90425) (xy 179.756761 -378.906246)
			(xy 179.818258 -378.916189) (xy 179.877979 -378.933913) (xy 179.934942 -378.95913) (xy 179.988213 -378.991423)
			(xy 180.036918 -379.030263) (xy 180.080255 -379.075013) (xy 180.117515 -379.124937) (xy 180.148084 -379.179216)
			(xy 180.171462 -379.236959) (xy 180.187263 -379.297217) (xy 180.195229 -379.359) (xy 180.195728 -379.390148)
			(xy 180.195229 -379.421296) (xy 180.187263 -379.483079) (xy 180.171462 -379.543337) (xy 180.148084 -379.60108)
			(xy 180.117515 -379.655359) (xy 180.080255 -379.705283) (xy 180.036918 -379.750033) (xy 179.988213 -379.788873)
			(xy 179.934942 -379.821166) (xy 179.877979 -379.846383) (xy 179.818258 -379.864107) (xy 179.756761 -379.87405)
			(xy 179.694498 -379.876046) (xy 179.632491 -379.870064) (xy 179.571757 -379.856202) (xy 179.513295 -379.834688)
			(xy 179.458064 -379.805874) (xy 179.406972 -379.770234) (xy 179.360856 -379.728353) (xy 179.320474 -379.680918)
			(xy 179.28649 -379.628709) (xy 179.259461 -379.572583) (xy 179.239832 -379.513462) (xy 179.227923 -379.452315)
			(xy 179.223932 -379.390148) (xy 178.28641 -379.390148) (xy 178.28641 -380.69012) (xy 179.223932 -380.69012)
			(xy 179.227923 -380.627953) (xy 179.239832 -380.566806) (xy 179.259461 -380.507685) (xy 179.28649 -380.451559)
			(xy 179.320474 -380.39935) (xy 179.360856 -380.351915) (xy 179.406972 -380.310034) (xy 179.458064 -380.274394)
			(xy 179.513295 -380.24558) (xy 179.571757 -380.224066) (xy 179.632491 -380.210204) (xy 179.694498 -380.204222)
			(xy 179.756761 -380.206218) (xy 179.818258 -380.216161) (xy 179.877979 -380.233885) (xy 179.934942 -380.259102)
			(xy 179.988213 -380.291395) (xy 180.036918 -380.330235) (xy 180.080255 -380.374985) (xy 180.117515 -380.424909)
			(xy 180.148084 -380.479188) (xy 180.171462 -380.536931) (xy 180.187263 -380.597189) (xy 180.195229 -380.658972)
			(xy 180.195728 -380.69012) (xy 180.195229 -380.721268) (xy 180.187263 -380.783051) (xy 180.171462 -380.843309)
			(xy 180.148084 -380.901052) (xy 180.117515 -380.955331) (xy 180.080255 -381.005255) (xy 180.036918 -381.050005)
			(xy 179.988213 -381.088845) (xy 179.934942 -381.121138) (xy 179.877979 -381.146355) (xy 179.818258 -381.164079)
			(xy 179.756761 -381.174022) (xy 179.694498 -381.176018) (xy 179.632491 -381.170036) (xy 179.571757 -381.156174)
			(xy 179.513295 -381.13466) (xy 179.458064 -381.105846) (xy 179.406972 -381.070206) (xy 179.360856 -381.028325)
			(xy 179.320474 -380.98089) (xy 179.28649 -380.928681) (xy 179.259461 -380.872555) (xy 179.239832 -380.813434)
			(xy 179.227923 -380.752287) (xy 179.223932 -380.69012) (xy 178.28641 -380.69012) (xy 178.28641 -383.290064)
			(xy 179.223932 -383.290064) (xy 179.227923 -383.227897) (xy 179.239832 -383.16675) (xy 179.259461 -383.107629)
			(xy 179.28649 -383.051503) (xy 179.320474 -382.999294) (xy 179.360856 -382.951859) (xy 179.406972 -382.909978)
			(xy 179.458064 -382.874338) (xy 179.513295 -382.845524) (xy 179.571757 -382.82401) (xy 179.632491 -382.810148)
			(xy 179.694498 -382.804166) (xy 179.756761 -382.806162) (xy 179.818258 -382.816105) (xy 179.877979 -382.833829)
			(xy 179.934942 -382.859046) (xy 179.988213 -382.891339) (xy 180.036918 -382.930179) (xy 180.080255 -382.974929)
			(xy 180.117515 -383.024853) (xy 180.148084 -383.079132) (xy 180.171462 -383.136875) (xy 180.187263 -383.197133)
			(xy 180.195229 -383.258916) (xy 180.195728 -383.290064) (xy 180.195229 -383.321212) (xy 180.187263 -383.382995)
			(xy 180.171462 -383.443253) (xy 180.148084 -383.500996) (xy 180.117515 -383.555275) (xy 180.080255 -383.605199)
			(xy 180.036918 -383.649949) (xy 179.988213 -383.688789) (xy 179.934942 -383.721082) (xy 179.877979 -383.746299)
			(xy 179.818258 -383.764023) (xy 179.756761 -383.773966) (xy 179.694498 -383.775962) (xy 179.632491 -383.76998)
			(xy 179.571757 -383.756118) (xy 179.513295 -383.734604) (xy 179.458064 -383.70579) (xy 179.406972 -383.67015)
			(xy 179.360856 -383.628269) (xy 179.320474 -383.580834) (xy 179.28649 -383.528625) (xy 179.259461 -383.472499)
			(xy 179.239832 -383.413378) (xy 179.227923 -383.352231) (xy 179.223932 -383.290064) (xy 178.28641 -383.290064)
			(xy 178.28641 -384.590036) (xy 179.223932 -384.590036) (xy 179.227923 -384.527869) (xy 179.239832 -384.466722)
			(xy 179.259461 -384.407601) (xy 179.28649 -384.351475) (xy 179.320474 -384.299266) (xy 179.360856 -384.251831)
			(xy 179.406972 -384.20995) (xy 179.458064 -384.17431) (xy 179.513295 -384.145496) (xy 179.571757 -384.123982)
			(xy 179.632491 -384.11012) (xy 179.694498 -384.104138) (xy 179.756761 -384.106134) (xy 179.818258 -384.116077)
			(xy 179.877979 -384.133801) (xy 179.934942 -384.159018) (xy 179.988213 -384.191311) (xy 180.036918 -384.230151)
			(xy 180.080255 -384.274901) (xy 180.117515 -384.324825) (xy 180.148084 -384.379104) (xy 180.171462 -384.436847)
			(xy 180.187263 -384.497105) (xy 180.195229 -384.558888) (xy 180.195728 -384.590036) (xy 180.195229 -384.621184)
			(xy 180.187263 -384.682967) (xy 180.171462 -384.743225) (xy 180.148084 -384.800968) (xy 180.117515 -384.855247)
			(xy 180.080255 -384.905171) (xy 180.036918 -384.949921) (xy 179.988213 -384.988761) (xy 179.934942 -385.021054)
			(xy 179.877979 -385.046271) (xy 179.818258 -385.063995) (xy 179.756761 -385.073938) (xy 179.694498 -385.075934)
			(xy 179.632491 -385.069952) (xy 179.571757 -385.05609) (xy 179.513295 -385.034576) (xy 179.458064 -385.005762)
			(xy 179.406972 -384.970122) (xy 179.360856 -384.928241) (xy 179.320474 -384.880806) (xy 179.28649 -384.828597)
			(xy 179.259461 -384.772471) (xy 179.239832 -384.71335) (xy 179.227923 -384.652203) (xy 179.223932 -384.590036)
			(xy 178.28641 -384.590036) (xy 178.28641 -397.59001) (xy 179.223932 -397.59001) (xy 179.227923 -397.527843)
			(xy 179.239832 -397.466696) (xy 179.259461 -397.407575) (xy 179.28649 -397.351449) (xy 179.320474 -397.29924)
			(xy 179.360856 -397.251805) (xy 179.406972 -397.209924) (xy 179.458064 -397.174284) (xy 179.513295 -397.14547)
			(xy 179.571757 -397.123956) (xy 179.632491 -397.110094) (xy 179.694498 -397.104112) (xy 179.756761 -397.106108)
			(xy 179.818258 -397.116051) (xy 179.877979 -397.133775) (xy 179.934942 -397.158992) (xy 179.988213 -397.191285)
			(xy 180.036918 -397.230125) (xy 180.080255 -397.274875) (xy 180.117515 -397.324799) (xy 180.148084 -397.379078)
			(xy 180.171462 -397.436821) (xy 180.187263 -397.497079) (xy 180.195229 -397.558862) (xy 180.195728 -397.59001)
			(xy 180.195229 -397.621158) (xy 180.187263 -397.682941) (xy 180.171462 -397.743199) (xy 180.148084 -397.800942)
			(xy 180.117515 -397.855221) (xy 180.080255 -397.905145) (xy 180.036918 -397.949895) (xy 179.988213 -397.988735)
			(xy 179.934942 -398.021028) (xy 179.877979 -398.046245) (xy 179.818258 -398.063969) (xy 179.756761 -398.073912)
			(xy 179.694498 -398.075908) (xy 179.632491 -398.069926) (xy 179.571757 -398.056064) (xy 179.513295 -398.03455)
			(xy 179.458064 -398.005736) (xy 179.406972 -397.970096) (xy 179.360856 -397.928215) (xy 179.320474 -397.88078)
			(xy 179.28649 -397.828571) (xy 179.259461 -397.772445) (xy 179.239832 -397.713324) (xy 179.227923 -397.652177)
			(xy 179.223932 -397.59001) (xy 178.28641 -397.59001) (xy 178.28641 -398.890236) (xy 179.223932 -398.890236)
			(xy 179.227923 -398.828069) (xy 179.239832 -398.766922) (xy 179.259461 -398.707801) (xy 179.28649 -398.651675)
			(xy 179.320474 -398.599466) (xy 179.360856 -398.552031) (xy 179.406972 -398.51015) (xy 179.458064 -398.47451)
			(xy 179.513295 -398.445696) (xy 179.571757 -398.424182) (xy 179.632491 -398.41032) (xy 179.694498 -398.404338)
			(xy 179.756761 -398.406334) (xy 179.818258 -398.416277) (xy 179.877979 -398.434001) (xy 179.934942 -398.459218)
			(xy 179.988213 -398.491511) (xy 180.036918 -398.530351) (xy 180.080255 -398.575101) (xy 180.117515 -398.625025)
			(xy 180.148084 -398.679304) (xy 180.171462 -398.737047) (xy 180.187263 -398.797305) (xy 180.195229 -398.859088)
			(xy 180.195728 -398.890236) (xy 180.195229 -398.921384) (xy 180.187263 -398.983167) (xy 180.171462 -399.043425)
			(xy 180.148084 -399.101168) (xy 180.117515 -399.155447) (xy 180.080255 -399.205371) (xy 180.036918 -399.250121)
			(xy 179.988213 -399.288961) (xy 179.934942 -399.321254) (xy 179.877979 -399.346471) (xy 179.818258 -399.364195)
			(xy 179.756761 -399.374138) (xy 179.694498 -399.376134) (xy 179.632491 -399.370152) (xy 179.571757 -399.35629)
			(xy 179.513295 -399.334776) (xy 179.458064 -399.305962) (xy 179.406972 -399.270322) (xy 179.360856 -399.228441)
			(xy 179.320474 -399.181006) (xy 179.28649 -399.128797) (xy 179.259461 -399.072671) (xy 179.239832 -399.01355)
			(xy 179.227923 -398.952403) (xy 179.223932 -398.890236) (xy 178.28641 -398.890236) (xy 178.28641 -401.49018)
			(xy 179.223932 -401.49018) (xy 179.227923 -401.428013) (xy 179.239832 -401.366866) (xy 179.259461 -401.307745)
			(xy 179.28649 -401.251619) (xy 179.320474 -401.19941) (xy 179.360856 -401.151975) (xy 179.406972 -401.110094)
			(xy 179.458064 -401.074454) (xy 179.513295 -401.04564) (xy 179.571757 -401.024126) (xy 179.632491 -401.010264)
			(xy 179.694498 -401.004282) (xy 179.756761 -401.006278) (xy 179.818258 -401.016221) (xy 179.877979 -401.033945)
			(xy 179.934942 -401.059162) (xy 179.988213 -401.091455) (xy 180.036918 -401.130295) (xy 180.080255 -401.175045)
			(xy 180.117515 -401.224969) (xy 180.148084 -401.279248) (xy 180.171462 -401.336991) (xy 180.187263 -401.397249)
			(xy 180.195229 -401.459032) (xy 180.195728 -401.49018) (xy 180.195229 -401.521328) (xy 180.187263 -401.583111)
			(xy 180.171462 -401.643369) (xy 180.148084 -401.701112) (xy 180.117515 -401.755391) (xy 180.080255 -401.805315)
			(xy 180.036918 -401.850065) (xy 179.988213 -401.888905) (xy 179.934942 -401.921198) (xy 179.877979 -401.946415)
			(xy 179.818258 -401.964139) (xy 179.756761 -401.974082) (xy 179.694498 -401.976078) (xy 179.632491 -401.970096)
			(xy 179.571757 -401.956234) (xy 179.513295 -401.93472) (xy 179.458064 -401.905906) (xy 179.406972 -401.870266)
			(xy 179.360856 -401.828385) (xy 179.320474 -401.78095) (xy 179.28649 -401.728741) (xy 179.259461 -401.672615)
			(xy 179.239832 -401.613494) (xy 179.227923 -401.552347) (xy 179.223932 -401.49018) (xy 178.28641 -401.49018)
			(xy 178.28641 -402.790152) (xy 179.223932 -402.790152) (xy 179.227923 -402.727985) (xy 179.239832 -402.666838)
			(xy 179.259461 -402.607717) (xy 179.28649 -402.551591) (xy 179.320474 -402.499382) (xy 179.360856 -402.451947)
			(xy 179.406972 -402.410066) (xy 179.458064 -402.374426) (xy 179.513295 -402.345612) (xy 179.571757 -402.324098)
			(xy 179.632491 -402.310236) (xy 179.694498 -402.304254) (xy 179.756761 -402.30625) (xy 179.818258 -402.316193)
			(xy 179.877979 -402.333917) (xy 179.934942 -402.359134) (xy 179.988213 -402.391427) (xy 180.036918 -402.430267)
			(xy 180.080255 -402.475017) (xy 180.117515 -402.524941) (xy 180.148084 -402.57922) (xy 180.171462 -402.636963)
			(xy 180.187263 -402.697221) (xy 180.195229 -402.759004) (xy 180.195728 -402.790152) (xy 180.195229 -402.8213)
			(xy 180.187263 -402.883083) (xy 180.171462 -402.943341) (xy 180.148084 -403.001084) (xy 180.117515 -403.055363)
			(xy 180.080255 -403.105287) (xy 180.036918 -403.150037) (xy 179.988213 -403.188877) (xy 179.934942 -403.22117)
			(xy 179.877979 -403.246387) (xy 179.818258 -403.264111) (xy 179.756761 -403.274054) (xy 179.694498 -403.27605)
			(xy 179.632491 -403.270068) (xy 179.571757 -403.256206) (xy 179.513295 -403.234692) (xy 179.458064 -403.205878)
			(xy 179.406972 -403.170238) (xy 179.360856 -403.128357) (xy 179.320474 -403.080922) (xy 179.28649 -403.028713)
			(xy 179.259461 -402.972587) (xy 179.239832 -402.913466) (xy 179.227923 -402.852319) (xy 179.223932 -402.790152)
			(xy 178.28641 -402.790152) (xy 178.28641 -405.390096) (xy 179.223932 -405.390096) (xy 179.227923 -405.327929)
			(xy 179.239832 -405.266782) (xy 179.259461 -405.207661) (xy 179.28649 -405.151535) (xy 179.320474 -405.099326)
			(xy 179.360856 -405.051891) (xy 179.406972 -405.01001) (xy 179.458064 -404.97437) (xy 179.513295 -404.945556)
			(xy 179.571757 -404.924042) (xy 179.632491 -404.91018) (xy 179.694498 -404.904198) (xy 179.756761 -404.906194)
			(xy 179.818258 -404.916137) (xy 179.877979 -404.933861) (xy 179.934942 -404.959078) (xy 179.988213 -404.991371)
			(xy 180.036918 -405.030211) (xy 180.080255 -405.074961) (xy 180.117515 -405.124885) (xy 180.148084 -405.179164)
			(xy 180.171462 -405.236907) (xy 180.187263 -405.297165) (xy 180.195229 -405.358948) (xy 180.195728 -405.390096)
			(xy 180.195229 -405.421244) (xy 180.187263 -405.483027) (xy 180.171462 -405.543285) (xy 180.148084 -405.601028)
			(xy 180.117515 -405.655307) (xy 180.080255 -405.705231) (xy 180.036918 -405.749981) (xy 179.988213 -405.788821)
			(xy 179.934942 -405.821114) (xy 179.877979 -405.846331) (xy 179.818258 -405.864055) (xy 179.756761 -405.873998)
			(xy 179.694498 -405.875994) (xy 179.632491 -405.870012) (xy 179.571757 -405.85615) (xy 179.513295 -405.834636)
			(xy 179.458064 -405.805822) (xy 179.406972 -405.770182) (xy 179.360856 -405.728301) (xy 179.320474 -405.680866)
			(xy 179.28649 -405.628657) (xy 179.259461 -405.572531) (xy 179.239832 -405.51341) (xy 179.227923 -405.452263)
			(xy 179.223932 -405.390096) (xy 178.28641 -405.390096) (xy 178.28641 -406.087072) (xy 178.285974 -406.097137)
			(xy 178.278243 -406.115723) (xy 178.271424 -406.12314) (xy 177.704496 -406.690068) (xy 179.223932 -406.690068)
			(xy 179.227923 -406.627901) (xy 179.239832 -406.566754) (xy 179.259461 -406.507633) (xy 179.28649 -406.451507)
			(xy 179.320474 -406.399298) (xy 179.360856 -406.351863) (xy 179.406972 -406.309982) (xy 179.458064 -406.274342)
			(xy 179.513295 -406.245528) (xy 179.571757 -406.224014) (xy 179.632491 -406.210152) (xy 179.694498 -406.20417)
			(xy 179.756761 -406.206166) (xy 179.818258 -406.216109) (xy 179.877979 -406.233833) (xy 179.934942 -406.25905)
			(xy 179.988213 -406.291343) (xy 180.036918 -406.330183) (xy 180.080255 -406.374933) (xy 180.117515 -406.424857)
			(xy 180.148084 -406.479136) (xy 180.171462 -406.536879) (xy 180.187263 -406.597137) (xy 180.195229 -406.65892)
			(xy 180.195728 -406.690068) (xy 180.195229 -406.721216) (xy 180.187263 -406.782999) (xy 180.171462 -406.843257)
			(xy 180.148084 -406.901) (xy 180.117515 -406.955279) (xy 180.088348 -406.99436) (xy 187.04255 -406.99436)
			(xy 187.046621 -406.938738) (xy 187.058747 -406.884301) (xy 187.07867 -406.83221) (xy 187.105966 -406.783575)
			(xy 187.140052 -406.739432) (xy 187.180201 -406.700723) (xy 187.225559 -406.668272) (xy 187.275159 -406.642771)
			(xy 187.327943 -406.624764) (xy 187.382786 -406.614634) (xy 187.43852 -406.612597) (xy 187.493957 -406.618697)
			(xy 187.547914 -406.632803) (xy 187.599243 -406.654615) (xy 187.646849 -406.683669) (xy 187.689717 -406.719344)
			(xy 187.726934 -406.760881) (xy 187.757707 -406.807394) (xy 187.781379 -406.857891) (xy 187.797447 -406.911298)
			(xy 187.805567 -406.966474) (xy 187.806076 -406.99436) (xy 187.805567 -407.022246) (xy 187.797447 -407.077422)
			(xy 187.781379 -407.130829) (xy 187.757707 -407.181326) (xy 187.726934 -407.227839) (xy 187.689717 -407.269376)
			(xy 187.646849 -407.305051) (xy 187.599243 -407.334105) (xy 187.547914 -407.355917) (xy 187.493957 -407.370023)
			(xy 187.43852 -407.376123) (xy 187.382786 -407.374086) (xy 187.327943 -407.363956) (xy 187.275159 -407.345949)
			(xy 187.225559 -407.320448) (xy 187.180201 -407.287997) (xy 187.140052 -407.249288) (xy 187.105966 -407.205145)
			(xy 187.07867 -407.15651) (xy 187.058747 -407.104419) (xy 187.046621 -407.049982) (xy 187.04255 -406.99436)
			(xy 180.088348 -406.99436) (xy 180.080255 -407.005203) (xy 180.036918 -407.049953) (xy 179.988213 -407.088793)
			(xy 179.934942 -407.121086) (xy 179.877979 -407.146303) (xy 179.818258 -407.164027) (xy 179.756761 -407.17397)
			(xy 179.694498 -407.175966) (xy 179.632491 -407.169984) (xy 179.571757 -407.156122) (xy 179.513295 -407.134608)
			(xy 179.458064 -407.105794) (xy 179.406972 -407.070154) (xy 179.360856 -407.028273) (xy 179.320474 -406.980838)
			(xy 179.28649 -406.928629) (xy 179.259461 -406.872503) (xy 179.239832 -406.813382) (xy 179.227923 -406.752235)
			(xy 179.223932 -406.690068) (xy 177.704496 -406.690068) (xy 177.486056 -406.908508) (xy 177.478655 -406.915347)
			(xy 177.460057 -406.923064) (xy 177.449988 -406.923494) (xy 176.671732 -406.923494) (xy 176.662689 -406.923893)
			(xy 176.645757 -406.930258) (xy 176.638712 -406.93594) (xy 176.601853 -406.967022) (xy 176.523132 -407.022701)
			(xy 176.439403 -407.070521) (xy 176.351449 -407.110037) (xy 176.260092 -407.140878) (xy 176.213262 -407.152348)
			(xy 176.203016 -407.155167) (xy 176.186041 -407.167921) (xy 176.180496 -407.176986) (xy 176.158544 -407.215222)
			(xy 176.108862 -407.288067) (xy 176.052943 -407.356242) (xy 175.991223 -407.419214) (xy 175.965256 -407.4414)
			(xy 185.755532 -407.4414) (xy 185.759603 -407.385778) (xy 185.771729 -407.331341) (xy 185.791652 -407.27925)
			(xy 185.818948 -407.230615) (xy 185.853034 -407.186472) (xy 185.893183 -407.147763) (xy 185.938541 -407.115312)
			(xy 185.988141 -407.089811) (xy 186.040925 -407.071804) (xy 186.095768 -407.061674) (xy 186.151502 -407.059637)
			(xy 186.206939 -407.065737) (xy 186.260896 -407.079843) (xy 186.312225 -407.101655) (xy 186.359831 -407.130709)
			(xy 186.402699 -407.166384) (xy 186.439916 -407.207921) (xy 186.470689 -407.254434) (xy 186.494361 -407.304931)
			(xy 186.510429 -407.358338) (xy 186.518549 -407.413514) (xy 186.519058 -407.4414) (xy 186.518549 -407.469286)
			(xy 186.510429 -407.524462) (xy 186.494361 -407.577869) (xy 186.470689 -407.628366) (xy 186.439916 -407.674879)
			(xy 186.402699 -407.716416) (xy 186.359831 -407.752091) (xy 186.312225 -407.781145) (xy 186.260896 -407.802957)
			(xy 186.206939 -407.817063) (xy 186.151502 -407.823163) (xy 186.095768 -407.821126) (xy 186.040925 -407.810996)
			(xy 185.988141 -407.792989) (xy 185.938541 -407.767488) (xy 185.893183 -407.735037) (xy 185.853034 -407.696328)
			(xy 185.818948 -407.652185) (xy 185.791652 -407.60355) (xy 185.771729 -407.551459) (xy 185.759603 -407.497022)
			(xy 185.755532 -407.4414) (xy 175.965256 -407.4414) (xy 175.924185 -407.476491) (xy 175.852352 -407.527625)
			(xy 175.776285 -407.572218) (xy 175.696579 -407.609922) (xy 175.613855 -407.640441) (xy 175.528759 -407.663538)
			(xy 175.441957 -407.679032) (xy 175.354125 -407.686803) (xy 175.310038 -407.687272) (xy 175.309784 -407.687272)
			(xy 175.268668 -407.686853) (xy 175.186716 -407.680084) (xy 175.105601 -407.666583) (xy 175.025874 -407.646445)
			(xy 174.948077 -407.619804) (xy 174.910242 -407.603706) (xy 174.90136 -407.600207) (xy 174.8823 -407.599431)
			(xy 174.873158 -407.602182) (xy 174.842804 -407.612096) (xy 174.779861 -407.622828) (xy 174.747936 -407.623518)
			(xy 174.720681 -407.623058) (xy 174.666726 -407.615305) (xy 174.614423 -407.599952) (xy 174.564838 -407.577312)
			(xy 174.518979 -407.547845) (xy 174.477781 -407.512151) (xy 174.442083 -407.470958) (xy 174.41261 -407.425103)
			(xy 174.389964 -407.37552) (xy 174.374605 -407.323219) (xy 174.366846 -407.269265) (xy 174.366428 -407.24201)
			(xy 174.366428 -407.241248) (xy 174.367155 -407.207707) (xy 174.378907 -407.141662) (xy 174.389796 -407.10993)
			(xy 174.392708 -407.100851) (xy 174.392304 -407.081803) (xy 174.389034 -407.072846) (xy 174.377859 -407.045305)
			(xy 174.358416 -406.989133) (xy 174.350172 -406.960578) (xy 174.346679 -406.950065) (xy 174.33233 -406.933219)
			(xy 174.312217 -406.923991) (xy 174.30115 -406.923494) (xy 173.716442 -406.923494) (xy 173.687994 -406.948386)
			(xy 173.685454 -406.967436) (xy 173.680321 -407.001851) (xy 173.662893 -407.069218) (xy 173.63754 -407.134019)
			(xy 173.604625 -407.195326) (xy 173.56462 -407.25226) (xy 173.518097 -407.304006) (xy 173.465724 -407.349822)
			(xy 173.408252 -407.38905) (xy 173.346504 -407.42113) (xy 173.281365 -407.445601) (xy 173.213768 -407.462113)
			(xy 173.144682 -407.470428) (xy 173.075098 -407.470428) (xy 173.006012 -407.462113) (xy 172.938415 -407.445601)
			(xy 172.873276 -407.42113) (xy 172.811528 -407.38905) (xy 172.754056 -407.349822) (xy 172.701683 -407.304006)
			(xy 172.65516 -407.25226) (xy 172.615155 -407.195326) (xy 172.58224 -407.134019) (xy 172.556887 -407.069218)
			(xy 172.539459 -407.001851) (xy 172.534326 -406.967436) (xy 172.531786 -406.948386) (xy 172.503338 -406.923494)
			(xy 172.27169 -406.923494) (xy 172.262674 -406.923855) (xy 172.24576 -406.930104) (xy 172.23867 -406.935686)
			(xy 172.238416 -406.93594) (xy 172.201562 -406.966988) (xy 172.122882 -407.022638) (xy 172.039204 -407.070444)
			(xy 171.951308 -407.109963) (xy 171.860012 -407.140826) (xy 171.81322 -407.152348) (xy 171.802979 -407.155173)
			(xy 171.786017 -407.167934) (xy 171.780454 -407.176986) (xy 171.758502 -407.215224) (xy 171.708821 -407.288072)
			(xy 171.652903 -407.35625) (xy 171.591185 -407.419225) (xy 171.524147 -407.476506) (xy 171.452315 -407.527645)
			(xy 171.376248 -407.572242) (xy 171.296542 -407.609951) (xy 171.213817 -407.640475) (xy 171.128721 -407.663576)
			(xy 171.041917 -407.679075) (xy 170.954084 -407.686851) (xy 170.909996 -407.687272) (xy 170.909742 -407.687272)
			(xy 170.868627 -407.686852) (xy 170.786676 -407.680079) (xy 170.705561 -407.666575) (xy 170.625836 -407.646433)
			(xy 170.548041 -407.61979) (xy 170.5102 -407.603706) (xy 170.501318 -407.600196) (xy 170.482251 -407.599399)
			(xy 170.473116 -407.602182) (xy 170.442761 -407.612093) (xy 170.379818 -407.622817) (xy 170.347894 -407.623518)
			(xy 170.320643 -407.623032) (xy 170.266695 -407.615275) (xy 170.214401 -407.599919) (xy 170.164823 -407.577278)
			(xy 170.118973 -407.547811) (xy 170.077783 -407.51212) (xy 170.042091 -407.47093) (xy 170.012624 -407.42508)
			(xy 169.989982 -407.375503) (xy 169.974626 -407.323209) (xy 169.966868 -407.269261) (xy 169.966386 -407.24201)
			(xy 169.966386 -407.241248) (xy 169.967113 -407.207707) (xy 169.978867 -407.141663) (xy 169.989754 -407.10993)
			(xy 169.992668 -407.100852) (xy 169.992263 -407.081803) (xy 169.988992 -407.072846) (xy 169.977818 -407.045305)
			(xy 169.958375 -406.989133) (xy 169.95013 -406.960578) (xy 169.946639 -406.950059) (xy 169.932293 -406.933197)
			(xy 169.912179 -406.923947) (xy 169.901108 -406.923494) (xy 169.316654 -406.923494) (xy 169.288206 -406.948386)
			(xy 169.285666 -406.967436) (xy 169.280533 -407.001851) (xy 169.263105 -407.069218) (xy 169.237752 -407.134019)
			(xy 169.204837 -407.195326) (xy 169.164832 -407.25226) (xy 169.118309 -407.304006) (xy 169.065936 -407.349822)
			(xy 169.008464 -407.38905) (xy 168.946716 -407.42113) (xy 168.881577 -407.445601) (xy 168.81398 -407.462113)
			(xy 168.744894 -407.470428) (xy 168.67531 -407.470428) (xy 168.606224 -407.462113) (xy 168.538627 -407.445601)
			(xy 168.473488 -407.42113) (xy 168.41174 -407.38905) (xy 168.354268 -407.349822) (xy 168.301895 -407.304006)
			(xy 168.255372 -407.25226) (xy 168.215367 -407.195326) (xy 168.182452 -407.134019) (xy 168.157099 -407.069218)
			(xy 168.139671 -407.001851) (xy 168.134538 -406.967436) (xy 168.131998 -406.948386) (xy 168.10355 -406.923494)
			(xy 167.871648 -406.923494) (xy 167.862635 -406.923862) (xy 167.84573 -406.930122) (xy 167.838628 -406.935686)
			(xy 167.838374 -406.93594) (xy 167.801521 -406.96699) (xy 167.722842 -407.022644) (xy 167.639166 -407.070455)
			(xy 167.551271 -407.109979) (xy 167.459975 -407.140848) (xy 167.413178 -407.152348) (xy 167.40293 -407.155164)
			(xy 167.38595 -407.167916) (xy 167.380412 -407.176986) (xy 167.35846 -407.215223) (xy 167.308778 -407.288069)
			(xy 167.252859 -407.356244) (xy 167.19114 -407.419217) (xy 167.124102 -407.476495) (xy 167.05227 -407.527631)
			(xy 166.976203 -407.572225) (xy 166.896496 -407.60993) (xy 166.813772 -407.640451) (xy 166.728676 -407.663549)
			(xy 166.641873 -407.679044) (xy 166.554042 -407.686816) (xy 166.509954 -407.687272) (xy 166.5097 -407.687272)
			(xy 166.468584 -407.686854) (xy 166.386632 -407.680086) (xy 166.305516 -407.666587) (xy 166.225788 -407.646449)
			(xy 166.147991 -407.619809) (xy 166.110158 -407.603706) (xy 166.101276 -407.600204) (xy 166.082214 -407.599423)
			(xy 166.073074 -407.602182) (xy 166.042719 -407.61209) (xy 165.979775 -407.622807) (xy 165.947852 -407.623518)
			(xy 165.920603 -407.623029) (xy 165.86666 -407.615267) (xy 165.81437 -407.599908) (xy 165.764798 -407.577264)
			(xy 165.718953 -407.547797) (xy 165.677768 -407.512105) (xy 165.642081 -407.470916) (xy 165.612618 -407.425068)
			(xy 165.589979 -407.375494) (xy 165.574625 -407.323203) (xy 165.566868 -407.269259) (xy 165.566344 -407.24201)
			(xy 165.566344 -407.241248) (xy 165.567071 -407.207707) (xy 165.578823 -407.141662) (xy 165.589712 -407.10993)
			(xy 165.592628 -407.100852) (xy 165.592223 -407.081803) (xy 165.58895 -407.072846) (xy 165.577775 -407.045305)
			(xy 165.558331 -406.989134) (xy 165.550088 -406.960578) (xy 165.546596 -406.950063) (xy 165.532247 -406.933213)
			(xy 165.512134 -406.923979) (xy 165.501066 -406.923494) (xy 164.916612 -406.923494) (xy 164.888164 -406.948386)
			(xy 164.885624 -406.967436) (xy 164.880491 -407.001851) (xy 164.863063 -407.069218) (xy 164.83771 -407.134019)
			(xy 164.804795 -407.195326) (xy 164.76479 -407.25226) (xy 164.718267 -407.304006) (xy 164.665894 -407.349822)
			(xy 164.608422 -407.38905) (xy 164.546674 -407.42113) (xy 164.481535 -407.445601) (xy 164.413938 -407.462113)
			(xy 164.344852 -407.470428) (xy 164.275268 -407.470428) (xy 164.206182 -407.462113) (xy 164.138585 -407.445601)
			(xy 164.073446 -407.42113) (xy 164.011698 -407.38905) (xy 163.954226 -407.349822) (xy 163.901853 -407.304006)
			(xy 163.85533 -407.25226) (xy 163.815325 -407.195326) (xy 163.78241 -407.134019) (xy 163.757057 -407.069218)
			(xy 163.739629 -407.001851) (xy 163.734496 -406.967436) (xy 163.731956 -406.948386) (xy 163.703508 -406.923494)
			(xy 163.471606 -406.923494) (xy 163.462589 -406.923852) (xy 163.445671 -406.930098) (xy 163.438586 -406.935686)
			(xy 163.438332 -406.93594) (xy 163.401478 -406.966989) (xy 163.322798 -407.022639) (xy 163.239121 -407.070448)
			(xy 163.151225 -407.109968) (xy 163.059929 -407.140832) (xy 163.013136 -407.152348) (xy 163.002893 -407.155171)
			(xy 162.985926 -407.167929) (xy 162.98037 -407.176986) (xy 162.958417 -407.215222) (xy 162.908735 -407.288065)
			(xy 162.852815 -407.356238) (xy 162.791095 -407.419208) (xy 162.724057 -407.476484) (xy 162.652224 -407.527616)
			(xy 162.576157 -407.572208) (xy 162.496451 -407.609909) (xy 162.413727 -407.640427) (xy 162.328631 -407.663521)
			(xy 162.241829 -407.679013) (xy 162.153999 -407.686781) (xy 162.109912 -407.687272) (xy 162.109658 -407.687272)
			(xy 162.068543 -407.686852) (xy 161.986591 -407.680081) (xy 161.905476 -407.666578) (xy 161.82575 -407.646438)
			(xy 161.747955 -407.619795) (xy 161.710116 -407.603706) (xy 161.701234 -407.600212) (xy 161.682178 -407.599445)
			(xy 161.673032 -407.602182) (xy 161.642678 -407.612094) (xy 161.579734 -407.622821) (xy 161.54781 -407.623518)
			(xy 161.520558 -407.623033) (xy 161.466609 -407.615278) (xy 161.414312 -407.599923) (xy 161.364733 -407.577283)
			(xy 161.318881 -407.547817) (xy 161.277688 -407.512126) (xy 161.241995 -407.470935) (xy 161.212527 -407.425085)
			(xy 161.189884 -407.375507) (xy 161.174527 -407.323211) (xy 161.166769 -407.269262) (xy 161.166302 -407.24201)
			(xy 161.166302 -407.241248) (xy 161.167029 -407.207707) (xy 161.17878 -407.141662) (xy 161.18967 -407.10993)
			(xy 161.192584 -407.100852) (xy 161.192179 -407.081803) (xy 161.188908 -407.072846) (xy 161.177734 -407.045305)
			(xy 161.158291 -406.989133) (xy 161.150046 -406.960578) (xy 161.146556 -406.950057) (xy 161.132211 -406.933191)
			(xy 161.112096 -406.923935) (xy 161.101024 -406.923494) (xy 160.51657 -406.923494) (xy 160.488122 -406.948386)
			(xy 160.485582 -406.967436) (xy 160.480449 -407.001851) (xy 160.463021 -407.069218) (xy 160.437668 -407.134019)
			(xy 160.404753 -407.195326) (xy 160.364748 -407.25226) (xy 160.318225 -407.304006) (xy 160.265852 -407.349822)
			(xy 160.20838 -407.38905) (xy 160.146632 -407.42113) (xy 160.081493 -407.445601) (xy 160.013896 -407.462113)
			(xy 159.94481 -407.470428) (xy 159.875226 -407.470428) (xy 159.80614 -407.462113) (xy 159.738543 -407.445601)
			(xy 159.673404 -407.42113) (xy 159.611656 -407.38905) (xy 159.554184 -407.349822) (xy 159.501811 -407.304006)
			(xy 159.455288 -407.25226) (xy 159.415283 -407.195326) (xy 159.382368 -407.134019) (xy 159.357015 -407.069218)
			(xy 159.339587 -407.001851) (xy 159.334454 -406.967436) (xy 159.331914 -406.948386) (xy 159.303466 -406.923494)
			(xy 158.987744 -406.923494) (xy 158.977678 -406.92306) (xy 158.959089 -406.915331) (xy 158.951676 -406.908508)
			(xy 154.66314 -402.619972) (xy 154.655709 -402.613176) (xy 154.637097 -402.60553) (xy 154.616975 -402.605596)
			(xy 154.607514 -402.60905) (xy 154.598495 -402.613315) (xy 154.584405 -402.627409) (xy 154.576778 -402.645821)
			(xy 154.576272 -402.655786) (xy 154.576272 -409.522889) (xy 159.424957 -409.522889) (xy 159.424961 -409.45745)
			(xy 159.433748 -409.392604) (xy 159.45116 -409.329524) (xy 159.47688 -409.269352) (xy 159.493204 -409.24099)
			(xy 159.496523 -409.234967) (xy 159.500126 -409.221702) (xy 159.500316 -409.214828) (xy 159.500316 -408.465528)
			(xy 159.500112 -408.458656) (xy 159.496512 -408.445393) (xy 159.493204 -408.439366) (xy 159.476876 -408.411008)
			(xy 159.451161 -408.350836) (xy 159.433755 -408.287756) (xy 159.424973 -408.222912) (xy 159.424974 -408.157475)
			(xy 159.433758 -408.09263) (xy 159.451165 -408.029551) (xy 159.476882 -407.96938) (xy 159.493204 -407.941018)
			(xy 159.496513 -407.93499) (xy 159.500122 -407.921729) (xy 159.500316 -407.914856) (xy 159.500316 -407.628852)
			(xy 159.500683 -407.618693) (xy 159.508497 -407.599936) (xy 159.522911 -407.585614) (xy 159.541716 -407.577919)
			(xy 159.551878 -407.577544) (xy 160.268158 -407.577544) (xy 160.278283 -407.578061) (xy 160.297003 -407.585776)
			(xy 160.311361 -407.600053) (xy 160.319181 -407.61873) (xy 160.31972 -407.628852) (xy 160.31972 -407.914856)
			(xy 160.319926 -407.921728) (xy 160.323525 -407.934991) (xy 160.326832 -407.941018) (xy 160.343148 -407.969383)
			(xy 160.368868 -408.029553) (xy 160.386278 -408.092631) (xy 160.395063 -408.157475) (xy 160.395064 -408.222911)
			(xy 160.386281 -408.287756) (xy 160.368873 -408.350834) (xy 160.343155 -408.411005) (xy 160.326832 -408.439366)
			(xy 160.323532 -408.445398) (xy 160.319917 -408.458656) (xy 160.31972 -408.465528) (xy 160.31972 -409.214828)
			(xy 160.319899 -409.221702) (xy 160.323516 -409.234965) (xy 160.326832 -409.24099) (xy 160.343125 -409.269368)
			(xy 160.368847 -409.329535) (xy 160.386259 -409.39261) (xy 160.395047 -409.457452) (xy 160.395051 -409.522886)
			(xy 160.386272 -409.587729) (xy 160.368867 -409.650807) (xy 160.343153 -409.710977) (xy 160.326832 -409.739338)
			(xy 160.323506 -409.745357) (xy 160.319907 -409.758625) (xy 160.31972 -409.7655) (xy 160.31972 -410.051504)
			(xy 160.319282 -410.061656) (xy 160.311489 -410.080404) (xy 160.297098 -410.094727) (xy 160.278312 -410.10243)
			(xy 160.268158 -410.102812) (xy 159.551878 -410.102812) (xy 159.541756 -410.102293) (xy 159.523044 -410.094568)
			(xy 159.508691 -410.080292) (xy 159.500863 -410.061623) (xy 159.500316 -410.051504) (xy 159.500316 -409.7655)
			(xy 159.500122 -409.758627) (xy 159.496515 -409.745364) (xy 159.493204 -409.739338) (xy 159.476852 -409.710993)
			(xy 159.451139 -409.650818) (xy 159.433736 -409.587736) (xy 159.424957 -409.522889) (xy 154.576272 -409.522889)
			(xy 154.576272 -410.589984) (xy 161.624264 -410.589984) (xy 161.62485 -410.557255) (xy 161.633701 -410.492398)
			(xy 161.651185 -410.429318) (xy 161.676987 -410.369159) (xy 161.693352 -410.34081) (xy 161.696659 -410.334782)
			(xy 161.70027 -410.321521) (xy 161.700464 -410.314648) (xy 161.700464 -409.565348) (xy 161.700258 -409.558476)
			(xy 161.69666 -409.545213) (xy 161.693352 -409.539186) (xy 161.676986 -409.510837) (xy 161.651183 -409.450678)
			(xy 161.633693 -409.387598) (xy 161.624834 -409.322741) (xy 161.624264 -409.290012) (xy 161.624817 -409.257282)
			(xy 161.633678 -409.192424) (xy 161.651172 -409.129343) (xy 161.676982 -409.069186) (xy 161.693352 -409.040838)
			(xy 161.696649 -409.034805) (xy 161.700267 -409.021548) (xy 161.700464 -409.014676) (xy 161.700464 -408.728672)
			(xy 161.700961 -408.718566) (xy 161.708701 -408.699894) (xy 161.722994 -408.685601) (xy 161.741666 -408.677861)
			(xy 161.751772 -408.677364) (xy 162.468052 -408.677364) (xy 162.478167 -408.677854) (xy 162.496863 -408.68558)
			(xy 162.511177 -408.699874) (xy 162.518931 -408.718558) (xy 162.51936 -408.728672) (xy 162.51936 -409.014676)
			(xy 162.519566 -409.021548) (xy 162.523165 -409.034811) (xy 162.526472 -409.040838) (xy 162.54285 -409.06918)
			(xy 162.568649 -409.129342) (xy 162.586136 -409.192424) (xy 162.594992 -409.257282) (xy 162.59556 -409.290012)
			(xy 162.594969 -409.322741) (xy 162.58612 -409.387598) (xy 162.568637 -409.450678) (xy 162.551703 -409.490164)
			(xy 163.824412 -409.490164) (xy 163.824982 -409.457435) (xy 163.833837 -409.392577) (xy 163.851326 -409.329496)
			(xy 163.877132 -409.269338) (xy 163.8935 -409.24099) (xy 163.896818 -409.234967) (xy 163.900422 -409.221702)
			(xy 163.900612 -409.214828) (xy 163.900612 -408.465528) (xy 163.900408 -408.458656) (xy 163.896808 -408.445393)
			(xy 163.8935 -408.439366) (xy 163.877121 -408.411024) (xy 163.851322 -408.350862) (xy 163.833836 -408.28778)
			(xy 163.82498 -408.222922) (xy 163.824412 -408.190192) (xy 163.824995 -408.157463) (xy 163.833845 -408.092605)
			(xy 163.851331 -408.029525) (xy 163.877134 -407.969367) (xy 163.8935 -407.941018) (xy 163.896808 -407.93499)
			(xy 163.900418 -407.921729) (xy 163.900612 -407.914856) (xy 163.900612 -407.628852) (xy 163.901046 -407.618739)
			(xy 163.908802 -407.600057) (xy 163.923114 -407.585764) (xy 163.941806 -407.578033) (xy 163.95192 -407.577544)
			(xy 164.6682 -407.577544) (xy 164.678302 -407.578084) (xy 164.696969 -407.585811) (xy 164.711262 -407.60009)
			(xy 164.719007 -407.618751) (xy 164.719508 -407.628852) (xy 164.719508 -407.914856) (xy 164.719716 -407.921728)
			(xy 164.723313 -407.934991) (xy 164.72662 -407.941018) (xy 164.742995 -407.969362) (xy 164.768794 -408.029524)
			(xy 164.786281 -408.092605) (xy 164.795139 -408.157463) (xy 164.795708 -408.190192) (xy 164.79516 -408.222922)
			(xy 164.786299 -408.287781) (xy 164.768804 -408.350861) (xy 164.742991 -408.411019) (xy 164.72662 -408.439366)
			(xy 164.723319 -408.445397) (xy 164.719704 -408.458656) (xy 164.719508 -408.465528) (xy 164.719508 -409.214828)
			(xy 164.719688 -409.221702) (xy 164.723304 -409.234965) (xy 164.72662 -409.24099) (xy 164.742984 -409.26934)
			(xy 164.768785 -409.3295) (xy 164.786276 -409.392579) (xy 164.795137 -409.457435) (xy 164.795708 -409.490164)
			(xy 164.795147 -409.522894) (xy 164.78629 -409.587752) (xy 164.768798 -409.650832) (xy 164.742989 -409.71099)
			(xy 164.72662 -409.739338) (xy 164.723293 -409.745357) (xy 164.719695 -409.758625) (xy 164.719508 -409.7655)
			(xy 164.719508 -410.051504) (xy 164.719018 -410.061612) (xy 164.711281 -410.080289) (xy 164.696985 -410.094583)
			(xy 164.678308 -410.102319) (xy 164.6682 -410.102812) (xy 163.95192 -410.102812) (xy 163.9418 -410.102368)
			(xy 163.923099 -410.094629) (xy 163.908785 -410.080321) (xy 163.901037 -410.061624) (xy 163.900612 -410.051504)
			(xy 163.900612 -409.7655) (xy 163.900419 -409.758627) (xy 163.896811 -409.745364) (xy 163.8935 -409.739338)
			(xy 163.87715 -409.71098) (xy 163.851344 -409.650824) (xy 163.83385 -409.587747) (xy 163.824985 -409.522892)
			(xy 163.824412 -409.490164) (xy 162.551703 -409.490164) (xy 162.542837 -409.510837) (xy 162.526472 -409.539186)
			(xy 162.52316 -409.545212) (xy 162.519553 -409.558475) (xy 162.51936 -409.565348) (xy 162.51936 -410.314648)
			(xy 162.519577 -410.321519) (xy 162.523169 -410.334782) (xy 162.526472 -410.34081) (xy 162.542839 -410.369159)
			(xy 162.568641 -410.429318) (xy 162.58613 -410.492398) (xy 162.59499 -410.557255) (xy 162.59556 -410.589984)
			(xy 162.595001 -410.622705) (xy 166.024899 -410.622705) (xy 166.024901 -410.557267) (xy 166.033687 -410.492422)
			(xy 166.051097 -410.429343) (xy 166.076817 -410.369171) (xy 166.09314 -410.34081) (xy 166.096446 -410.334781)
			(xy 166.100058 -410.321521) (xy 166.100252 -410.314648) (xy 166.100252 -409.565348) (xy 166.100048 -409.558476)
			(xy 166.096449 -409.545213) (xy 166.09314 -409.539186) (xy 166.076828 -409.510819) (xy 166.051109 -409.450649)
			(xy 166.0337 -409.387572) (xy 166.024915 -409.322728) (xy 166.024914 -409.257292) (xy 166.033696 -409.192448)
			(xy 166.051102 -409.12937) (xy 166.076819 -409.069199) (xy 166.09314 -409.040838) (xy 166.096437 -409.034804)
			(xy 166.100054 -409.021548) (xy 166.100252 -409.014676) (xy 166.100252 -408.728672) (xy 166.100698 -408.718522)
			(xy 166.108493 -408.699778) (xy 166.122882 -408.685458) (xy 166.141662 -408.67775) (xy 166.151814 -408.677364)
			(xy 166.868094 -408.677364) (xy 166.878223 -408.677832) (xy 166.896949 -408.685562) (xy 166.911306 -408.699855)
			(xy 166.919121 -408.718545) (xy 166.919656 -408.728672) (xy 166.919656 -409.014676) (xy 166.91985 -409.021549)
			(xy 166.923456 -409.034812) (xy 166.926768 -409.040838) (xy 166.9431 -409.069194) (xy 166.968816 -409.129366)
			(xy 166.986223 -409.192446) (xy 166.995005 -409.257292) (xy 166.995004 -409.322729) (xy 166.986219 -409.387574)
			(xy 166.96881 -409.450653) (xy 166.943091 -409.510825) (xy 166.936148 -409.522888) (xy 168.225043 -409.522888)
			(xy 168.225047 -409.45745) (xy 168.233834 -409.392604) (xy 168.251245 -409.329524) (xy 168.276965 -409.269352)
			(xy 168.293288 -409.24099) (xy 168.296605 -409.234967) (xy 168.30021 -409.221702) (xy 168.3004 -409.214828)
			(xy 168.3004 -408.465528) (xy 168.300197 -408.458656) (xy 168.296596 -408.445393) (xy 168.293288 -408.439366)
			(xy 168.276961 -408.411008) (xy 168.251246 -408.350835) (xy 168.233841 -408.287756) (xy 168.225059 -408.222911)
			(xy 168.22506 -408.157475) (xy 168.233844 -408.09263) (xy 168.251251 -408.029552) (xy 168.276967 -407.96938)
			(xy 168.293288 -407.941018) (xy 168.296595 -407.93499) (xy 168.300206 -407.921729) (xy 168.3004 -407.914856)
			(xy 168.3004 -407.628852) (xy 168.300782 -407.618695) (xy 168.308594 -407.599941) (xy 168.323002 -407.58562)
			(xy 168.341802 -407.577922) (xy 168.351962 -407.577544) (xy 169.068242 -407.577544) (xy 169.078372 -407.577992)
			(xy 169.097095 -407.585735) (xy 169.11145 -407.600032) (xy 169.119267 -407.618724) (xy 169.119804 -407.628852)
			(xy 169.119804 -407.914856) (xy 169.120012 -407.921728) (xy 169.123609 -407.934991) (xy 169.126916 -407.941018)
			(xy 169.143233 -407.969383) (xy 169.168953 -408.029552) (xy 169.186364 -408.09263) (xy 169.195149 -408.157475)
			(xy 169.19515 -408.222912) (xy 169.186367 -408.287756) (xy 169.168958 -408.350835) (xy 169.143239 -408.411005)
			(xy 169.126916 -408.439366) (xy 169.123614 -408.445397) (xy 169.12 -408.458656) (xy 169.119804 -408.465528)
			(xy 169.119804 -409.214828) (xy 169.119985 -409.221702) (xy 169.1236 -409.234965) (xy 169.126916 -409.24099)
			(xy 169.143209 -409.269368) (xy 169.168932 -409.329534) (xy 169.186345 -409.39261) (xy 169.195133 -409.457452)
			(xy 169.195137 -409.522887) (xy 169.186357 -409.58773) (xy 169.168952 -409.650807) (xy 169.143237 -409.710977)
			(xy 169.126916 -409.739338) (xy 169.123589 -409.745357) (xy 169.119991 -409.758625) (xy 169.119804 -409.7655)
			(xy 169.119804 -410.051504) (xy 169.119382 -410.061658) (xy 169.111586 -410.08041) (xy 169.097189 -410.094733)
			(xy 169.078398 -410.102433) (xy 169.068242 -410.102812) (xy 168.351962 -410.102812) (xy 168.341839 -410.102306)
			(xy 168.323127 -410.094575) (xy 168.308774 -410.080296) (xy 168.300947 -410.061624) (xy 168.3004 -410.051504)
			(xy 168.3004 -409.7655) (xy 168.300208 -409.758627) (xy 168.2966 -409.745364) (xy 168.293288 -409.739338)
			(xy 168.276937 -409.710993) (xy 168.251225 -409.650817) (xy 168.233822 -409.587735) (xy 168.225043 -409.522888)
			(xy 166.936148 -409.522888) (xy 166.926768 -409.539186) (xy 166.923456 -409.545212) (xy 166.919849 -409.558475)
			(xy 166.919656 -409.565348) (xy 166.919656 -410.314648) (xy 166.919861 -410.32152) (xy 166.923459 -410.334783)
			(xy 166.926768 -410.34081) (xy 166.943076 -410.369179) (xy 166.968795 -410.429348) (xy 166.986204 -410.492425)
			(xy 166.994989 -410.557269) (xy 166.99499 -410.589984) (xy 170.424348 -410.589984) (xy 170.424936 -410.557255)
			(xy 170.433786 -410.492398) (xy 170.45127 -410.429318) (xy 170.477071 -410.369159) (xy 170.493436 -410.34081)
			(xy 170.496742 -410.334781) (xy 170.500354 -410.321521) (xy 170.500548 -410.314648) (xy 170.500548 -409.565348)
			(xy 170.500344 -409.558476) (xy 170.496745 -409.545212) (xy 170.493436 -409.539186) (xy 170.477068 -409.510838)
			(xy 170.451266 -409.450678) (xy 170.433777 -409.387598) (xy 170.424918 -409.322741) (xy 170.424348 -409.290012)
			(xy 170.424904 -409.257282) (xy 170.433764 -409.192424) (xy 170.451257 -409.129344) (xy 170.477066 -409.069186)
			(xy 170.493436 -409.040838) (xy 170.496732 -409.034804) (xy 170.50035 -409.021548) (xy 170.500548 -409.014676)
			(xy 170.500548 -408.728672) (xy 170.501061 -408.718568) (xy 170.508798 -408.699899) (xy 170.523086 -408.685607)
			(xy 170.541752 -408.677864) (xy 170.551856 -408.677364) (xy 171.268136 -408.677364) (xy 171.278243 -408.677855)
			(xy 171.296915 -408.685598) (xy 171.311207 -408.699892) (xy 171.318947 -408.718565) (xy 171.319444 -408.728672)
			(xy 171.319444 -409.014676) (xy 171.31964 -409.021549) (xy 171.323245 -409.034812) (xy 171.326556 -409.040838)
			(xy 171.342932 -409.069181) (xy 171.368733 -409.129343) (xy 171.386219 -409.192424) (xy 171.395076 -409.257282)
			(xy 171.395644 -409.290012) (xy 171.395056 -409.322741) (xy 171.386206 -409.387598) (xy 171.368722 -409.450678)
			(xy 171.342921 -409.510837) (xy 171.335964 -409.522889) (xy 172.624819 -409.522889) (xy 172.624823 -409.457449)
			(xy 172.633612 -409.392602) (xy 172.651026 -409.329522) (xy 172.67675 -409.269351) (xy 172.693076 -409.24099)
			(xy 172.696393 -409.234966) (xy 172.699998 -409.221702) (xy 172.700188 -409.214828) (xy 172.700188 -408.465528)
			(xy 172.699987 -408.458655) (xy 172.696385 -408.445393) (xy 172.693076 -408.439366) (xy 172.676746 -408.411009)
			(xy 172.651027 -408.350837) (xy 172.633618 -408.287758) (xy 172.624835 -408.222912) (xy 172.624836 -408.157474)
			(xy 172.633621 -408.092629) (xy 172.651031 -408.02955) (xy 172.676752 -407.969379) (xy 172.693076 -407.941018)
			(xy 172.696383 -407.934989) (xy 172.699994 -407.921729) (xy 172.700188 -407.914856) (xy 172.700188 -407.628852)
			(xy 172.700582 -407.618696) (xy 172.708391 -407.599945) (xy 172.722796 -407.585624) (xy 172.741592 -407.577924)
			(xy 172.75175 -407.577544) (xy 173.46803 -407.577544) (xy 173.478159 -407.578002) (xy 173.496882 -407.58574)
			(xy 173.511237 -407.600035) (xy 173.519055 -407.618725) (xy 173.519592 -407.628852) (xy 173.519592 -407.914856)
			(xy 173.519802 -407.921728) (xy 173.523398 -407.934991) (xy 173.526704 -407.941018) (xy 173.543018 -407.969383)
			(xy 173.568734 -408.029554) (xy 173.586141 -408.092632) (xy 173.594925 -408.157475) (xy 173.594925 -408.190192)
			(xy 177.023784 -408.190192) (xy 177.027775 -408.128025) (xy 177.039684 -408.066878) (xy 177.059313 -408.007757)
			(xy 177.086342 -407.951631) (xy 177.120326 -407.899422) (xy 177.160708 -407.851987) (xy 177.206824 -407.810106)
			(xy 177.257916 -407.774466) (xy 177.313147 -407.745652) (xy 177.371609 -407.724138) (xy 177.432343 -407.710276)
			(xy 177.49435 -407.704294) (xy 177.556613 -407.70629) (xy 177.61811 -407.716233) (xy 177.677831 -407.733957)
			(xy 177.734794 -407.759174) (xy 177.788065 -407.791467) (xy 177.83677 -407.830307) (xy 177.880107 -407.875057)
			(xy 177.917367 -407.924981) (xy 177.947936 -407.97926) (xy 177.971314 -408.037003) (xy 177.987115 -408.097261)
			(xy 177.995081 -408.159044) (xy 177.99558 -408.190192) (xy 177.995081 -408.22134) (xy 177.987115 -408.283123)
			(xy 177.971314 -408.343381) (xy 177.947936 -408.401124) (xy 177.917367 -408.455403) (xy 177.880107 -408.505327)
			(xy 177.83677 -408.550077) (xy 177.788065 -408.588917) (xy 177.734794 -408.62121) (xy 177.677831 -408.646427)
			(xy 177.61811 -408.664151) (xy 177.556613 -408.674094) (xy 177.49435 -408.67609) (xy 177.432343 -408.670108)
			(xy 177.371609 -408.656246) (xy 177.313147 -408.634732) (xy 177.257916 -408.605918) (xy 177.206824 -408.570278)
			(xy 177.160708 -408.528397) (xy 177.120326 -408.480962) (xy 177.086342 -408.428753) (xy 177.059313 -408.372627)
			(xy 177.039684 -408.313506) (xy 177.027775 -408.252359) (xy 177.023784 -408.190192) (xy 173.594925 -408.190192)
			(xy 173.594926 -408.222911) (xy 173.586144 -408.287755) (xy 173.568739 -408.350833) (xy 173.543024 -408.411004)
			(xy 173.526704 -408.439366) (xy 173.523402 -408.445397) (xy 173.519788 -408.458656) (xy 173.519592 -408.465528)
			(xy 173.519592 -409.214828) (xy 173.519774 -409.221702) (xy 173.523389 -409.234965) (xy 173.526704 -409.24099)
			(xy 173.542994 -409.269369) (xy 173.568713 -409.329536) (xy 173.586122 -409.392611) (xy 173.594909 -409.457452)
			(xy 173.594913 -409.522886) (xy 173.586135 -409.587728) (xy 173.568733 -409.650805) (xy 173.543022 -409.710976)
			(xy 173.526704 -409.739338) (xy 173.523376 -409.745356) (xy 173.519779 -409.758625) (xy 173.519592 -409.7655)
			(xy 173.519592 -410.051504) (xy 173.519181 -410.061659) (xy 173.511383 -410.080413) (xy 173.496983 -410.094737)
			(xy 173.478187 -410.102435) (xy 173.46803 -410.102812) (xy 172.75175 -410.102812) (xy 172.741633 -410.102234)
			(xy 172.722923 -410.094532) (xy 172.708567 -410.080274) (xy 172.700736 -410.061618) (xy 172.700188 -410.051504)
			(xy 172.700188 -409.7655) (xy 172.699997 -409.758627) (xy 172.696388 -409.745364) (xy 172.693076 -409.739338)
			(xy 172.676722 -409.710994) (xy 172.651005 -409.650819) (xy 172.633599 -409.587737) (xy 172.624819 -409.522889)
			(xy 171.335964 -409.522889) (xy 171.326556 -409.539186) (xy 171.323251 -409.545215) (xy 171.319638 -409.558475)
			(xy 171.319444 -409.565348) (xy 171.319444 -410.314648) (xy 171.31965 -410.32152) (xy 171.323248 -410.334783)
			(xy 171.326556 -410.34081) (xy 171.342921 -410.369159) (xy 171.368724 -410.429319) (xy 171.386214 -410.492398)
			(xy 171.395074 -410.557255) (xy 171.395644 -410.589984) (xy 171.395088 -410.622705) (xy 174.824985 -410.622705)
			(xy 174.824987 -410.557267) (xy 174.833773 -410.492422) (xy 174.851182 -410.429343) (xy 174.876901 -410.369171)
			(xy 174.893224 -410.34081) (xy 174.896537 -410.334785) (xy 174.900143 -410.321521) (xy 174.900336 -410.314648)
			(xy 174.900336 -409.565348) (xy 174.900121 -409.558476) (xy 174.896528 -409.545214) (xy 174.893224 -409.539186)
			(xy 174.876912 -409.510819) (xy 174.851195 -409.450649) (xy 174.833786 -409.387572) (xy 174.825001 -409.322728)
			(xy 174.825 -409.257292) (xy 174.833782 -409.192449) (xy 174.851188 -409.12937) (xy 174.876903 -409.069199)
			(xy 174.893224 -409.040838) (xy 174.896527 -409.034808) (xy 174.90014 -409.021548) (xy 174.900336 -409.014676)
			(xy 174.900336 -408.728672) (xy 174.900699 -408.718512) (xy 174.908511 -408.699752) (xy 174.922926 -408.685428)
			(xy 174.941735 -408.677736) (xy 174.951898 -408.677364) (xy 175.668178 -408.677364) (xy 175.678306 -408.677845)
			(xy 175.697032 -408.68557) (xy 175.711389 -408.699859) (xy 175.719205 -408.718546) (xy 175.71974 -408.728672)
			(xy 175.71974 -409.014676) (xy 175.719936 -409.021549) (xy 175.723541 -409.034812) (xy 175.726852 -409.040838)
			(xy 175.743185 -409.069194) (xy 175.768902 -409.129366) (xy 175.786309 -409.192446) (xy 175.795092 -409.257291)
			(xy 175.79509 -409.322729) (xy 175.786305 -409.387574) (xy 175.768895 -409.450654) (xy 175.752007 -409.490164)
			(xy 177.023784 -409.490164) (xy 177.027775 -409.427997) (xy 177.039684 -409.36685) (xy 177.059313 -409.307729)
			(xy 177.086342 -409.251603) (xy 177.120326 -409.199394) (xy 177.160708 -409.151959) (xy 177.206824 -409.110078)
			(xy 177.257916 -409.074438) (xy 177.313147 -409.045624) (xy 177.371609 -409.02411) (xy 177.432343 -409.010248)
			(xy 177.49435 -409.004266) (xy 177.556613 -409.006262) (xy 177.61811 -409.016205) (xy 177.677831 -409.033929)
			(xy 177.734794 -409.059146) (xy 177.788065 -409.091439) (xy 177.83677 -409.130279) (xy 177.880107 -409.175029)
			(xy 177.917367 -409.224953) (xy 177.947936 -409.279232) (xy 177.9523 -409.290012) (xy 179.223932 -409.290012)
			(xy 179.227923 -409.227845) (xy 179.239832 -409.166698) (xy 179.259461 -409.107577) (xy 179.28649 -409.051451)
			(xy 179.320474 -408.999242) (xy 179.360856 -408.951807) (xy 179.406972 -408.909926) (xy 179.458064 -408.874286)
			(xy 179.513295 -408.845472) (xy 179.571757 -408.823958) (xy 179.632491 -408.810096) (xy 179.694498 -408.804114)
			(xy 179.756761 -408.80611) (xy 179.818258 -408.816053) (xy 179.877979 -408.833777) (xy 179.934942 -408.858994)
			(xy 179.988213 -408.891287) (xy 180.036918 -408.930127) (xy 180.080255 -408.974877) (xy 180.117515 -409.024801)
			(xy 180.148084 -409.07908) (xy 180.171462 -409.136823) (xy 180.187263 -409.197081) (xy 180.195229 -409.258864)
			(xy 180.195728 -409.290012) (xy 180.195229 -409.32116) (xy 180.187263 -409.382943) (xy 180.177397 -409.420568)
			(xy 186.579 -409.420568) (xy 186.583071 -409.364946) (xy 186.595197 -409.310509) (xy 186.61512 -409.258418)
			(xy 186.642416 -409.209783) (xy 186.676502 -409.16564) (xy 186.716651 -409.126931) (xy 186.762009 -409.09448)
			(xy 186.811609 -409.068979) (xy 186.864393 -409.050972) (xy 186.919236 -409.040842) (xy 186.97497 -409.038805)
			(xy 187.030407 -409.044905) (xy 187.084364 -409.059011) (xy 187.135693 -409.080823) (xy 187.183299 -409.109877)
			(xy 187.226167 -409.145552) (xy 187.263384 -409.187089) (xy 187.294157 -409.233602) (xy 187.317829 -409.284099)
			(xy 187.333897 -409.337506) (xy 187.342017 -409.392682) (xy 187.342526 -409.420568) (xy 187.342017 -409.448454)
			(xy 187.333897 -409.50363) (xy 187.317829 -409.557037) (xy 187.294157 -409.607534) (xy 187.263384 -409.654047)
			(xy 187.226167 -409.695584) (xy 187.183299 -409.731259) (xy 187.135693 -409.760313) (xy 187.084364 -409.782125)
			(xy 187.030407 -409.796231) (xy 186.97497 -409.802331) (xy 186.919236 -409.800294) (xy 186.864393 -409.790164)
			(xy 186.811609 -409.772157) (xy 186.762009 -409.746656) (xy 186.716651 -409.714205) (xy 186.676502 -409.675496)
			(xy 186.642416 -409.631353) (xy 186.61512 -409.582718) (xy 186.595197 -409.530627) (xy 186.583071 -409.47619)
			(xy 186.579 -409.420568) (xy 180.177397 -409.420568) (xy 180.171462 -409.443201) (xy 180.148084 -409.500944)
			(xy 180.117515 -409.555223) (xy 180.080255 -409.605147) (xy 180.036918 -409.649897) (xy 179.988213 -409.688737)
			(xy 179.934942 -409.72103) (xy 179.877979 -409.746247) (xy 179.818258 -409.763971) (xy 179.756761 -409.773914)
			(xy 179.694498 -409.77591) (xy 179.632491 -409.769928) (xy 179.571757 -409.756066) (xy 179.513295 -409.734552)
			(xy 179.458064 -409.705738) (xy 179.406972 -409.670098) (xy 179.360856 -409.628217) (xy 179.320474 -409.580782)
			(xy 179.28649 -409.528573) (xy 179.259461 -409.472447) (xy 179.239832 -409.413326) (xy 179.227923 -409.352179)
			(xy 179.223932 -409.290012) (xy 177.9523 -409.290012) (xy 177.971314 -409.336975) (xy 177.987115 -409.397233)
			(xy 177.995081 -409.459016) (xy 177.99558 -409.490164) (xy 177.995081 -409.521312) (xy 177.987115 -409.583095)
			(xy 177.971314 -409.643353) (xy 177.947936 -409.701096) (xy 177.917367 -409.755375) (xy 177.880107 -409.805299)
			(xy 177.83677 -409.850049) (xy 177.788065 -409.888889) (xy 177.734794 -409.921182) (xy 177.677831 -409.946399)
			(xy 177.61811 -409.964123) (xy 177.556613 -409.974066) (xy 177.49435 -409.976062) (xy 177.432343 -409.97008)
			(xy 177.371609 -409.956218) (xy 177.313147 -409.934704) (xy 177.257916 -409.90589) (xy 177.206824 -409.87025)
			(xy 177.160708 -409.828369) (xy 177.120326 -409.780934) (xy 177.086342 -409.728725) (xy 177.059313 -409.672599)
			(xy 177.039684 -409.613478) (xy 177.027775 -409.552331) (xy 177.023784 -409.490164) (xy 175.752007 -409.490164)
			(xy 175.743175 -409.510825) (xy 175.726852 -409.539186) (xy 175.723546 -409.545215) (xy 175.719934 -409.558475)
			(xy 175.71974 -409.565348) (xy 175.71974 -410.314648) (xy 175.719947 -410.32152) (xy 175.723544 -410.334783)
			(xy 175.726852 -410.34081) (xy 175.743161 -410.369179) (xy 175.76888 -410.429348) (xy 175.78629 -410.492425)
			(xy 175.795076 -410.557268) (xy 175.795076 -410.589984) (xy 179.223932 -410.589984) (xy 179.227923 -410.527817)
			(xy 179.239832 -410.46667) (xy 179.259461 -410.407549) (xy 179.28649 -410.351423) (xy 179.320474 -410.299214)
			(xy 179.360856 -410.251779) (xy 179.406972 -410.209898) (xy 179.458064 -410.174258) (xy 179.513295 -410.145444)
			(xy 179.571757 -410.12393) (xy 179.632491 -410.110068) (xy 179.694498 -410.104086) (xy 179.756761 -410.106082)
			(xy 179.818258 -410.116025) (xy 179.877979 -410.133749) (xy 179.934942 -410.158966) (xy 179.988213 -410.191259)
			(xy 180.036918 -410.230099) (xy 180.080255 -410.274849) (xy 180.117515 -410.324773) (xy 180.148084 -410.379052)
			(xy 180.171462 -410.436795) (xy 180.187263 -410.497053) (xy 180.195229 -410.558836) (xy 180.195728 -410.589984)
			(xy 180.195229 -410.621132) (xy 180.187263 -410.682915) (xy 180.171462 -410.743173) (xy 180.148084 -410.800916)
			(xy 180.117515 -410.855195) (xy 180.080255 -410.905119) (xy 180.036918 -410.949869) (xy 179.988213 -410.988709)
			(xy 179.934942 -411.021002) (xy 179.896455 -411.03804) (xy 185.614054 -411.03804) (xy 185.618125 -410.982418)
			(xy 185.630251 -410.927981) (xy 185.650174 -410.87589) (xy 185.67747 -410.827255) (xy 185.711556 -410.783112)
			(xy 185.751705 -410.744403) (xy 185.797063 -410.711952) (xy 185.846663 -410.686451) (xy 185.899447 -410.668444)
			(xy 185.95429 -410.658314) (xy 186.010024 -410.656277) (xy 186.065461 -410.662377) (xy 186.119418 -410.676483)
			(xy 186.170747 -410.698295) (xy 186.218353 -410.727349) (xy 186.261221 -410.763024) (xy 186.298438 -410.804561)
			(xy 186.329211 -410.851074) (xy 186.352883 -410.901571) (xy 186.368951 -410.954978) (xy 186.377071 -411.010154)
			(xy 186.37758 -411.03804) (xy 186.377071 -411.065926) (xy 186.368951 -411.121102) (xy 186.352883 -411.174509)
			(xy 186.329211 -411.225006) (xy 186.298438 -411.271519) (xy 186.261221 -411.313056) (xy 186.218353 -411.348731)
			(xy 186.170747 -411.377785) (xy 186.119418 -411.399597) (xy 186.065461 -411.413703) (xy 186.010024 -411.419803)
			(xy 185.95429 -411.417766) (xy 185.899447 -411.407636) (xy 185.846663 -411.389629) (xy 185.797063 -411.364128)
			(xy 185.751705 -411.331677) (xy 185.711556 -411.292968) (xy 185.67747 -411.248825) (xy 185.650174 -411.20019)
			(xy 185.630251 -411.148099) (xy 185.618125 -411.093662) (xy 185.614054 -411.03804) (xy 179.896455 -411.03804)
			(xy 179.877979 -411.046219) (xy 179.818258 -411.063943) (xy 179.756761 -411.073886) (xy 179.694498 -411.075882)
			(xy 179.632491 -411.0699) (xy 179.571757 -411.056038) (xy 179.513295 -411.034524) (xy 179.458064 -411.00571)
			(xy 179.406972 -410.97007) (xy 179.360856 -410.928189) (xy 179.320474 -410.880754) (xy 179.28649 -410.828545)
			(xy 179.259461 -410.772419) (xy 179.239832 -410.713298) (xy 179.227923 -410.652151) (xy 179.223932 -410.589984)
			(xy 175.795076 -410.589984) (xy 175.795077 -410.622704) (xy 175.786296 -410.687548) (xy 175.768889 -410.750626)
			(xy 175.743173 -410.810797) (xy 175.726852 -410.839158) (xy 175.723556 -410.845192) (xy 175.719938 -410.858448)
			(xy 175.71974 -410.86532) (xy 175.71974 -411.151324) (xy 175.719299 -411.161475) (xy 175.711503 -411.18022)
			(xy 175.697113 -411.194541) (xy 175.678331 -411.202247) (xy 175.668178 -411.202632) (xy 174.951898 -411.202632)
			(xy 174.941768 -411.202174) (xy 174.923041 -411.194441) (xy 174.908684 -411.180145) (xy 174.90087 -411.161452)
			(xy 174.900336 -411.151324) (xy 174.900336 -410.86532) (xy 174.900132 -410.858448) (xy 174.896531 -410.845185)
			(xy 174.893224 -410.839158) (xy 174.876889 -410.810804) (xy 174.851173 -410.750631) (xy 174.833767 -410.687551)
			(xy 174.824985 -410.622705) (xy 171.395088 -410.622705) (xy 171.395088 -410.622714) (xy 171.386228 -410.687572)
			(xy 171.368735 -410.750652) (xy 171.342926 -410.81081) (xy 171.326556 -410.839158) (xy 171.323261 -410.845192)
			(xy 171.319642 -410.858448) (xy 171.319444 -410.86532) (xy 171.319444 -411.151324) (xy 171.318936 -411.161429)
			(xy 171.311198 -411.180099) (xy 171.296909 -411.194392) (xy 171.278241 -411.202133) (xy 171.268136 -411.202632)
			(xy 170.551856 -411.202632) (xy 170.541748 -411.202152) (xy 170.523075 -411.194405) (xy 170.508783 -411.180108)
			(xy 170.501044 -411.161432) (xy 170.500548 -411.151324) (xy 170.500548 -410.86532) (xy 170.500355 -410.858447)
			(xy 170.496748 -410.845184) (xy 170.493436 -410.839158) (xy 170.477057 -410.810816) (xy 170.451258 -410.750654)
			(xy 170.433772 -410.687572) (xy 170.424916 -410.622714) (xy 170.424348 -410.589984) (xy 166.99499 -410.589984)
			(xy 166.994991 -410.622704) (xy 166.98621 -410.687548) (xy 166.968804 -410.750626) (xy 166.943089 -410.810797)
			(xy 166.926768 -410.839158) (xy 166.923466 -410.845189) (xy 166.919853 -410.858448) (xy 166.919656 -410.86532)
			(xy 166.919656 -411.151324) (xy 166.919199 -411.161473) (xy 166.911406 -411.180215) (xy 166.897021 -411.194535)
			(xy 166.878245 -411.202244) (xy 166.868094 -411.202632) (xy 166.151814 -411.202632) (xy 166.141685 -411.202161)
			(xy 166.122959 -411.194433) (xy 166.108601 -411.180141) (xy 166.100786 -411.161451) (xy 166.100252 -411.151324)
			(xy 166.100252 -410.86532) (xy 166.100058 -410.858447) (xy 166.096452 -410.845184) (xy 166.09314 -410.839158)
			(xy 166.076804 -410.810804) (xy 166.051088 -410.750631) (xy 166.033681 -410.687551) (xy 166.024899 -410.622705)
			(xy 162.595001 -410.622705) (xy 162.595001 -410.622714) (xy 162.586142 -410.687572) (xy 162.56865 -410.750652)
			(xy 162.542841 -410.81081) (xy 162.526472 -410.839158) (xy 162.52317 -410.845189) (xy 162.519557 -410.858448)
			(xy 162.51936 -410.86532) (xy 162.51936 -411.151324) (xy 162.519003 -411.161453) (xy 162.511239 -411.180165)
			(xy 162.496904 -411.19448) (xy 162.478182 -411.202217) (xy 162.468052 -411.202632) (xy 161.751772 -411.202632)
			(xy 161.741665 -411.202139) (xy 161.722993 -411.194398) (xy 161.7087 -411.180104) (xy 161.700961 -411.161431)
			(xy 161.700464 -411.151324) (xy 161.700464 -410.86532) (xy 161.700269 -410.858447) (xy 161.696663 -410.845184)
			(xy 161.693352 -410.839158) (xy 161.676975 -410.810815) (xy 161.651175 -410.750654) (xy 161.633688 -410.687572)
			(xy 161.624832 -410.622714) (xy 161.624264 -410.589984) (xy 154.576272 -410.589984) (xy 154.576272 -412.090108)
			(xy 159.42387 -412.090108) (xy 159.427861 -412.027941) (xy 159.43977 -411.966794) (xy 159.459399 -411.907673)
			(xy 159.486428 -411.851547) (xy 159.520412 -411.799338) (xy 159.560794 -411.751903) (xy 159.60691 -411.710022)
			(xy 159.658002 -411.674382) (xy 159.713233 -411.645568) (xy 159.771695 -411.624054) (xy 159.832429 -411.610192)
			(xy 159.894436 -411.60421) (xy 159.956699 -411.606206) (xy 160.018196 -411.616149) (xy 160.077917 -411.633873)
			(xy 160.13488 -411.65909) (xy 160.188151 -411.691383) (xy 160.236856 -411.730223) (xy 160.280193 -411.774973)
			(xy 160.317453 -411.824897) (xy 160.348022 -411.879176) (xy 160.3714 -411.936919) (xy 160.387201 -411.997177)
			(xy 160.395167 -412.05896) (xy 160.395666 -412.090108) (xy 163.823912 -412.090108) (xy 163.827903 -412.027941)
			(xy 163.839812 -411.966794) (xy 163.859441 -411.907673) (xy 163.88647 -411.851547) (xy 163.920454 -411.799338)
			(xy 163.960836 -411.751903) (xy 164.006952 -411.710022) (xy 164.058044 -411.674382) (xy 164.113275 -411.645568)
			(xy 164.171737 -411.624054) (xy 164.232471 -411.610192) (xy 164.294478 -411.60421) (xy 164.356741 -411.606206)
			(xy 164.418238 -411.616149) (xy 164.477959 -411.633873) (xy 164.534922 -411.65909) (xy 164.588193 -411.691383)
			(xy 164.636898 -411.730223) (xy 164.680235 -411.774973) (xy 164.717495 -411.824897) (xy 164.748064 -411.879176)
			(xy 164.771442 -411.936919) (xy 164.787243 -411.997177) (xy 164.795209 -412.05896) (xy 164.795708 -412.090108)
			(xy 168.223954 -412.090108) (xy 168.227945 -412.027941) (xy 168.239854 -411.966794) (xy 168.259483 -411.907673)
			(xy 168.286512 -411.851547) (xy 168.320496 -411.799338) (xy 168.360878 -411.751903) (xy 168.406994 -411.710022)
			(xy 168.458086 -411.674382) (xy 168.513317 -411.645568) (xy 168.571779 -411.624054) (xy 168.632513 -411.610192)
			(xy 168.69452 -411.60421) (xy 168.756783 -411.606206) (xy 168.81828 -411.616149) (xy 168.878001 -411.633873)
			(xy 168.934964 -411.65909) (xy 168.988235 -411.691383) (xy 169.03694 -411.730223) (xy 169.080277 -411.774973)
			(xy 169.117537 -411.824897) (xy 169.148106 -411.879176) (xy 169.171484 -411.936919) (xy 169.187285 -411.997177)
			(xy 169.195251 -412.05896) (xy 169.19575 -412.090108) (xy 172.623742 -412.090108) (xy 172.627733 -412.027941)
			(xy 172.639642 -411.966794) (xy 172.659271 -411.907673) (xy 172.6863 -411.851547) (xy 172.720284 -411.799338)
			(xy 172.760666 -411.751903) (xy 172.806782 -411.710022) (xy 172.857874 -411.674382) (xy 172.913105 -411.645568)
			(xy 172.971567 -411.624054) (xy 173.032301 -411.610192) (xy 173.094308 -411.60421) (xy 173.156571 -411.606206)
			(xy 173.218068 -411.616149) (xy 173.277789 -411.633873) (xy 173.334752 -411.65909) (xy 173.388023 -411.691383)
			(xy 173.436728 -411.730223) (xy 173.480065 -411.774973) (xy 173.517325 -411.824897) (xy 173.547894 -411.879176)
			(xy 173.571272 -411.936919) (xy 173.587073 -411.997177) (xy 173.595039 -412.05896) (xy 173.595538 -412.090108)
			(xy 177.023784 -412.090108) (xy 177.027775 -412.027941) (xy 177.039684 -411.966794) (xy 177.059313 -411.907673)
			(xy 177.086342 -411.851547) (xy 177.120326 -411.799338) (xy 177.160708 -411.751903) (xy 177.206824 -411.710022)
			(xy 177.257916 -411.674382) (xy 177.313147 -411.645568) (xy 177.371609 -411.624054) (xy 177.432343 -411.610192)
			(xy 177.49435 -411.60421) (xy 177.556613 -411.606206) (xy 177.61811 -411.616149) (xy 177.677831 -411.633873)
			(xy 177.734794 -411.65909) (xy 177.788065 -411.691383) (xy 177.83677 -411.730223) (xy 177.880107 -411.774973)
			(xy 177.917367 -411.824897) (xy 177.947936 -411.879176) (xy 177.971314 -411.936919) (xy 177.987115 -411.997177)
			(xy 177.995081 -412.05896) (xy 177.99558 -412.090108) (xy 177.995081 -412.121256) (xy 177.987115 -412.183039)
			(xy 177.971314 -412.243297) (xy 177.947936 -412.30104) (xy 177.917367 -412.355319) (xy 177.880107 -412.405243)
			(xy 177.83677 -412.449993) (xy 177.788065 -412.488833) (xy 177.734794 -412.521126) (xy 177.677831 -412.546343)
			(xy 177.61811 -412.564067) (xy 177.556613 -412.57401) (xy 177.49435 -412.576006) (xy 177.432343 -412.570024)
			(xy 177.371609 -412.556162) (xy 177.313147 -412.534648) (xy 177.257916 -412.505834) (xy 177.206824 -412.470194)
			(xy 177.160708 -412.428313) (xy 177.120326 -412.380878) (xy 177.086342 -412.328669) (xy 177.059313 -412.272543)
			(xy 177.039684 -412.213422) (xy 177.027775 -412.152275) (xy 177.023784 -412.090108) (xy 173.595538 -412.090108)
			(xy 173.595039 -412.121256) (xy 173.587073 -412.183039) (xy 173.571272 -412.243297) (xy 173.547894 -412.30104)
			(xy 173.517325 -412.355319) (xy 173.480065 -412.405243) (xy 173.436728 -412.449993) (xy 173.388023 -412.488833)
			(xy 173.334752 -412.521126) (xy 173.277789 -412.546343) (xy 173.218068 -412.564067) (xy 173.156571 -412.57401)
			(xy 173.094308 -412.576006) (xy 173.032301 -412.570024) (xy 172.971567 -412.556162) (xy 172.913105 -412.534648)
			(xy 172.857874 -412.505834) (xy 172.806782 -412.470194) (xy 172.760666 -412.428313) (xy 172.720284 -412.380878)
			(xy 172.6863 -412.328669) (xy 172.659271 -412.272543) (xy 172.639642 -412.213422) (xy 172.627733 -412.152275)
			(xy 172.623742 -412.090108) (xy 169.19575 -412.090108) (xy 169.195251 -412.121256) (xy 169.187285 -412.183039)
			(xy 169.171484 -412.243297) (xy 169.148106 -412.30104) (xy 169.117537 -412.355319) (xy 169.080277 -412.405243)
			(xy 169.03694 -412.449993) (xy 168.988235 -412.488833) (xy 168.934964 -412.521126) (xy 168.878001 -412.546343)
			(xy 168.81828 -412.564067) (xy 168.756783 -412.57401) (xy 168.69452 -412.576006) (xy 168.632513 -412.570024)
			(xy 168.571779 -412.556162) (xy 168.513317 -412.534648) (xy 168.458086 -412.505834) (xy 168.406994 -412.470194)
			(xy 168.360878 -412.428313) (xy 168.320496 -412.380878) (xy 168.286512 -412.328669) (xy 168.259483 -412.272543)
			(xy 168.239854 -412.213422) (xy 168.227945 -412.152275) (xy 168.223954 -412.090108) (xy 164.795708 -412.090108)
			(xy 164.795209 -412.121256) (xy 164.787243 -412.183039) (xy 164.771442 -412.243297) (xy 164.748064 -412.30104)
			(xy 164.717495 -412.355319) (xy 164.680235 -412.405243) (xy 164.636898 -412.449993) (xy 164.588193 -412.488833)
			(xy 164.534922 -412.521126) (xy 164.477959 -412.546343) (xy 164.418238 -412.564067) (xy 164.356741 -412.57401)
			(xy 164.294478 -412.576006) (xy 164.232471 -412.570024) (xy 164.171737 -412.556162) (xy 164.113275 -412.534648)
			(xy 164.058044 -412.505834) (xy 164.006952 -412.470194) (xy 163.960836 -412.428313) (xy 163.920454 -412.380878)
			(xy 163.88647 -412.328669) (xy 163.859441 -412.272543) (xy 163.839812 -412.213422) (xy 163.827903 -412.152275)
			(xy 163.823912 -412.090108) (xy 160.395666 -412.090108) (xy 160.395167 -412.121256) (xy 160.387201 -412.183039)
			(xy 160.3714 -412.243297) (xy 160.348022 -412.30104) (xy 160.317453 -412.355319) (xy 160.280193 -412.405243)
			(xy 160.236856 -412.449993) (xy 160.188151 -412.488833) (xy 160.13488 -412.521126) (xy 160.077917 -412.546343)
			(xy 160.018196 -412.564067) (xy 159.956699 -412.57401) (xy 159.894436 -412.576006) (xy 159.832429 -412.570024)
			(xy 159.771695 -412.556162) (xy 159.713233 -412.534648) (xy 159.658002 -412.505834) (xy 159.60691 -412.470194)
			(xy 159.560794 -412.428313) (xy 159.520412 -412.380878) (xy 159.486428 -412.328669) (xy 159.459399 -412.272543)
			(xy 159.43977 -412.213422) (xy 159.427861 -412.152275) (xy 159.42387 -412.090108) (xy 154.576272 -412.090108)
			(xy 154.576272 -413.479234) (xy 188.424056 -413.479234) (xy 188.428127 -413.423612) (xy 188.440253 -413.369175)
			(xy 188.460176 -413.317084) (xy 188.487472 -413.268449) (xy 188.521558 -413.224306) (xy 188.561707 -413.185597)
			(xy 188.607065 -413.153146) (xy 188.656665 -413.127645) (xy 188.709449 -413.109638) (xy 188.764292 -413.099508)
			(xy 188.820026 -413.097471) (xy 188.875463 -413.103571) (xy 188.92942 -413.117677) (xy 188.980749 -413.139489)
			(xy 189.028355 -413.168543) (xy 189.071223 -413.204218) (xy 189.10844 -413.245755) (xy 189.139213 -413.292268)
			(xy 189.162885 -413.342765) (xy 189.169325 -413.364172) (xy 197.320914 -413.364172) (xy 197.324985 -413.30855)
			(xy 197.337111 -413.254113) (xy 197.357034 -413.202022) (xy 197.38433 -413.153387) (xy 197.418416 -413.109244)
			(xy 197.458565 -413.070535) (xy 197.503923 -413.038084) (xy 197.553523 -413.012583) (xy 197.606307 -412.994576)
			(xy 197.66115 -412.984446) (xy 197.716884 -412.982409) (xy 197.772321 -412.988509) (xy 197.826278 -413.002615)
			(xy 197.877607 -413.024427) (xy 197.925213 -413.053481) (xy 197.968081 -413.089156) (xy 198.005298 -413.130693)
			(xy 198.036071 -413.177206) (xy 198.059743 -413.227703) (xy 198.075811 -413.28111) (xy 198.083931 -413.336286)
			(xy 198.08444 -413.364172) (xy 198.083931 -413.392058) (xy 198.075811 -413.447234) (xy 198.059743 -413.500641)
			(xy 198.036071 -413.551138) (xy 198.005298 -413.597651) (xy 197.968081 -413.639188) (xy 197.925213 -413.674863)
			(xy 197.877607 -413.703917) (xy 197.826278 -413.725729) (xy 197.772321 -413.739835) (xy 197.716884 -413.745935)
			(xy 197.66115 -413.743898) (xy 197.606307 -413.733768) (xy 197.553523 -413.715761) (xy 197.503923 -413.69026)
			(xy 197.458565 -413.657809) (xy 197.418416 -413.6191) (xy 197.38433 -413.574957) (xy 197.357034 -413.526322)
			(xy 197.337111 -413.474231) (xy 197.324985 -413.419794) (xy 197.320914 -413.364172) (xy 189.169325 -413.364172)
			(xy 189.178953 -413.396172) (xy 189.187073 -413.451348) (xy 189.187582 -413.479234) (xy 189.187073 -413.50712)
			(xy 189.178953 -413.562296) (xy 189.162885 -413.615703) (xy 189.139213 -413.6662) (xy 189.10844 -413.712713)
			(xy 189.071223 -413.75425) (xy 189.028355 -413.789925) (xy 188.980749 -413.818979) (xy 188.92942 -413.840791)
			(xy 188.875463 -413.854897) (xy 188.820026 -413.860997) (xy 188.764292 -413.85896) (xy 188.709449 -413.84883)
			(xy 188.656665 -413.830823) (xy 188.607065 -413.805322) (xy 188.561707 -413.772871) (xy 188.521558 -413.734162)
			(xy 188.487472 -413.690019) (xy 188.460176 -413.641384) (xy 188.440253 -413.589293) (xy 188.428127 -413.534856)
			(xy 188.424056 -413.479234) (xy 154.576272 -413.479234) (xy 154.576272 -415.15919) (xy 187.152532 -415.15919)
			(xy 187.156603 -415.103568) (xy 187.168729 -415.049131) (xy 187.188652 -414.99704) (xy 187.215948 -414.948405)
			(xy 187.250034 -414.904262) (xy 187.290183 -414.865553) (xy 187.335541 -414.833102) (xy 187.385141 -414.807601)
			(xy 187.437925 -414.789594) (xy 187.492768 -414.779464) (xy 187.548502 -414.777427) (xy 187.603939 -414.783527)
			(xy 187.657896 -414.797633) (xy 187.709225 -414.819445) (xy 187.756831 -414.848499) (xy 187.799699 -414.884174)
			(xy 187.836916 -414.925711) (xy 187.867689 -414.972224) (xy 187.891361 -415.022721) (xy 187.907429 -415.076128)
			(xy 187.915549 -415.131304) (xy 187.916058 -415.15919) (xy 187.915549 -415.187076) (xy 187.907429 -415.242252)
			(xy 187.891361 -415.295659) (xy 187.867689 -415.346156) (xy 187.836916 -415.392669) (xy 187.799699 -415.434206)
			(xy 187.756831 -415.469881) (xy 187.709225 -415.498935) (xy 187.657896 -415.520747) (xy 187.603939 -415.534853)
			(xy 187.548502 -415.540953) (xy 187.492768 -415.538916) (xy 187.437925 -415.528786) (xy 187.385141 -415.510779)
			(xy 187.335541 -415.485278) (xy 187.290183 -415.452827) (xy 187.250034 -415.414118) (xy 187.215948 -415.369975)
			(xy 187.188652 -415.32134) (xy 187.168729 -415.269249) (xy 187.156603 -415.214812) (xy 187.152532 -415.15919)
			(xy 154.576272 -415.15919) (xy 154.576272 -417.092892) (xy 154.576758 -417.102903) (xy 154.584415 -417.121402)
			(xy 154.598568 -417.135564) (xy 154.617062 -417.143235) (xy 154.627072 -417.143692)
		)
		(stroke
			(width 0)
			(type solid)
		)
		(fill yes)
		(layer "In5.Cu")
		(net "GND")
	)
	(gr_poly
		(pts
			(xy 28.674314 -93.449902) (xy 28.681485 -93.452612) (xy 28.69674 -93.454042) (xy 28.704286 -93.452696)
			(xy 28.71089 -93.451426) (xy 28.72359 -93.444568) (xy 34.8742 -87.294212) (xy 34.878088 -87.290077)
			(xy 34.884119 -87.280466) (xy 34.886138 -87.275162) (xy 34.88744 -87.271093) (xy 34.888851 -87.262669)
			(xy 34.888932 -87.258398) (xy 34.888932 -61.592714) (xy 34.888728 -61.586626) (xy 34.885782 -61.57481)
			(xy 34.88309 -61.569346) (xy 34.88309 -61.569092) (xy 34.869253 -61.541564) (xy 34.849672 -61.483151)
			(xy 34.839741 -61.42235) (xy 34.839148 -61.391546) (xy 34.839607 -61.364633) (xy 34.84717 -61.311341)
			(xy 34.86215 -61.259642) (xy 34.884252 -61.210563) (xy 34.913035 -61.165079) (xy 34.947928 -61.124095)
			(xy 34.988237 -61.088424) (xy 35.033162 -61.058776) (xy 35.081809 -61.035739) (xy 35.107372 -61.02731)
			(xy 35.110166 -61.026548) (xy 35.115107 -61.024462) (xy 35.124064 -61.018565) (xy 35.127946 -61.014864)
			(xy 35.223196 -60.919614) (xy 35.416998 -60.726066) (xy 35.422811 -60.719639) (xy 35.430083 -60.703923)
			(xy 35.431222 -60.695332) (xy 35.431476 -60.690506) (xy 35.431476 -58.912252) (xy 35.430782 -58.900384)
			(xy 35.420051 -58.879203) (xy 35.410902 -58.871612) (xy 35.34537 -58.823098) (xy 35.340621 -58.819756)
			(xy 35.329975 -58.815127) (xy 35.324288 -58.813954) (xy 35.31235 -58.811668) (xy 35.300666 -58.815224)
			(xy 35.27404 -58.822667) (xy 35.219342 -58.8307) (xy 35.1917 -58.831226) (xy 35.190938 -58.831226)
			(xy 35.163682 -58.830766) (xy 35.109724 -58.823013) (xy 35.057419 -58.807659) (xy 35.007832 -58.785018)
			(xy 34.961972 -58.755549) (xy 34.920773 -58.719854) (xy 34.885073 -58.678658) (xy 34.8556 -58.632801)
			(xy 34.832954 -58.583216) (xy 34.817595 -58.530913) (xy 34.809837 -58.476956) (xy 34.809837 -58.422444)
			(xy 34.817595 -58.368487) (xy 34.832954 -58.316184) (xy 34.8556 -58.266599) (xy 34.885073 -58.220742)
			(xy 34.920773 -58.179546) (xy 34.961972 -58.143851) (xy 35.007832 -58.114382) (xy 35.057419 -58.091741)
			(xy 35.109724 -58.076387) (xy 35.163682 -58.068634) (xy 35.190938 -58.06821) (xy 35.1917 -58.06821)
			(xy 35.219344 -58.068715) (xy 35.274046 -58.076742) (xy 35.300666 -58.084212) (xy 35.306508 -58.08599)
			(xy 35.318446 -58.086752) (xy 35.324288 -58.085482) (xy 35.329966 -58.084279) (xy 35.340616 -58.079668)
			(xy 35.34537 -58.076338) (xy 35.410902 -58.027824) (xy 35.42009 -58.020264) (xy 35.430826 -57.999064)
			(xy 35.431476 -57.987184) (xy 35.431476 -54.976776) (xy 35.431077 -54.967254) (xy 35.424119 -54.949528)
			(xy 35.411171 -54.935563) (xy 35.402774 -54.931056) (xy 35.399726 -54.929786) (xy 35.392555 -54.927086)
			(xy 35.377303 -54.925674) (xy 35.369754 -54.926992) (xy 35.36315 -54.928262) (xy 35.35045 -54.93512)
			(xy 32.418274 -57.867296) (xy 33.64306 -57.867296) (xy 33.647131 -57.811674) (xy 33.659257 -57.757237)
			(xy 33.67918 -57.705146) (xy 33.706476 -57.656511) (xy 33.740562 -57.612368) (xy 33.780711 -57.573659)
			(xy 33.826069 -57.541208) (xy 33.875669 -57.515707) (xy 33.928453 -57.4977) (xy 33.983296 -57.48757)
			(xy 34.03903 -57.485533) (xy 34.094467 -57.491633) (xy 34.148424 -57.505739) (xy 34.199753 -57.527551)
			(xy 34.247359 -57.556605) (xy 34.290227 -57.59228) (xy 34.327444 -57.633817) (xy 34.358217 -57.68033)
			(xy 34.381889 -57.730827) (xy 34.397957 -57.784234) (xy 34.406077 -57.83941) (xy 34.406586 -57.867296)
			(xy 34.406077 -57.895182) (xy 34.397957 -57.950358) (xy 34.381889 -58.003765) (xy 34.358217 -58.054262)
			(xy 34.327444 -58.100775) (xy 34.290227 -58.142312) (xy 34.247359 -58.177987) (xy 34.199753 -58.207041)
			(xy 34.148424 -58.228853) (xy 34.094467 -58.242959) (xy 34.03903 -58.249059) (xy 33.983296 -58.247022)
			(xy 33.928453 -58.236892) (xy 33.875669 -58.218885) (xy 33.826069 -58.193384) (xy 33.780711 -58.160933)
			(xy 33.740562 -58.122224) (xy 33.706476 -58.078081) (xy 33.67918 -58.029446) (xy 33.659257 -57.977355)
			(xy 33.647131 -57.922918) (xy 33.64306 -57.867296) (xy 32.418274 -57.867296) (xy 32.116776 -58.168794)
			(xy 32.113047 -58.172653) (xy 32.107155 -58.18162) (xy 32.105092 -58.186574) (xy 32.10433 -58.189368)
			(xy 32.095894 -58.214925) (xy 32.072841 -58.263557) (xy 32.043183 -58.308467) (xy 32.007509 -58.348764)
			(xy 31.966526 -58.383648) (xy 31.921048 -58.412426) (xy 31.871977 -58.434529) (xy 31.820287 -58.449517)
			(xy 31.767003 -58.457093) (xy 31.740094 -58.457592) (xy 31.712842 -58.457128) (xy 31.658892 -58.44937)
			(xy 31.606596 -58.434014) (xy 31.557018 -58.411371) (xy 31.511167 -58.381902) (xy 31.469976 -58.346208)
			(xy 31.434284 -58.305016) (xy 31.404819 -58.259163) (xy 31.382179 -58.209583) (xy 31.366825 -58.157286)
			(xy 31.35907 -58.103336) (xy 31.358586 -58.076084) (xy 31.359048 -58.049184) (xy 31.366608 -57.995918)
			(xy 31.381577 -57.944242) (xy 31.403657 -57.895182) (xy 31.43241 -57.849711) (xy 31.467267 -57.808729)
			(xy 31.507535 -57.773051) (xy 31.552416 -57.743384) (xy 31.601019 -57.720317) (xy 31.626556 -57.711848)
			(xy 31.62681 -57.711848) (xy 31.629604 -57.711086) (xy 31.634549 -57.709006) (xy 31.643517 -57.70312)
			(xy 31.647384 -57.699402) (xy 34.905442 -54.441344) (xy 34.910423 -54.435842) (xy 34.917254 -54.422673)
			(xy 34.918904 -54.415436) (xy 34.91992 -54.405784) (xy 34.91992 -47.551594) (xy 34.919496 -47.541524)
			(xy 34.911783 -47.522919) (xy 34.904934 -47.515526) (xy 27.708098 -40.318436) (xy 27.704078 -40.314635)
			(xy 27.694722 -40.308734) (xy 27.689556 -40.306752) (xy 27.685377 -40.305342) (xy 27.676693 -40.30381)
			(xy 27.672284 -40.303704) (xy 26.478992 -40.303704) (xy 26.472904 -40.303909) (xy 26.461089 -40.306857)
			(xy 26.455624 -40.309546) (xy 26.45537 -40.309546) (xy 26.427842 -40.32338) (xy 26.369428 -40.342956)
			(xy 26.308627 -40.352883) (xy 26.277824 -40.353488) (xy 26.250571 -40.353026) (xy 26.196621 -40.345273)
			(xy 26.144323 -40.329919) (xy 26.094742 -40.307279) (xy 26.048888 -40.277814) (xy 26.007695 -40.242122)
			(xy 25.972001 -40.200931) (xy 25.942532 -40.155079) (xy 25.919889 -40.1055) (xy 25.904533 -40.053203)
			(xy 25.896775 -39.999253) (xy 25.896775 -39.944747) (xy 25.904533 -39.890797) (xy 25.919889 -39.8385)
			(xy 25.942532 -39.788921) (xy 25.972001 -39.743069) (xy 26.007695 -39.701878) (xy 26.048888 -39.666186)
			(xy 26.094742 -39.636721) (xy 26.144323 -39.614081) (xy 26.196621 -39.598727) (xy 26.250571 -39.590974)
			(xy 26.277824 -39.590472) (xy 26.308625 -39.591086) (xy 26.369421 -39.601027) (xy 26.427833 -39.6206)
			(xy 26.45537 -39.634414) (xy 26.455624 -39.634414) (xy 26.461097 -39.637082) (xy 26.472907 -39.640025)
			(xy 26.478992 -39.640256) (xy 27.744928 -39.640256) (xy 27.754448 -39.639856) (xy 27.772171 -39.632895)
			(xy 27.786131 -39.619945) (xy 27.790648 -39.611554) (xy 27.791918 -39.608506) (xy 27.79463 -39.601335)
			(xy 27.796065 -39.586079) (xy 27.794712 -39.578534) (xy 27.793442 -39.57193) (xy 27.786584 -39.55923)
			(xy 24.814784 -36.58743) (xy 24.80662 -36.58116) (xy 24.786959 -36.575122) (xy 24.776684 -36.575746)
			(xy 24.703532 -36.588446) (xy 24.697702 -36.589644) (xy 24.686791 -36.594392) (xy 24.681942 -36.597844)
			(xy 24.65959 -36.614354) (xy 24.652478 -36.62299) (xy 24.649684 -36.628324) (xy 24.637338 -36.651343)
			(xy 24.607297 -36.694076) (xy 24.571707 -36.732312) (xy 24.531235 -36.765335) (xy 24.486637 -36.792529)
			(xy 24.438746 -36.813386) (xy 24.388457 -36.827516) (xy 24.336712 -36.834654) (xy 24.310594 -36.83508)
			(xy 24.280226 -36.83449) (xy 24.220259 -36.824858) (xy 24.162577 -36.805838) (xy 24.135334 -36.792408)
			(xy 24.125682 -36.787582) (xy 24.11603 -36.78682) (xy 24.110661 -36.786571) (xy 24.100024 -36.788101)
			(xy 24.094948 -36.789868) (xy 24.02459 -36.815522) (xy 24.015998 -36.819059) (xy 24.001923 -36.831168)
			(xy 23.997158 -36.839144) (xy 23.983665 -36.87123) (xy 23.950141 -36.932234) (xy 23.909631 -36.988839)
			(xy 23.862702 -37.040249) (xy 23.810017 -37.085742) (xy 23.752316 -37.124676) (xy 23.690411 -37.156504)
			(xy 23.625173 -37.180778) (xy 23.557519 -37.197157) (xy 23.488402 -37.205411) (xy 23.453598 -37.20592)
			(xy 22.545802 -37.20592) (xy 22.536546 -37.206278) (xy 22.519228 -37.212801) (xy 22.51202 -37.21862)
			(xy 22.490938 -37.237162) (xy 22.484636 -37.243163) (xy 22.476176 -37.258357) (xy 22.474428 -37.26688)
			(xy 22.469349 -37.293066) (xy 22.452886 -37.3438) (xy 22.429522 -37.39175) (xy 22.399714 -37.435983)
			(xy 22.364041 -37.475637) (xy 22.323196 -37.509941) (xy 22.277976 -37.538228) (xy 22.229259 -37.559947)
			(xy 22.177993 -37.574675) (xy 22.125177 -37.582127) (xy 22.098508 -37.582602) (xy 22.071551 -37.582138)
			(xy 22.018173 -37.574553) (xy 21.966394 -37.559532) (xy 21.917243 -37.537374) (xy 21.8717 -37.508521)
			(xy 21.830669 -37.473546) (xy 21.794969 -37.433145) (xy 21.779738 -37.410898) (xy 21.778214 -37.408612)
			(xy 21.73605 -37.385752) (xy 21.726626 -37.38602) (xy 21.708997 -37.392666) (xy 21.70176 -37.398706)
			(xy 21.692616 -37.408104) (xy 21.669061 -37.431048) (xy 21.61766 -37.472064) (xy 21.561988 -37.507064)
			(xy 21.502746 -37.535606) (xy 21.440679 -37.557332) (xy 21.376568 -37.571967) (xy 21.311222 -37.579328)
			(xy 21.278342 -37.579808) (xy 20.813014 -37.579808) (xy 20.803972 -37.580211) (xy 20.787046 -37.586582)
			(xy 20.779994 -37.592254) (xy 20.725638 -37.64407) (xy 20.719546 -37.651047) (xy 20.712374 -37.668109)
			(xy 20.711668 -37.677344) (xy 20.71007 -37.705141) (xy 20.69982 -37.759867) (xy 20.681726 -37.812521)
			(xy 20.656171 -37.861987) (xy 20.623697 -37.907213) (xy 20.584995 -37.947239) (xy 20.540887 -37.981216)
			(xy 20.492309 -38.00842) (xy 20.440293 -38.028276) (xy 20.385943 -38.04036) (xy 20.330414 -38.044417)
			(xy 20.274885 -38.04036) (xy 20.220535 -38.028276) (xy 20.168519 -38.00842) (xy 20.119941 -37.981216)
			(xy 20.075833 -37.947239) (xy 20.037131 -37.907213) (xy 20.004657 -37.861987) (xy 19.979102 -37.812521)
			(xy 19.961008 -37.759867) (xy 19.950758 -37.705141) (xy 19.94916 -37.677344) (xy 19.948441 -37.66811)
			(xy 19.941285 -37.651043) (xy 19.93519 -37.64407) (xy 19.880834 -37.592254) (xy 19.873764 -37.586615)
			(xy 19.856848 -37.580255) (xy 19.847814 -37.579808) (xy 19.568922 -37.579808) (xy 19.536045 -37.579327)
			(xy 19.470709 -37.571931) (xy 19.406609 -37.557273) (xy 19.344551 -37.535538) (xy 19.285314 -37.506998)
			(xy 19.22964 -37.472012) (xy 19.178229 -37.431018) (xy 19.154648 -37.408104) (xy 19.08937 -37.342572)
			(xy 18.948146 -37.201094) (xy 18.941659 -37.195441) (xy 18.925951 -37.188444) (xy 18.917412 -37.187378)
			(xy 18.913094 -37.187124) (xy 18.586958 -37.187124) (xy 18.574408 -37.187776) (xy 18.552291 -37.199643)
			(xy 18.544794 -37.20973) (xy 18.524474 -37.24021) (xy 18.49755 -37.280596) (xy 18.494331 -37.285818)
			(xy 18.490222 -37.297374) (xy 18.489422 -37.303456) (xy 18.488152 -37.315902) (xy 18.493232 -37.328094)
			(xy 18.502561 -37.351477) (xy 18.515688 -37.400081) (xy 18.522311 -37.449988) (xy 18.522696 -37.47516)
			(xy 18.522235 -37.502414) (xy 18.514483 -37.556369) (xy 18.49913 -37.608671) (xy 18.47649 -37.658255)
			(xy 18.447023 -37.704113) (xy 18.411329 -37.745309) (xy 18.370135 -37.781006) (xy 18.32428 -37.810476)
			(xy 18.274697 -37.83312) (xy 18.222396 -37.848477) (xy 18.168442 -37.856233) (xy 18.141188 -37.856668)
			(xy 18.14068 -37.856668) (xy 18.112039 -37.856131) (xy 18.055407 -37.847523) (xy 18.000697 -37.830548)
			(xy 17.949138 -37.805588) (xy 17.901888 -37.773203) (xy 17.880584 -37.754052) (xy 17.877536 -37.751258)
			(xy 17.870033 -37.745842) (xy 17.852402 -37.740269) (xy 17.833941 -37.741305) (xy 17.817044 -37.748814)
			(xy 17.810226 -37.755068) (xy 16.835346 -38.729948) (xy 23.70102 -38.729948) (xy 23.70102 -38.675452)
			(xy 23.708776 -38.621511) (xy 23.724129 -38.569222) (xy 23.746767 -38.519651) (xy 23.776229 -38.473806)
			(xy 23.811916 -38.432621) (xy 23.853101 -38.396933) (xy 23.898946 -38.36747) (xy 23.948517 -38.344831)
			(xy 24.000805 -38.329477) (xy 24.054746 -38.321721) (xy 24.081994 -38.321234) (xy 24.110299 -38.321713)
			(xy 24.166288 -38.330064) (xy 24.220429 -38.3466) (xy 24.27153 -38.370957) (xy 24.31847 -38.4026)
			(xy 24.360216 -38.440834) (xy 24.395854 -38.484818) (xy 24.41067 -38.50894) (xy 24.41834 -38.520924)
			(xy 24.438944 -38.540523) (xy 24.46416 -38.553667) (xy 24.492027 -38.559332) (xy 24.520374 -38.557078)
			(xy 24.546994 -38.54708) (xy 24.569817 -38.530116) (xy 24.578818 -38.5191) (xy 24.596999 -38.49622)
			(xy 24.639163 -38.455756) (xy 24.687 -38.422189) (xy 24.739393 -38.396303) (xy 24.795118 -38.378701)
			(xy 24.852875 -38.369796) (xy 24.882094 -38.36924) (xy 24.909345 -38.36973) (xy 24.963292 -38.377487)
			(xy 25.015586 -38.392842) (xy 25.065162 -38.415484) (xy 25.111012 -38.44495) (xy 25.152202 -38.480641)
			(xy 25.187893 -38.521831) (xy 25.217358 -38.567681) (xy 25.239999 -38.617258) (xy 25.255354 -38.669552)
			(xy 25.26311 -38.723499) (xy 25.26311 -38.778001) (xy 25.255354 -38.831948) (xy 25.239999 -38.884242)
			(xy 25.217358 -38.933819) (xy 25.187893 -38.979669) (xy 25.152202 -39.020859) (xy 25.111012 -39.05655)
			(xy 25.065162 -39.086016) (xy 25.015586 -39.108658) (xy 24.963292 -39.124013) (xy 24.909345 -39.13177)
			(xy 24.882094 -39.132256) (xy 24.853789 -39.131792) (xy 24.797798 -39.123438) (xy 24.743657 -39.1069)
			(xy 24.692556 -39.08254) (xy 24.645616 -39.050895) (xy 24.60387 -39.01266) (xy 24.568234 -38.968673)
			(xy 24.553418 -38.94455) (xy 24.545763 -38.932555) (xy 24.525156 -38.912957) (xy 24.499936 -38.899815)
			(xy 24.472067 -38.894152) (xy 24.443718 -38.896408) (xy 24.417096 -38.906408) (xy 24.394272 -38.923373)
			(xy 24.38527 -38.93439) (xy 24.367093 -38.957274) (xy 24.324929 -38.997738) (xy 24.277091 -39.031305)
			(xy 24.224697 -39.057191) (xy 24.168971 -39.074791) (xy 24.111214 -39.083694) (xy 24.081994 -39.08425)
			(xy 24.054746 -39.083679) (xy 24.000805 -39.075923) (xy 23.948517 -39.060569) (xy 23.898946 -39.03793)
			(xy 23.853101 -39.008467) (xy 23.811916 -38.972779) (xy 23.776229 -38.931594) (xy 23.746767 -38.885749)
			(xy 23.724129 -38.836178) (xy 23.708776 -38.783889) (xy 23.70102 -38.729948) (xy 16.835346 -38.729948)
			(xy 14.296539 -41.268755) (xy 15.843927 -41.268755) (xy 15.843927 -41.214245) (xy 15.851685 -41.160289)
			(xy 15.867043 -41.107986) (xy 15.889688 -41.058401) (xy 15.919159 -41.012544) (xy 15.954857 -40.971348)
			(xy 15.996054 -40.935652) (xy 16.041912 -40.906182) (xy 16.091497 -40.883538) (xy 16.1438 -40.868182)
			(xy 16.197757 -40.860426) (xy 16.225012 -40.859964) (xy 16.253751 -40.86049) (xy 16.310578 -40.869114)
			(xy 16.365468 -40.886164) (xy 16.41718 -40.911254) (xy 16.464543 -40.943818) (xy 16.48587 -40.963088)
			(xy 16.492728 -40.969692) (xy 16.510762 -40.976804) (xy 16.599662 -40.976804) (xy 16.617696 -40.969692)
			(xy 16.624554 -40.963088) (xy 16.645883 -40.94382) (xy 16.693244 -40.911251) (xy 16.744955 -40.886157)
			(xy 16.799845 -40.869106) (xy 16.856673 -40.860484) (xy 16.885412 -40.859964) (xy 16.912661 -40.860507)
			(xy 16.966603 -40.868264) (xy 17.018892 -40.883619) (xy 17.068464 -40.90626) (xy 17.11431 -40.935724)
			(xy 17.155496 -40.971413) (xy 17.191183 -41.0126) (xy 17.220646 -41.058446) (xy 17.243285 -41.108019)
			(xy 17.258638 -41.160309) (xy 17.266394 -41.214251) (xy 17.266394 -41.268749) (xy 17.258638 -41.322691)
			(xy 17.243285 -41.374981) (xy 17.220646 -41.424554) (xy 17.191183 -41.4704) (xy 17.155496 -41.511587)
			(xy 17.11431 -41.547276) (xy 17.068464 -41.57674) (xy 17.018892 -41.599381) (xy 16.966603 -41.614736)
			(xy 16.912661 -41.622493) (xy 16.885412 -41.62298) (xy 16.856674 -41.622428) (xy 16.799849 -41.613809)
			(xy 16.74496 -41.596764) (xy 16.693248 -41.57168) (xy 16.645883 -41.539123) (xy 16.624554 -41.519856)
			(xy 16.617696 -41.513252) (xy 16.599662 -41.50614) (xy 16.510762 -41.50614) (xy 16.492728 -41.513252)
			(xy 16.48587 -41.519856) (xy 16.464537 -41.53912) (xy 16.417177 -41.571687) (xy 16.365467 -41.596781)
			(xy 16.310577 -41.613834) (xy 16.253751 -41.622458) (xy 16.225012 -41.62298) (xy 16.197757 -41.622574)
			(xy 16.1438 -41.614818) (xy 16.091497 -41.599462) (xy 16.041912 -41.576818) (xy 15.996054 -41.547348)
			(xy 15.954857 -41.511652) (xy 15.919159 -41.470456) (xy 15.889688 -41.424599) (xy 15.867043 -41.375014)
			(xy 15.851685 -41.322711) (xy 15.843927 -41.268755) (xy 14.296539 -41.268755) (xy 12.37742 -43.187874)
			(xy 12.353855 -43.210769) (xy 12.30247 -43.251719) (xy 12.246827 -43.286662) (xy 12.208269 -43.305222)
			(xy 18.307304 -43.305222) (xy 18.307782 -43.277852) (xy 18.315597 -43.223674) (xy 18.331083 -43.171171)
			(xy 18.353922 -43.121424) (xy 18.383644 -43.075456) (xy 18.401284 -43.054524) (xy 18.401538 -43.05427)
			(xy 18.407106 -43.047171) (xy 18.413363 -43.030264) (xy 18.41373 -43.02125) (xy 18.41373 -42.954194)
			(xy 18.413369 -42.945178) (xy 18.407123 -42.928261) (xy 18.401538 -42.921174) (xy 18.401284 -42.921174)
			(xy 18.401284 -42.92092) (xy 18.383638 -42.899993) (xy 18.353928 -42.854019) (xy 18.331094 -42.80427)
			(xy 18.315604 -42.751768) (xy 18.307777 -42.697591) (xy 18.307304 -42.670222) (xy 18.30784 -42.641484)
			(xy 18.316459 -42.584657) (xy 18.333507 -42.529766) (xy 18.358595 -42.478054) (xy 18.391158 -42.430691)
			(xy 18.410428 -42.409364) (xy 18.417032 -42.402506) (xy 18.424144 -42.384472) (xy 18.424144 -42.295572)
			(xy 18.417032 -42.277538) (xy 18.410428 -42.27068) (xy 18.391179 -42.249334) (xy 18.358613 -42.201975)
			(xy 18.333519 -42.150267) (xy 18.316468 -42.095379) (xy 18.307843 -42.038554) (xy 18.30784 -41.981078)
			(xy 18.31646 -41.924253) (xy 18.333508 -41.869363) (xy 18.358596 -41.817653) (xy 18.391159 -41.770291)
			(xy 18.410428 -41.748964) (xy 18.417032 -41.742106) (xy 18.424144 -41.724072) (xy 18.424144 -41.635172)
			(xy 18.417032 -41.617138) (xy 18.410428 -41.61028) (xy 18.391166 -41.588945) (xy 18.358599 -41.541585)
			(xy 18.333505 -41.489876) (xy 18.316452 -41.434987) (xy 18.307827 -41.37816) (xy 18.307304 -41.349422)
			(xy 18.30779 -41.322171) (xy 18.315546 -41.268223) (xy 18.330901 -41.215928) (xy 18.353543 -41.166351)
			(xy 18.383009 -41.120501) (xy 18.4187 -41.07931) (xy 18.459891 -41.043619) (xy 18.505741 -41.014153)
			(xy 18.555318 -40.991511) (xy 18.607613 -40.976156) (xy 18.661561 -40.9684) (xy 18.716063 -40.9684)
			(xy 18.739184 -40.971724) (xy 26.594052 -40.971724) (xy 26.598123 -40.916102) (xy 26.610249 -40.861665)
			(xy 26.630172 -40.809574) (xy 26.657468 -40.760939) (xy 26.691554 -40.716796) (xy 26.731703 -40.678087)
			(xy 26.777061 -40.645636) (xy 26.826661 -40.620135) (xy 26.879445 -40.602128) (xy 26.934288 -40.591998)
			(xy 26.990022 -40.589961) (xy 27.045459 -40.596061) (xy 27.099416 -40.610167) (xy 27.150745 -40.631979)
			(xy 27.198351 -40.661033) (xy 27.241219 -40.696708) (xy 27.278436 -40.738245) (xy 27.309209 -40.784758)
			(xy 27.332881 -40.835255) (xy 27.348949 -40.888662) (xy 27.357069 -40.943838) (xy 27.357578 -40.971724)
			(xy 27.357069 -40.99961) (xy 27.348949 -41.054786) (xy 27.332881 -41.108193) (xy 27.309209 -41.15869)
			(xy 27.278436 -41.205203) (xy 27.241219 -41.24674) (xy 27.198351 -41.282415) (xy 27.150745 -41.311469)
			(xy 27.099416 -41.333281) (xy 27.045459 -41.347387) (xy 26.990022 -41.353487) (xy 26.934288 -41.35145)
			(xy 26.879445 -41.34132) (xy 26.826661 -41.323313) (xy 26.777061 -41.297812) (xy 26.731703 -41.265361)
			(xy 26.691554 -41.226652) (xy 26.657468 -41.182509) (xy 26.630172 -41.133874) (xy 26.610249 -41.081783)
			(xy 26.598123 -41.027346) (xy 26.594052 -40.971724) (xy 18.739184 -40.971724) (xy 18.770011 -40.976156)
			(xy 18.822306 -40.991511) (xy 18.871883 -41.014153) (xy 18.917733 -41.043619) (xy 18.958924 -41.07931)
			(xy 18.994615 -41.120501) (xy 19.024081 -41.166351) (xy 19.046723 -41.215928) (xy 19.062078 -41.268223)
			(xy 19.069834 -41.322171) (xy 19.07032 -41.349422) (xy 19.069804 -41.378161) (xy 19.061179 -41.434989)
			(xy 19.044127 -41.489879) (xy 19.019033 -41.541591) (xy 18.986467 -41.588953) (xy 18.967196 -41.61028)
			(xy 18.960592 -41.617138) (xy 18.95348 -41.635172) (xy 18.95348 -41.724072) (xy 18.960592 -41.742106)
			(xy 18.967196 -41.748964) (xy 18.986488 -41.770272) (xy 19.019051 -41.817639) (xy 19.04414 -41.869353)
			(xy 19.061187 -41.924247) (xy 19.069807 -41.981076) (xy 19.069805 -42.038556) (xy 19.06118 -42.095385)
			(xy 19.044128 -42.150276) (xy 19.019034 -42.201989) (xy 18.986468 -42.249353) (xy 18.967196 -42.27068)
			(xy 18.960592 -42.277538) (xy 18.95348 -42.295572) (xy 18.95348 -42.384472) (xy 18.960592 -42.402506)
			(xy 18.967196 -42.409364) (xy 18.986466 -42.430692) (xy 19.019035 -42.478053) (xy 19.044128 -42.529764)
			(xy 19.061179 -42.584655) (xy 19.0698 -42.641483) (xy 19.07032 -42.670222) (xy 19.069886 -42.697594)
			(xy 19.062064 -42.751775) (xy 19.046568 -42.804279) (xy 19.02601 -42.849038) (xy 20.892006 -42.849038)
			(xy 20.896077 -42.793416) (xy 20.908203 -42.738979) (xy 20.928126 -42.686888) (xy 20.955422 -42.638253)
			(xy 20.989508 -42.59411) (xy 21.029657 -42.555401) (xy 21.075015 -42.52295) (xy 21.124615 -42.497449)
			(xy 21.177399 -42.479442) (xy 21.232242 -42.469312) (xy 21.287976 -42.467275) (xy 21.343413 -42.473375)
			(xy 21.39737 -42.487481) (xy 21.448699 -42.509293) (xy 21.496305 -42.538347) (xy 21.539173 -42.574022)
			(xy 21.57639 -42.615559) (xy 21.607163 -42.662072) (xy 21.630835 -42.712569) (xy 21.646903 -42.765976)
			(xy 21.655023 -42.821152) (xy 21.655384 -42.84091) (xy 26.933142 -42.84091) (xy 26.937213 -42.785288)
			(xy 26.949339 -42.730851) (xy 26.969262 -42.67876) (xy 26.996558 -42.630125) (xy 27.030644 -42.585982)
			(xy 27.070793 -42.547273) (xy 27.116151 -42.514822) (xy 27.165751 -42.489321) (xy 27.218535 -42.471314)
			(xy 27.273378 -42.461184) (xy 27.329112 -42.459147) (xy 27.384549 -42.465247) (xy 27.438506 -42.479353)
			(xy 27.489835 -42.501165) (xy 27.537441 -42.530219) (xy 27.580309 -42.565894) (xy 27.617526 -42.607431)
			(xy 27.648299 -42.653944) (xy 27.671971 -42.704441) (xy 27.688039 -42.757848) (xy 27.696159 -42.813024)
			(xy 27.696668 -42.84091) (xy 27.696159 -42.868796) (xy 27.688039 -42.923972) (xy 27.671971 -42.977379)
			(xy 27.648299 -43.027876) (xy 27.617526 -43.074389) (xy 27.580309 -43.115926) (xy 27.537441 -43.151601)
			(xy 27.489835 -43.180655) (xy 27.438506 -43.202467) (xy 27.384549 -43.216573) (xy 27.329112 -43.222673)
			(xy 27.273378 -43.220636) (xy 27.218535 -43.210506) (xy 27.165751 -43.192499) (xy 27.116151 -43.166998)
			(xy 27.070793 -43.134547) (xy 27.030644 -43.095838) (xy 26.996558 -43.051695) (xy 26.969262 -43.00306)
			(xy 26.949339 -42.950969) (xy 26.937213 -42.896532) (xy 26.933142 -42.84091) (xy 21.655384 -42.84091)
			(xy 21.655532 -42.849038) (xy 21.655023 -42.876924) (xy 21.646903 -42.9321) (xy 21.630835 -42.985507)
			(xy 21.607163 -43.036004) (xy 21.57639 -43.082517) (xy 21.539173 -43.124054) (xy 21.496305 -43.159729)
			(xy 21.448699 -43.188783) (xy 21.39737 -43.210595) (xy 21.343413 -43.224701) (xy 21.287976 -43.230801)
			(xy 21.232242 -43.228764) (xy 21.177399 -43.218634) (xy 21.124615 -43.200627) (xy 21.075015 -43.175126)
			(xy 21.029657 -43.142675) (xy 20.989508 -43.103966) (xy 20.955422 -43.059823) (xy 20.928126 -43.011188)
			(xy 20.908203 -42.959097) (xy 20.896077 -42.90466) (xy 20.892006 -42.849038) (xy 19.02601 -42.849038)
			(xy 19.023719 -42.854026) (xy 18.993986 -42.89999) (xy 18.97634 -42.92092) (xy 18.976086 -42.921174)
			(xy 18.970503 -42.928263) (xy 18.964254 -42.945178) (xy 18.963894 -42.954194) (xy 18.963894 -43.02125)
			(xy 18.964277 -43.030264) (xy 18.970507 -43.047181) (xy 18.976086 -43.05427) (xy 18.97634 -43.05427)
			(xy 18.97634 -43.054524) (xy 18.993964 -43.075468) (xy 19.023676 -43.121438) (xy 19.046515 -43.171183)
			(xy 19.06201 -43.223681) (xy 19.069843 -43.277854) (xy 19.07032 -43.305222) (xy 19.069834 -43.332473)
			(xy 19.062078 -43.386421) (xy 19.046723 -43.438716) (xy 19.024081 -43.488293) (xy 18.994615 -43.534143)
			(xy 18.958924 -43.575334) (xy 18.917733 -43.611025) (xy 18.871883 -43.640491) (xy 18.822306 -43.663133)
			(xy 18.770011 -43.678488) (xy 18.716063 -43.686244) (xy 18.661561 -43.686244) (xy 18.607613 -43.678488)
			(xy 18.555318 -43.663133) (xy 18.505741 -43.640491) (xy 18.459891 -43.611025) (xy 18.4187 -43.575334)
			(xy 18.383009 -43.534143) (xy 18.353543 -43.488293) (xy 18.330901 -43.438716) (xy 18.315546 -43.386421)
			(xy 18.30779 -43.332473) (xy 18.307304 -43.305222) (xy 12.208269 -43.305222) (xy 12.187623 -43.31516)
			(xy 12.125603 -43.336856) (xy 12.061545 -43.351477) (xy 11.996253 -43.358839) (xy 11.9634 -43.359324)
			(xy 11.27379 -43.359324) (xy 11.266079 -43.359548) (xy 11.251336 -43.364064) (xy 11.244834 -43.368214)
			(xy 11.24077 -43.371516) (xy 10.876026 -43.73626) (xy 20.213064 -43.73626) (xy 20.217135 -43.680638)
			(xy 20.229261 -43.626201) (xy 20.249184 -43.57411) (xy 20.27648 -43.525475) (xy 20.310566 -43.481332)
			(xy 20.350715 -43.442623) (xy 20.396073 -43.410172) (xy 20.445673 -43.384671) (xy 20.498457 -43.366664)
			(xy 20.5533 -43.356534) (xy 20.609034 -43.354497) (xy 20.664471 -43.360597) (xy 20.718428 -43.374703)
			(xy 20.769757 -43.396515) (xy 20.817363 -43.425569) (xy 20.860231 -43.461244) (xy 20.897448 -43.502781)
			(xy 20.928221 -43.549294) (xy 20.951893 -43.599791) (xy 20.967961 -43.653198) (xy 20.976081 -43.708374)
			(xy 20.97659 -43.73626) (xy 20.976081 -43.764146) (xy 20.967961 -43.819322) (xy 20.956652 -43.85691)
			(xy 24.719786 -43.85691) (xy 24.723857 -43.801288) (xy 24.735983 -43.746851) (xy 24.755906 -43.69476)
			(xy 24.783202 -43.646125) (xy 24.817288 -43.601982) (xy 24.857437 -43.563273) (xy 24.902795 -43.530822)
			(xy 24.952395 -43.505321) (xy 25.005179 -43.487314) (xy 25.060022 -43.477184) (xy 25.115756 -43.475147)
			(xy 25.171193 -43.481247) (xy 25.22515 -43.495353) (xy 25.276479 -43.517165) (xy 25.324085 -43.546219)
			(xy 25.366953 -43.581894) (xy 25.40417 -43.623431) (xy 25.434943 -43.669944) (xy 25.458615 -43.720441)
			(xy 25.474683 -43.773848) (xy 25.482803 -43.829024) (xy 25.483312 -43.85691) (xy 25.482803 -43.884796)
			(xy 25.474683 -43.939972) (xy 25.458615 -43.993379) (xy 25.434943 -44.043876) (xy 25.40417 -44.090389)
			(xy 25.366953 -44.131926) (xy 25.324085 -44.167601) (xy 25.276479 -44.196655) (xy 25.22515 -44.218467)
			(xy 25.171193 -44.232573) (xy 25.115756 -44.238673) (xy 25.060022 -44.236636) (xy 25.005179 -44.226506)
			(xy 24.952395 -44.208499) (xy 24.902795 -44.182998) (xy 24.857437 -44.150547) (xy 24.817288 -44.111838)
			(xy 24.783202 -44.067695) (xy 24.755906 -44.01906) (xy 24.735983 -43.966969) (xy 24.723857 -43.912532)
			(xy 24.719786 -43.85691) (xy 20.956652 -43.85691) (xy 20.951893 -43.872729) (xy 20.928221 -43.923226)
			(xy 20.897448 -43.969739) (xy 20.860231 -44.011276) (xy 20.817363 -44.046951) (xy 20.769757 -44.076005)
			(xy 20.718428 -44.097817) (xy 20.664471 -44.111923) (xy 20.609034 -44.118023) (xy 20.5533 -44.115986)
			(xy 20.498457 -44.105856) (xy 20.445673 -44.087849) (xy 20.396073 -44.062348) (xy 20.350715 -44.029897)
			(xy 20.310566 -43.991188) (xy 20.27648 -43.947045) (xy 20.249184 -43.89841) (xy 20.229261 -43.846319)
			(xy 20.217135 -43.791882) (xy 20.213064 -43.73626) (xy 10.876026 -43.73626) (xy 10.27684 -44.335446)
			(xy 10.273538 -44.33951) (xy 10.269409 -44.346022) (xy 10.264895 -44.360758) (xy 10.264648 -44.368466)
			(xy 10.264648 -45.114464) (xy 20.06549 -45.114464) (xy 20.069561 -45.058842) (xy 20.081687 -45.004405)
			(xy 20.10161 -44.952314) (xy 20.128906 -44.903679) (xy 20.162992 -44.859536) (xy 20.203141 -44.820827)
			(xy 20.248499 -44.788376) (xy 20.298099 -44.762875) (xy 20.350883 -44.744868) (xy 20.405726 -44.734738)
			(xy 20.46146 -44.732701) (xy 20.516897 -44.738801) (xy 20.570854 -44.752907) (xy 20.622183 -44.774719)
			(xy 20.669789 -44.803773) (xy 20.712657 -44.839448) (xy 20.742639 -44.87291) (xy 26.933142 -44.87291)
			(xy 26.937213 -44.817288) (xy 26.949339 -44.762851) (xy 26.969262 -44.71076) (xy 26.996558 -44.662125)
			(xy 27.030644 -44.617982) (xy 27.070793 -44.579273) (xy 27.116151 -44.546822) (xy 27.165751 -44.521321)
			(xy 27.218535 -44.503314) (xy 27.273378 -44.493184) (xy 27.329112 -44.491147) (xy 27.384549 -44.497247)
			(xy 27.438506 -44.511353) (xy 27.489835 -44.533165) (xy 27.537441 -44.562219) (xy 27.580309 -44.597894)
			(xy 27.617526 -44.639431) (xy 27.648299 -44.685944) (xy 27.671971 -44.736441) (xy 27.688039 -44.789848)
			(xy 27.696159 -44.845024) (xy 27.696668 -44.87291) (xy 27.696159 -44.900796) (xy 27.688039 -44.955972)
			(xy 27.671971 -45.009379) (xy 27.648299 -45.059876) (xy 27.617526 -45.106389) (xy 27.580309 -45.147926)
			(xy 27.537441 -45.183601) (xy 27.489835 -45.212655) (xy 27.438506 -45.234467) (xy 27.384549 -45.248573)
			(xy 27.329112 -45.254673) (xy 27.273378 -45.252636) (xy 27.218535 -45.242506) (xy 27.165751 -45.224499)
			(xy 27.116151 -45.198998) (xy 27.070793 -45.166547) (xy 27.030644 -45.127838) (xy 26.996558 -45.083695)
			(xy 26.969262 -45.03506) (xy 26.949339 -44.982969) (xy 26.937213 -44.928532) (xy 26.933142 -44.87291)
			(xy 20.742639 -44.87291) (xy 20.749874 -44.880985) (xy 20.780647 -44.927498) (xy 20.804319 -44.977995)
			(xy 20.820387 -45.031402) (xy 20.828507 -45.086578) (xy 20.829016 -45.114464) (xy 20.828507 -45.14235)
			(xy 20.820387 -45.197526) (xy 20.804319 -45.250933) (xy 20.780647 -45.30143) (xy 20.749874 -45.347943)
			(xy 20.744232 -45.35424) (xy 24.703784 -45.35424) (xy 24.707855 -45.298618) (xy 24.719981 -45.244181)
			(xy 24.739904 -45.19209) (xy 24.7672 -45.143455) (xy 24.801286 -45.099312) (xy 24.841435 -45.060603)
			(xy 24.886793 -45.028152) (xy 24.936393 -45.002651) (xy 24.989177 -44.984644) (xy 25.04402 -44.974514)
			(xy 25.099754 -44.972477) (xy 25.155191 -44.978577) (xy 25.209148 -44.992683) (xy 25.260477 -45.014495)
			(xy 25.308083 -45.043549) (xy 25.350951 -45.079224) (xy 25.388168 -45.120761) (xy 25.418941 -45.167274)
			(xy 25.442613 -45.217771) (xy 25.458681 -45.271178) (xy 25.466801 -45.326354) (xy 25.46731 -45.35424)
			(xy 25.466801 -45.382126) (xy 25.458681 -45.437302) (xy 25.442613 -45.490709) (xy 25.418941 -45.541206)
			(xy 25.388168 -45.587719) (xy 25.350951 -45.629256) (xy 25.308083 -45.664931) (xy 25.260477 -45.693985)
			(xy 25.209148 -45.715797) (xy 25.155191 -45.729903) (xy 25.099754 -45.736003) (xy 25.04402 -45.733966)
			(xy 24.989177 -45.723836) (xy 24.936393 -45.705829) (xy 24.886793 -45.680328) (xy 24.841435 -45.647877)
			(xy 24.801286 -45.609168) (xy 24.7672 -45.565025) (xy 24.739904 -45.51639) (xy 24.719981 -45.464299)
			(xy 24.707855 -45.409862) (xy 24.703784 -45.35424) (xy 20.744232 -45.35424) (xy 20.712657 -45.38948)
			(xy 20.669789 -45.425155) (xy 20.622183 -45.454209) (xy 20.570854 -45.476021) (xy 20.516897 -45.490127)
			(xy 20.46146 -45.496227) (xy 20.405726 -45.49419) (xy 20.350883 -45.48406) (xy 20.298099 -45.466053)
			(xy 20.248499 -45.440552) (xy 20.203141 -45.408101) (xy 20.162992 -45.369392) (xy 20.128906 -45.325249)
			(xy 20.10161 -45.276614) (xy 20.081687 -45.224523) (xy 20.069561 -45.170086) (xy 20.06549 -45.114464)
			(xy 10.264648 -45.114464) (xy 10.264648 -45.926248) (xy 11.930886 -45.926248) (xy 11.934957 -45.870626)
			(xy 11.947083 -45.816189) (xy 11.967006 -45.764098) (xy 11.994302 -45.715463) (xy 12.028388 -45.67132)
			(xy 12.068537 -45.632611) (xy 12.113895 -45.60016) (xy 12.163495 -45.574659) (xy 12.216279 -45.556652)
			(xy 12.271122 -45.546522) (xy 12.326856 -45.544485) (xy 12.382293 -45.550585) (xy 12.43625 -45.564691)
			(xy 12.487579 -45.586503) (xy 12.535185 -45.615557) (xy 12.578053 -45.651232) (xy 12.61527 -45.692769)
			(xy 12.646043 -45.739282) (xy 12.669715 -45.789779) (xy 12.685783 -45.843186) (xy 12.693903 -45.898362)
			(xy 12.694412 -45.926248) (xy 12.693903 -45.954134) (xy 12.685783 -46.00931) (xy 12.669715 -46.062717)
			(xy 12.66058 -46.082204) (xy 18.052542 -46.082204) (xy 18.052959 -46.054949) (xy 18.060717 -46.000994)
			(xy 18.076075 -45.948692) (xy 18.098721 -45.899109) (xy 18.128193 -45.853253) (xy 18.163892 -45.812059)
			(xy 18.20509 -45.776365) (xy 18.250949 -45.746899) (xy 18.300535 -45.724259) (xy 18.352839 -45.708907)
			(xy 18.406795 -45.701156) (xy 18.43405 -45.700696) (xy 18.460954 -45.70112) (xy 18.514226 -45.708699)
			(xy 18.565905 -45.723685) (xy 18.614967 -45.745781) (xy 18.660438 -45.774549) (xy 18.701419 -45.80942)
			(xy 18.737095 -45.8497) (xy 18.752312 -45.871892) (xy 18.759424 -45.882814) (xy 18.782284 -45.894752)
			(xy 18.894552 -45.89272) (xy 18.916904 -45.879766) (xy 18.923762 -45.86859) (xy 18.938655 -45.844969)
			(xy 18.974339 -45.802018) (xy 19.015902 -45.764726) (xy 19.062457 -45.733891) (xy 19.113009 -45.710171)
			(xy 19.166479 -45.694072) (xy 19.221724 -45.685939) (xy 19.249644 -45.685456) (xy 19.276638 -45.685892)
			(xy 19.330087 -45.693504) (xy 19.381931 -45.70857) (xy 19.431135 -45.730789) (xy 19.476718 -45.759719)
			(xy 19.497548 -45.776896) (xy 19.505676 -45.784008) (xy 19.52625 -45.790104) (xy 19.611594 -45.779182)
			(xy 19.62214 -45.777415) (xy 19.640422 -45.766355) (xy 19.6469 -45.757846) (xy 19.66226 -45.73662)
			(xy 19.697846 -45.698167) (xy 19.738362 -45.664948) (xy 19.783044 -45.637589) (xy 19.831051 -45.616605)
			(xy 19.881479 -45.602391) (xy 19.933378 -45.595214) (xy 19.959574 -45.594778) (xy 19.986827 -45.595268)
			(xy 20.040779 -45.603021) (xy 20.093078 -45.618374) (xy 20.142659 -45.641015) (xy 20.188514 -45.670481)
			(xy 20.229708 -45.706173) (xy 20.265404 -45.747365) (xy 20.294873 -45.793218) (xy 20.317516 -45.842798)
			(xy 20.332873 -45.895096) (xy 20.340631 -45.949047) (xy 20.340631 -46.003553) (xy 20.332873 -46.057504)
			(xy 20.317516 -46.109802) (xy 20.294873 -46.159382) (xy 20.265404 -46.205235) (xy 20.229708 -46.246427)
			(xy 20.188514 -46.282119) (xy 20.142659 -46.311585) (xy 20.093078 -46.334226) (xy 20.040779 -46.349579)
			(xy 19.986827 -46.357332) (xy 19.959574 -46.357794) (xy 19.932581 -46.357336) (xy 19.879133 -46.349728)
			(xy 19.82729 -46.334666) (xy 19.778085 -46.312452) (xy 19.732501 -46.283528) (xy 19.71167 -46.266354)
			(xy 19.703542 -46.259242) (xy 19.682968 -46.253146) (xy 19.597624 -46.264068) (xy 19.587085 -46.265862)
			(xy 19.568801 -46.276903) (xy 19.562318 -46.285404) (xy 19.544699 -46.3097) (xy 19.503108 -46.352962)
			(xy 19.479514 -46.37151) (xy 19.47164 -46.377352) (xy 19.461226 -46.394878) (xy 19.448018 -46.485302)
			(xy 19.452844 -46.504606) (xy 19.458686 -46.51248) (xy 19.458686 -46.512734) (xy 19.47619 -46.537477)
			(xy 19.503992 -46.59133) (xy 19.522928 -46.648903) (xy 19.530131 -46.693836) (xy 24.676354 -46.693836)
			(xy 24.67684 -46.666585) (xy 24.684596 -46.612637) (xy 24.699951 -46.560342) (xy 24.722593 -46.510765)
			(xy 24.752059 -46.464915) (xy 24.78775 -46.423724) (xy 24.828941 -46.388033) (xy 24.874791 -46.358567)
			(xy 24.924368 -46.335925) (xy 24.976663 -46.32057) (xy 25.030611 -46.312814) (xy 25.085113 -46.312814)
			(xy 25.139061 -46.32057) (xy 25.191356 -46.335925) (xy 25.240933 -46.358567) (xy 25.286783 -46.388033)
			(xy 25.327974 -46.423724) (xy 25.363665 -46.464915) (xy 25.393131 -46.510765) (xy 25.415773 -46.560342)
			(xy 25.431128 -46.612637) (xy 25.438884 -46.666585) (xy 25.43937 -46.693836) (xy 25.438901 -46.720264)
			(xy 25.431591 -46.772611) (xy 25.417117 -46.823446) (xy 25.395755 -46.871793) (xy 25.38222 -46.894496)
			(xy 25.381966 -46.89475) (xy 25.37663 -46.904768) (xy 25.374372 -46.927318) (xy 25.377648 -46.938184)
			(xy 25.40381 -47.01286) (xy 25.408168 -47.023389) (xy 25.424274 -47.039472) (xy 25.434798 -47.043848)
			(xy 25.435052 -47.043848) (xy 25.459562 -47.052914) (xy 25.506014 -47.076857) (xy 25.548766 -47.106914)
			(xy 25.587018 -47.142522) (xy 25.620054 -47.183015) (xy 25.647258 -47.227636) (xy 25.668119 -47.275552)
			(xy 25.682249 -47.325865) (xy 25.689383 -47.377636) (xy 25.689814 -47.403766) (xy 25.689328 -47.431017)
			(xy 25.687805 -47.441612) (xy 26.961844 -47.441612) (xy 26.965915 -47.38599) (xy 26.978041 -47.331553)
			(xy 26.997964 -47.279462) (xy 27.02526 -47.230827) (xy 27.059346 -47.186684) (xy 27.099495 -47.147975)
			(xy 27.144853 -47.115524) (xy 27.194453 -47.090023) (xy 27.247237 -47.072016) (xy 27.30208 -47.061886)
			(xy 27.357814 -47.059849) (xy 27.413251 -47.065949) (xy 27.467208 -47.080055) (xy 27.518537 -47.101867)
			(xy 27.566143 -47.130921) (xy 27.609011 -47.166596) (xy 27.646228 -47.208133) (xy 27.677001 -47.254646)
			(xy 27.700673 -47.305143) (xy 27.716741 -47.35855) (xy 27.724861 -47.413726) (xy 27.72537 -47.441612)
			(xy 27.724861 -47.469498) (xy 27.716741 -47.524674) (xy 27.700673 -47.578081) (xy 27.677001 -47.628578)
			(xy 27.646228 -47.675091) (xy 27.609011 -47.716628) (xy 27.566143 -47.752303) (xy 27.518537 -47.781357)
			(xy 27.467208 -47.803169) (xy 27.413251 -47.817275) (xy 27.357814 -47.823375) (xy 27.30208 -47.821338)
			(xy 27.247237 -47.811208) (xy 27.194453 -47.793201) (xy 27.144853 -47.7677) (xy 27.099495 -47.735249)
			(xy 27.059346 -47.69654) (xy 27.02526 -47.652397) (xy 26.997964 -47.603762) (xy 26.978041 -47.551671)
			(xy 26.965915 -47.497234) (xy 26.961844 -47.441612) (xy 25.687805 -47.441612) (xy 25.681572 -47.484965)
			(xy 25.666217 -47.53726) (xy 25.643575 -47.586837) (xy 25.614109 -47.632687) (xy 25.578418 -47.673878)
			(xy 25.537227 -47.709569) (xy 25.491377 -47.739035) (xy 25.4418 -47.761677) (xy 25.389505 -47.777032)
			(xy 25.335557 -47.784788) (xy 25.281055 -47.784788) (xy 25.227107 -47.777032) (xy 25.174812 -47.761677)
			(xy 25.125235 -47.739035) (xy 25.079385 -47.709569) (xy 25.038194 -47.673878) (xy 25.002503 -47.632687)
			(xy 24.973037 -47.586837) (xy 24.950395 -47.53726) (xy 24.93504 -47.484965) (xy 24.927284 -47.431017)
			(xy 24.926798 -47.403766) (xy 24.927272 -47.377338) (xy 24.934581 -47.324991) (xy 24.949054 -47.274156)
			(xy 24.970413 -47.225809) (xy 24.983948 -47.203106) (xy 24.984202 -47.202852) (xy 24.989537 -47.192833)
			(xy 24.991798 -47.170283) (xy 24.98852 -47.159418) (xy 24.962358 -47.084742) (xy 24.958014 -47.074206)
			(xy 24.941898 -47.058126) (xy 24.93137 -47.053754) (xy 24.931116 -47.053754) (xy 24.9066 -47.044704)
			(xy 24.860148 -47.020757) (xy 24.817398 -46.990698) (xy 24.779147 -46.955088) (xy 24.746112 -46.914592)
			(xy 24.718909 -46.869969) (xy 24.698048 -46.822053) (xy 24.683919 -46.771738) (xy 24.676785 -46.719966)
			(xy 24.676354 -46.693836) (xy 19.530131 -46.693836) (xy 19.532521 -46.708745) (xy 19.533108 -46.739048)
			(xy 19.532667 -46.7663) (xy 19.524904 -46.82025) (xy 19.509543 -46.872545) (xy 19.486896 -46.922123)
			(xy 19.457425 -46.967973) (xy 19.421729 -47.009163) (xy 19.380534 -47.044853) (xy 19.334681 -47.074319)
			(xy 19.2851 -47.096959) (xy 19.232803 -47.112314) (xy 19.178852 -47.12007) (xy 19.1516 -47.120556)
			(xy 19.125567 -47.120101) (xy 19.073984 -47.113015) (xy 19.023843 -47.098987) (xy 18.976072 -47.078278)
			(xy 18.931557 -47.051271) (xy 18.911062 -47.035212) (xy 18.903294 -47.029488) (xy 18.884892 -47.023736)
			(xy 18.875248 -47.024036) (xy 18.795492 -47.030386) (xy 18.777712 -47.039022) (xy 18.771362 -47.046388)
			(xy 18.753173 -47.066026) (xy 18.712267 -47.100549) (xy 18.66694 -47.129019) (xy 18.61808 -47.150878)
			(xy 18.566645 -47.165697) (xy 18.513645 -47.173186) (xy 18.486882 -47.173642) (xy 18.459632 -47.173139)
			(xy 18.405687 -47.165381) (xy 18.353394 -47.150025) (xy 18.303819 -47.127385) (xy 18.25797 -47.09792)
			(xy 18.216781 -47.06223) (xy 18.18109 -47.021042) (xy 18.151623 -46.975195) (xy 18.12898 -46.925621)
			(xy 18.113622 -46.873329) (xy 18.105862 -46.819384) (xy 18.105374 -46.792134) (xy 18.105905 -46.76336)
			(xy 18.114556 -46.706467) (xy 18.131651 -46.651517) (xy 18.156803 -46.599756) (xy 18.189441 -46.55236)
			(xy 18.208752 -46.531022) (xy 18.216118 -46.523148) (xy 18.22323 -46.503336) (xy 18.215864 -46.40707)
			(xy 18.205958 -46.388274) (xy 18.197576 -46.38167) (xy 18.175382 -46.363456) (xy 18.136175 -46.321517)
			(xy 18.103692 -46.274179) (xy 18.078665 -46.222509) (xy 18.06166 -46.167674) (xy 18.05306 -46.11091)
			(xy 18.052542 -46.082204) (xy 12.66058 -46.082204) (xy 12.646043 -46.113214) (xy 12.61527 -46.159727)
			(xy 12.578053 -46.201264) (xy 12.535185 -46.236939) (xy 12.487579 -46.265993) (xy 12.43625 -46.287805)
			(xy 12.382293 -46.301911) (xy 12.326856 -46.308011) (xy 12.271122 -46.305974) (xy 12.216279 -46.295844)
			(xy 12.163495 -46.277837) (xy 12.113895 -46.252336) (xy 12.068537 -46.219885) (xy 12.028388 -46.181176)
			(xy 11.994302 -46.137033) (xy 11.967006 -46.088398) (xy 11.947083 -46.036307) (xy 11.934957 -45.98187)
			(xy 11.930886 -45.926248) (xy 10.264648 -45.926248) (xy 10.264648 -48.30699) (xy 24.553924 -48.30699)
			(xy 24.557995 -48.251368) (xy 24.570121 -48.196931) (xy 24.590044 -48.14484) (xy 24.61734 -48.096205)
			(xy 24.651426 -48.052062) (xy 24.691575 -48.013353) (xy 24.736933 -47.980902) (xy 24.786533 -47.955401)
			(xy 24.839317 -47.937394) (xy 24.89416 -47.927264) (xy 24.949894 -47.925227) (xy 25.005331 -47.931327)
			(xy 25.059288 -47.945433) (xy 25.110617 -47.967245) (xy 25.158223 -47.996299) (xy 25.201091 -48.031974)
			(xy 25.238308 -48.073511) (xy 25.269081 -48.120024) (xy 25.292753 -48.170521) (xy 25.308821 -48.223928)
			(xy 25.316941 -48.279104) (xy 25.31745 -48.30699) (xy 25.316941 -48.334876) (xy 25.308821 -48.390052)
			(xy 25.292753 -48.443459) (xy 25.269081 -48.493956) (xy 25.238308 -48.540469) (xy 25.201091 -48.582006)
			(xy 25.158223 -48.617681) (xy 25.110617 -48.646735) (xy 25.059288 -48.668547) (xy 25.005331 -48.682653)
			(xy 24.949894 -48.688753) (xy 24.89416 -48.686716) (xy 24.839317 -48.676586) (xy 24.786533 -48.658579)
			(xy 24.736933 -48.633078) (xy 24.691575 -48.600627) (xy 24.651426 -48.561918) (xy 24.61734 -48.517775)
			(xy 24.590044 -48.46914) (xy 24.570121 -48.417049) (xy 24.557995 -48.362612) (xy 24.553924 -48.30699)
			(xy 10.264648 -48.30699) (xy 10.264648 -48.753014) (xy 21.168358 -48.753014) (xy 21.172429 -48.697392)
			(xy 21.184555 -48.642955) (xy 21.204478 -48.590864) (xy 21.231774 -48.542229) (xy 21.26586 -48.498086)
			(xy 21.306009 -48.459377) (xy 21.351367 -48.426926) (xy 21.400967 -48.401425) (xy 21.453751 -48.383418)
			(xy 21.508594 -48.373288) (xy 21.564328 -48.371251) (xy 21.619765 -48.377351) (xy 21.673722 -48.391457)
			(xy 21.725051 -48.413269) (xy 21.772657 -48.442323) (xy 21.815525 -48.477998) (xy 21.852742 -48.519535)
			(xy 21.883515 -48.566048) (xy 21.907187 -48.616545) (xy 21.923255 -48.669952) (xy 21.931375 -48.725128)
			(xy 21.931884 -48.753014) (xy 21.931375 -48.7809) (xy 21.923255 -48.836076) (xy 21.907187 -48.889483)
			(xy 21.905791 -48.89246) (xy 23.214074 -48.89246) (xy 23.218145 -48.836838) (xy 23.230271 -48.782401)
			(xy 23.250194 -48.73031) (xy 23.27749 -48.681675) (xy 23.311576 -48.637532) (xy 23.351725 -48.598823)
			(xy 23.397083 -48.566372) (xy 23.446683 -48.540871) (xy 23.499467 -48.522864) (xy 23.55431 -48.512734)
			(xy 23.610044 -48.510697) (xy 23.665481 -48.516797) (xy 23.719438 -48.530903) (xy 23.770767 -48.552715)
			(xy 23.818373 -48.581769) (xy 23.861241 -48.617444) (xy 23.898458 -48.658981) (xy 23.929231 -48.705494)
			(xy 23.952903 -48.755991) (xy 23.968971 -48.809398) (xy 23.977091 -48.864574) (xy 23.9776 -48.89246)
			(xy 23.977091 -48.920346) (xy 23.974653 -48.93691) (xy 26.933142 -48.93691) (xy 26.937213 -48.881288)
			(xy 26.949339 -48.826851) (xy 26.969262 -48.77476) (xy 26.996558 -48.726125) (xy 27.030644 -48.681982)
			(xy 27.070793 -48.643273) (xy 27.116151 -48.610822) (xy 27.165751 -48.585321) (xy 27.218535 -48.567314)
			(xy 27.273378 -48.557184) (xy 27.329112 -48.555147) (xy 27.384549 -48.561247) (xy 27.438506 -48.575353)
			(xy 27.489835 -48.597165) (xy 27.537441 -48.626219) (xy 27.580309 -48.661894) (xy 27.617526 -48.703431)
			(xy 27.648299 -48.749944) (xy 27.671971 -48.800441) (xy 27.688039 -48.853848) (xy 27.696159 -48.909024)
			(xy 27.696668 -48.93691) (xy 27.696159 -48.964796) (xy 27.688039 -49.019972) (xy 27.671971 -49.073379)
			(xy 27.648299 -49.123876) (xy 27.617526 -49.170389) (xy 27.580309 -49.211926) (xy 27.537441 -49.247601)
			(xy 27.489835 -49.276655) (xy 27.438506 -49.298467) (xy 27.384549 -49.312573) (xy 27.329112 -49.318673)
			(xy 27.273378 -49.316636) (xy 27.218535 -49.306506) (xy 27.165751 -49.288499) (xy 27.116151 -49.262998)
			(xy 27.070793 -49.230547) (xy 27.030644 -49.191838) (xy 26.996558 -49.147695) (xy 26.969262 -49.09906)
			(xy 26.949339 -49.046969) (xy 26.937213 -48.992532) (xy 26.933142 -48.93691) (xy 23.974653 -48.93691)
			(xy 23.968971 -48.975522) (xy 23.952903 -49.028929) (xy 23.929231 -49.079426) (xy 23.898458 -49.125939)
			(xy 23.861241 -49.167476) (xy 23.818373 -49.203151) (xy 23.770767 -49.232205) (xy 23.719438 -49.254017)
			(xy 23.665481 -49.268123) (xy 23.610044 -49.274223) (xy 23.55431 -49.272186) (xy 23.499467 -49.262056)
			(xy 23.446683 -49.244049) (xy 23.397083 -49.218548) (xy 23.351725 -49.186097) (xy 23.311576 -49.147388)
			(xy 23.27749 -49.103245) (xy 23.250194 -49.05461) (xy 23.230271 -49.002519) (xy 23.218145 -48.948082)
			(xy 23.214074 -48.89246) (xy 21.905791 -48.89246) (xy 21.883515 -48.93998) (xy 21.852742 -48.986493)
			(xy 21.815525 -49.02803) (xy 21.772657 -49.063705) (xy 21.725051 -49.092759) (xy 21.673722 -49.114571)
			(xy 21.619765 -49.128677) (xy 21.564328 -49.134777) (xy 21.508594 -49.13274) (xy 21.453751 -49.12261)
			(xy 21.400967 -49.104603) (xy 21.351367 -49.079102) (xy 21.306009 -49.046651) (xy 21.26586 -49.007942)
			(xy 21.231774 -48.963799) (xy 21.204478 -48.915164) (xy 21.184555 -48.863073) (xy 21.172429 -48.808636)
			(xy 21.168358 -48.753014) (xy 10.264648 -48.753014) (xy 10.264648 -49.95291) (xy 26.933142 -49.95291)
			(xy 26.937213 -49.897288) (xy 26.949339 -49.842851) (xy 26.969262 -49.79076) (xy 26.996558 -49.742125)
			(xy 27.030644 -49.697982) (xy 27.070793 -49.659273) (xy 27.116151 -49.626822) (xy 27.165751 -49.601321)
			(xy 27.218535 -49.583314) (xy 27.273378 -49.573184) (xy 27.329112 -49.571147) (xy 27.384549 -49.577247)
			(xy 27.438506 -49.591353) (xy 27.463441 -49.601949) (xy 32.112982 -49.601949) (xy 32.112982 -49.547451)
			(xy 32.120737 -49.493506) (xy 32.13609 -49.441215) (xy 32.158729 -49.39164) (xy 32.188192 -49.345792)
			(xy 32.223879 -49.304603) (xy 32.265065 -49.268912) (xy 32.310911 -49.239445) (xy 32.360483 -49.216802)
			(xy 32.412773 -49.201444) (xy 32.466717 -49.193684) (xy 32.493966 -49.193196) (xy 32.521335 -49.193683)
			(xy 32.575514 -49.201496) (xy 32.628016 -49.21698) (xy 32.677764 -49.239817) (xy 32.723732 -49.269537)
			(xy 32.744664 -49.287176) (xy 32.744918 -49.28743) (xy 32.751993 -49.293034) (xy 32.768919 -49.299269)
			(xy 32.777938 -49.299622) (xy 32.844994 -49.299622) (xy 32.85401 -49.299257) (xy 32.870927 -49.293014)
			(xy 32.878014 -49.28743) (xy 32.878014 -49.287176) (xy 32.878268 -49.287176) (xy 32.899201 -49.269535)
			(xy 32.945169 -49.239811) (xy 32.994915 -49.216965) (xy 33.047417 -49.201469) (xy 33.101595 -49.19364)
			(xy 33.156337 -49.19364) (xy 33.210515 -49.201469) (xy 33.263017 -49.216965) (xy 33.312763 -49.239811)
			(xy 33.358731 -49.269535) (xy 33.379664 -49.287176) (xy 33.379918 -49.28743) (xy 33.386993 -49.293034)
			(xy 33.403919 -49.299269) (xy 33.412938 -49.299622) (xy 33.479994 -49.299622) (xy 33.48901 -49.299257)
			(xy 33.505927 -49.293014) (xy 33.513014 -49.28743) (xy 33.513014 -49.287176) (xy 33.513268 -49.287176)
			(xy 33.534201 -49.269535) (xy 33.580169 -49.239811) (xy 33.629915 -49.216965) (xy 33.682417 -49.201469)
			(xy 33.736595 -49.19364) (xy 33.791337 -49.19364) (xy 33.845515 -49.201469) (xy 33.898017 -49.216965)
			(xy 33.947763 -49.239811) (xy 33.993731 -49.269535) (xy 34.014664 -49.287176) (xy 34.014918 -49.28743)
			(xy 34.021993 -49.293034) (xy 34.038919 -49.299269) (xy 34.047938 -49.299622) (xy 34.114994 -49.299622)
			(xy 34.12401 -49.299257) (xy 34.140927 -49.293014) (xy 34.148014 -49.28743) (xy 34.148014 -49.287176)
			(xy 34.148268 -49.287176) (xy 34.169198 -49.269535) (xy 34.215172 -49.239824) (xy 34.26492 -49.216989)
			(xy 34.317421 -49.201498) (xy 34.371597 -49.19367) (xy 34.398966 -49.193196) (xy 34.426221 -49.193649)
			(xy 34.480176 -49.201402) (xy 34.532478 -49.216755) (xy 34.582063 -49.239396) (xy 34.627921 -49.268864)
			(xy 34.669118 -49.304558) (xy 34.704816 -49.345752) (xy 34.734287 -49.391607) (xy 34.756933 -49.44119)
			(xy 34.772291 -49.493491) (xy 34.780049 -49.547445) (xy 34.780049 -49.601955) (xy 34.772291 -49.655909)
			(xy 34.756933 -49.70821) (xy 34.734287 -49.757793) (xy 34.704816 -49.803648) (xy 34.669118 -49.844842)
			(xy 34.627921 -49.880536) (xy 34.582063 -49.910004) (xy 34.532478 -49.932645) (xy 34.480176 -49.947998)
			(xy 34.426221 -49.955751) (xy 34.398966 -49.956212) (xy 34.371595 -49.955763) (xy 34.317416 -49.947941)
			(xy 34.264912 -49.932447) (xy 34.215166 -49.909602) (xy 34.169199 -49.879874) (xy 34.148268 -49.862232)
			(xy 34.148014 -49.861978) (xy 34.140929 -49.856389) (xy 34.124011 -49.850144) (xy 34.114994 -49.849786)
			(xy 34.047938 -49.849786) (xy 34.038923 -49.850164) (xy 34.022006 -49.856397) (xy 34.014918 -49.861978)
			(xy 34.014664 -49.862232) (xy 33.993731 -49.879873) (xy 33.947763 -49.909597) (xy 33.898017 -49.932443)
			(xy 33.845515 -49.947939) (xy 33.791337 -49.955768) (xy 33.736595 -49.955768) (xy 33.682417 -49.947939)
			(xy 33.629915 -49.932443) (xy 33.580169 -49.909597) (xy 33.534201 -49.879873) (xy 33.513268 -49.862232)
			(xy 33.513014 -49.861978) (xy 33.505929 -49.856389) (xy 33.489011 -49.850144) (xy 33.479994 -49.849786)
			(xy 33.412938 -49.849786) (xy 33.403923 -49.850164) (xy 33.387006 -49.856397) (xy 33.379918 -49.861978)
			(xy 33.379918 -49.862232) (xy 33.379664 -49.862232) (xy 33.358731 -49.879873) (xy 33.312763 -49.909597)
			(xy 33.263017 -49.932443) (xy 33.210515 -49.947939) (xy 33.156337 -49.955768) (xy 33.101595 -49.955768)
			(xy 33.047417 -49.947939) (xy 32.994915 -49.932443) (xy 32.945169 -49.909597) (xy 32.899201 -49.879873)
			(xy 32.878268 -49.862232) (xy 32.878014 -49.861978) (xy 32.870929 -49.856389) (xy 32.854011 -49.850144)
			(xy 32.844994 -49.849786) (xy 32.777938 -49.849786) (xy 32.768923 -49.850164) (xy 32.752006 -49.856397)
			(xy 32.744918 -49.861978) (xy 32.744918 -49.862232) (xy 32.744664 -49.862232) (xy 32.723723 -49.87986)
			(xy 32.677752 -49.909572) (xy 32.628007 -49.93241) (xy 32.575508 -49.947904) (xy 32.521334 -49.955736)
			(xy 32.493966 -49.956212) (xy 32.466717 -49.955716) (xy 32.412773 -49.947956) (xy 32.360483 -49.932598)
			(xy 32.310911 -49.909955) (xy 32.265065 -49.880488) (xy 32.223879 -49.844797) (xy 32.188192 -49.803608)
			(xy 32.158729 -49.75776) (xy 32.13609 -49.708185) (xy 32.120737 -49.655894) (xy 32.112982 -49.601949)
			(xy 27.463441 -49.601949) (xy 27.489835 -49.613165) (xy 27.537441 -49.642219) (xy 27.580309 -49.677894)
			(xy 27.617526 -49.719431) (xy 27.648299 -49.765944) (xy 27.671971 -49.816441) (xy 27.688039 -49.869848)
			(xy 27.696159 -49.925024) (xy 27.696668 -49.95291) (xy 27.696159 -49.980796) (xy 27.688039 -50.035972)
			(xy 27.671971 -50.089379) (xy 27.648299 -50.139876) (xy 27.617526 -50.186389) (xy 27.580309 -50.227926)
			(xy 27.537441 -50.263601) (xy 27.489835 -50.292655) (xy 27.438506 -50.314467) (xy 27.384549 -50.328573)
			(xy 27.329112 -50.334673) (xy 27.273378 -50.332636) (xy 27.218535 -50.322506) (xy 27.165751 -50.304499)
			(xy 27.116151 -50.278998) (xy 27.070793 -50.246547) (xy 27.030644 -50.207838) (xy 26.996558 -50.163695)
			(xy 26.969262 -50.11506) (xy 26.949339 -50.062969) (xy 26.937213 -50.008532) (xy 26.933142 -49.95291)
			(xy 10.264648 -49.95291) (xy 10.264648 -51.019456) (xy 24.749504 -51.019456) (xy 24.753575 -50.963834)
			(xy 24.765701 -50.909397) (xy 24.785624 -50.857306) (xy 24.81292 -50.808671) (xy 24.847006 -50.764528)
			(xy 24.887155 -50.725819) (xy 24.932513 -50.693368) (xy 24.982113 -50.667867) (xy 25.034897 -50.64986)
			(xy 25.08974 -50.63973) (xy 25.145474 -50.637693) (xy 25.200911 -50.643793) (xy 25.254868 -50.657899)
			(xy 25.306197 -50.679711) (xy 25.353803 -50.708765) (xy 25.396671 -50.74444) (xy 25.433888 -50.785977)
			(xy 25.464661 -50.83249) (xy 25.488333 -50.882987) (xy 25.504401 -50.936394) (xy 25.512521 -50.99157)
			(xy 25.51303 -51.019456) (xy 25.512521 -51.047342) (xy 25.504401 -51.102518) (xy 25.488333 -51.155925)
			(xy 25.464661 -51.206422) (xy 25.439805 -51.243992) (xy 33.13303 -51.243992) (xy 33.133484 -51.216621)
			(xy 33.141304 -51.162441) (xy 33.156795 -51.109938) (xy 33.17964 -51.060191) (xy 33.209367 -51.014225)
			(xy 33.22701 -50.993294) (xy 33.227264 -50.99304) (xy 33.232848 -50.985952) (xy 33.239094 -50.969036)
			(xy 33.239456 -50.96002) (xy 33.239456 -50.892964) (xy 33.239126 -50.883944) (xy 33.232861 -50.867027)
			(xy 33.227264 -50.859944) (xy 33.22701 -50.859944) (xy 33.22701 -50.85969) (xy 33.209354 -50.838771)
			(xy 33.179645 -50.792795) (xy 33.156812 -50.743044) (xy 33.141325 -50.69054) (xy 33.133501 -50.636362)
			(xy 33.13303 -50.608992) (xy 33.133448 -50.581737) (xy 33.141207 -50.527783) (xy 33.156566 -50.475482)
			(xy 33.179212 -50.425899) (xy 33.208685 -50.380044) (xy 33.244383 -50.338851) (xy 33.285581 -50.303157)
			(xy 33.331439 -50.27369) (xy 33.381025 -50.25105) (xy 33.433328 -50.235697) (xy 33.487283 -50.227945)
			(xy 33.514538 -50.227484) (xy 33.543455 -50.228015) (xy 33.600627 -50.236737) (xy 33.655827 -50.25399)
			(xy 33.707789 -50.27938) (xy 33.755323 -50.312322) (xy 33.797339 -50.352064) (xy 33.815528 -50.37455)
			(xy 33.823124 -50.383368) (xy 33.844033 -50.393544) (xy 33.85566 -50.394108) (xy 33.935416 -50.394108)
			(xy 33.947047 -50.393561) (xy 33.967956 -50.383377) (xy 33.975548 -50.37455) (xy 33.993756 -50.352081)
			(xy 34.035774 -50.312347) (xy 34.083305 -50.279408) (xy 34.135263 -50.254018) (xy 34.190457 -50.236757)
			(xy 34.247623 -50.228023) (xy 34.276538 -50.227484) (xy 34.30379 -50.227942) (xy 34.357738 -50.235704)
			(xy 34.410033 -50.251063) (xy 34.45961 -50.273708) (xy 34.50546 -50.303178) (xy 34.546649 -50.338872)
			(xy 34.58234 -50.380065) (xy 34.611806 -50.425917) (xy 34.634447 -50.475495) (xy 34.649802 -50.527791)
			(xy 34.65756 -50.58174) (xy 34.658046 -50.608992) (xy 34.657591 -50.635307) (xy 34.650356 -50.687436)
			(xy 34.636035 -50.73808) (xy 34.614901 -50.786279) (xy 34.587352 -50.831122) (xy 34.553909 -50.871761)
			(xy 34.534856 -50.889916) (xy 34.527454 -50.897437) (xy 34.518928 -50.916717) (xy 34.518346 -50.927254)
			(xy 34.518346 -51.00193) (xy 34.518886 -51.012479) (xy 34.527412 -51.031775) (xy 34.534856 -51.039268)
			(xy 34.553948 -51.057386) (xy 34.5874 -51.098025) (xy 34.614953 -51.142874) (xy 34.636084 -51.191082)
			(xy 34.650394 -51.241735) (xy 34.657611 -51.293874) (xy 34.658046 -51.320192) (xy 34.657515 -51.347441)
			(xy 34.64976 -51.401385) (xy 34.634408 -51.453677) (xy 34.611771 -51.503252) (xy 34.582309 -51.5491)
			(xy 34.546622 -51.59029) (xy 34.505437 -51.625981) (xy 34.459592 -51.655449) (xy 34.41002 -51.678092)
			(xy 34.35773 -51.693451) (xy 34.303787 -51.701212) (xy 34.276538 -51.7017) (xy 34.248874 -51.701158)
			(xy 34.194126 -51.693164) (xy 34.141105 -51.677353) (xy 34.090921 -51.654055) (xy 34.044625 -51.623758)
			(xy 34.003186 -51.587097) (xy 33.967472 -51.544839) (xy 33.952434 -51.521614) (xy 33.945791 -51.511943)
			(xy 33.925934 -51.499497) (xy 33.914334 -51.497738) (xy 33.834324 -51.489864) (xy 33.822686 -51.48925)
			(xy 33.80085 -51.497317) (xy 33.792414 -51.505358) (xy 33.79216 -51.505612) (xy 33.774083 -51.524197)
			(xy 33.73375 -51.556775) (xy 33.689375 -51.583587) (xy 33.641776 -51.604139) (xy 33.591831 -51.618052)
			(xy 33.540461 -51.625069) (xy 33.514538 -51.6255) (xy 33.487286 -51.625009) (xy 33.433335 -51.617257)
			(xy 33.381038 -51.601906) (xy 33.331457 -51.579267) (xy 33.285603 -51.549802) (xy 33.24441 -51.514111)
			(xy 33.208716 -51.472921) (xy 33.179247 -51.427069) (xy 33.156605 -51.377491) (xy 33.141249 -51.325194)
			(xy 33.133493 -51.271244) (xy 33.13303 -51.243992) (xy 25.439805 -51.243992) (xy 25.433888 -51.252935)
			(xy 25.396671 -51.294472) (xy 25.353803 -51.330147) (xy 25.306197 -51.359201) (xy 25.254868 -51.381013)
			(xy 25.200911 -51.395119) (xy 25.145474 -51.401219) (xy 25.08974 -51.399182) (xy 25.034897 -51.389052)
			(xy 24.982113 -51.371045) (xy 24.932513 -51.345544) (xy 24.887155 -51.313093) (xy 24.847006 -51.274384)
			(xy 24.81292 -51.230241) (xy 24.785624 -51.181606) (xy 24.765701 -51.129515) (xy 24.753575 -51.075078)
			(xy 24.749504 -51.019456) (xy 10.264648 -51.019456) (xy 10.264648 -52.035456) (xy 26.94127 -52.035456)
			(xy 26.945341 -51.979834) (xy 26.957467 -51.925397) (xy 26.97739 -51.873306) (xy 27.004686 -51.824671)
			(xy 27.038772 -51.780528) (xy 27.078921 -51.741819) (xy 27.124279 -51.709368) (xy 27.173879 -51.683867)
			(xy 27.226663 -51.66586) (xy 27.281506 -51.65573) (xy 27.33724 -51.653693) (xy 27.392677 -51.659793)
			(xy 27.446634 -51.673899) (xy 27.497963 -51.695711) (xy 27.545569 -51.724765) (xy 27.588437 -51.76044)
			(xy 27.625654 -51.801977) (xy 27.656427 -51.84849) (xy 27.680099 -51.898987) (xy 27.696167 -51.952394)
			(xy 27.704287 -52.00757) (xy 27.704796 -52.035456) (xy 27.704287 -52.063342) (xy 27.696167 -52.118518)
			(xy 27.680099 -52.171925) (xy 27.656427 -52.222422) (xy 27.625654 -52.268935) (xy 27.588437 -52.310472)
			(xy 27.545569 -52.346147) (xy 27.497963 -52.375201) (xy 27.446634 -52.397013) (xy 27.392677 -52.411119)
			(xy 27.33724 -52.417219) (xy 27.281506 -52.415182) (xy 27.226663 -52.405052) (xy 27.173879 -52.387045)
			(xy 27.124279 -52.361544) (xy 27.078921 -52.329093) (xy 27.038772 -52.290384) (xy 27.004686 -52.246241)
			(xy 26.97739 -52.197606) (xy 26.957467 -52.145515) (xy 26.945341 -52.091078) (xy 26.94127 -52.035456)
			(xy 10.264648 -52.035456) (xy 10.264648 -54.731412) (xy 13.520674 -54.731412) (xy 13.521129 -54.704041)
			(xy 13.528947 -54.649861) (xy 13.544437 -54.597357) (xy 13.567282 -54.54761) (xy 13.597011 -54.501645)
			(xy 13.614654 -54.480714) (xy 13.614908 -54.48046) (xy 13.620476 -54.473361) (xy 13.626734 -54.456454)
			(xy 13.6271 -54.44744) (xy 13.6271 -54.380384) (xy 13.626751 -54.371366) (xy 13.620498 -54.35445)
			(xy 13.614908 -54.347364) (xy 13.614654 -54.347364) (xy 13.614654 -54.34711) (xy 13.597024 -54.326168)
			(xy 13.567297 -54.280203) (xy 13.544449 -54.230458) (xy 13.528951 -54.177957) (xy 13.52112 -54.123779)
			(xy 13.521119 -54.069039) (xy 13.528947 -54.014861) (xy 13.544443 -53.962359) (xy 13.567288 -53.912613)
			(xy 13.597013 -53.866646) (xy 13.614654 -53.845714) (xy 13.614908 -53.84546) (xy 13.620476 -53.838361)
			(xy 13.626734 -53.821454) (xy 13.6271 -53.81244) (xy 13.6271 -53.745384) (xy 13.626751 -53.736366)
			(xy 13.620498 -53.71945) (xy 13.614908 -53.712364) (xy 13.614654 -53.712364) (xy 13.614654 -53.71211)
			(xy 13.597024 -53.691168) (xy 13.567297 -53.645203) (xy 13.544449 -53.595458) (xy 13.528951 -53.542957)
			(xy 13.52112 -53.488779) (xy 13.521119 -53.434039) (xy 13.528947 -53.379861) (xy 13.544443 -53.327359)
			(xy 13.567288 -53.277613) (xy 13.597013 -53.231646) (xy 13.614654 -53.210714) (xy 13.614908 -53.21046)
			(xy 13.620476 -53.203361) (xy 13.626734 -53.186454) (xy 13.6271 -53.17744) (xy 13.6271 -53.110384)
			(xy 13.626751 -53.101366) (xy 13.620498 -53.08445) (xy 13.614908 -53.077364) (xy 13.614654 -53.077364)
			(xy 13.614654 -53.07711) (xy 13.597015 -53.056178) (xy 13.567301 -53.010206) (xy 13.544464 -52.960459)
			(xy 13.528973 -52.907958) (xy 13.521147 -52.853781) (xy 13.520674 -52.826412) (xy 13.52116 -52.799161)
			(xy 13.528916 -52.745213) (xy 13.544271 -52.692918) (xy 13.566913 -52.643341) (xy 13.596379 -52.597491)
			(xy 13.63207 -52.5563) (xy 13.673261 -52.520609) (xy 13.719111 -52.491143) (xy 13.768688 -52.468501)
			(xy 13.820983 -52.453146) (xy 13.874931 -52.44539) (xy 13.929433 -52.44539) (xy 13.983381 -52.453146)
			(xy 14.035676 -52.468501) (xy 14.085253 -52.491143) (xy 14.131103 -52.520609) (xy 14.172294 -52.5563)
			(xy 14.207985 -52.597491) (xy 14.237451 -52.643341) (xy 14.260093 -52.692918) (xy 14.275448 -52.745213)
			(xy 14.283204 -52.799161) (xy 14.28369 -52.826412) (xy 14.283233 -52.853783) (xy 14.275414 -52.907962)
			(xy 14.259922 -52.960466) (xy 14.237079 -53.010212) (xy 14.207352 -53.056179) (xy 14.18971 -53.07711)
			(xy 14.189456 -53.077364) (xy 14.183873 -53.084453) (xy 14.177625 -53.101368) (xy 14.177264 -53.110384)
			(xy 14.177264 -53.17744) (xy 14.17761 -53.186458) (xy 14.183866 -53.203374) (xy 14.189456 -53.21046)
			(xy 14.18971 -53.21046) (xy 14.18971 -53.210714) (xy 14.207361 -53.231638) (xy 14.237082 -53.277608)
			(xy 14.259925 -53.327356) (xy 14.275419 -53.379859) (xy 14.283245 -53.434038) (xy 14.283244 -53.48878)
			(xy 14.275415 -53.542958) (xy 14.259918 -53.595461) (xy 14.237074 -53.645208) (xy 14.20735 -53.691177)
			(xy 14.18971 -53.71211) (xy 14.189456 -53.712364) (xy 14.183873 -53.719453) (xy 14.177625 -53.736368)
			(xy 14.177264 -53.745384) (xy 14.177264 -53.81244) (xy 14.17761 -53.821458) (xy 14.183866 -53.838374)
			(xy 14.189456 -53.84546) (xy 14.18971 -53.84546) (xy 14.18971 -53.845714) (xy 14.207361 -53.866638)
			(xy 14.237082 -53.912608) (xy 14.259925 -53.962356) (xy 14.275419 -54.014859) (xy 14.283245 -54.069038)
			(xy 14.283244 -54.12378) (xy 14.275415 -54.177958) (xy 14.259918 -54.230461) (xy 14.237074 -54.280208)
			(xy 14.20735 -54.326177) (xy 14.18971 -54.34711) (xy 14.189456 -54.347364) (xy 14.183873 -54.354453)
			(xy 14.177625 -54.371368) (xy 14.177264 -54.380384) (xy 14.177264 -54.44744) (xy 14.17761 -54.456458)
			(xy 14.183866 -54.473374) (xy 14.189456 -54.48046) (xy 14.18971 -54.48046) (xy 14.18971 -54.480714)
			(xy 14.207324 -54.501666) (xy 14.237039 -54.547634) (xy 14.25988 -54.597376) (xy 14.275377 -54.649872)
			(xy 14.283212 -54.704044) (xy 14.28369 -54.731412) (xy 14.283204 -54.758663) (xy 14.27854 -54.791102)
			(xy 16.176498 -54.791102) (xy 16.176966 -54.763732) (xy 16.184783 -54.709553) (xy 16.200272 -54.65705)
			(xy 16.223113 -54.607303) (xy 16.252837 -54.561336) (xy 16.270478 -54.540404) (xy 16.270732 -54.54015)
			(xy 16.276307 -54.533056) (xy 16.28256 -54.516145) (xy 16.282924 -54.50713) (xy 16.282924 -54.440074)
			(xy 16.282574 -54.431056) (xy 16.276321 -54.41414) (xy 16.270732 -54.407054) (xy 16.270478 -54.407054)
			(xy 16.270478 -54.4068) (xy 16.252841 -54.385865) (xy 16.22312 -54.339896) (xy 16.200278 -54.29015)
			(xy 16.184783 -54.237649) (xy 16.176956 -54.183471) (xy 16.176955 -54.128732) (xy 16.184783 -54.074554)
			(xy 16.200277 -54.022053) (xy 16.223119 -53.972307) (xy 16.252839 -53.926338) (xy 16.270478 -53.905404)
			(xy 16.270732 -53.90515) (xy 16.276307 -53.898056) (xy 16.28256 -53.881145) (xy 16.282924 -53.87213)
			(xy 16.282924 -53.805074) (xy 16.282574 -53.796056) (xy 16.276321 -53.77914) (xy 16.270732 -53.772054)
			(xy 16.270478 -53.772054) (xy 16.270478 -53.7718) (xy 16.252841 -53.750865) (xy 16.22312 -53.704896)
			(xy 16.200278 -53.65515) (xy 16.184783 -53.602649) (xy 16.176956 -53.548471) (xy 16.176955 -53.493732)
			(xy 16.184783 -53.439554) (xy 16.200277 -53.387053) (xy 16.223119 -53.337307) (xy 16.252839 -53.291338)
			(xy 16.270478 -53.270404) (xy 16.270732 -53.27015) (xy 16.276307 -53.263056) (xy 16.28256 -53.246145)
			(xy 16.282924 -53.23713) (xy 16.282924 -53.170074) (xy 16.282574 -53.161056) (xy 16.276321 -53.14414)
			(xy 16.270732 -53.137054) (xy 16.270478 -53.137054) (xy 16.270478 -53.1368) (xy 16.252822 -53.115882)
			(xy 16.223113 -53.069905) (xy 16.200281 -53.020154) (xy 16.184794 -52.96765) (xy 16.17697 -52.913472)
			(xy 16.176498 -52.886102) (xy 16.176984 -52.858851) (xy 16.18474 -52.804903) (xy 16.200095 -52.752608)
			(xy 16.222737 -52.703031) (xy 16.252203 -52.657181) (xy 16.287894 -52.61599) (xy 16.329085 -52.580299)
			(xy 16.374935 -52.550833) (xy 16.424512 -52.528191) (xy 16.476807 -52.512836) (xy 16.530755 -52.50508)
			(xy 16.585257 -52.50508) (xy 16.639205 -52.512836) (xy 16.6915 -52.528191) (xy 16.7306 -52.546048)
			(xy 21.679696 -52.546048) (xy 21.679696 -52.491552) (xy 21.687451 -52.43761) (xy 21.702804 -52.385321)
			(xy 21.725441 -52.335749) (xy 21.754902 -52.289902) (xy 21.790588 -52.248715) (xy 21.831772 -52.213025)
			(xy 21.877615 -52.183559) (xy 21.927185 -52.160917) (xy 21.979473 -52.145559) (xy 22.033414 -52.137799)
			(xy 22.060662 -52.13731) (xy 22.088032 -52.137796) (xy 22.14221 -52.145609) (xy 22.194713 -52.161093)
			(xy 22.24446 -52.18393) (xy 22.290428 -52.213651) (xy 22.31136 -52.23129) (xy 22.311614 -52.231544)
			(xy 22.318689 -52.237148) (xy 22.335615 -52.243383) (xy 22.344634 -52.243736) (xy 22.41169 -52.243736)
			(xy 22.420705 -52.243366) (xy 22.437622 -52.237127) (xy 22.44471 -52.231544) (xy 22.44471 -52.23129)
			(xy 22.444964 -52.23129) (xy 22.465897 -52.213649) (xy 22.511865 -52.183925) (xy 22.561611 -52.161079)
			(xy 22.614113 -52.145583) (xy 22.668291 -52.137754) (xy 22.723033 -52.137754) (xy 22.777211 -52.145583)
			(xy 22.829713 -52.161079) (xy 22.879459 -52.183925) (xy 22.925427 -52.213649) (xy 22.94636 -52.23129)
			(xy 22.946614 -52.231544) (xy 22.953689 -52.237148) (xy 22.970615 -52.243383) (xy 22.979634 -52.243736)
			(xy 23.04669 -52.243736) (xy 23.055705 -52.243366) (xy 23.072622 -52.237127) (xy 23.07971 -52.231544)
			(xy 23.07971 -52.23129) (xy 23.079964 -52.23129) (xy 23.100898 -52.213653) (xy 23.14687 -52.183941)
			(xy 23.196617 -52.161105) (xy 23.249118 -52.145613) (xy 23.303293 -52.137784) (xy 23.330662 -52.13731)
			(xy 23.357918 -52.137734) (xy 23.411876 -52.145487) (xy 23.464181 -52.160841) (xy 23.513768 -52.183482)
			(xy 23.559628 -52.212951) (xy 23.600827 -52.248646) (xy 23.636527 -52.289842) (xy 23.666 -52.335699)
			(xy 23.688646 -52.385284) (xy 23.704005 -52.437587) (xy 23.711763 -52.491544) (xy 23.711763 -52.546056)
			(xy 23.705819 -52.587398) (xy 24.755346 -52.587398) (xy 24.759417 -52.531776) (xy 24.771543 -52.477339)
			(xy 24.791466 -52.425248) (xy 24.818762 -52.376613) (xy 24.852848 -52.33247) (xy 24.892997 -52.293761)
			(xy 24.938355 -52.26131) (xy 24.987955 -52.235809) (xy 25.040739 -52.217802) (xy 25.095582 -52.207672)
			(xy 25.151316 -52.205635) (xy 25.206753 -52.211735) (xy 25.26071 -52.225841) (xy 25.312039 -52.247653)
			(xy 25.359645 -52.276707) (xy 25.402513 -52.312382) (xy 25.43973 -52.353919) (xy 25.470503 -52.400432)
			(xy 25.494175 -52.450929) (xy 25.510243 -52.504336) (xy 25.517839 -52.555949) (xy 32.583902 -52.555949)
			(xy 32.583902 -52.501451) (xy 32.591658 -52.447509) (xy 32.607011 -52.395219) (xy 32.629649 -52.345646)
			(xy 32.659112 -52.299799) (xy 32.694799 -52.258612) (xy 32.735985 -52.222923) (xy 32.78183 -52.193458)
			(xy 32.831402 -52.170817) (xy 32.883691 -52.155462) (xy 32.937633 -52.147703) (xy 32.964882 -52.147216)
			(xy 32.992252 -52.147689) (xy 33.046431 -52.155504) (xy 33.098934 -52.170992) (xy 33.148681 -52.193832)
			(xy 33.194648 -52.223555) (xy 33.21558 -52.241196) (xy 33.215834 -52.24145) (xy 33.222931 -52.247021)
			(xy 33.23984 -52.253276) (xy 33.248854 -52.253642) (xy 33.31591 -52.253642) (xy 33.324929 -52.253302)
			(xy 33.341846 -52.247044) (xy 33.34893 -52.24145) (xy 33.34893 -52.241196) (xy 33.349184 -52.241196)
			(xy 33.370111 -52.22355) (xy 33.416085 -52.19384) (xy 33.465834 -52.171005) (xy 33.518336 -52.155515)
			(xy 33.572512 -52.147689) (xy 33.599882 -52.147216) (xy 33.627137 -52.14763) (xy 33.681094 -52.155385)
			(xy 33.733397 -52.170741) (xy 33.782983 -52.193383) (xy 33.828841 -52.222853) (xy 33.870038 -52.258549)
			(xy 33.905736 -52.299745) (xy 33.935208 -52.345601) (xy 33.957853 -52.395186) (xy 33.973211 -52.447489)
			(xy 33.980969 -52.501445) (xy 33.980969 -52.555955) (xy 33.973211 -52.609911) (xy 33.957853 -52.662214)
			(xy 33.935208 -52.711799) (xy 33.905736 -52.757655) (xy 33.870038 -52.798851) (xy 33.828841 -52.834547)
			(xy 33.782983 -52.864017) (xy 33.733397 -52.886659) (xy 33.681094 -52.902015) (xy 33.627137 -52.90977)
			(xy 33.599882 -52.910232) (xy 33.572511 -52.909793) (xy 33.51833 -52.901971) (xy 33.465826 -52.886477)
			(xy 33.416079 -52.863629) (xy 33.370114 -52.833897) (xy 33.349184 -52.816252) (xy 33.34893 -52.815998)
			(xy 33.341839 -52.810418) (xy 33.324926 -52.804167) (xy 33.31591 -52.803806) (xy 33.248854 -52.803806)
			(xy 33.23984 -52.804188) (xy 33.222922 -52.810418) (xy 33.215834 -52.815998) (xy 33.215834 -52.816252)
			(xy 33.21558 -52.816252) (xy 33.194622 -52.83386) (xy 33.148657 -52.863578) (xy 33.098916 -52.886421)
			(xy 33.046421 -52.901919) (xy 32.99225 -52.909754) (xy 32.964882 -52.910232) (xy 32.937633 -52.909697)
			(xy 32.883691 -52.901938) (xy 32.831402 -52.886583) (xy 32.78183 -52.863942) (xy 32.735985 -52.834477)
			(xy 32.694799 -52.798788) (xy 32.659112 -52.757601) (xy 32.629649 -52.711754) (xy 32.607011 -52.662181)
			(xy 32.591658 -52.609891) (xy 32.583902 -52.555949) (xy 25.517839 -52.555949) (xy 25.518363 -52.559512)
			(xy 25.518872 -52.587398) (xy 25.518363 -52.615284) (xy 25.510243 -52.67046) (xy 25.494175 -52.723867)
			(xy 25.470503 -52.774364) (xy 25.43973 -52.820877) (xy 25.402513 -52.862414) (xy 25.359645 -52.898089)
			(xy 25.312039 -52.927143) (xy 25.26071 -52.948955) (xy 25.206753 -52.963061) (xy 25.151316 -52.969161)
			(xy 25.095582 -52.967124) (xy 25.040739 -52.956994) (xy 24.987955 -52.938987) (xy 24.938355 -52.913486)
			(xy 24.892997 -52.881035) (xy 24.852848 -52.842326) (xy 24.818762 -52.798183) (xy 24.791466 -52.749548)
			(xy 24.771543 -52.697457) (xy 24.759417 -52.64302) (xy 24.755346 -52.587398) (xy 23.705819 -52.587398)
			(xy 23.704005 -52.600013) (xy 23.688646 -52.652316) (xy 23.666 -52.701901) (xy 23.636527 -52.747758)
			(xy 23.600827 -52.788954) (xy 23.559628 -52.824649) (xy 23.513768 -52.854118) (xy 23.464181 -52.876759)
			(xy 23.411876 -52.892113) (xy 23.357918 -52.899866) (xy 23.330662 -52.900326) (xy 23.303292 -52.899842)
			(xy 23.249113 -52.892031) (xy 23.19661 -52.876547) (xy 23.146862 -52.853709) (xy 23.100895 -52.823987)
			(xy 23.079964 -52.806346) (xy 23.07971 -52.806092) (xy 23.072625 -52.800503) (xy 23.055707 -52.794258)
			(xy 23.04669 -52.7939) (xy 22.979634 -52.7939) (xy 22.970619 -52.794273) (xy 22.953702 -52.800509)
			(xy 22.946614 -52.806092) (xy 22.94636 -52.806346) (xy 22.925427 -52.823987) (xy 22.879459 -52.853711)
			(xy 22.829713 -52.876557) (xy 22.777211 -52.892053) (xy 22.723033 -52.899882) (xy 22.668291 -52.899882)
			(xy 22.614113 -52.892053) (xy 22.561611 -52.876557) (xy 22.511865 -52.853711) (xy 22.465897 -52.823987)
			(xy 22.444964 -52.806346) (xy 22.44471 -52.806092) (xy 22.437625 -52.800503) (xy 22.420707 -52.794258)
			(xy 22.41169 -52.7939) (xy 22.344634 -52.7939) (xy 22.335619 -52.794273) (xy 22.318702 -52.800509)
			(xy 22.311614 -52.806092) (xy 22.311614 -52.806346) (xy 22.31136 -52.806346) (xy 22.290409 -52.823962)
			(xy 22.244442 -52.853679) (xy 22.1947 -52.87652) (xy 22.142203 -52.892017) (xy 22.08803 -52.89985)
			(xy 22.060662 -52.900326) (xy 22.033414 -52.899801) (xy 21.979473 -52.892041) (xy 21.927185 -52.876683)
			(xy 21.877615 -52.854041) (xy 21.831772 -52.824575) (xy 21.790588 -52.788885) (xy 21.754902 -52.747698)
			(xy 21.725441 -52.701851) (xy 21.702804 -52.652279) (xy 21.687451 -52.59999) (xy 21.679696 -52.546048)
			(xy 16.7306 -52.546048) (xy 16.741077 -52.550833) (xy 16.786927 -52.580299) (xy 16.828118 -52.61599)
			(xy 16.863809 -52.657181) (xy 16.893275 -52.703031) (xy 16.915917 -52.752608) (xy 16.931272 -52.804903)
			(xy 16.939028 -52.858851) (xy 16.939514 -52.886102) (xy 16.939046 -52.913472) (xy 16.931228 -52.967651)
			(xy 16.915739 -53.020154) (xy 16.892898 -53.069901) (xy 16.863175 -53.115868) (xy 16.845534 -53.1368)
			(xy 16.84528 -53.137054) (xy 16.839704 -53.144148) (xy 16.833452 -53.161059) (xy 16.833088 -53.170074)
			(xy 16.833088 -53.23713) (xy 16.833434 -53.246148) (xy 16.839689 -53.263065) (xy 16.84528 -53.27015)
			(xy 16.845534 -53.27015) (xy 16.845534 -53.270404) (xy 16.863178 -53.291334) (xy 16.892906 -53.337302)
			(xy 16.915754 -53.387048) (xy 16.931251 -53.439551) (xy 16.939081 -53.49373) (xy 16.93908 -53.548473)
			(xy 16.931251 -53.602652) (xy 16.915753 -53.655155) (xy 16.892905 -53.704901) (xy 16.863176 -53.750868)
			(xy 16.846604 -53.77053) (xy 17.210786 -53.77053) (xy 17.211293 -53.741612) (xy 17.22002 -53.684439)
			(xy 17.237278 -53.629239) (xy 17.262671 -53.577276) (xy 17.295619 -53.529743) (xy 17.335364 -53.487728)
			(xy 17.357852 -53.46954) (xy 17.36664 -53.461915) (xy 17.376832 -53.441027) (xy 17.37741 -53.429408)
			(xy 17.37741 -53.349652) (xy 17.376881 -53.338019) (xy 17.366685 -53.31711) (xy 17.357852 -53.30952)
			(xy 17.335368 -53.29133) (xy 17.295635 -53.249308) (xy 17.262698 -53.201773) (xy 17.23731 -53.149812)
			(xy 17.220053 -53.094615) (xy 17.211322 -53.037446) (xy 17.210786 -53.00853) (xy 17.211283 -52.981278)
			(xy 17.219036 -52.927329) (xy 17.234388 -52.875032) (xy 17.257026 -52.825452) (xy 17.286491 -52.779599)
			(xy 17.322181 -52.738406) (xy 17.36337 -52.702712) (xy 17.409221 -52.673244) (xy 17.458798 -52.6506)
			(xy 17.511094 -52.635244) (xy 17.565042 -52.627486) (xy 17.592294 -52.627022) (xy 17.618608 -52.627486)
			(xy 17.670737 -52.634721) (xy 17.72138 -52.64904) (xy 17.769579 -52.670173) (xy 17.814423 -52.69772)
			(xy 17.855062 -52.73116) (xy 17.873218 -52.750212) (xy 17.880729 -52.757625) (xy 17.900017 -52.766143)
			(xy 17.910556 -52.766722) (xy 17.985232 -52.766722) (xy 17.995778 -52.766163) (xy 18.015073 -52.757648)
			(xy 18.02257 -52.750212) (xy 18.04075 -52.73118) (xy 18.081374 -52.697721) (xy 18.126209 -52.670158)
			(xy 18.174405 -52.649015) (xy 18.225049 -52.634693) (xy 18.277179 -52.627463) (xy 18.303494 -52.627022)
			(xy 18.330748 -52.627461) (xy 18.384701 -52.635218) (xy 18.437002 -52.650575) (xy 18.486584 -52.673219)
			(xy 18.532438 -52.702689) (xy 18.573632 -52.738385) (xy 18.609326 -52.779581) (xy 18.638793 -52.825437)
			(xy 18.661434 -52.875021) (xy 18.676787 -52.927322) (xy 18.684541 -52.981276) (xy 18.685002 -53.00853)
			(xy 18.684512 -53.036196) (xy 18.676509 -53.090946) (xy 18.660688 -53.143968) (xy 18.637381 -53.194152)
			(xy 18.607077 -53.240448) (xy 18.570409 -53.281885) (xy 18.528144 -53.317597) (xy 18.504916 -53.332634)
			(xy 18.495219 -53.339246) (xy 18.482787 -53.359126) (xy 18.48104 -53.370734) (xy 18.473166 -53.450744)
			(xy 18.47251 -53.462383) (xy 18.480606 -53.484222) (xy 18.48866 -53.492654) (xy 18.488914 -53.492908)
			(xy 18.507484 -53.511) (xy 18.540063 -53.55133) (xy 18.566877 -53.595702) (xy 18.587432 -53.643298)
			(xy 18.601348 -53.69324) (xy 18.608368 -53.744608) (xy 18.608802 -53.77053) (xy 18.60835 -53.797782)
			(xy 18.600589 -53.851732) (xy 18.58523 -53.904027) (xy 18.562585 -53.953605) (xy 18.533115 -53.999456)
			(xy 18.49742 -54.040646) (xy 18.456227 -54.076337) (xy 18.410373 -54.105802) (xy 18.360793 -54.128443)
			(xy 18.308496 -54.143797) (xy 18.254546 -54.151553) (xy 18.227294 -54.152038) (xy 18.199923 -54.151591)
			(xy 18.145742 -54.143771) (xy 18.093239 -54.128278) (xy 18.043492 -54.105432) (xy 17.997526 -54.075702)
			(xy 17.976596 -54.058058) (xy 17.976342 -54.057804) (xy 17.969247 -54.052229) (xy 17.952337 -54.045975)
			(xy 17.943322 -54.045612) (xy 17.876266 -54.045612) (xy 17.867247 -54.04595) (xy 17.85033 -54.052211)
			(xy 17.843246 -54.057804) (xy 17.843246 -54.058058) (xy 17.842992 -54.058058) (xy 17.822068 -54.075708)
			(xy 17.776094 -54.105419) (xy 17.726344 -54.128254) (xy 17.673842 -54.143742) (xy 17.619664 -54.151567)
			(xy 17.592294 -54.152038) (xy 17.565044 -54.151528) (xy 17.511099 -54.143771) (xy 17.458806 -54.128417)
			(xy 17.409231 -54.105777) (xy 17.363382 -54.076313) (xy 17.322193 -54.040624) (xy 17.286501 -53.999437)
			(xy 17.257034 -53.95359) (xy 17.234391 -53.904016) (xy 17.219034 -53.851725) (xy 17.211274 -53.79778)
			(xy 17.210786 -53.77053) (xy 16.846604 -53.77053) (xy 16.845534 -53.7718) (xy 16.84528 -53.772054)
			(xy 16.839704 -53.779148) (xy 16.833452 -53.796059) (xy 16.833088 -53.805074) (xy 16.833088 -53.87213)
			(xy 16.833434 -53.881148) (xy 16.839689 -53.898065) (xy 16.84528 -53.90515) (xy 16.845534 -53.90515)
			(xy 16.845534 -53.905404) (xy 16.863178 -53.926334) (xy 16.892906 -53.972302) (xy 16.915754 -54.022048)
			(xy 16.931251 -54.074551) (xy 16.939081 -54.12873) (xy 16.93908 -54.183473) (xy 16.931251 -54.237652)
			(xy 16.915753 -54.290155) (xy 16.90196 -54.320186) (xy 19.130518 -54.320186) (xy 19.130971 -54.292815)
			(xy 19.138792 -54.238635) (xy 19.154283 -54.186132) (xy 19.177128 -54.136385) (xy 19.206855 -54.090419)
			(xy 19.224498 -54.069488) (xy 19.224752 -54.069234) (xy 19.230337 -54.062146) (xy 19.236583 -54.04523)
			(xy 19.236944 -54.036214) (xy 19.236944 -53.969158) (xy 19.236572 -53.960142) (xy 19.230336 -53.943225)
			(xy 19.224752 -53.936138) (xy 19.224498 -53.936138) (xy 19.224498 -53.935884) (xy 19.206885 -53.914931)
			(xy 19.177169 -53.868964) (xy 19.154328 -53.819222) (xy 19.138831 -53.766726) (xy 19.130996 -53.712554)
			(xy 19.130518 -53.685186) (xy 19.131004 -53.657935) (xy 19.13876 -53.603987) (xy 19.154115 -53.551692)
			(xy 19.176757 -53.502115) (xy 19.206223 -53.456265) (xy 19.241914 -53.415074) (xy 19.283105 -53.379383)
			(xy 19.328955 -53.349917) (xy 19.378532 -53.327275) (xy 19.430827 -53.31192) (xy 19.484775 -53.304164)
			(xy 19.539277 -53.304164) (xy 19.593225 -53.31192) (xy 19.64552 -53.327275) (xy 19.695097 -53.349917)
			(xy 19.740947 -53.379383) (xy 19.782138 -53.415074) (xy 19.817829 -53.456265) (xy 19.847295 -53.502115)
			(xy 19.869937 -53.551692) (xy 19.885292 -53.603987) (xy 19.893048 -53.657935) (xy 19.893534 -53.685186)
			(xy 19.893076 -53.712557) (xy 19.885259 -53.766737) (xy 19.869769 -53.819241) (xy 19.846925 -53.868987)
			(xy 19.817197 -53.914953) (xy 19.799554 -53.935884) (xy 19.7993 -53.936138) (xy 19.793733 -53.943238)
			(xy 19.787475 -53.960145) (xy 19.787108 -53.969158) (xy 19.787108 -54.036214) (xy 19.787457 -54.045232)
			(xy 19.79371 -54.062149) (xy 19.7993 -54.069234) (xy 19.799554 -54.069234) (xy 19.799554 -54.069488)
			(xy 19.817194 -54.09042) (xy 19.846907 -54.136392) (xy 19.869744 -54.186139) (xy 19.885234 -54.23864)
			(xy 19.893061 -54.292817) (xy 19.893534 -54.320186) (xy 19.893048 -54.347437) (xy 19.885292 -54.401385)
			(xy 19.869937 -54.45368) (xy 19.847295 -54.503257) (xy 19.817829 -54.549107) (xy 19.782138 -54.590298)
			(xy 19.740947 -54.625989) (xy 19.695097 -54.655455) (xy 19.64552 -54.678097) (xy 19.593225 -54.693452)
			(xy 19.539277 -54.701208) (xy 19.484775 -54.701208) (xy 19.430827 -54.693452) (xy 19.378532 -54.678097)
			(xy 19.328955 -54.655455) (xy 19.283105 -54.625989) (xy 19.241914 -54.590298) (xy 19.206223 -54.549107)
			(xy 19.176757 -54.503257) (xy 19.154115 -54.45368) (xy 19.13876 -54.401385) (xy 19.131004 -54.347437)
			(xy 19.130518 -54.320186) (xy 16.90196 -54.320186) (xy 16.892905 -54.339901) (xy 16.863176 -54.385868)
			(xy 16.845534 -54.4068) (xy 16.84528 -54.407054) (xy 16.839704 -54.414148) (xy 16.833452 -54.431059)
			(xy 16.833088 -54.440074) (xy 16.833088 -54.50713) (xy 16.833434 -54.516148) (xy 16.839689 -54.533065)
			(xy 16.84528 -54.54015) (xy 16.845534 -54.54015) (xy 16.845534 -54.540404) (xy 16.863194 -54.561319)
			(xy 16.892901 -54.607297) (xy 16.915733 -54.657049) (xy 16.931219 -54.709553) (xy 16.939042 -54.763732)
			(xy 16.939159 -54.770528) (xy 20.07108 -54.770528) (xy 20.071543 -54.743157) (xy 20.079359 -54.688977)
			(xy 20.094847 -54.636474) (xy 20.11769 -54.586727) (xy 20.147417 -54.540761) (xy 20.16506 -54.51983)
			(xy 20.165314 -54.519576) (xy 20.170918 -54.512502) (xy 20.177154 -54.495575) (xy 20.177506 -54.486556)
			(xy 20.177506 -54.4195) (xy 20.177148 -54.410483) (xy 20.170901 -54.393566) (xy 20.165314 -54.38648)
			(xy 20.16506 -54.38648) (xy 20.16506 -54.386226) (xy 20.147413 -54.3653) (xy 20.117704 -54.319325)
			(xy 20.09487 -54.269576) (xy 20.07938 -54.217074) (xy 20.071553 -54.162898) (xy 20.07108 -54.135528)
			(xy 20.071566 -54.108277) (xy 20.079322 -54.054329) (xy 20.094677 -54.002034) (xy 20.117319 -53.952457)
			(xy 20.146785 -53.906607) (xy 20.182476 -53.865416) (xy 20.223667 -53.829725) (xy 20.269517 -53.800259)
			(xy 20.319094 -53.777617) (xy 20.371389 -53.762262) (xy 20.425337 -53.754506) (xy 20.479839 -53.754506)
			(xy 20.533787 -53.762262) (xy 20.586082 -53.777617) (xy 20.635659 -53.800259) (xy 20.681509 -53.829725)
			(xy 20.7227 -53.865416) (xy 20.758391 -53.906607) (xy 20.787857 -53.952457) (xy 20.792932 -53.96357)
			(xy 24.77211 -53.96357) (xy 24.776181 -53.907948) (xy 24.788307 -53.853511) (xy 24.80823 -53.80142)
			(xy 24.835526 -53.752785) (xy 24.869612 -53.708642) (xy 24.909761 -53.669933) (xy 24.955119 -53.637482)
			(xy 25.004719 -53.611981) (xy 25.057503 -53.593974) (xy 25.112346 -53.583844) (xy 25.16808 -53.581807)
			(xy 25.223517 -53.587907) (xy 25.277474 -53.602013) (xy 25.328803 -53.623825) (xy 25.376409 -53.652879)
			(xy 25.419277 -53.688554) (xy 25.456494 -53.730091) (xy 25.487267 -53.776604) (xy 25.510939 -53.827101)
			(xy 25.527007 -53.880508) (xy 25.535127 -53.935684) (xy 25.535636 -53.96357) (xy 25.535127 -53.991456)
			(xy 25.527007 -54.046632) (xy 25.510939 -54.100039) (xy 25.487267 -54.150536) (xy 25.456494 -54.197049)
			(xy 25.419277 -54.238586) (xy 25.376409 -54.274261) (xy 25.328803 -54.303315) (xy 25.277474 -54.325127)
			(xy 25.223517 -54.339233) (xy 25.16808 -54.345333) (xy 25.112346 -54.343296) (xy 25.057503 -54.333166)
			(xy 25.004719 -54.315159) (xy 24.955119 -54.289658) (xy 24.909761 -54.257207) (xy 24.869612 -54.218498)
			(xy 24.835526 -54.174355) (xy 24.80823 -54.12572) (xy 24.788307 -54.073629) (xy 24.776181 -54.019192)
			(xy 24.77211 -53.96357) (xy 20.792932 -53.96357) (xy 20.810499 -54.002034) (xy 20.825854 -54.054329)
			(xy 20.83361 -54.108277) (xy 20.834096 -54.135528) (xy 20.833647 -54.162899) (xy 20.825825 -54.217079)
			(xy 20.810332 -54.269582) (xy 20.787487 -54.319329) (xy 20.757759 -54.365295) (xy 20.740116 -54.386226)
			(xy 20.739862 -54.38648) (xy 20.734273 -54.393565) (xy 20.728029 -54.410483) (xy 20.72767 -54.4195)
			(xy 20.72767 -54.486556) (xy 20.728055 -54.49557) (xy 20.734284 -54.512487) (xy 20.739862 -54.519576)
			(xy 20.740116 -54.519576) (xy 20.740116 -54.51983) (xy 20.757738 -54.540776) (xy 20.787452 -54.586745)
			(xy 20.810291 -54.636489) (xy 20.825786 -54.688987) (xy 20.833619 -54.74316) (xy 20.834096 -54.770528)
			(xy 20.83361 -54.797779) (xy 20.825854 -54.851727) (xy 20.810499 -54.904022) (xy 20.787857 -54.953599)
			(xy 20.758391 -54.999449) (xy 20.7227 -55.04064) (xy 20.681509 -55.076331) (xy 20.635659 -55.105797)
			(xy 20.586082 -55.128439) (xy 20.533787 -55.143794) (xy 20.479839 -55.15155) (xy 20.425337 -55.15155)
			(xy 20.371389 -55.143794) (xy 20.319094 -55.128439) (xy 20.269517 -55.105797) (xy 20.223667 -55.076331)
			(xy 20.182476 -55.04064) (xy 20.146785 -54.999449) (xy 20.117319 -54.953599) (xy 20.094677 -54.904022)
			(xy 20.079322 -54.851727) (xy 20.071566 -54.797779) (xy 20.07108 -54.770528) (xy 16.939159 -54.770528)
			(xy 16.939514 -54.791102) (xy 16.939028 -54.818353) (xy 16.931272 -54.872301) (xy 16.915917 -54.924596)
			(xy 16.893275 -54.974173) (xy 16.863809 -55.020023) (xy 16.828118 -55.061214) (xy 16.786927 -55.096905)
			(xy 16.741077 -55.126371) (xy 16.6915 -55.149013) (xy 16.639205 -55.164368) (xy 16.585257 -55.172124)
			(xy 16.530755 -55.172124) (xy 16.476807 -55.164368) (xy 16.424512 -55.149013) (xy 16.374935 -55.126371)
			(xy 16.329085 -55.096905) (xy 16.287894 -55.061214) (xy 16.252203 -55.020023) (xy 16.222737 -54.974173)
			(xy 16.200095 -54.924596) (xy 16.18474 -54.872301) (xy 16.176984 -54.818353) (xy 16.176498 -54.791102)
			(xy 14.27854 -54.791102) (xy 14.275448 -54.812611) (xy 14.260093 -54.864906) (xy 14.237451 -54.914483)
			(xy 14.207985 -54.960333) (xy 14.172294 -55.001524) (xy 14.131103 -55.037215) (xy 14.085253 -55.066681)
			(xy 14.035676 -55.089323) (xy 13.983381 -55.104678) (xy 13.929433 -55.112434) (xy 13.874931 -55.112434)
			(xy 13.820983 -55.104678) (xy 13.768688 -55.089323) (xy 13.719111 -55.066681) (xy 13.673261 -55.037215)
			(xy 13.63207 -55.001524) (xy 13.596379 -54.960333) (xy 13.566913 -54.914483) (xy 13.544271 -54.864906)
			(xy 13.528916 -54.812611) (xy 13.52116 -54.758663) (xy 13.520674 -54.731412) (xy 10.264648 -54.731412)
			(xy 10.264648 -57.002934) (xy 21.563584 -57.002934) (xy 21.564105 -56.974843) (xy 21.572327 -56.919267)
			(xy 21.588614 -56.865499) (xy 21.612612 -56.814702) (xy 21.643803 -56.767974) (xy 21.681511 -56.726329)
			(xy 21.724921 -56.690665) (xy 21.74875 -56.675782) (xy 21.75764 -56.670448) (xy 21.769832 -56.65343)
			(xy 21.790152 -56.560212) (xy 21.785834 -56.539638) (xy 21.779992 -56.531002) (xy 21.76399 -56.50694)
			(xy 21.738648 -56.455008) (xy 21.721423 -56.399849) (xy 21.712708 -56.342725) (xy 21.712174 -56.313832)
			(xy 21.712685 -56.286581) (xy 21.720437 -56.232632) (xy 21.735788 -56.180337) (xy 21.758426 -56.130758)
			(xy 21.787889 -56.084905) (xy 21.823577 -56.043713) (xy 21.864765 -56.008019) (xy 21.910614 -55.97855)
			(xy 21.96019 -55.955906) (xy 22.012484 -55.940548) (xy 22.066431 -55.932789) (xy 22.093682 -55.932324)
			(xy 22.121052 -55.932795) (xy 22.175231 -55.940611) (xy 22.227735 -55.956098) (xy 22.277481 -55.978939)
			(xy 22.323448 -56.008663) (xy 22.34438 -56.026304) (xy 22.344634 -56.026558) (xy 22.35173 -56.03213)
			(xy 22.36864 -56.038384) (xy 22.377654 -56.03875) (xy 22.44471 -56.03875) (xy 22.453729 -56.038408)
			(xy 22.470646 -56.032151) (xy 22.47773 -56.026558) (xy 22.47773 -56.026304) (xy 22.477984 -56.026304)
			(xy 22.498917 -56.008663) (xy 22.544885 -55.978939) (xy 22.594631 -55.956093) (xy 22.647133 -55.940597)
			(xy 22.701311 -55.932768) (xy 22.756053 -55.932768) (xy 22.810231 -55.940597) (xy 22.862733 -55.956093)
			(xy 22.912479 -55.978939) (xy 22.958447 -56.008663) (xy 22.97938 -56.026304) (xy 22.979634 -56.026558)
			(xy 22.98673 -56.03213) (xy 23.00364 -56.038384) (xy 23.012654 -56.03875) (xy 23.07971 -56.03875)
			(xy 23.088729 -56.038408) (xy 23.105646 -56.032151) (xy 23.11273 -56.026558) (xy 23.11273 -56.026304)
			(xy 23.112984 -56.026304) (xy 23.133912 -56.00866) (xy 23.179886 -55.978948) (xy 23.229634 -55.956113)
			(xy 23.282136 -55.940624) (xy 23.336313 -55.932797) (xy 23.363682 -55.932324) (xy 23.390938 -55.932722)
			(xy 23.444895 -55.940477) (xy 23.4972 -55.955833) (xy 23.546787 -55.978476) (xy 23.592646 -56.007946)
			(xy 23.633844 -56.043643) (xy 23.669543 -56.08484) (xy 23.699015 -56.130698) (xy 23.721661 -56.180283)
			(xy 23.737019 -56.232587) (xy 23.744777 -56.286544) (xy 23.744777 -56.341056) (xy 23.737019 -56.395013)
			(xy 23.721661 -56.447317) (xy 23.699015 -56.496902) (xy 23.669543 -56.54276) (xy 23.633844 -56.583957)
			(xy 23.592646 -56.619654) (xy 23.546787 -56.649124) (xy 23.4972 -56.671767) (xy 23.444895 -56.687123)
			(xy 23.390938 -56.694878) (xy 23.363682 -56.69534) (xy 23.336311 -56.694899) (xy 23.28213 -56.687077)
			(xy 23.229626 -56.671583) (xy 23.179879 -56.648736) (xy 23.133914 -56.619005) (xy 23.112984 -56.60136)
			(xy 23.11273 -56.601106) (xy 23.105639 -56.595527) (xy 23.088726 -56.589275) (xy 23.07971 -56.588914)
			(xy 23.012654 -56.588914) (xy 23.003639 -56.589294) (xy 22.986722 -56.595525) (xy 22.979634 -56.601106)
			(xy 22.979634 -56.60136) (xy 22.97938 -56.60136) (xy 22.958447 -56.619001) (xy 22.912479 -56.648725)
			(xy 22.862733 -56.671571) (xy 22.810231 -56.687067) (xy 22.756053 -56.694896) (xy 22.701311 -56.694896)
			(xy 22.647133 -56.687067) (xy 22.594631 -56.671571) (xy 22.544885 -56.648725) (xy 22.498917 -56.619001)
			(xy 22.477984 -56.60136) (xy 22.47773 -56.601106) (xy 22.470639 -56.595527) (xy 22.453726 -56.589275)
			(xy 22.44471 -56.588914) (xy 22.377654 -56.588914) (xy 22.368639 -56.589294) (xy 22.351722 -56.595525)
			(xy 22.344634 -56.601106) (xy 22.344126 -56.60136) (xy 22.331394 -56.612307) (xy 22.304301 -56.632146)
			(xy 22.290024 -56.640984) (xy 22.281134 -56.646318) (xy 22.268942 -56.663336) (xy 22.248622 -56.756554)
			(xy 22.25294 -56.777128) (xy 22.258782 -56.785764) (xy 22.274767 -56.809837) (xy 22.300113 -56.861765)
			(xy 22.317343 -56.91692) (xy 22.326063 -56.974042) (xy 22.3266 -57.002934) (xy 22.326114 -57.030185)
			(xy 22.318358 -57.084133) (xy 22.303003 -57.136428) (xy 22.280361 -57.186005) (xy 22.250895 -57.231855)
			(xy 22.215204 -57.273046) (xy 22.174013 -57.308737) (xy 22.128163 -57.338203) (xy 22.078586 -57.360845)
			(xy 22.026291 -57.3762) (xy 21.972343 -57.383956) (xy 21.917841 -57.383956) (xy 21.863893 -57.3762)
			(xy 21.811598 -57.360845) (xy 21.762021 -57.338203) (xy 21.716171 -57.308737) (xy 21.67498 -57.273046)
			(xy 21.639289 -57.231855) (xy 21.609823 -57.186005) (xy 21.587181 -57.136428) (xy 21.571826 -57.084133)
			(xy 21.56407 -57.030185) (xy 21.563584 -57.002934) (xy 10.264648 -57.002934) (xy 10.264648 -58.679334)
			(xy 21.995384 -58.679334) (xy 21.995813 -58.653019) (xy 22.003056 -58.600889) (xy 22.017383 -58.550246)
			(xy 22.038523 -58.502047) (xy 22.066076 -58.457204) (xy 22.09952 -58.416566) (xy 22.118574 -58.39841)
			(xy 22.125969 -58.390883) (xy 22.134498 -58.371607) (xy 22.135084 -58.361072) (xy 22.135084 -58.286396)
			(xy 22.134575 -58.275844) (xy 22.126026 -58.256549) (xy 22.118574 -58.249058) (xy 22.0995 -58.230921)
			(xy 22.066046 -58.190287) (xy 22.03849 -58.145442) (xy 22.017355 -58.097238) (xy 22.003041 -58.046588)
			(xy 21.99582 -57.994451) (xy 21.995384 -57.968134) (xy 21.99587 -57.940883) (xy 22.003626 -57.886935)
			(xy 22.018981 -57.83464) (xy 22.041623 -57.785063) (xy 22.071089 -57.739213) (xy 22.10678 -57.698022)
			(xy 22.147971 -57.662331) (xy 22.193821 -57.632865) (xy 22.243398 -57.610223) (xy 22.295693 -57.594868)
			(xy 22.349641 -57.587112) (xy 22.404143 -57.587112) (xy 22.458091 -57.594868) (xy 22.510386 -57.610223)
			(xy 22.559963 -57.632865) (xy 22.605813 -57.662331) (xy 22.647004 -57.698022) (xy 22.682695 -57.739213)
			(xy 22.712161 -57.785063) (xy 22.734803 -57.83464) (xy 22.750158 -57.886935) (xy 22.757914 -57.940883)
			(xy 22.7584 -57.968134) (xy 22.757955 -57.994449) (xy 22.750716 -58.046578) (xy 22.736392 -58.097221)
			(xy 22.715256 -58.14542) (xy 22.687705 -58.190263) (xy 22.654263 -58.230902) (xy 22.63521 -58.249058)
			(xy 22.627826 -58.256595) (xy 22.619291 -58.275863) (xy 22.6187 -58.286396) (xy 22.6187 -58.361072)
			(xy 22.619231 -58.371621) (xy 22.627765 -58.390917) (xy 22.63521 -58.39841) (xy 22.654265 -58.416566)
			(xy 22.687722 -58.457196) (xy 22.715281 -58.502036) (xy 22.736419 -58.550237) (xy 22.750737 -58.600884)
			(xy 22.757961 -58.653018) (xy 22.7584 -58.679334) (xy 22.757914 -58.706585) (xy 22.750158 -58.760533)
			(xy 22.734803 -58.812828) (xy 22.712161 -58.862405) (xy 22.682695 -58.908255) (xy 22.647004 -58.949446)
			(xy 22.605813 -58.985137) (xy 22.559963 -59.014603) (xy 22.510386 -59.037245) (xy 22.458091 -59.0526)
			(xy 22.404143 -59.060356) (xy 22.349641 -59.060356) (xy 22.295693 -59.0526) (xy 22.243398 -59.037245)
			(xy 22.193821 -59.014603) (xy 22.147971 -58.985137) (xy 22.10678 -58.949446) (xy 22.071089 -58.908255)
			(xy 22.041623 -58.862405) (xy 22.018981 -58.812828) (xy 22.003626 -58.760533) (xy 21.99587 -58.706585)
			(xy 21.995384 -58.679334) (xy 10.264648 -58.679334) (xy 10.264648 -60.019261) (xy 22.135824 -60.019261)
			(xy 22.135824 -59.964759) (xy 22.14358 -59.910811) (xy 22.158935 -59.858516) (xy 22.181576 -59.808938)
			(xy 22.211043 -59.763088) (xy 22.246734 -59.721897) (xy 22.287924 -59.686205) (xy 22.333775 -59.656738)
			(xy 22.383352 -59.634097) (xy 22.435647 -59.618741) (xy 22.489595 -59.610984) (xy 22.516846 -59.610498)
			(xy 22.544215 -59.610996) (xy 22.598393 -59.618806) (xy 22.650895 -59.634288) (xy 22.700643 -59.657123)
			(xy 22.746611 -59.68684) (xy 22.767544 -59.704478) (xy 22.767798 -59.704732) (xy 22.774878 -59.710327)
			(xy 22.7918 -59.716568) (xy 22.800818 -59.716924) (xy 22.867874 -59.716924) (xy 22.876889 -59.716549)
			(xy 22.893806 -59.710313) (xy 22.900894 -59.704732) (xy 22.900894 -59.704478) (xy 22.901148 -59.704478)
			(xy 22.922081 -59.686837) (xy 22.968049 -59.657113) (xy 23.017795 -59.634267) (xy 23.070297 -59.618771)
			(xy 23.124475 -59.610942) (xy 23.179217 -59.610942) (xy 23.233395 -59.618771) (xy 23.285897 -59.634267)
			(xy 23.335643 -59.657113) (xy 23.381611 -59.686837) (xy 23.402544 -59.704478) (xy 23.402798 -59.704732)
			(xy 23.409878 -59.710327) (xy 23.4268 -59.716568) (xy 23.435818 -59.716924) (xy 23.502874 -59.716924)
			(xy 23.511889 -59.716549) (xy 23.528806 -59.710313) (xy 23.535894 -59.704732) (xy 23.535894 -59.704478)
			(xy 23.536148 -59.704478) (xy 23.557086 -59.686846) (xy 23.603058 -59.657134) (xy 23.652804 -59.634297)
			(xy 23.705303 -59.618804) (xy 23.759477 -59.610974) (xy 23.786846 -59.610498) (xy 23.814099 -59.610969)
			(xy 23.86805 -59.618725) (xy 23.920347 -59.634081) (xy 23.969927 -59.656723) (xy 24.015781 -59.686191)
			(xy 24.056973 -59.721884) (xy 24.092667 -59.763076) (xy 24.122135 -59.808929) (xy 24.144778 -59.858509)
			(xy 24.160134 -59.910807) (xy 24.167891 -59.964757) (xy 24.167891 -60.019263) (xy 24.160134 -60.073213)
			(xy 24.144778 -60.125511) (xy 24.122135 -60.175091) (xy 24.092667 -60.220944) (xy 24.056973 -60.262136)
			(xy 24.015781 -60.297829) (xy 23.969927 -60.327297) (xy 23.920347 -60.349939) (xy 23.86805 -60.365295)
			(xy 23.814099 -60.373051) (xy 23.786846 -60.373514) (xy 23.759477 -60.373018) (xy 23.705299 -60.365207)
			(xy 23.652797 -60.349724) (xy 23.603049 -60.32689) (xy 23.557081 -60.297172) (xy 23.536148 -60.279534)
			(xy 23.535894 -60.27928) (xy 23.528815 -60.273683) (xy 23.511892 -60.267443) (xy 23.502874 -60.267088)
			(xy 23.435818 -60.267088) (xy 23.426802 -60.267456) (xy 23.409885 -60.273696) (xy 23.402798 -60.27928)
			(xy 23.402544 -60.279534) (xy 23.381611 -60.297175) (xy 23.335643 -60.326899) (xy 23.285897 -60.349745)
			(xy 23.233395 -60.365241) (xy 23.179217 -60.37307) (xy 23.124475 -60.37307) (xy 23.070297 -60.365241)
			(xy 23.017795 -60.349745) (xy 22.968049 -60.326899) (xy 22.922081 -60.297175) (xy 22.901148 -60.279534)
			(xy 22.900894 -60.27928) (xy 22.893815 -60.273683) (xy 22.876892 -60.267443) (xy 22.867874 -60.267088)
			(xy 22.800818 -60.267088) (xy 22.791802 -60.267456) (xy 22.774885 -60.273696) (xy 22.767798 -60.27928)
			(xy 22.767798 -60.279534) (xy 22.767544 -60.279534) (xy 22.746611 -60.297171) (xy 22.700638 -60.326882)
			(xy 22.65089 -60.349718) (xy 22.59839 -60.36521) (xy 22.544215 -60.373039) (xy 22.516846 -60.373514)
			(xy 22.489595 -60.373036) (xy 22.435647 -60.365279) (xy 22.383352 -60.349923) (xy 22.333775 -60.327282)
			(xy 22.287924 -60.297815) (xy 22.246734 -60.262123) (xy 22.211043 -60.220932) (xy 22.181576 -60.175082)
			(xy 22.158935 -60.125504) (xy 22.14358 -60.073209) (xy 22.135824 -60.019261) (xy 10.264648 -60.019261)
			(xy 10.264648 -61.009784) (xy 10.264189 -61.042638) (xy 10.256834 -61.107934) (xy 10.242216 -61.171996)
			(xy 10.220518 -61.234018) (xy 10.192013 -61.293221) (xy 10.157059 -61.348861) (xy 10.116095 -61.400239)
			(xy 10.093198 -61.423804) (xy 9.609328 -61.907674) (xy 9.585763 -61.93057) (xy 9.534378 -61.97152)
			(xy 9.478735 -62.006464) (xy 9.419532 -62.034963) (xy 9.357511 -62.05666) (xy 9.293453 -62.071281)
			(xy 9.228161 -62.078645) (xy 9.195308 -62.079124) (xy 9.03605 -62.079124) (xy 9.027214 -62.079496)
			(xy 9.010577 -62.085456) (xy 9.003538 -62.090808) (xy 8.99668 -62.096396) (xy 8.98779 -62.111636)
			(xy 8.986266 -62.12078) (xy 8.981006 -62.146745) (xy 8.964262 -62.197005) (xy 8.940725 -62.244466)
			(xy 8.910847 -62.288214) (xy 8.875204 -62.327407) (xy 8.834482 -62.361291) (xy 8.789462 -62.389216)
			(xy 8.741012 -62.410642) (xy 8.690063 -62.425159) (xy 8.637596 -62.432488) (xy 8.611108 -62.432946)
			(xy 8.58036 -62.432329) (xy 8.51966 -62.42247) (xy 8.461327 -62.403004) (xy 8.433816 -62.389258)
			(xy 8.427212 -62.385956) (xy 8.416544 -62.383416) (xy 8.38327 -62.383416) (xy 8.374165 -62.383792)
			(xy 8.3571 -62.390149) (xy 8.34332 -62.402055) (xy 8.338566 -62.409832) (xy 8.33628 -62.414912) (xy 8.334507 -62.41954)
			(xy 8.332588 -62.429261) (xy 8.33247 -62.434216) (xy 8.33247 -62.442852) (xy 8.338312 -62.459108)
			(xy 8.3439 -62.465966) (xy 8.359864 -62.486417) (xy 8.386705 -62.530814) (xy 8.40729 -62.578435)
			(xy 8.421239 -62.628405) (xy 8.428296 -62.679802) (xy 8.428736 -62.705742) (xy 8.428736 -62.711584)
			(xy 8.427872 -62.738573) (xy 8.419476 -62.791914) (xy 8.403642 -62.843538) (xy 8.380687 -62.892413)
			(xy 8.351069 -62.937562) (xy 8.31538 -62.978084) (xy 8.274333 -63.013168) (xy 8.228749 -63.042114)
			(xy 8.179539 -63.064342) (xy 8.127686 -63.079409) (xy 8.074227 -63.087014) (xy 8.047228 -63.087504)
			(xy 8.019974 -63.087043) (xy 7.96602 -63.079289) (xy 7.913719 -63.063935) (xy 7.864136 -63.041294)
			(xy 7.818279 -63.011827) (xy 7.777084 -62.976133) (xy 7.741387 -62.93494) (xy 7.711917 -62.889085)
			(xy 7.689273 -62.839503) (xy 7.673916 -62.787203) (xy 7.666159 -62.73325) (xy 7.66572 -62.705996)
			(xy 7.66572 -62.705742) (xy 7.666293 -62.675563) (xy 7.675808 -62.615961) (xy 7.694607 -62.558606)
			(xy 7.707884 -62.531498) (xy 7.707884 -62.531244) (xy 7.710764 -62.525305) (xy 7.713719 -62.512445)
			(xy 7.713726 -62.505844) (xy 7.713218 -62.493398) (xy 7.677658 -62.434978) (xy 7.659878 -62.406022)
			(xy 7.652357 -62.395969) (xy 7.63025 -62.38413) (xy 7.617714 -62.383416) (xy 7.139178 -62.383416)
			(xy 7.129213 -62.383895) (xy 7.110778 -62.391473) (xy 7.103364 -62.398148) (xy 6.287963 -63.213549)
			(xy 22.120888 -63.213549) (xy 22.120888 -63.159051) (xy 22.128643 -63.105109) (xy 22.143996 -63.052818)
			(xy 22.166634 -63.003245) (xy 22.196095 -62.957398) (xy 22.231782 -62.91621) (xy 22.272966 -62.880519)
			(xy 22.31881 -62.851053) (xy 22.368381 -62.82841) (xy 22.420669 -62.813052) (xy 22.474611 -62.805291)
			(xy 22.50186 -62.804802) (xy 22.529229 -62.805291) (xy 22.583408 -62.813103) (xy 22.63591 -62.828587)
			(xy 22.685658 -62.851424) (xy 22.731626 -62.881143) (xy 22.752558 -62.898782) (xy 22.752812 -62.899036)
			(xy 22.759888 -62.904638) (xy 22.776813 -62.910874) (xy 22.785832 -62.911228) (xy 22.852888 -62.911228)
			(xy 22.861904 -62.910859) (xy 22.87882 -62.904619) (xy 22.885908 -62.899036) (xy 22.885908 -62.898782)
			(xy 22.886162 -62.898782) (xy 22.907095 -62.881141) (xy 22.953063 -62.851417) (xy 23.002809 -62.828571)
			(xy 23.055311 -62.813075) (xy 23.109489 -62.805246) (xy 23.164231 -62.805246) (xy 23.218409 -62.813075)
			(xy 23.270911 -62.828571) (xy 23.320657 -62.851417) (xy 23.366625 -62.881141) (xy 23.387558 -62.898782)
			(xy 23.387812 -62.899036) (xy 23.394888 -62.904638) (xy 23.411813 -62.910874) (xy 23.420832 -62.911228)
			(xy 23.487888 -62.911228) (xy 23.496904 -62.910859) (xy 23.51382 -62.904619) (xy 23.520908 -62.899036)
			(xy 23.520908 -62.898782) (xy 23.521162 -62.898782) (xy 23.542095 -62.881144) (xy 23.588068 -62.851433)
			(xy 23.637815 -62.828597) (xy 23.690316 -62.813106) (xy 23.744491 -62.805277) (xy 23.77186 -62.804802)
			(xy 23.799115 -62.805242) (xy 23.853072 -62.812995) (xy 23.905376 -62.828348) (xy 23.954963 -62.850989)
			(xy 24.000822 -62.880456) (xy 24.042021 -62.916151) (xy 24.07772 -62.957346) (xy 24.107192 -63.003202)
			(xy 24.129838 -63.052786) (xy 24.145197 -63.105089) (xy 24.152955 -63.159045) (xy 24.152955 -63.213555)
			(xy 24.145197 -63.267511) (xy 24.129838 -63.319814) (xy 24.107192 -63.369398) (xy 24.07772 -63.415254)
			(xy 24.042021 -63.456449) (xy 24.000822 -63.492144) (xy 23.954963 -63.521611) (xy 23.905376 -63.544252)
			(xy 23.853072 -63.559605) (xy 23.799115 -63.567358) (xy 23.77186 -63.567818) (xy 23.74449 -63.567337)
			(xy 23.690311 -63.559526) (xy 23.637807 -63.544041) (xy 23.58806 -63.521202) (xy 23.542093 -63.491479)
			(xy 23.521162 -63.473838) (xy 23.520908 -63.473584) (xy 23.513825 -63.467993) (xy 23.496905 -63.461749)
			(xy 23.487888 -63.461392) (xy 23.420832 -63.461392) (xy 23.411817 -63.461766) (xy 23.3949 -63.468002)
			(xy 23.387812 -63.473584) (xy 23.387558 -63.473838) (xy 23.366625 -63.491479) (xy 23.320657 -63.521203)
			(xy 23.270911 -63.544049) (xy 23.218409 -63.559545) (xy 23.164231 -63.567374) (xy 23.109489 -63.567374)
			(xy 23.055311 -63.559545) (xy 23.002809 -63.544049) (xy 22.953063 -63.521203) (xy 22.907095 -63.491479)
			(xy 22.886162 -63.473838) (xy 22.885908 -63.473584) (xy 22.878825 -63.467993) (xy 22.861905 -63.461749)
			(xy 22.852888 -63.461392) (xy 22.785832 -63.461392) (xy 22.776817 -63.461766) (xy 22.7599 -63.468002)
			(xy 22.752812 -63.473584) (xy 22.752812 -63.473838) (xy 22.752558 -63.473838) (xy 22.73162 -63.49147)
			(xy 22.685648 -63.521181) (xy 22.635902 -63.544018) (xy 22.583403 -63.559511) (xy 22.529229 -63.567343)
			(xy 22.50186 -63.567818) (xy 22.474611 -63.567309) (xy 22.420669 -63.559548) (xy 22.368381 -63.54419)
			(xy 22.31881 -63.521547) (xy 22.272966 -63.492081) (xy 22.231782 -63.45639) (xy 22.196095 -63.415202)
			(xy 22.166634 -63.369355) (xy 22.143996 -63.319782) (xy 22.128643 -63.267491) (xy 22.120888 -63.213549)
			(xy 6.287963 -63.213549) (xy 6.28015 -63.221362) (xy 4.608576 -64.892682) (xy 4.60399 -64.897628)
			(xy 4.5973 -64.909334) (xy 4.595368 -64.915796) (xy 4.593844 -64.928496) (xy 4.593844 -65.104772)
			(xy 4.593452 -65.124076) (xy 6.107428 -65.124076) (xy 6.111499 -65.068454) (xy 6.123625 -65.014017)
			(xy 6.143548 -64.961926) (xy 6.170844 -64.913291) (xy 6.20493 -64.869148) (xy 6.245079 -64.830439)
			(xy 6.290437 -64.797988) (xy 6.340037 -64.772487) (xy 6.392821 -64.75448) (xy 6.447664 -64.74435)
			(xy 6.503398 -64.742313) (xy 6.558835 -64.748413) (xy 6.612792 -64.762519) (xy 6.664121 -64.784331)
			(xy 6.711727 -64.813385) (xy 6.754595 -64.84906) (xy 6.791812 -64.890597) (xy 6.822585 -64.93711)
			(xy 6.846257 -64.987607) (xy 6.862325 -65.041014) (xy 6.870445 -65.09619) (xy 6.870954 -65.124076)
			(xy 6.870445 -65.151962) (xy 6.862325 -65.207138) (xy 6.846257 -65.260545) (xy 6.822585 -65.311042)
			(xy 6.791812 -65.357555) (xy 6.754595 -65.399092) (xy 6.711727 -65.434767) (xy 6.664121 -65.463821)
			(xy 6.612792 -65.485633) (xy 6.558835 -65.499739) (xy 6.503398 -65.505839) (xy 6.447664 -65.503802)
			(xy 6.392821 -65.493672) (xy 6.340037 -65.475665) (xy 6.290437 -65.450164) (xy 6.245079 -65.417713)
			(xy 6.20493 -65.379004) (xy 6.170844 -65.334861) (xy 6.143548 -65.286226) (xy 6.123625 -65.234135)
			(xy 6.111499 -65.179698) (xy 6.107428 -65.124076) (xy 4.593452 -65.124076) (xy 4.593315 -65.130795)
			(xy 4.585145 -65.182196) (xy 4.569048 -65.231691) (xy 4.545419 -65.278065) (xy 4.514839 -65.32018)
			(xy 4.496816 -65.33896) (xy 3.860292 -65.975484) (xy 3.85631 -65.979654) (xy 3.850153 -65.9894) (xy 3.8481 -65.994788)
			(xy 3.847846 -65.996058) (xy 3.839611 -66.021026) (xy 3.817241 -66.068605) (xy 3.788559 -66.112668)
			(xy 3.754106 -66.152381) (xy 3.714532 -66.186995) (xy 3.670586 -66.215855) (xy 3.623098 -66.238417)
			(xy 3.598164 -66.246756) (xy 3.595116 -66.247772) (xy 3.590022 -66.249783) (xy 3.580796 -66.255681)
			(xy 3.576828 -66.259456) (xy 3.570224 -66.26606) (xy 3.566414 -66.275204) (xy 3.564642 -66.279832)
			(xy 3.562724 -66.289554) (xy 3.562604 -66.294508) (xy 3.562604 -66.567812) (xy 6.304532 -66.567812)
			(xy 6.308603 -66.51219) (xy 6.320729 -66.457753) (xy 6.340652 -66.405662) (xy 6.367948 -66.357027)
			(xy 6.402034 -66.312884) (xy 6.442183 -66.274175) (xy 6.487541 -66.241724) (xy 6.537141 -66.216223)
			(xy 6.589925 -66.198216) (xy 6.644768 -66.188086) (xy 6.700502 -66.186049) (xy 6.755939 -66.192149)
			(xy 6.809896 -66.206255) (xy 6.861225 -66.228067) (xy 6.908831 -66.257121) (xy 6.951699 -66.292796)
			(xy 6.988916 -66.334333) (xy 7.019689 -66.380846) (xy 7.043361 -66.431343) (xy 7.059429 -66.48475)
			(xy 7.067549 -66.539926) (xy 7.068058 -66.567812) (xy 7.067549 -66.595698) (xy 7.059429 -66.650874)
			(xy 7.043361 -66.704281) (xy 7.019689 -66.754778) (xy 6.988916 -66.801291) (xy 6.951699 -66.842828)
			(xy 6.908831 -66.878503) (xy 6.861225 -66.907557) (xy 6.809896 -66.929369) (xy 6.755939 -66.943475)
			(xy 6.700502 -66.949575) (xy 6.644768 -66.947538) (xy 6.589925 -66.937408) (xy 6.537141 -66.919401)
			(xy 6.487541 -66.8939) (xy 6.442183 -66.861449) (xy 6.402034 -66.82274) (xy 6.367948 -66.778597)
			(xy 6.340652 -66.729962) (xy 6.320729 -66.677871) (xy 6.308603 -66.623434) (xy 6.304532 -66.567812)
			(xy 3.562604 -66.567812) (xy 3.562604 -67.201034) (xy 4.242306 -67.201034) (xy 4.246377 -67.145412)
			(xy 4.258503 -67.090975) (xy 4.278426 -67.038884) (xy 4.305722 -66.990249) (xy 4.339808 -66.946106)
			(xy 4.379957 -66.907397) (xy 4.425315 -66.874946) (xy 4.474915 -66.849445) (xy 4.527699 -66.831438)
			(xy 4.582542 -66.821308) (xy 4.638276 -66.819271) (xy 4.693713 -66.825371) (xy 4.74767 -66.839477)
			(xy 4.798999 -66.861289) (xy 4.846605 -66.890343) (xy 4.889473 -66.926018) (xy 4.92669 -66.967555)
			(xy 4.957463 -67.014068) (xy 4.981135 -67.064565) (xy 4.997203 -67.117972) (xy 4.998822 -67.128971)
			(xy 14.366728 -67.128971) (xy 14.366728 -67.074469) (xy 14.374484 -67.020521) (xy 14.389839 -66.968227)
			(xy 14.41248 -66.91865) (xy 14.441946 -66.872799) (xy 14.477638 -66.831609) (xy 14.518828 -66.795918)
			(xy 14.564678 -66.766451) (xy 14.614255 -66.74381) (xy 14.666549 -66.728455) (xy 14.720497 -66.720698)
			(xy 14.747748 -66.720212) (xy 14.775117 -66.720706) (xy 14.829295 -66.728516) (xy 14.881798 -66.743999)
			(xy 14.931546 -66.766834) (xy 14.977514 -66.796553) (xy 14.998446 -66.814192) (xy 14.9987 -66.814446)
			(xy 15.005778 -66.820044) (xy 15.022702 -66.826283) (xy 15.03172 -66.826638) (xy 15.098776 -66.826638)
			(xy 15.107791 -66.826261) (xy 15.124707 -66.820026) (xy 15.131796 -66.814446) (xy 15.131796 -66.814192)
			(xy 15.13205 -66.814192) (xy 15.152989 -66.796562) (xy 15.19896 -66.766849) (xy 15.248706 -66.744011)
			(xy 15.301205 -66.728518) (xy 15.355379 -66.720687) (xy 15.382748 -66.720212) (xy 15.410001 -66.720675)
			(xy 15.463952 -66.728432) (xy 15.51625 -66.743788) (xy 15.565831 -66.76643) (xy 15.611684 -66.795898)
			(xy 15.652877 -66.831592) (xy 15.688571 -66.872784) (xy 15.718039 -66.918638) (xy 15.740682 -66.968218)
			(xy 15.756038 -67.020516) (xy 15.763795 -67.074467) (xy 15.763795 -67.128973) (xy 15.756038 -67.182924)
			(xy 15.740682 -67.235222) (xy 15.718039 -67.284802) (xy 15.688571 -67.330656) (xy 15.652877 -67.371848)
			(xy 15.611684 -67.407542) (xy 15.565831 -67.43701) (xy 15.51625 -67.459652) (xy 15.463952 -67.475008)
			(xy 15.410001 -67.482765) (xy 15.382748 -67.483228) (xy 15.355378 -67.482751) (xy 15.301199 -67.474939)
			(xy 15.248695 -67.459453) (xy 15.198948 -67.436613) (xy 15.152981 -67.406889) (xy 15.13205 -67.389248)
			(xy 15.131796 -67.388994) (xy 15.124715 -67.383399) (xy 15.107794 -67.377158) (xy 15.098776 -67.376802)
			(xy 15.03172 -67.376802) (xy 15.022704 -67.377168) (xy 15.005787 -67.383409) (xy 14.9987 -67.388994)
			(xy 14.9987 -67.389248) (xy 14.998446 -67.389248) (xy 14.977501 -67.406871) (xy 14.931532 -67.436587)
			(xy 14.881788 -67.459427) (xy 14.82929 -67.474922) (xy 14.775116 -67.482753) (xy 14.747748 -67.483228)
			(xy 14.720497 -67.482742) (xy 14.666549 -67.474985) (xy 14.614255 -67.45963) (xy 14.564678 -67.436989)
			(xy 14.518828 -67.407522) (xy 14.477638 -67.371831) (xy 14.441946 -67.330641) (xy 14.41248 -67.28479)
			(xy 14.389839 -67.235213) (xy 14.374484 -67.182919) (xy 14.366728 -67.128971) (xy 4.998822 -67.128971)
			(xy 5.005323 -67.173148) (xy 5.005832 -67.201034) (xy 5.005323 -67.22892) (xy 4.997203 -67.284096)
			(xy 4.981135 -67.337503) (xy 4.957463 -67.388) (xy 4.92669 -67.434513) (xy 4.889473 -67.47605) (xy 4.846605 -67.511725)
			(xy 4.798999 -67.540779) (xy 4.74767 -67.562591) (xy 4.693713 -67.576697) (xy 4.638276 -67.582797)
			(xy 4.582542 -67.58076) (xy 4.527699 -67.57063) (xy 4.474915 -67.552623) (xy 4.425315 -67.527122)
			(xy 4.379957 -67.494671) (xy 4.339808 -67.455962) (xy 4.305722 -67.411819) (xy 4.278426 -67.363184)
			(xy 4.258503 -67.311093) (xy 4.246377 -67.256656) (xy 4.242306 -67.201034) (xy 3.562604 -67.201034)
			(xy 3.562604 -67.785996) (xy 7.66521 -67.785996) (xy 7.669281 -67.730374) (xy 7.681407 -67.675937)
			(xy 7.70133 -67.623846) (xy 7.728626 -67.575211) (xy 7.762712 -67.531068) (xy 7.802861 -67.492359)
			(xy 7.848219 -67.459908) (xy 7.897819 -67.434407) (xy 7.950603 -67.4164) (xy 8.005446 -67.40627)
			(xy 8.06118 -67.404233) (xy 8.116617 -67.410333) (xy 8.170574 -67.424439) (xy 8.221903 -67.446251)
			(xy 8.269509 -67.475305) (xy 8.284829 -67.488054) (xy 18.779234 -67.488054) (xy 18.783305 -67.432432)
			(xy 18.795431 -67.377995) (xy 18.815354 -67.325904) (xy 18.84265 -67.277269) (xy 18.876736 -67.233126)
			(xy 18.916885 -67.194417) (xy 18.962243 -67.161966) (xy 19.011843 -67.136465) (xy 19.064627 -67.118458)
			(xy 19.11947 -67.108328) (xy 19.175204 -67.106291) (xy 19.230641 -67.112391) (xy 19.284598 -67.126497)
			(xy 19.335927 -67.148309) (xy 19.383533 -67.177363) (xy 19.426401 -67.213038) (xy 19.463618 -67.254575)
			(xy 19.494391 -67.301088) (xy 19.518063 -67.351585) (xy 19.534131 -67.404992) (xy 19.542251 -67.460168)
			(xy 19.54276 -67.488054) (xy 19.542251 -67.51594) (xy 19.539066 -67.537584) (xy 20.071332 -67.537584)
			(xy 20.075403 -67.481962) (xy 20.087529 -67.427525) (xy 20.107452 -67.375434) (xy 20.134748 -67.326799)
			(xy 20.168834 -67.282656) (xy 20.208983 -67.243947) (xy 20.254341 -67.211496) (xy 20.303941 -67.185995)
			(xy 20.356725 -67.167988) (xy 20.411568 -67.157858) (xy 20.467302 -67.155821) (xy 20.522739 -67.161921)
			(xy 20.576696 -67.176027) (xy 20.628025 -67.197839) (xy 20.675631 -67.226893) (xy 20.718499 -67.262568)
			(xy 20.755716 -67.304105) (xy 20.786489 -67.350618) (xy 20.810161 -67.401115) (xy 20.826229 -67.454522)
			(xy 20.834349 -67.509698) (xy 20.834858 -67.537584) (xy 20.834349 -67.56547) (xy 20.830304 -67.592956)
			(xy 21.345396 -67.592956) (xy 21.349467 -67.537334) (xy 21.361593 -67.482897) (xy 21.381516 -67.430806)
			(xy 21.408812 -67.382171) (xy 21.442898 -67.338028) (xy 21.483047 -67.299319) (xy 21.528405 -67.266868)
			(xy 21.578005 -67.241367) (xy 21.630789 -67.22336) (xy 21.685632 -67.21323) (xy 21.741366 -67.211193)
			(xy 21.796803 -67.217293) (xy 21.85076 -67.231399) (xy 21.902089 -67.253211) (xy 21.949695 -67.282265)
			(xy 21.992563 -67.31794) (xy 22.02978 -67.359477) (xy 22.060553 -67.40599) (xy 22.084225 -67.456487)
			(xy 22.100293 -67.509894) (xy 22.10841 -67.565052) (xy 24.446693 -67.565052) (xy 24.446693 -67.510548)
			(xy 24.454451 -67.456599) (xy 24.469807 -67.404304) (xy 24.49245 -67.354726) (xy 24.521919 -67.308875)
			(xy 24.557613 -67.267686) (xy 24.598806 -67.231996) (xy 24.644659 -67.202532) (xy 24.694239 -67.179894)
			(xy 24.746536 -67.164542) (xy 24.800486 -67.156791) (xy 24.827738 -67.15633) (xy 24.855107 -67.156825)
			(xy 24.909285 -67.164635) (xy 24.961788 -67.180117) (xy 25.011536 -67.202952) (xy 25.057504 -67.232671)
			(xy 25.078436 -67.25031) (xy 25.07869 -67.250564) (xy 25.08577 -67.25616) (xy 25.102692 -67.262399)
			(xy 25.11171 -67.262756) (xy 25.178766 -67.262756) (xy 25.187782 -67.262392) (xy 25.2047 -67.25615)
			(xy 25.211786 -67.250564) (xy 25.211786 -67.25031) (xy 25.21204 -67.25031) (xy 25.232985 -67.232687)
			(xy 25.278954 -67.202973) (xy 25.328698 -67.180133) (xy 25.381196 -67.164638) (xy 25.43537 -67.156806)
			(xy 25.462738 -67.15633) (xy 25.48999 -67.156742) (xy 25.543939 -67.164504) (xy 25.596235 -67.179864)
			(xy 25.645812 -67.20251) (xy 25.691662 -67.23198) (xy 25.732852 -67.267675) (xy 25.768543 -67.308868)
			(xy 25.798009 -67.354721) (xy 25.820649 -67.404301) (xy 25.836004 -67.456598) (xy 25.84376 -67.510548)
			(xy 25.84376 -67.565052) (xy 25.836004 -67.619002) (xy 25.820649 -67.671299) (xy 25.798009 -67.720879)
			(xy 25.768543 -67.766732) (xy 25.732852 -67.807925) (xy 25.691662 -67.84362) (xy 25.645812 -67.87309)
			(xy 25.596235 -67.895736) (xy 25.543939 -67.911096) (xy 25.48999 -67.918858) (xy 25.462738 -67.919346)
			(xy 25.435368 -67.918871) (xy 25.381189 -67.911057) (xy 25.328685 -67.895571) (xy 25.278938 -67.872731)
			(xy 25.232971 -67.843007) (xy 25.21204 -67.825366) (xy 25.211786 -67.825112) (xy 25.204707 -67.819515)
			(xy 25.187784 -67.813274) (xy 25.178766 -67.81292) (xy 25.11171 -67.81292) (xy 25.102693 -67.813277)
			(xy 25.085776 -67.819524) (xy 25.07869 -67.825112) (xy 25.07869 -67.825366) (xy 25.078436 -67.825366)
			(xy 25.057497 -67.842996) (xy 25.011527 -67.872711) (xy 24.961781 -67.895549) (xy 24.909282 -67.911042)
			(xy 24.855107 -67.918871) (xy 24.827738 -67.919346) (xy 24.800486 -67.918809) (xy 24.746536 -67.911058)
			(xy 24.694239 -67.895706) (xy 24.644659 -67.873068) (xy 24.598806 -67.843604) (xy 24.557613 -67.807914)
			(xy 24.521919 -67.766725) (xy 24.49245 -67.720874) (xy 24.469807 -67.671296) (xy 24.454451 -67.619001)
			(xy 24.446693 -67.565052) (xy 22.10841 -67.565052) (xy 22.108413 -67.56507) (xy 22.108922 -67.592956)
			(xy 22.108413 -67.620842) (xy 22.100293 -67.676018) (xy 22.084225 -67.729425) (xy 22.060553 -67.779922)
			(xy 22.02978 -67.826435) (xy 21.992563 -67.867972) (xy 21.949695 -67.903647) (xy 21.902089 -67.932701)
			(xy 21.85076 -67.954513) (xy 21.796803 -67.968619) (xy 21.741366 -67.974719) (xy 21.685632 -67.972682)
			(xy 21.630789 -67.962552) (xy 21.578005 -67.944545) (xy 21.528405 -67.919044) (xy 21.483047 -67.886593)
			(xy 21.442898 -67.847884) (xy 21.408812 -67.803741) (xy 21.381516 -67.755106) (xy 21.361593 -67.703015)
			(xy 21.349467 -67.648578) (xy 21.345396 -67.592956) (xy 20.830304 -67.592956) (xy 20.826229 -67.620646)
			(xy 20.810161 -67.674053) (xy 20.786489 -67.72455) (xy 20.755716 -67.771063) (xy 20.718499 -67.8126)
			(xy 20.675631 -67.848275) (xy 20.628025 -67.877329) (xy 20.576696 -67.899141) (xy 20.522739 -67.913247)
			(xy 20.467302 -67.919347) (xy 20.411568 -67.91731) (xy 20.356725 -67.90718) (xy 20.303941 -67.889173)
			(xy 20.254341 -67.863672) (xy 20.208983 -67.831221) (xy 20.168834 -67.792512) (xy 20.134748 -67.748369)
			(xy 20.107452 -67.699734) (xy 20.087529 -67.647643) (xy 20.075403 -67.593206) (xy 20.071332 -67.537584)
			(xy 19.539066 -67.537584) (xy 19.534131 -67.571116) (xy 19.518063 -67.624523) (xy 19.494391 -67.67502)
			(xy 19.463618 -67.721533) (xy 19.426401 -67.76307) (xy 19.383533 -67.798745) (xy 19.335927 -67.827799)
			(xy 19.284598 -67.849611) (xy 19.230641 -67.863717) (xy 19.175204 -67.869817) (xy 19.11947 -67.86778)
			(xy 19.064627 -67.85765) (xy 19.011843 -67.839643) (xy 18.962243 -67.814142) (xy 18.916885 -67.781691)
			(xy 18.876736 -67.742982) (xy 18.84265 -67.698839) (xy 18.815354 -67.650204) (xy 18.795431 -67.598113)
			(xy 18.783305 -67.543676) (xy 18.779234 -67.488054) (xy 8.284829 -67.488054) (xy 8.312377 -67.51098)
			(xy 8.349594 -67.552517) (xy 8.380367 -67.59903) (xy 8.404039 -67.649527) (xy 8.420107 -67.702934)
			(xy 8.428227 -67.75811) (xy 8.428736 -67.785996) (xy 8.428227 -67.813882) (xy 8.420107 -67.869058)
			(xy 8.404039 -67.922465) (xy 8.380367 -67.972962) (xy 8.349594 -68.019475) (xy 8.312377 -68.061012)
			(xy 8.269509 -68.096687) (xy 8.221903 -68.125741) (xy 8.170574 -68.147553) (xy 8.116617 -68.161659)
			(xy 8.06118 -68.167759) (xy 8.005446 -68.165722) (xy 7.950603 -68.155592) (xy 7.897819 -68.137585)
			(xy 7.848219 -68.112084) (xy 7.802861 -68.079633) (xy 7.762712 -68.040924) (xy 7.728626 -67.996781)
			(xy 7.70133 -67.948146) (xy 7.681407 -67.896055) (xy 7.669281 -67.841618) (xy 7.66521 -67.785996)
			(xy 3.562604 -67.785996) (xy 3.562604 -67.970654) (xy 3.562604 -67.972432) (xy 3.56328 -67.981449)
			(xy 3.570148 -67.998161) (xy 3.582407 -68.011435) (xy 3.59029 -68.015866) (xy 3.59537 -68.018152)
			(xy 3.673094 -68.056252) (xy 3.679474 -68.059177) (xy 3.693266 -68.061756) (xy 3.700272 -68.061332)
			(xy 3.707384 -68.06057) (xy 3.720592 -68.055236) (xy 3.72618 -68.050918) (xy 3.750238 -68.033179)
			(xy 3.802743 -68.004618) (xy 3.85906 -67.984595) (xy 3.917811 -67.973601) (xy 3.947668 -67.972178)
			(xy 3.948176 -67.972178) (xy 3.956558 -67.971924) (xy 3.963416 -67.971924) (xy 3.990454 -67.972719)
			(xy 4.043907 -67.981001) (xy 4.095654 -67.996748) (xy 4.144659 -68.019647) (xy 4.189938 -68.049237)
			(xy 4.230585 -68.084925) (xy 4.265783 -68.125997) (xy 4.294828 -68.171628) (xy 4.317137 -68.220904)
			(xy 4.332263 -68.272836) (xy 4.339902 -68.326385) (xy 4.339902 -68.380475) (xy 4.332263 -68.434024)
			(xy 4.317137 -68.485956) (xy 4.294828 -68.535232) (xy 4.265783 -68.580863) (xy 4.260863 -68.586604)
			(xy 16.625316 -68.586604) (xy 16.625781 -68.559234) (xy 16.633598 -68.505054) (xy 16.649087 -68.452551)
			(xy 16.67193 -68.402804) (xy 16.701655 -68.356838) (xy 16.719296 -68.335906) (xy 16.71955 -68.335652)
			(xy 16.725127 -68.328559) (xy 16.731378 -68.311647) (xy 16.731742 -68.302632) (xy 16.731742 -68.235576)
			(xy 16.731409 -68.226556) (xy 16.725146 -68.209639) (xy 16.71955 -68.202556) (xy 16.719296 -68.202556)
			(xy 16.719296 -68.202302) (xy 16.701644 -68.181381) (xy 16.671934 -68.135405) (xy 16.649101 -68.085655)
			(xy 16.633613 -68.033152) (xy 16.625788 -67.978974) (xy 16.625316 -67.951604) (xy 16.625759 -67.92435)
			(xy 16.633516 -67.870397) (xy 16.648873 -67.818098) (xy 16.671517 -67.768516) (xy 16.700987 -67.722662)
			(xy 16.736682 -67.681468) (xy 16.777878 -67.645775) (xy 16.823733 -67.616307) (xy 16.873316 -67.593666)
			(xy 16.925617 -67.578312) (xy 16.97957 -67.570558) (xy 17.006824 -67.570096) (xy 17.033138 -67.570549)
			(xy 17.085268 -67.577787) (xy 17.13591 -67.592109) (xy 17.184109 -67.613244) (xy 17.228953 -67.640793)
			(xy 17.269592 -67.674233) (xy 17.287748 -67.693286) (xy 17.295252 -67.700709) (xy 17.314545 -67.709221)
			(xy 17.325086 -67.709796) (xy 17.399762 -67.709796) (xy 17.410311 -67.709261) (xy 17.429607 -67.70073)
			(xy 17.4371 -67.693286) (xy 17.45526 -67.674235) (xy 17.495889 -67.640778) (xy 17.540728 -67.613219)
			(xy 17.588928 -67.592079) (xy 17.639575 -67.577761) (xy 17.691708 -67.570535) (xy 17.718024 -67.570096)
			(xy 17.745395 -67.570549) (xy 17.799574 -67.57837) (xy 17.852078 -67.593862) (xy 17.901824 -67.616707)
			(xy 17.947791 -67.646434) (xy 17.968722 -67.664076) (xy 17.968976 -67.66433) (xy 17.976063 -67.669916)
			(xy 17.99298 -67.676162) (xy 18.001996 -67.676522) (xy 18.069052 -67.676522) (xy 18.078066 -67.676137)
			(xy 18.094983 -67.669908) (xy 18.102072 -67.66433) (xy 18.102072 -67.664076) (xy 18.102326 -67.664076)
			(xy 18.123272 -67.646454) (xy 18.169241 -67.616741) (xy 18.218985 -67.593902) (xy 18.271483 -67.578407)
			(xy 18.325656 -67.570573) (xy 18.353024 -67.570096) (xy 18.380276 -67.570555) (xy 18.434225 -67.578315)
			(xy 18.48652 -67.593674) (xy 18.536098 -67.616318) (xy 18.581948 -67.645787) (xy 18.623138 -67.681481)
			(xy 18.65883 -67.722674) (xy 18.688295 -67.768527) (xy 18.710936 -67.818106) (xy 18.726291 -67.870402)
			(xy 18.734047 -67.924352) (xy 18.734532 -67.951604) (xy 18.734085 -67.978975) (xy 18.726265 -68.033156)
			(xy 18.710772 -68.08566) (xy 18.687926 -68.135406) (xy 18.658196 -68.181372) (xy 18.640552 -68.202302)
			(xy 18.640298 -68.202556) (xy 18.634723 -68.209651) (xy 18.62847 -68.226561) (xy 18.628106 -68.235576)
			(xy 18.628106 -68.302632) (xy 18.628447 -68.311651) (xy 18.634705 -68.328567) (xy 18.640298 -68.335652)
			(xy 18.640552 -68.335652) (xy 18.640552 -68.335906) (xy 18.6582 -68.356831) (xy 18.687912 -68.402805)
			(xy 18.710747 -68.452554) (xy 18.726236 -68.505057) (xy 18.73406 -68.559234) (xy 18.734532 -68.586604)
			(xy 18.734026 -68.613854) (xy 18.72627 -68.6678) (xy 18.710915 -68.720093) (xy 18.694275 -68.75653)
			(xy 22.17039 -68.75653) (xy 22.170876 -68.729161) (xy 22.178689 -68.674982) (xy 22.194174 -68.62248)
			(xy 22.217011 -68.572732) (xy 22.246731 -68.526765) (xy 22.26437 -68.505832) (xy 22.264624 -68.505578)
			(xy 22.270229 -68.498504) (xy 22.276464 -68.481577) (xy 22.276816 -68.472558) (xy 22.276816 -68.405502)
			(xy 22.276454 -68.396486) (xy 22.27021 -68.379569) (xy 22.264624 -68.372482) (xy 22.26437 -68.372482)
			(xy 22.26437 -68.372228) (xy 22.246726 -68.3513) (xy 22.217016 -68.305326) (xy 22.194181 -68.255577)
			(xy 22.178691 -68.203076) (xy 22.170864 -68.148899) (xy 22.17039 -68.12153) (xy 22.170883 -68.094278)
			(xy 22.178636 -68.040328) (xy 22.193988 -67.988031) (xy 22.216627 -67.938451) (xy 22.246092 -67.892598)
			(xy 22.281782 -67.851405) (xy 22.322972 -67.815711) (xy 22.368823 -67.786242) (xy 22.418401 -67.763599)
			(xy 22.470697 -67.748243) (xy 22.524646 -67.740485) (xy 22.551898 -67.740022) (xy 22.579268 -67.740484)
			(xy 22.633448 -67.748302) (xy 22.685951 -67.763792) (xy 22.735698 -67.786634) (xy 22.781665 -67.81636)
			(xy 22.802596 -67.834002) (xy 22.80285 -67.834256) (xy 22.809942 -67.839834) (xy 22.826855 -67.846085)
			(xy 22.83587 -67.846448) (xy 22.902926 -67.846448) (xy 22.911946 -67.846115) (xy 22.928863 -67.839852)
			(xy 22.935946 -67.834256) (xy 22.935946 -67.834002) (xy 22.9362 -67.834002) (xy 22.957121 -67.81635)
			(xy 23.003097 -67.78664) (xy 23.052847 -67.763806) (xy 23.10535 -67.748318) (xy 23.159528 -67.740494)
			(xy 23.186898 -67.740022) (xy 23.213212 -67.740484) (xy 23.265341 -67.747719) (xy 23.315984 -67.762038)
			(xy 23.364184 -67.783172) (xy 23.409027 -67.810719) (xy 23.449666 -67.84416) (xy 23.467822 -67.863212)
			(xy 23.475332 -67.870627) (xy 23.494621 -67.879144) (xy 23.50516 -67.879722) (xy 23.579836 -67.879722)
			(xy 23.590382 -67.879165) (xy 23.609678 -67.870649) (xy 23.617174 -67.863212) (xy 23.635352 -67.844178)
			(xy 23.675976 -67.810719) (xy 23.720812 -67.783157) (xy 23.769008 -67.762014) (xy 23.819652 -67.747693)
			(xy 23.871783 -67.740463) (xy 23.898098 -67.740022) (xy 23.925352 -67.740457) (xy 23.979306 -67.748215)
			(xy 24.031606 -67.763572) (xy 24.081188 -67.786217) (xy 24.127043 -67.815687) (xy 24.168236 -67.851384)
			(xy 24.20393 -67.89258) (xy 24.233397 -67.938437) (xy 24.256038 -67.98802) (xy 24.271391 -68.040322)
			(xy 24.279145 -68.094276) (xy 24.279606 -68.12153) (xy 24.279156 -68.148901) (xy 24.271334 -68.203081)
			(xy 24.255841 -68.255584) (xy 24.232996 -68.30533) (xy 24.203268 -68.351297) (xy 24.185626 -68.372228)
			(xy 24.185372 -68.372482) (xy 24.179784 -68.379567) (xy 24.173539 -68.396485) (xy 24.17318 -68.405502)
			(xy 24.17318 -68.472558) (xy 24.173561 -68.481572) (xy 24.179792 -68.498489) (xy 24.185372 -68.505578)
			(xy 24.185626 -68.505578) (xy 24.185626 -68.505832) (xy 24.203251 -68.526776) (xy 24.232964 -68.572746)
			(xy 24.255802 -68.62249) (xy 24.271297 -68.674988) (xy 24.279129 -68.729162) (xy 24.279606 -68.75653)
			(xy 24.27915 -68.783782) (xy 24.271389 -68.837731) (xy 24.25603 -68.890026) (xy 24.233386 -68.939604)
			(xy 24.203916 -68.985454) (xy 24.168221 -69.026644) (xy 24.127029 -69.062335) (xy 24.081176 -69.091801)
			(xy 24.031596 -69.114442) (xy 23.9793 -69.129796) (xy 23.92535 -69.137552) (xy 23.898098 -69.138038)
			(xy 23.871783 -69.137592) (xy 23.819653 -69.130355) (xy 23.769009 -69.116033) (xy 23.72081 -69.094897)
			(xy 23.675967 -69.067346) (xy 23.635329 -69.033902) (xy 23.617174 -69.014848) (xy 23.609657 -69.00744)
			(xy 23.590374 -68.998918) (xy 23.579836 -68.998338) (xy 23.50516 -68.998338) (xy 23.494611 -68.998875)
			(xy 23.475315 -69.007403) (xy 23.467822 -69.014848) (xy 23.449658 -69.033895) (xy 23.409029 -69.067351)
			(xy 23.36419 -69.09491) (xy 23.315991 -69.11605) (xy 23.265346 -69.130369) (xy 23.213213 -69.137597)
			(xy 23.186898 -69.138038) (xy 23.159527 -69.137588) (xy 23.105347 -69.129769) (xy 23.052843 -69.114277)
			(xy 23.003096 -69.091431) (xy 22.957131 -69.061702) (xy 22.9362 -69.044058) (xy 22.935946 -69.043804)
			(xy 22.92885 -69.038231) (xy 22.911941 -69.031976) (xy 22.902926 -69.031612) (xy 22.83587 -69.031612)
			(xy 22.826851 -69.031952) (xy 22.809934 -69.038211) (xy 22.80285 -69.043804) (xy 22.80285 -69.044058)
			(xy 22.802596 -69.044058) (xy 22.781671 -69.061706) (xy 22.735697 -69.091418) (xy 22.685948 -69.114253)
			(xy 22.633445 -69.129742) (xy 22.579268 -69.137566) (xy 22.551898 -69.138038) (xy 22.524648 -69.137524)
			(xy 22.470703 -69.129768) (xy 22.418411 -69.114414) (xy 22.368835 -69.091775) (xy 22.322986 -69.062311)
			(xy 22.281797 -69.026623) (xy 22.246105 -68.985436) (xy 22.216638 -68.939589) (xy 22.193995 -68.890016)
			(xy 22.178638 -68.837724) (xy 22.170878 -68.78378) (xy 22.17039 -68.75653) (xy 18.694275 -68.75653)
			(xy 18.688275 -68.769669) (xy 18.658811 -68.815518) (xy 18.623122 -68.856707) (xy 18.581934 -68.892399)
			(xy 18.536086 -68.921866) (xy 18.486512 -68.944508) (xy 18.43422 -68.959865) (xy 18.380274 -68.967625)
			(xy 18.353024 -68.968112) (xy 18.325654 -68.967629) (xy 18.271476 -68.959815) (xy 18.218973 -68.944329)
			(xy 18.169226 -68.921492) (xy 18.123258 -68.891771) (xy 18.102326 -68.874132) (xy 18.102072 -68.873878)
			(xy 18.094971 -68.868313) (xy 18.078065 -68.862054) (xy 18.069052 -68.861686) (xy 18.001996 -68.861686)
			(xy 17.992979 -68.862044) (xy 17.976063 -68.868291) (xy 17.968976 -68.873878) (xy 17.968976 -68.874132)
			(xy 17.968722 -68.874132) (xy 17.947797 -68.891779) (xy 17.901821 -68.921489) (xy 17.852072 -68.944323)
			(xy 17.79957 -68.959812) (xy 17.745394 -68.967639) (xy 17.718024 -68.968112) (xy 17.691711 -68.967625)
			(xy 17.639583 -68.960393) (xy 17.588941 -68.946078) (xy 17.540742 -68.924949) (xy 17.495898 -68.897407)
			(xy 17.455257 -68.863972) (xy 17.4371 -68.844922) (xy 17.429577 -68.837522) (xy 17.410298 -68.828996)
			(xy 17.399762 -68.828412) (xy 17.325086 -68.828412) (xy 17.314533 -68.828916) (xy 17.295238 -68.837468)
			(xy 17.287748 -68.844922) (xy 17.269615 -68.864) (xy 17.22898 -68.897454) (xy 17.184135 -68.92501)
			(xy 17.13593 -68.946144) (xy 17.085278 -68.960457) (xy 17.033141 -68.967676) (xy 17.006824 -68.968112)
			(xy 16.979572 -68.967622) (xy 16.925622 -68.959869) (xy 16.873325 -68.944516) (xy 16.823745 -68.921877)
			(xy 16.777892 -68.892411) (xy 16.736699 -68.85672) (xy 16.701005 -68.81553) (xy 16.671537 -68.769679)
			(xy 16.648894 -68.720101) (xy 16.633537 -68.667805) (xy 16.62578 -68.613856) (xy 16.625316 -68.586604)
			(xy 4.260863 -68.586604) (xy 4.230585 -68.621935) (xy 4.189938 -68.657623) (xy 4.144659 -68.687213)
			(xy 4.095654 -68.710112) (xy 4.043907 -68.725859) (xy 3.990454 -68.734141) (xy 3.963416 -68.73494)
			(xy 3.958336 -68.73494) (xy 3.933359 -68.734538) (xy 3.883835 -68.727992) (xy 3.83559 -68.715034)
			(xy 3.78945 -68.695886) (xy 3.746207 -68.670877) (xy 3.72618 -68.655946) (xy 3.720592 -68.651628)
			(xy 3.707384 -68.646294) (xy 3.700272 -68.645532) (xy 3.693266 -68.645122) (xy 3.679476 -68.647695)
			(xy 3.673094 -68.650612) (xy 3.59537 -68.688712) (xy 3.59029 -68.690998) (xy 3.582408 -68.69543)
			(xy 3.570156 -68.708713) (xy 3.563255 -68.725415) (xy 3.562604 -68.734432) (xy 3.562604 -70.204076)
			(xy 6.107428 -70.204076) (xy 6.111499 -70.148454) (xy 6.123625 -70.094017) (xy 6.143548 -70.041926)
			(xy 6.170844 -69.993291) (xy 6.20493 -69.949148) (xy 6.245079 -69.910439) (xy 6.290437 -69.877988)
			(xy 6.340037 -69.852487) (xy 6.392821 -69.83448) (xy 6.447664 -69.82435) (xy 6.503398 -69.822313)
			(xy 6.558835 -69.828413) (xy 6.612792 -69.842519) (xy 6.664121 -69.864331) (xy 6.711727 -69.893385)
			(xy 6.754595 -69.92906) (xy 6.791812 -69.970597) (xy 6.822585 -70.01711) (xy 6.846257 -70.067607)
			(xy 6.862325 -70.121014) (xy 6.870445 -70.17619) (xy 6.870954 -70.204076) (xy 6.870445 -70.231962)
			(xy 6.862325 -70.287138) (xy 6.846257 -70.340545) (xy 6.822585 -70.391042) (xy 6.791812 -70.437555)
			(xy 6.754595 -70.479092) (xy 6.711727 -70.514767) (xy 6.664121 -70.543821) (xy 6.612792 -70.565633)
			(xy 6.558835 -70.579739) (xy 6.503398 -70.585839) (xy 6.447664 -70.583802) (xy 6.392821 -70.573672)
			(xy 6.340037 -70.555665) (xy 6.290437 -70.530164) (xy 6.245079 -70.497713) (xy 6.20493 -70.459004)
			(xy 6.170844 -70.414861) (xy 6.143548 -70.366226) (xy 6.123625 -70.314135) (xy 6.111499 -70.259698)
			(xy 6.107428 -70.204076) (xy 3.562604 -70.204076) (xy 3.562604 -70.480428) (xy 3.562076 -70.506452)
			(xy 3.553908 -70.557855) (xy 3.537814 -70.607351) (xy 3.514187 -70.653728) (xy 3.483609 -70.695846)
			(xy 3.465576 -70.714616) (xy 3.0353 -71.144892) (xy 3.032595 -71.147744) (xy 3.028004 -71.154123)
			(xy 3.026156 -71.157592) (xy 3.023576 -71.163019) (xy 3.02076 -71.174699) (xy 3.020568 -71.180706)
			(xy 3.020568 -71.673974) (xy 3.37896 -71.673974) (xy 3.383031 -71.618352) (xy 3.395157 -71.563915)
			(xy 3.41508 -71.511824) (xy 3.442376 -71.463189) (xy 3.476462 -71.419046) (xy 3.516611 -71.380337)
			(xy 3.561969 -71.347886) (xy 3.611569 -71.322385) (xy 3.664353 -71.304378) (xy 3.719196 -71.294248)
			(xy 3.77493 -71.292211) (xy 3.830367 -71.298311) (xy 3.884324 -71.312417) (xy 3.935653 -71.334229)
			(xy 3.983259 -71.363283) (xy 4.026127 -71.398958) (xy 4.033123 -71.406766) (xy 7.013446 -71.406766)
			(xy 7.017517 -71.351144) (xy 7.029643 -71.296707) (xy 7.049566 -71.244616) (xy 7.076862 -71.195981)
			(xy 7.110948 -71.151838) (xy 7.151097 -71.113129) (xy 7.196455 -71.080678) (xy 7.246055 -71.055177)
			(xy 7.298839 -71.03717) (xy 7.353682 -71.02704) (xy 7.409416 -71.025003) (xy 7.464853 -71.031103)
			(xy 7.51881 -71.045209) (xy 7.570139 -71.067021) (xy 7.617745 -71.096075) (xy 7.660613 -71.13175)
			(xy 7.69783 -71.173287) (xy 7.728603 -71.2198) (xy 7.752275 -71.270297) (xy 7.768343 -71.323704)
			(xy 7.776463 -71.37888) (xy 7.776972 -71.406766) (xy 7.776463 -71.434652) (xy 7.768343 -71.489828)
			(xy 7.752275 -71.543235) (xy 7.728603 -71.593732) (xy 7.69783 -71.640245) (xy 7.660613 -71.681782)
			(xy 7.617745 -71.717457) (xy 7.570139 -71.746511) (xy 7.51881 -71.768323) (xy 7.464853 -71.782429)
			(xy 7.409416 -71.788529) (xy 7.353682 -71.786492) (xy 7.298839 -71.776362) (xy 7.246055 -71.758355)
			(xy 7.196455 -71.732854) (xy 7.151097 -71.700403) (xy 7.110948 -71.661694) (xy 7.076862 -71.617551)
			(xy 7.049566 -71.568916) (xy 7.029643 -71.516825) (xy 7.017517 -71.462388) (xy 7.013446 -71.406766)
			(xy 4.033123 -71.406766) (xy 4.063344 -71.440495) (xy 4.094117 -71.487008) (xy 4.117789 -71.537505)
			(xy 4.133857 -71.590912) (xy 4.141977 -71.646088) (xy 4.142486 -71.673974) (xy 4.141977 -71.70186)
			(xy 4.133857 -71.757036) (xy 4.117789 -71.810443) (xy 4.094117 -71.86094) (xy 4.063344 -71.907453)
			(xy 4.026127 -71.94899) (xy 3.983259 -71.984665) (xy 3.935653 -72.013719) (xy 3.884324 -72.035531)
			(xy 3.830367 -72.049637) (xy 3.77493 -72.055737) (xy 3.719196 -72.0537) (xy 3.664353 -72.04357) (xy 3.611569 -72.025563)
			(xy 3.561969 -72.000062) (xy 3.516611 -71.967611) (xy 3.476462 -71.928902) (xy 3.442376 -71.884759)
			(xy 3.41508 -71.836124) (xy 3.395157 -71.784033) (xy 3.383031 -71.729596) (xy 3.37896 -71.673974)
			(xy 3.020568 -71.673974) (xy 3.020568 -71.883016) (xy 3.021584 -71.892668) (xy 3.023212 -71.899912)
			(xy 3.030052 -71.913082) (xy 3.035046 -71.918576) (xy 4.029456 -72.912986) (xy 4.033316 -72.916714)
			(xy 4.042283 -72.922605) (xy 4.047236 -72.92467) (xy 4.05003 -72.925432) (xy 4.072552 -72.932775)
			(xy 4.115732 -72.95226) (xy 4.136136 -72.964294) (xy 4.143248 -72.96785) (xy 4.15163 -72.97039) (xy 4.162552 -72.97166)
			(xy 6.666992 -72.97166) (xy 6.676644 -72.970644) (xy 6.683888 -72.969017) (xy 6.697056 -72.962174)
			(xy 6.702552 -72.957182) (xy 8.064754 -71.594726) (xy 8.071594 -71.587326) (xy 8.079309 -71.568727)
			(xy 8.07974 -71.558658) (xy 8.07974 -69.817742) (xy 8.080175 -69.807677) (xy 8.087909 -69.789092)
			(xy 8.094726 -69.781674) (xy 8.392414 -69.483986) (xy 8.399809 -69.477132) (xy 8.418408 -69.46939)
			(xy 8.428482 -69.469) (xy 11.548364 -69.469) (xy 11.558429 -69.469435) (xy 11.577017 -69.477166)
			(xy 11.584432 -69.483986) (xy 12.824714 -70.724268) (xy 12.824968 -70.724522) (xy 13.656277 -71.555864)
			(xy 19.194524 -71.555864) (xy 19.198595 -71.500242) (xy 19.210721 -71.445805) (xy 19.230644 -71.393714)
			(xy 19.25794 -71.345079) (xy 19.292026 -71.300936) (xy 19.332175 -71.262227) (xy 19.377533 -71.229776)
			(xy 19.427133 -71.204275) (xy 19.479917 -71.186268) (xy 19.53476 -71.176138) (xy 19.590494 -71.174101)
			(xy 19.645931 -71.180201) (xy 19.699888 -71.194307) (xy 19.751217 -71.216119) (xy 19.798823 -71.245173)
			(xy 19.841691 -71.280848) (xy 19.878908 -71.322385) (xy 19.909681 -71.368898) (xy 19.933353 -71.419395)
			(xy 19.949421 -71.472802) (xy 19.957541 -71.527978) (xy 19.95805 -71.555864) (xy 19.957541 -71.58375)
			(xy 19.951702 -71.623428) (xy 20.703538 -71.623428) (xy 20.707609 -71.567806) (xy 20.719735 -71.513369)
			(xy 20.739658 -71.461278) (xy 20.766954 -71.412643) (xy 20.80104 -71.3685) (xy 20.841189 -71.329791)
			(xy 20.886547 -71.29734) (xy 20.936147 -71.271839) (xy 20.988931 -71.253832) (xy 21.043774 -71.243702)
			(xy 21.099508 -71.241665) (xy 21.154945 -71.247765) (xy 21.208902 -71.261871) (xy 21.260231 -71.283683)
			(xy 21.307837 -71.312737) (xy 21.350705 -71.348412) (xy 21.387922 -71.389949) (xy 21.418695 -71.436462)
			(xy 21.442367 -71.486959) (xy 21.458435 -71.540366) (xy 21.466555 -71.595542) (xy 21.467064 -71.623428)
			(xy 21.466555 -71.651314) (xy 21.458435 -71.70649) (xy 21.442367 -71.759897) (xy 21.418695 -71.810394)
			(xy 21.387922 -71.856907) (xy 21.350705 -71.898444) (xy 21.307837 -71.934119) (xy 21.260231 -71.963173)
			(xy 21.208902 -71.984985) (xy 21.154945 -71.999091) (xy 21.099508 -72.005191) (xy 21.043774 -72.003154)
			(xy 20.988931 -71.993024) (xy 20.936147 -71.975017) (xy 20.886547 -71.949516) (xy 20.841189 -71.917065)
			(xy 20.80104 -71.878356) (xy 20.766954 -71.834213) (xy 20.739658 -71.785578) (xy 20.719735 -71.733487)
			(xy 20.707609 -71.67905) (xy 20.703538 -71.623428) (xy 19.951702 -71.623428) (xy 19.949421 -71.638926)
			(xy 19.933353 -71.692333) (xy 19.909681 -71.74283) (xy 19.878908 -71.789343) (xy 19.841691 -71.83088)
			(xy 19.798823 -71.866555) (xy 19.751217 -71.895609) (xy 19.699888 -71.917421) (xy 19.645931 -71.931527)
			(xy 19.590494 -71.937627) (xy 19.53476 -71.93559) (xy 19.479917 -71.92546) (xy 19.427133 -71.907453)
			(xy 19.377533 -71.881952) (xy 19.332175 -71.849501) (xy 19.292026 -71.810792) (xy 19.25794 -71.766649)
			(xy 19.230644 -71.718014) (xy 19.210721 -71.665923) (xy 19.198595 -71.611486) (xy 19.194524 -71.555864)
			(xy 13.656277 -71.555864) (xy 19.211036 -77.110844) (xy 19.21517 -77.114732) (xy 19.224783 -77.120761)
			(xy 19.230086 -77.122782) (xy 19.234155 -77.124082) (xy 19.24258 -77.125486) (xy 19.24685 -77.125576)
			(xy 26.379424 -77.125576) (xy 26.405448 -77.126101) (xy 26.456853 -77.134265) (xy 26.506352 -77.150357)
			(xy 26.552731 -77.173983) (xy 26.59485 -77.204562) (xy 26.613612 -77.222604) (xy 27.472894 -78.081886)
			(xy 27.479949 -78.088345) (xy 27.497503 -78.095903) (xy 27.516607 -78.096455) (xy 27.525726 -78.09357)
			(xy 27.528012 -78.092554) (xy 27.534997 -78.089394) (xy 27.546867 -78.079703) (xy 27.55138 -78.073504)
			(xy 27.55519 -78.067662) (xy 27.559508 -78.053692) (xy 27.559508 -68.11772) (xy 27.559 -68.1101)
			(xy 27.557541 -68.102269) (xy 27.550417 -68.088028) (xy 27.54503 -68.08216) (xy 26.172922 -66.710306)
			(xy 26.154805 -66.691527) (xy 26.124112 -66.649332) (xy 26.100404 -66.602852) (xy 26.084265 -66.553233)
			(xy 26.076095 -66.501699) (xy 26.07564 -66.47561) (xy 26.07564 -64.720978) (xy 26.075227 -64.711879)
			(xy 26.068795 -64.694852) (xy 26.05682 -64.681144) (xy 26.04897 -64.676528) (xy 26.04389 -64.674496)
			(xy 26.036858 -64.671773) (xy 26.021865 -64.670216) (xy 26.014426 -64.671448) (xy 26.007822 -64.672718)
			(xy 25.994614 -64.67983) (xy 25.542748 -65.131696) (xy 25.523977 -65.149729) (xy 25.481861 -65.180311)
			(xy 25.435485 -65.203941) (xy 25.385988 -65.220038) (xy 25.334584 -65.228207) (xy 25.30856 -65.228724)
			(xy 22.63648 -65.228724) (xy 22.629114 -65.229232) (xy 22.621135 -65.230702) (xy 22.606636 -65.237962)
			(xy 22.600666 -65.243456) (xy 21.96592 -65.878456) (xy 21.94715 -65.896489) (xy 21.905034 -65.927072)
			(xy 21.858658 -65.9507) (xy 21.80916 -65.966795) (xy 21.757756 -65.974961) (xy 21.731732 -65.975484)
			(xy 21.056854 -65.975484) (xy 21.03083 -65.974957) (xy 20.979426 -65.966791) (xy 20.929927 -65.950699)
			(xy 20.883548 -65.927075) (xy 20.841428 -65.896498) (xy 20.822666 -65.878456) (xy 20.421854 -65.477644)
			(xy 20.417995 -65.473914) (xy 20.409031 -65.468017) (xy 20.404074 -65.46596) (xy 20.40128 -65.465198)
			(xy 20.375842 -65.456807) (xy 20.327424 -65.433892) (xy 20.282687 -65.404432) (xy 20.242509 -65.369006)
			(xy 20.207679 -65.328309) (xy 20.178882 -65.283143) (xy 20.156684 -65.234393) (xy 20.141521 -65.183018)
			(xy 20.133691 -65.130027) (xy 20.133056 -65.103248) (xy 20.133056 -65.100454) (xy 20.133496 -65.074926)
			(xy 20.140375 -65.024334) (xy 20.146772 -64.999616) (xy 20.146772 -64.999362) (xy 20.149242 -64.988398)
			(xy 20.145563 -64.966253) (xy 20.13966 -64.95669) (xy 20.107402 -64.914272) (xy 20.089368 -64.89065)
			(xy 20.081774 -64.881664) (xy 20.06073 -64.871203) (xy 20.048982 -64.870584) (xy 19.593306 -64.870584)
			(xy 19.583908 -64.871346) (xy 19.576479 -64.872991) (xy 19.563034 -64.880101) (xy 19.557492 -64.885316)
			(xy 18.452846 -65.990216) (xy 18.434077 -66.008253) (xy 18.391963 -66.038842) (xy 18.345587 -66.062477)
			(xy 18.296089 -66.078578) (xy 18.244683 -66.086749) (xy 18.218658 -66.087244) (xy 14.929866 -66.087244)
			(xy 14.923779 -66.087453) (xy 14.911968 -66.090408) (xy 14.906498 -66.093086) (xy 14.906244 -66.093086)
			(xy 14.878715 -66.106917) (xy 14.820301 -66.126486) (xy 14.7595 -66.136408) (xy 14.728698 -66.137028)
			(xy 14.701445 -66.136542) (xy 14.647495 -66.128785) (xy 14.595198 -66.113429) (xy 14.545618 -66.090786)
			(xy 14.499766 -66.061318) (xy 14.458574 -66.025625) (xy 14.42288 -65.984433) (xy 14.393413 -65.93858)
			(xy 14.370771 -65.889) (xy 14.355415 -65.836703) (xy 14.347658 -65.782753) (xy 14.347658 -65.728247)
			(xy 14.355415 -65.674297) (xy 14.370771 -65.622) (xy 14.393413 -65.57242) (xy 14.42288 -65.526567)
			(xy 14.458574 -65.485375) (xy 14.499766 -65.449682) (xy 14.545618 -65.420214) (xy 14.595198 -65.397571)
			(xy 14.647495 -65.382215) (xy 14.701445 -65.374458) (xy 14.728698 -65.374012) (xy 14.7595 -65.374624)
			(xy 14.820297 -65.384563) (xy 14.87871 -65.404134) (xy 14.906244 -65.417954) (xy 14.906498 -65.417954)
			(xy 14.911969 -65.420628) (xy 14.92378 -65.42358) (xy 14.929866 -65.423796) (xy 18.059654 -65.423796)
			(xy 18.069052 -65.423034) (xy 18.076484 -65.421393) (xy 18.089935 -65.414289) (xy 18.095468 -65.409064)
			(xy 19.200114 -64.304164) (xy 19.218884 -64.286132) (xy 19.261001 -64.255552) (xy 19.307377 -64.231927)
			(xy 19.356875 -64.215836) (xy 19.408279 -64.207675) (xy 19.434302 -64.207136) (xy 24.857456 -64.207136)
			(xy 24.863466 -64.206968) (xy 24.875148 -64.204145) (xy 24.88057 -64.201548) (xy 24.884045 -64.19971)
			(xy 24.890425 -64.195117) (xy 24.89327 -64.192404) (xy 24.91486 -64.170814) (xy 24.917567 -64.167964)
			(xy 24.922162 -64.161586) (xy 24.924004 -64.158114) (xy 24.926582 -64.152686) (xy 24.929396 -64.141007)
			(xy 24.929592 -64.135) (xy 24.929592 -56.619902) (xy 24.929086 -56.609705) (xy 24.92108 -56.590942)
			(xy 24.906436 -56.576741) (xy 24.89708 -56.572658) (xy 24.85263 -56.55564) (xy 24.807926 -56.538622)
			(xy 24.798246 -56.535418) (xy 24.777889 -56.536164) (xy 24.759443 -56.544808) (xy 24.7523 -56.552084)
			(xy 24.734139 -56.571625) (xy 24.693299 -56.605947) (xy 24.648077 -56.634246) (xy 24.599354 -56.65597)
			(xy 24.54808 -56.670697) (xy 24.495255 -56.678139) (xy 24.468582 -56.678576) (xy 24.441334 -56.678089)
			(xy 24.387393 -56.670331) (xy 24.335105 -56.654975) (xy 24.285534 -56.632335) (xy 24.23969 -56.602871)
			(xy 24.198505 -56.567182) (xy 24.162818 -56.525996) (xy 24.133356 -56.48015) (xy 24.110718 -56.430579)
			(xy 24.095366 -56.37829) (xy 24.08761 -56.324348) (xy 24.08761 -56.269852) (xy 24.095366 -56.21591)
			(xy 24.110718 -56.163621) (xy 24.133356 -56.11405) (xy 24.162818 -56.068204) (xy 24.198505 -56.027018)
			(xy 24.23969 -55.991329) (xy 24.285534 -55.961865) (xy 24.335105 -55.939225) (xy 24.387393 -55.923869)
			(xy 24.441334 -55.916111) (xy 24.468582 -55.91556) (xy 24.495247 -55.915983) (xy 24.548063 -55.923372)
			(xy 24.599334 -55.938049) (xy 24.648059 -55.959728) (xy 24.693287 -55.987986) (xy 24.734135 -56.022272)
			(xy 24.7523 -56.041798) (xy 24.752554 -56.042306) (xy 24.757821 -56.047646) (xy 24.770731 -56.05527)
			(xy 24.777954 -56.057292) (xy 24.778208 -56.057292) (xy 24.785687 -56.058886) (xy 24.800947 -56.057994)
			(xy 24.80818 -56.055514) (xy 24.89708 -56.021478) (xy 24.90645 -56.017399) (xy 24.921153 -56.003231)
			(xy 24.929147 -55.984443) (xy 24.929592 -55.974234) (xy 24.929592 -55.11292) (xy 24.930121 -55.086897)
			(xy 24.938291 -55.035495) (xy 24.954387 -54.985999) (xy 24.978013 -54.939623) (xy 25.00859 -54.897505)
			(xy 25.02662 -54.878732) (xy 26.946606 -52.958746) (xy 26.950339 -52.954889) (xy 26.956239 -52.945926)
			(xy 26.95829 -52.940966) (xy 26.959052 -52.938172) (xy 26.967475 -52.912611) (xy 26.990503 -52.86397)
			(xy 27.020141 -52.819049) (xy 27.055798 -52.77874) (xy 27.096768 -52.743843) (xy 27.142237 -52.715053)
			(xy 27.191301 -52.692939) (xy 27.242986 -52.677942) (xy 27.296267 -52.67036) (xy 27.350084 -52.670342)
			(xy 27.403369 -52.67789) (xy 27.455065 -52.692853) (xy 27.504143 -52.714934) (xy 27.549631 -52.743695)
			(xy 27.590623 -52.778565) (xy 27.626307 -52.81885) (xy 27.655974 -52.863752) (xy 27.679035 -52.912378)
			(xy 27.687524 -52.937918) (xy 27.687524 -52.938172) (xy 27.688286 -52.940966) (xy 27.69037 -52.945909)
			(xy 27.696261 -52.954871) (xy 27.69997 -52.958746) (xy 28.210256 -53.469032) (xy 28.228286 -53.487803)
			(xy 28.23464 -53.496556) (xy 32.133441 -53.496556) (xy 32.133441 -53.442044) (xy 32.141199 -53.388088)
			(xy 32.156558 -53.335785) (xy 32.179204 -53.2862) (xy 32.208677 -53.240343) (xy 32.244376 -53.199148)
			(xy 32.285575 -53.163453) (xy 32.331435 -53.133985) (xy 32.381022 -53.111344) (xy 32.433327 -53.095991)
			(xy 32.487284 -53.088238) (xy 32.51454 -53.087778) (xy 32.54191 -53.08826) (xy 32.596089 -53.096071)
			(xy 32.648593 -53.111555) (xy 32.69834 -53.134394) (xy 32.744307 -53.164117) (xy 32.765238 -53.181758)
			(xy 32.765492 -53.182012) (xy 32.772576 -53.187603) (xy 32.789495 -53.193847) (xy 32.798512 -53.194204)
			(xy 32.865568 -53.194204) (xy 32.874583 -53.193831) (xy 32.8915 -53.187594) (xy 32.898588 -53.182012)
			(xy 32.898588 -53.181758) (xy 32.898842 -53.181758) (xy 32.919779 -53.164126) (xy 32.965751 -53.134414)
			(xy 33.015498 -53.111578) (xy 33.067997 -53.096085) (xy 33.122171 -53.088253) (xy 33.14954 -53.087778)
			(xy 33.176788 -53.088295) (xy 33.23073 -53.096056) (xy 33.283018 -53.111414) (xy 33.332588 -53.134056)
			(xy 33.378432 -53.163523) (xy 33.419616 -53.199213) (xy 33.455301 -53.2404) (xy 33.484763 -53.286247)
			(xy 33.5074 -53.33582) (xy 33.522753 -53.388109) (xy 33.530508 -53.442052) (xy 33.530508 -53.496548)
			(xy 33.522753 -53.550491) (xy 33.5074 -53.60278) (xy 33.484763 -53.652353) (xy 33.455301 -53.6982)
			(xy 33.419616 -53.739387) (xy 33.378432 -53.775077) (xy 33.332588 -53.804544) (xy 33.283018 -53.827186)
			(xy 33.23073 -53.842544) (xy 33.176788 -53.850305) (xy 33.14954 -53.850794) (xy 33.122171 -53.850306)
			(xy 33.067992 -53.842494) (xy 33.015489 -53.82701) (xy 32.965742 -53.804173) (xy 32.919774 -53.774453)
			(xy 32.898842 -53.756814) (xy 32.898588 -53.75656) (xy 32.891513 -53.750957) (xy 32.874587 -53.744721)
			(xy 32.865568 -53.744368) (xy 32.798512 -53.744368) (xy 32.789497 -53.744738) (xy 32.77258 -53.750977)
			(xy 32.765492 -53.75656) (xy 32.765492 -53.756814) (xy 32.765238 -53.756814) (xy 32.744304 -53.774451)
			(xy 32.698332 -53.804163) (xy 32.648585 -53.826999) (xy 32.596084 -53.84249) (xy 32.541909 -53.850319)
			(xy 32.51454 -53.850794) (xy 32.487284 -53.850362) (xy 32.433327 -53.842609) (xy 32.381022 -53.827256)
			(xy 32.331435 -53.804615) (xy 32.285575 -53.775147) (xy 32.244376 -53.739452) (xy 32.208677 -53.698257)
			(xy 32.179204 -53.6524) (xy 32.156558 -53.602815) (xy 32.141199 -53.550512) (xy 32.133441 -53.496556)
			(xy 28.23464 -53.496556) (xy 28.258862 -53.529921) (xy 28.282483 -53.576298) (xy 28.29857 -53.625795)
			(xy 28.306728 -53.677197) (xy 28.307284 -53.70322) (xy 28.307284 -54.952392) (xy 28.308023 -54.965065)
			(xy 28.320137 -54.98734) (xy 28.322493 -54.989055) (xy 29.901045 -54.989055) (xy 29.901045 -54.934545)
			(xy 29.908803 -54.880589) (xy 29.924161 -54.828287) (xy 29.946807 -54.778704) (xy 29.976279 -54.732848)
			(xy 30.011977 -54.691653) (xy 30.053175 -54.655958) (xy 30.099034 -54.62649) (xy 30.148619 -54.603849)
			(xy 30.200923 -54.588496) (xy 30.254879 -54.580743) (xy 30.282134 -54.580282) (xy 30.310226 -54.58075)
			(xy 30.365805 -54.588982) (xy 30.419575 -54.605278) (xy 30.470372 -54.629285) (xy 30.517098 -54.660484)
			(xy 30.558743 -54.698199) (xy 30.594404 -54.741616) (xy 30.609286 -54.765448) (xy 30.61462 -54.774338)
			(xy 30.631638 -54.78653) (xy 30.724856 -54.80685) (xy 30.74543 -54.802532) (xy 30.754066 -54.79669)
			(xy 30.778137 -54.780701) (xy 30.830066 -54.755356) (xy 30.885222 -54.738127) (xy 30.942344 -54.729409)
			(xy 30.971236 -54.728872) (xy 30.998487 -54.729344) (xy 31.052434 -54.737105) (xy 31.104728 -54.752464)
			(xy 31.154304 -54.775108) (xy 31.200153 -54.804576) (xy 31.241343 -54.840269) (xy 31.277034 -54.881459)
			(xy 31.3065 -54.92731) (xy 31.329142 -54.976887) (xy 31.344498 -55.029181) (xy 31.352257 -55.083129)
			(xy 31.352744 -55.11038) (xy 31.35228 -55.13775) (xy 31.344464 -55.19193) (xy 31.328975 -55.244434)
			(xy 31.306132 -55.294181) (xy 31.276406 -55.340147) (xy 31.258764 -55.361078) (xy 31.25851 -55.361332)
			(xy 31.252947 -55.368435) (xy 31.246686 -55.385339) (xy 31.246318 -55.394352) (xy 31.246318 -55.461408)
			(xy 31.246667 -55.470426) (xy 31.25292 -55.487343) (xy 31.25851 -55.494428) (xy 31.258764 -55.494428)
			(xy 31.258764 -55.494682) (xy 31.276385 -55.51563) (xy 31.306112 -55.561595) (xy 31.328959 -55.611339)
			(xy 31.344457 -55.663839) (xy 31.352288 -55.718015) (xy 31.35229 -55.772755) (xy 31.344463 -55.826932)
			(xy 31.328969 -55.879433) (xy 31.306126 -55.929178) (xy 31.276404 -55.975145) (xy 31.258764 -55.996078)
			(xy 31.25851 -55.996332) (xy 31.252947 -56.003435) (xy 31.246686 -56.020339) (xy 31.246318 -56.029352)
			(xy 31.246318 -56.096408) (xy 31.246667 -56.105426) (xy 31.25292 -56.122343) (xy 31.25851 -56.129428)
			(xy 31.258764 -56.129428) (xy 31.258764 -56.129682) (xy 31.276403 -56.150615) (xy 31.306116 -56.196587)
			(xy 31.328952 -56.246334) (xy 31.344443 -56.298835) (xy 31.352271 -56.353011) (xy 31.352744 -56.38038)
			(xy 31.352258 -56.407631) (xy 31.344502 -56.461579) (xy 31.329147 -56.513874) (xy 31.306505 -56.563451)
			(xy 31.277039 -56.609301) (xy 31.241348 -56.650492) (xy 31.200157 -56.686183) (xy 31.154307 -56.715649)
			(xy 31.10473 -56.738291) (xy 31.052435 -56.753646) (xy 30.998487 -56.761402) (xy 30.943985 -56.761402)
			(xy 30.890037 -56.753646) (xy 30.837742 -56.738291) (xy 30.788165 -56.715649) (xy 30.742315 -56.686183)
			(xy 30.701124 -56.650492) (xy 30.665433 -56.609301) (xy 30.635967 -56.563451) (xy 30.613325 -56.513874)
			(xy 30.59797 -56.461579) (xy 30.590214 -56.407631) (xy 30.589728 -56.38038) (xy 30.590176 -56.353009)
			(xy 30.597997 -56.298829) (xy 30.61349 -56.246325) (xy 30.636336 -56.196579) (xy 30.666065 -56.150613)
			(xy 30.683708 -56.129682) (xy 30.683962 -56.129428) (xy 30.68955 -56.122343) (xy 30.695794 -56.105425)
			(xy 30.696154 -56.096408) (xy 30.696154 -56.029352) (xy 30.695782 -56.020336) (xy 30.689546 -56.003419)
			(xy 30.683962 -55.996332) (xy 30.683708 -55.996332) (xy 30.683708 -55.996078) (xy 30.666049 -55.975161)
			(xy 30.636326 -55.92919) (xy 30.613483 -55.879441) (xy 30.597989 -55.826937) (xy 30.590163 -55.772756)
			(xy 30.590165 -55.718014) (xy 30.597995 -55.663834) (xy 30.613494 -55.611331) (xy 30.63634 -55.561584)
			(xy 30.666067 -55.515615) (xy 30.683708 -55.494682) (xy 30.683962 -55.494428) (xy 30.68955 -55.487343)
			(xy 30.695794 -55.470425) (xy 30.696154 -55.461408) (xy 30.696154 -55.394352) (xy 30.695782 -55.385336)
			(xy 30.689546 -55.368419) (xy 30.683962 -55.361332) (xy 30.683708 -55.360824) (xy 30.672765 -55.348089)
			(xy 30.652923 -55.320998) (xy 30.644084 -55.306722) (xy 30.63875 -55.297832) (xy 30.621732 -55.28564)
			(xy 30.528514 -55.26532) (xy 30.50794 -55.269638) (xy 30.499304 -55.27548) (xy 30.475239 -55.291478)
			(xy 30.423308 -55.316822) (xy 30.368151 -55.334048) (xy 30.311026 -55.342763) (xy 30.282134 -55.343298)
			(xy 30.254879 -55.342857) (xy 30.200923 -55.335104) (xy 30.148619 -55.319751) (xy 30.099034 -55.29711)
			(xy 30.053175 -55.267642) (xy 30.011977 -55.231947) (xy 29.976279 -55.190752) (xy 29.946807 -55.144896)
			(xy 29.924161 -55.095313) (xy 29.908803 -55.043011) (xy 29.901045 -54.989055) (xy 28.322493 -54.989055)
			(xy 28.330398 -54.99481) (xy 28.346146 -55.00497) (xy 28.402026 -55.041292) (xy 28.407477 -55.044615)
			(xy 28.419555 -55.048739) (xy 28.425902 -55.04942) (xy 28.438348 -55.050436) (xy 28.450286 -55.045102)
			(xy 28.47482 -55.034684) (xy 28.526052 -55.01998) (xy 28.57883 -55.01254) (xy 28.60548 -55.012082)
			(xy 28.605734 -55.012082) (xy 28.632019 -55.012522) (xy 28.684092 -55.019737) (xy 28.734684 -55.034026)
			(xy 28.782837 -55.055119) (xy 28.827643 -55.082617) (xy 28.868253 -55.116001) (xy 28.886404 -55.135018)
			(xy 28.886912 -55.135526) (xy 28.914344 -55.147464) (xy 28.919184 -55.149468) (xy 28.929428 -55.151648)
			(xy 28.934664 -55.151782) (xy 28.988004 -55.151782) (xy 28.993238 -55.151627) (xy 29.00348 -55.149454)
			(xy 29.008324 -55.147464) (xy 29.035756 -55.135526) (xy 29.036264 -55.135018) (xy 29.054406 -55.115991)
			(xy 29.095013 -55.0826) (xy 29.139818 -55.0551) (xy 29.187975 -55.03401) (xy 29.238571 -55.019731)
			(xy 29.290648 -55.012532) (xy 29.316934 -55.012082) (xy 29.344184 -55.01257) (xy 29.39813 -55.020331)
			(xy 29.450422 -55.035689) (xy 29.499996 -55.058333) (xy 29.545843 -55.087801) (xy 29.587031 -55.123493)
			(xy 29.62272 -55.164684) (xy 29.652183 -55.210534) (xy 29.674823 -55.26011) (xy 29.690176 -55.312403)
			(xy 29.697932 -55.36635) (xy 29.697932 -55.42085) (xy 29.690176 -55.474797) (xy 29.674823 -55.52709)
			(xy 29.652183 -55.576666) (xy 29.62272 -55.622516) (xy 29.587031 -55.663707) (xy 29.545843 -55.699399)
			(xy 29.499996 -55.728867) (xy 29.450422 -55.751511) (xy 29.39813 -55.766869) (xy 29.344184 -55.77463)
			(xy 29.316934 -55.775098) (xy 29.290649 -55.774656) (xy 29.238577 -55.767438) (xy 29.187986 -55.753148)
			(xy 29.139833 -55.732056) (xy 29.095027 -55.70456) (xy 29.054415 -55.671179) (xy 29.036264 -55.652162)
			(xy 29.035756 -55.651654) (xy 29.008324 -55.639716) (xy 29.003484 -55.637716) (xy 28.99324 -55.635544)
			(xy 28.988004 -55.635398) (xy 28.934664 -55.635398) (xy 28.92943 -55.635556) (xy 28.919191 -55.637734)
			(xy 28.914344 -55.639716) (xy 28.886912 -55.651654) (xy 28.886404 -55.652162) (xy 28.866658 -55.672774)
			(xy 28.822134 -55.708488) (xy 28.772789 -55.737173) (xy 28.719722 -55.758191) (xy 28.664116 -55.771072)
			(xy 28.635706 -55.773828) (xy 28.608949 -55.775504) (xy 28.555438 -55.772241) (xy 28.502909 -55.761523)
			(xy 28.452397 -55.743561) (xy 28.404895 -55.718708) (xy 28.361337 -55.687453) (xy 28.322581 -55.650411)
			(xy 28.289389 -55.608311) (xy 28.275534 -55.58536) (xy 28.27528 -55.584852) (xy 28.272299 -55.580083)
			(xy 28.264602 -55.571886) (xy 28.26004 -55.568596) (xy 28.255468 -55.565294) (xy 28.244292 -55.56123)
			(xy 28.182316 -55.553102) (xy 28.158694 -55.550054) (xy 28.147258 -55.549195) (xy 28.125488 -55.556306)
			(xy 28.116784 -55.56377) (xy 27.719782 -55.961026) (xy 27.701001 -55.979139) (xy 27.658804 -56.009825)
			(xy 27.612323 -56.033526) (xy 27.562705 -56.049659) (xy 27.511173 -56.057824) (xy 27.485086 -56.058308)
			(xy 27.189684 -56.058308) (xy 27.179679 -56.058799) (xy 27.161194 -56.066462) (xy 27.147048 -56.080614)
			(xy 27.139394 -56.099103) (xy 27.138884 -56.109108) (xy 27.138884 -56.932322) (xy 27.139048 -56.938333)
			(xy 27.141865 -56.950018) (xy 27.144472 -56.955436) (xy 27.146312 -56.95891) (xy 27.150905 -56.965289)
			(xy 27.153616 -56.968136) (xy 27.177746 -56.992266) (xy 27.195855 -57.011048) (xy 27.226533 -57.053247)
			(xy 27.250226 -57.099729) (xy 27.26635 -57.149346) (xy 27.274508 -57.200876) (xy 27.275028 -57.226962)
			(xy 27.275028 -57.48528) (xy 30.605982 -57.48528) (xy 30.610053 -57.429658) (xy 30.622179 -57.375221)
			(xy 30.642102 -57.32313) (xy 30.669398 -57.274495) (xy 30.703484 -57.230352) (xy 30.743633 -57.191643)
			(xy 30.788991 -57.159192) (xy 30.838591 -57.133691) (xy 30.891375 -57.115684) (xy 30.946218 -57.105554)
			(xy 31.001952 -57.103517) (xy 31.057389 -57.109617) (xy 31.111346 -57.123723) (xy 31.162675 -57.145535)
			(xy 31.210281 -57.174589) (xy 31.253149 -57.210264) (xy 31.290366 -57.251801) (xy 31.321139 -57.298314)
			(xy 31.344811 -57.348811) (xy 31.360879 -57.402218) (xy 31.368999 -57.457394) (xy 31.369508 -57.48528)
			(xy 31.368999 -57.513166) (xy 31.360879 -57.568342) (xy 31.344811 -57.621749) (xy 31.321139 -57.672246)
			(xy 31.290366 -57.718759) (xy 31.253149 -57.760296) (xy 31.210281 -57.795971) (xy 31.162675 -57.825025)
			(xy 31.111346 -57.846837) (xy 31.057389 -57.860943) (xy 31.001952 -57.867043) (xy 30.946218 -57.865006)
			(xy 30.891375 -57.854876) (xy 30.838591 -57.836869) (xy 30.788991 -57.811368) (xy 30.743633 -57.778917)
			(xy 30.703484 -57.740208) (xy 30.669398 -57.696065) (xy 30.642102 -57.64743) (xy 30.622179 -57.595339)
			(xy 30.610053 -57.540902) (xy 30.605982 -57.48528) (xy 27.275028 -57.48528) (xy 27.275028 -58.561224)
			(xy 32.56229 -58.561224) (xy 32.566361 -58.505602) (xy 32.578487 -58.451165) (xy 32.59841 -58.399074)
			(xy 32.625706 -58.350439) (xy 32.659792 -58.306296) (xy 32.699941 -58.267587) (xy 32.745299 -58.235136)
			(xy 32.794899 -58.209635) (xy 32.847683 -58.191628) (xy 32.902526 -58.181498) (xy 32.95826 -58.179461)
			(xy 33.013697 -58.185561) (xy 33.067654 -58.199667) (xy 33.118983 -58.221479) (xy 33.166589 -58.250533)
			(xy 33.209457 -58.286208) (xy 33.246674 -58.327745) (xy 33.277447 -58.374258) (xy 33.301119 -58.424755)
			(xy 33.317187 -58.478162) (xy 33.325307 -58.533338) (xy 33.325816 -58.561224) (xy 33.325307 -58.58911)
			(xy 33.317187 -58.644286) (xy 33.301119 -58.697693) (xy 33.277447 -58.74819) (xy 33.246674 -58.794703)
			(xy 33.209457 -58.83624) (xy 33.166589 -58.871915) (xy 33.118983 -58.900969) (xy 33.067654 -58.922781)
			(xy 33.013697 -58.936887) (xy 32.95826 -58.942987) (xy 32.902526 -58.94095) (xy 32.847683 -58.93082)
			(xy 32.794899 -58.912813) (xy 32.745299 -58.887312) (xy 32.699941 -58.854861) (xy 32.659792 -58.816152)
			(xy 32.625706 -58.772009) (xy 32.59841 -58.723374) (xy 32.578487 -58.671283) (xy 32.566361 -58.616846)
			(xy 32.56229 -58.561224) (xy 27.275028 -58.561224) (xy 27.275028 -59.174634) (xy 31.093154 -59.174634)
			(xy 31.097225 -59.119012) (xy 31.109351 -59.064575) (xy 31.129274 -59.012484) (xy 31.15657 -58.963849)
			(xy 31.190656 -58.919706) (xy 31.230805 -58.880997) (xy 31.276163 -58.848546) (xy 31.325763 -58.823045)
			(xy 31.378547 -58.805038) (xy 31.43339 -58.794908) (xy 31.489124 -58.792871) (xy 31.544561 -58.798971)
			(xy 31.598518 -58.813077) (xy 31.649847 -58.834889) (xy 31.697453 -58.863943) (xy 31.740321 -58.899618)
			(xy 31.777538 -58.941155) (xy 31.808311 -58.987668) (xy 31.831983 -59.038165) (xy 31.848051 -59.091572)
			(xy 31.856171 -59.146748) (xy 31.85668 -59.174634) (xy 31.856171 -59.20252) (xy 31.848051 -59.257696)
			(xy 31.831983 -59.311103) (xy 31.808311 -59.3616) (xy 31.777538 -59.408113) (xy 31.740321 -59.44965)
			(xy 31.697453 -59.485325) (xy 31.649847 -59.514379) (xy 31.598518 -59.536191) (xy 31.544561 -59.550297)
			(xy 31.489124 -59.556397) (xy 31.43339 -59.55436) (xy 31.378547 -59.54423) (xy 31.325763 -59.526223)
			(xy 31.276163 -59.500722) (xy 31.230805 -59.468271) (xy 31.190656 -59.429562) (xy 31.15657 -59.385419)
			(xy 31.129274 -59.336784) (xy 31.109351 -59.284693) (xy 31.097225 -59.230256) (xy 31.093154 -59.174634)
			(xy 27.275028 -59.174634) (xy 27.275028 -60.633356) (xy 33.796984 -60.633356) (xy 33.801055 -60.577734)
			(xy 33.813181 -60.523297) (xy 33.833104 -60.471206) (xy 33.8604 -60.422571) (xy 33.894486 -60.378428)
			(xy 33.934635 -60.339719) (xy 33.979993 -60.307268) (xy 34.029593 -60.281767) (xy 34.082377 -60.26376)
			(xy 34.13722 -60.25363) (xy 34.192954 -60.251593) (xy 34.248391 -60.257693) (xy 34.302348 -60.271799)
			(xy 34.353677 -60.293611) (xy 34.401283 -60.322665) (xy 34.444151 -60.35834) (xy 34.481368 -60.399877)
			(xy 34.512141 -60.44639) (xy 34.535813 -60.496887) (xy 34.551881 -60.550294) (xy 34.560001 -60.60547)
			(xy 34.56051 -60.633356) (xy 34.560001 -60.661242) (xy 34.551881 -60.716418) (xy 34.535813 -60.769825)
			(xy 34.512141 -60.820322) (xy 34.481368 -60.866835) (xy 34.444151 -60.908372) (xy 34.401283 -60.944047)
			(xy 34.353677 -60.973101) (xy 34.302348 -60.994913) (xy 34.248391 -61.009019) (xy 34.192954 -61.015119)
			(xy 34.13722 -61.013082) (xy 34.082377 -61.002952) (xy 34.029593 -60.984945) (xy 33.979993 -60.959444)
			(xy 33.934635 -60.926993) (xy 33.894486 -60.888284) (xy 33.8604 -60.844141) (xy 33.833104 -60.795506)
			(xy 33.813181 -60.743415) (xy 33.801055 -60.688978) (xy 33.796984 -60.633356) (xy 27.275028 -60.633356)
			(xy 27.275028 -61.487812) (xy 32.30448 -61.487812) (xy 32.308551 -61.43219) (xy 32.320677 -61.377753)
			(xy 32.3406 -61.325662) (xy 32.367896 -61.277027) (xy 32.401982 -61.232884) (xy 32.442131 -61.194175)
			(xy 32.487489 -61.161724) (xy 32.537089 -61.136223) (xy 32.589873 -61.118216) (xy 32.644716 -61.108086)
			(xy 32.70045 -61.106049) (xy 32.755887 -61.112149) (xy 32.809844 -61.126255) (xy 32.861173 -61.148067)
			(xy 32.908779 -61.177121) (xy 32.951647 -61.212796) (xy 32.988864 -61.254333) (xy 33.019637 -61.300846)
			(xy 33.043309 -61.351343) (xy 33.059377 -61.40475) (xy 33.067497 -61.459926) (xy 33.068006 -61.487812)
			(xy 33.067497 -61.515698) (xy 33.059377 -61.570874) (xy 33.043309 -61.624281) (xy 33.019637 -61.674778)
			(xy 32.988864 -61.721291) (xy 32.951647 -61.762828) (xy 32.908779 -61.798503) (xy 32.861173 -61.827557)
			(xy 32.809844 -61.849369) (xy 32.755887 -61.863475) (xy 32.70045 -61.869575) (xy 32.644716 -61.867538)
			(xy 32.589873 -61.857408) (xy 32.537089 -61.839401) (xy 32.487489 -61.8139) (xy 32.442131 -61.781449)
			(xy 32.401982 -61.74274) (xy 32.367896 -61.698597) (xy 32.3406 -61.649962) (xy 32.320677 -61.597871)
			(xy 32.308551 -61.543434) (xy 32.30448 -61.487812) (xy 27.275028 -61.487812) (xy 27.275028 -62.121034)
			(xy 30.242254 -62.121034) (xy 30.246325 -62.065412) (xy 30.258451 -62.010975) (xy 30.278374 -61.958884)
			(xy 30.30567 -61.910249) (xy 30.339756 -61.866106) (xy 30.379905 -61.827397) (xy 30.425263 -61.794946)
			(xy 30.474863 -61.769445) (xy 30.527647 -61.751438) (xy 30.58249 -61.741308) (xy 30.638224 -61.739271)
			(xy 30.693661 -61.745371) (xy 30.747618 -61.759477) (xy 30.798947 -61.781289) (xy 30.846553 -61.810343)
			(xy 30.889421 -61.846018) (xy 30.926638 -61.887555) (xy 30.957411 -61.934068) (xy 30.981083 -61.984565)
			(xy 30.997151 -62.037972) (xy 31.005271 -62.093148) (xy 31.00578 -62.121034) (xy 31.005271 -62.14892)
			(xy 30.997151 -62.204096) (xy 30.981083 -62.257503) (xy 30.957411 -62.308) (xy 30.926638 -62.354513)
			(xy 30.889421 -62.39605) (xy 30.846553 -62.431725) (xy 30.798947 -62.460779) (xy 30.747618 -62.482591)
			(xy 30.693661 -62.496697) (xy 30.638224 -62.502797) (xy 30.58249 -62.50076) (xy 30.527647 -62.49063)
			(xy 30.474863 -62.472623) (xy 30.425263 -62.447122) (xy 30.379905 -62.414671) (xy 30.339756 -62.375962)
			(xy 30.30567 -62.331819) (xy 30.278374 -62.283184) (xy 30.258451 -62.231093) (xy 30.246325 -62.176656)
			(xy 30.242254 -62.121034) (xy 27.275028 -62.121034) (xy 27.275028 -63.086234) (xy 27.387548 -63.086234)
			(xy 27.391619 -63.030612) (xy 27.403745 -62.976175) (xy 27.423668 -62.924084) (xy 27.450964 -62.875449)
			(xy 27.48505 -62.831306) (xy 27.525199 -62.792597) (xy 27.570557 -62.760146) (xy 27.620157 -62.734645)
			(xy 27.672941 -62.716638) (xy 27.727784 -62.706508) (xy 27.783518 -62.704471) (xy 27.797377 -62.705996)
			(xy 33.665158 -62.705996) (xy 33.669229 -62.650374) (xy 33.681355 -62.595937) (xy 33.701278 -62.543846)
			(xy 33.728574 -62.495211) (xy 33.76266 -62.451068) (xy 33.802809 -62.412359) (xy 33.848167 -62.379908)
			(xy 33.897767 -62.354407) (xy 33.950551 -62.3364) (xy 34.005394 -62.32627) (xy 34.061128 -62.324233)
			(xy 34.116565 -62.330333) (xy 34.170522 -62.344439) (xy 34.221851 -62.366251) (xy 34.269457 -62.395305)
			(xy 34.312325 -62.43098) (xy 34.349542 -62.472517) (xy 34.380315 -62.51903) (xy 34.403987 -62.569527)
			(xy 34.420055 -62.622934) (xy 34.428175 -62.67811) (xy 34.428684 -62.705996) (xy 34.428175 -62.733882)
			(xy 34.420055 -62.789058) (xy 34.403987 -62.842465) (xy 34.380315 -62.892962) (xy 34.349542 -62.939475)
			(xy 34.312325 -62.981012) (xy 34.269457 -63.016687) (xy 34.221851 -63.045741) (xy 34.170522 -63.067553)
			(xy 34.116565 -63.081659) (xy 34.061128 -63.087759) (xy 34.005394 -63.085722) (xy 33.950551 -63.075592)
			(xy 33.897767 -63.057585) (xy 33.848167 -63.032084) (xy 33.802809 -62.999633) (xy 33.76266 -62.960924)
			(xy 33.728574 -62.916781) (xy 33.701278 -62.868146) (xy 33.681355 -62.816055) (xy 33.669229 -62.761618)
			(xy 33.665158 -62.705996) (xy 27.797377 -62.705996) (xy 27.838955 -62.710571) (xy 27.892912 -62.724677)
			(xy 27.944241 -62.746489) (xy 27.991847 -62.775543) (xy 28.034715 -62.811218) (xy 28.071932 -62.852755)
			(xy 28.102705 -62.899268) (xy 28.126377 -62.949765) (xy 28.142445 -63.003172) (xy 28.150565 -63.058348)
			(xy 28.151074 -63.086234) (xy 28.150565 -63.11412) (xy 28.142445 -63.169296) (xy 28.126377 -63.222703)
			(xy 28.102705 -63.2732) (xy 28.102552 -63.273432) (xy 29.576774 -63.273432) (xy 29.580845 -63.21781)
			(xy 29.592971 -63.163373) (xy 29.612894 -63.111282) (xy 29.64019 -63.062647) (xy 29.674276 -63.018504)
			(xy 29.714425 -62.979795) (xy 29.759783 -62.947344) (xy 29.809383 -62.921843) (xy 29.862167 -62.903836)
			(xy 29.91701 -62.893706) (xy 29.972744 -62.891669) (xy 30.028181 -62.897769) (xy 30.082138 -62.911875)
			(xy 30.133467 -62.933687) (xy 30.181073 -62.962741) (xy 30.223941 -62.998416) (xy 30.261158 -63.039953)
			(xy 30.291931 -63.086466) (xy 30.315603 -63.136963) (xy 30.331671 -63.19037) (xy 30.339791 -63.245546)
			(xy 30.3403 -63.273432) (xy 30.339791 -63.301318) (xy 30.331671 -63.356494) (xy 30.315603 -63.409901)
			(xy 30.291931 -63.460398) (xy 30.261158 -63.506911) (xy 30.223941 -63.548448) (xy 30.181073 -63.584123)
			(xy 30.133467 -63.613177) (xy 30.082138 -63.634989) (xy 30.028181 -63.649095) (xy 29.972744 -63.655195)
			(xy 29.91701 -63.653158) (xy 29.862167 -63.643028) (xy 29.809383 -63.625021) (xy 29.759783 -63.59952)
			(xy 29.714425 -63.567069) (xy 29.674276 -63.52836) (xy 29.64019 -63.484217) (xy 29.612894 -63.435582)
			(xy 29.592971 -63.383491) (xy 29.580845 -63.329054) (xy 29.576774 -63.273432) (xy 28.102552 -63.273432)
			(xy 28.071932 -63.319713) (xy 28.034715 -63.36125) (xy 27.991847 -63.396925) (xy 27.944241 -63.425979)
			(xy 27.892912 -63.447791) (xy 27.838955 -63.461897) (xy 27.783518 -63.467997) (xy 27.727784 -63.46596)
			(xy 27.672941 -63.45583) (xy 27.620157 -63.437823) (xy 27.570557 -63.412322) (xy 27.525199 -63.379871)
			(xy 27.48505 -63.341162) (xy 27.450964 -63.297019) (xy 27.423668 -63.248384) (xy 27.403745 -63.196293)
			(xy 27.391619 -63.141856) (xy 27.387548 -63.086234) (xy 27.275028 -63.086234) (xy 27.275028 -65.124076)
			(xy 32.107376 -65.124076) (xy 32.111447 -65.068454) (xy 32.123573 -65.014017) (xy 32.143496 -64.961926)
			(xy 32.170792 -64.913291) (xy 32.204878 -64.869148) (xy 32.245027 -64.830439) (xy 32.290385 -64.797988)
			(xy 32.339985 -64.772487) (xy 32.392769 -64.75448) (xy 32.447612 -64.74435) (xy 32.503346 -64.742313)
			(xy 32.558783 -64.748413) (xy 32.61274 -64.762519) (xy 32.664069 -64.784331) (xy 32.711675 -64.813385)
			(xy 32.754543 -64.84906) (xy 32.79176 -64.890597) (xy 32.822533 -64.93711) (xy 32.846205 -64.987607)
			(xy 32.862273 -65.041014) (xy 32.870393 -65.09619) (xy 32.870902 -65.124076) (xy 32.870393 -65.151962)
			(xy 32.862273 -65.207138) (xy 32.846205 -65.260545) (xy 32.822533 -65.311042) (xy 32.79176 -65.357555)
			(xy 32.754543 -65.399092) (xy 32.711675 -65.434767) (xy 32.664069 -65.463821) (xy 32.61274 -65.485633)
			(xy 32.558783 -65.499739) (xy 32.503346 -65.505839) (xy 32.447612 -65.503802) (xy 32.392769 -65.493672)
			(xy 32.339985 -65.475665) (xy 32.290385 -65.450164) (xy 32.245027 -65.417713) (xy 32.204878 -65.379004)
			(xy 32.170792 -65.334861) (xy 32.143496 -65.286226) (xy 32.123573 -65.234135) (xy 32.111447 -65.179698)
			(xy 32.107376 -65.124076) (xy 27.275028 -65.124076) (xy 27.275028 -66.076576) (xy 27.276044 -66.086228)
			(xy 27.277669 -66.093473) (xy 27.284507 -66.106646) (xy 27.289506 -66.112136) (xy 28.545536 -67.368166)
			(xy 28.563571 -67.386935) (xy 28.594157 -67.429051) (xy 28.617789 -67.475427) (xy 28.633887 -67.524925)
			(xy 28.642055 -67.576329) (xy 28.642564 -67.602354) (xy 28.642564 -93.402912) (xy 28.642962 -93.412433)
			(xy 28.64992 -93.430159) (xy 28.662872 -93.444118) (xy 28.671266 -93.448632)
		)
		(stroke
			(width 0)
			(type solid)
		)
		(fill yes)
		(layer "In5.Cu")
		(net "GND")
	)
	(gr_poly
		(pts
			(xy 371.109748 -164.5031) (xy 371.110256 -164.5031) (xy 371.117773 -164.501496) (xy 371.131457 -164.494515)
			(xy 371.13718 -164.489384) (xy 371.734842 -163.891722) (xy 371.739831 -163.886224) (xy 371.746682 -163.873059)
			(xy 371.748304 -163.865814) (xy 371.74932 -163.856162) (xy 371.74932 -152.733248) (xy 371.749177 -152.727665)
			(xy 371.746748 -152.716767) (xy 371.744494 -152.711658) (xy 371.718078 -152.700736) (xy 371.708634 -152.697189)
			(xy 371.688477 -152.697086) (xy 371.669856 -152.704806) (xy 371.662452 -152.711658) (xy 371.047518 -153.326846)
			(xy 371.046502 -153.327862) (xy 371.026845 -153.347975) (xy 370.982028 -153.381943) (xy 370.932128 -153.407873)
			(xy 370.905532 -153.417016) (xy 370.904008 -153.417524) (xy 370.888514 -153.43378) (xy 370.866924 -153.50617)
			(xy 370.865384 -153.511947) (xy 370.864749 -153.523882) (xy 370.865654 -153.529792) (xy 370.867686 -153.541476)
			(xy 370.875306 -153.551382) (xy 370.89364 -153.576458) (xy 370.922775 -153.631316) (xy 370.942636 -153.69017)
			(xy 370.952697 -153.751465) (xy 370.953284 -153.782522) (xy 370.952798 -153.809773) (xy 370.945042 -153.863721)
			(xy 370.929687 -153.916016) (xy 370.907045 -153.965593) (xy 370.877579 -154.011443) (xy 370.841888 -154.052634)
			(xy 370.800697 -154.088325) (xy 370.754847 -154.117791) (xy 370.70527 -154.140433) (xy 370.652975 -154.155788)
			(xy 370.599027 -154.163544) (xy 370.544525 -154.163544) (xy 370.490577 -154.155788) (xy 370.438282 -154.140433)
			(xy 370.388705 -154.117791) (xy 370.342855 -154.088325) (xy 370.301664 -154.052634) (xy 370.265973 -154.011443)
			(xy 370.236507 -153.965593) (xy 370.213865 -153.916016) (xy 370.19851 -153.863721) (xy 370.190754 -153.809773)
			(xy 370.190268 -153.782522) (xy 370.190768 -153.754433) (xy 370.199013 -153.698865) (xy 370.215328 -153.645109)
			(xy 370.239359 -153.594331) (xy 370.25453 -153.570686) (xy 370.254784 -153.570432) (xy 370.256054 -153.5684)
			(xy 370.257324 -153.56586) (xy 370.259784 -153.560985) (xy 370.262739 -153.550475) (xy 370.263166 -153.545032)
			(xy 370.263928 -153.530808) (xy 370.214398 -153.43759) (xy 370.213636 -153.43632) (xy 370.211096 -153.432764)
			(xy 368.90071 -153.432764) (xy 368.897154 -153.437844) (xy 368.85372 -153.519378) (xy 368.850925 -153.525401)
			(xy 368.848217 -153.538395) (xy 368.848386 -153.545032) (xy 368.849148 -153.558748) (xy 368.856768 -153.570432)
			(xy 368.857022 -153.570686) (xy 368.872202 -153.594324) (xy 368.896209 -153.645112) (xy 368.912516 -153.698868)
			(xy 368.920771 -153.754434) (xy 368.921284 -153.782522) (xy 368.920798 -153.809773) (xy 368.913042 -153.863721)
			(xy 368.897687 -153.916016) (xy 368.875045 -153.965593) (xy 368.845579 -154.011443) (xy 368.809888 -154.052634)
			(xy 368.768697 -154.088325) (xy 368.722847 -154.117791) (xy 368.67327 -154.140433) (xy 368.620975 -154.155788)
			(xy 368.567027 -154.163544) (xy 368.512525 -154.163544) (xy 368.458577 -154.155788) (xy 368.406282 -154.140433)
			(xy 368.356705 -154.117791) (xy 368.310855 -154.088325) (xy 368.269664 -154.052634) (xy 368.233973 -154.011443)
			(xy 368.204507 -153.965593) (xy 368.181865 -153.916016) (xy 368.16651 -153.863721) (xy 368.158754 -153.809773)
			(xy 368.158268 -153.782522) (xy 368.158768 -153.754433) (xy 368.167013 -153.698865) (xy 368.183328 -153.645109)
			(xy 368.207359 -153.594331) (xy 368.22253 -153.570686) (xy 368.222784 -153.570432) (xy 368.224054 -153.5684)
			(xy 368.225324 -153.56586) (xy 368.227784 -153.560985) (xy 368.230739 -153.550475) (xy 368.231166 -153.545032)
			(xy 368.231928 -153.530808) (xy 368.182398 -153.43759) (xy 368.181636 -153.43632) (xy 368.179096 -153.432764)
			(xy 366.050322 -153.432764) (xy 366.04026 -153.433203) (xy 366.021682 -153.440945) (xy 366.014254 -153.44775)
			(xy 365.8235 -153.638504) (xy 365.8235 -153.643584) (xy 365.835329 -153.665177) (xy 365.853947 -153.710758)
			(xy 365.866542 -153.758356) (xy 365.872905 -153.80718) (xy 365.873284 -153.831798) (xy 365.872821 -153.85905)
			(xy 365.865064 -153.913) (xy 365.849708 -153.965297) (xy 365.827065 -154.014876) (xy 365.797597 -154.060727)
			(xy 365.761903 -154.101918) (xy 365.72071 -154.13761) (xy 365.674856 -154.167076) (xy 365.625276 -154.189716)
			(xy 365.572979 -154.205069) (xy 365.519028 -154.212822) (xy 365.491776 -154.213306) (xy 365.491268 -154.213306)
			(xy 365.462131 -154.212737) (xy 365.404539 -154.203842) (xy 365.348969 -154.186294) (xy 365.296714 -154.160501)
			(xy 365.248987 -154.127063) (xy 365.206899 -154.086758) (xy 365.188754 -154.063954) (xy 365.182404 -154.055572)
			(xy 365.155226 -154.040332) (xy 365.150361 -154.037817) (xy 365.139851 -154.034745) (xy 365.134398 -154.034236)
			(xy 365.082074 -154.029918) (xy 365.071044 -154.029582) (xy 365.050373 -154.037237) (xy 365.042196 -154.04465)
			(xy 364.89005 -154.196796) (xy 364.866495 -154.219742) (xy 364.815096 -154.260762) (xy 364.759425 -154.295765)
			(xy 364.700182 -154.324311) (xy 364.638115 -154.346041) (xy 364.574004 -154.36068) (xy 364.508657 -154.368044)
			(xy 364.475776 -154.3685) (xy 364.439719 -154.367951) (xy 364.368148 -154.359108) (xy 364.298204 -154.341546)
			(xy 364.230946 -154.315531) (xy 364.167389 -154.281457) (xy 364.108496 -154.239838) (xy 364.055157 -154.191304)
			(xy 364.031276 -154.164284) (xy 364.024418 -154.156156) (xy 364.005114 -154.147012) (xy 363.938058 -154.144726)
			(xy 363.934502 -154.144726) (xy 363.925612 -154.145234) (xy 363.87405 -154.196796) (xy 363.850495 -154.219742)
			(xy 363.799096 -154.260762) (xy 363.743425 -154.295765) (xy 363.684182 -154.324311) (xy 363.622115 -154.346041)
			(xy 363.558004 -154.36068) (xy 363.492657 -154.368044) (xy 363.459776 -154.3685) (xy 363.424369 -154.367985)
			(xy 363.354072 -154.359444) (xy 363.285317 -154.34249) (xy 363.219109 -154.317369) (xy 363.156411 -154.284449)
			(xy 363.098141 -154.24421) (xy 363.045147 -154.197239) (xy 362.998203 -154.144221) (xy 362.957994 -154.08593)
			(xy 362.925107 -154.023216) (xy 362.90002 -153.956994) (xy 362.883102 -153.888231) (xy 362.874597 -153.817929)
			(xy 362.874052 -153.782522) (xy 362.874478 -153.749647) (xy 362.881807 -153.684308) (xy 362.896409 -153.620202)
			(xy 362.918101 -153.558134) (xy 362.946608 -153.498887) (xy 362.981573 -153.443206) (xy 363.022555 -153.391792)
			(xy 363.045502 -153.368248) (xy 364.036864 -152.376886) (xy 364.060428 -152.353988) (xy 364.111811 -152.313033)
			(xy 364.167453 -152.278085) (xy 364.226657 -152.249582) (xy 364.288677 -152.227882) (xy 364.352737 -152.213258)
			(xy 364.41803 -152.205893) (xy 364.450884 -152.205436) (xy 364.524798 -152.205436) (xy 364.534867 -152.205012)
			(xy 364.553466 -152.197291) (xy 364.560866 -152.19045) (xy 364.627668 -152.123394) (xy 364.634348 -152.115983)
			(xy 364.641938 -152.097552) (xy 364.641933 -152.07762) (xy 364.634332 -152.059194) (xy 364.627668 -152.051766)
			(xy 364.617762 -152.04186) (xy 364.591346 -152.034748) (xy 364.583218 -152.037034) (xy 364.557009 -152.044248)
			(xy 364.503209 -152.052031) (xy 364.47603 -152.052528) (xy 364.475776 -152.052528) (xy 364.455202 -152.05202)
			(xy 364.452408 -152.051766) (xy 364.423686 -152.049475) (xy 364.367363 -152.037337) (xy 364.313504 -152.01687)
			(xy 364.263335 -151.988538) (xy 364.217996 -151.952985) (xy 364.178517 -151.91102) (xy 364.145796 -151.863597)
			(xy 364.120576 -151.811793) (xy 364.103431 -151.756787) (xy 364.094751 -151.699828) (xy 364.094268 -151.67102)
			(xy 364.094754 -151.643769) (xy 364.10251 -151.589821) (xy 364.117865 -151.537526) (xy 364.140507 -151.487949)
			(xy 364.169973 -151.442099) (xy 364.205664 -151.400908) (xy 364.246855 -151.365217) (xy 364.292705 -151.335751)
			(xy 364.342282 -151.313109) (xy 364.394577 -151.297754) (xy 364.448525 -151.289998) (xy 364.503027 -151.289998)
			(xy 364.556975 -151.297754) (xy 364.60927 -151.313109) (xy 364.658847 -151.335751) (xy 364.704697 -151.365217)
			(xy 364.745888 -151.400908) (xy 364.781579 -151.442099) (xy 364.811045 -151.487949) (xy 364.833687 -151.537526)
			(xy 364.849042 -151.589821) (xy 364.856798 -151.643769) (xy 364.857284 -151.67102) (xy 364.85685 -151.696937)
			(xy 364.849838 -151.748295) (xy 364.843314 -151.773382) (xy 364.843314 -151.773636) (xy 364.841279 -151.782334)
			(xy 364.842741 -151.800127) (xy 364.850218 -151.816339) (xy 364.856268 -151.822912) (xy 364.863634 -151.829752)
			(xy 364.882167 -151.837494) (xy 364.902251 -151.837494) (xy 364.920784 -151.829752) (xy 364.92815 -151.822912)
			(xy 364.98403 -151.767032) (xy 365.008322 -151.743449) (xy 365.061411 -151.701429) (xy 365.089948 -151.683212)
			(xy 365.09921 -151.676805) (xy 365.111484 -151.657956) (xy 365.11357 -151.64689) (xy 365.117645 -151.619721)
			(xy 365.132583 -151.566853) (xy 365.15495 -151.516675) (xy 365.184283 -151.470224) (xy 365.219975 -151.42846)
			(xy 365.261288 -151.392248) (xy 365.307368 -151.362335) (xy 365.357262 -151.339341) (xy 365.409938 -151.323741)
			(xy 365.464307 -151.315858) (xy 365.491776 -151.31542) (xy 365.520665 -151.315957) (xy 365.57778 -151.324677)
			(xy 365.632929 -151.341906) (xy 365.684851 -151.36725) (xy 365.73236 -151.40013) (xy 365.77437 -151.439795)
			(xy 365.809923 -151.485339) (xy 365.838204 -151.535721) (xy 365.8489 -151.562562) (xy 365.854234 -151.577294)
			(xy 365.880396 -151.595328) (xy 366.284002 -151.595328) (xy 366.295761 -151.594741) (xy 366.316826 -151.584285)
			(xy 366.324388 -151.575262) (xy 366.343438 -151.55037) (xy 366.348971 -151.541792) (xy 366.353411 -151.521883)
			(xy 366.352074 -151.511762) (xy 366.350804 -151.507444) (xy 366.344527 -151.482902) (xy 366.337779 -151.432696)
			(xy 366.337342 -151.407368) (xy 366.337342 -151.406606) (xy 366.337828 -151.379355) (xy 366.345584 -151.325407)
			(xy 366.360939 -151.273112) (xy 366.383581 -151.223535) (xy 366.413047 -151.177685) (xy 366.448738 -151.136494)
			(xy 366.489929 -151.100803) (xy 366.535779 -151.071337) (xy 366.585356 -151.048695) (xy 366.637651 -151.03334)
			(xy 366.691599 -151.025584) (xy 366.746101 -151.025584) (xy 366.800049 -151.03334) (xy 366.852344 -151.048695)
			(xy 366.901921 -151.071337) (xy 366.947771 -151.100803) (xy 366.988962 -151.136494) (xy 367.024653 -151.177685)
			(xy 367.054119 -151.223535) (xy 367.076761 -151.273112) (xy 367.092116 -151.325407) (xy 367.099872 -151.379355)
			(xy 367.100358 -151.406606) (xy 367.100358 -151.407368) (xy 367.099907 -151.432695) (xy 367.093151 -151.482898)
			(xy 367.086896 -151.507444) (xy 367.085626 -151.511762) (xy 367.084238 -151.521883) (xy 367.088701 -151.5418)
			(xy 367.094262 -151.55037) (xy 367.113312 -151.575262) (xy 367.120905 -151.58425) (xy 367.141949 -151.594716)
			(xy 367.153698 -151.595328) (xy 367.633758 -151.595328) (xy 367.662714 -151.568658) (xy 367.663984 -151.555704)
			(xy 367.666368 -151.528552) (xy 367.67791 -151.475282) (xy 367.696917 -151.424198) (xy 367.723001 -151.376339)
			(xy 367.755631 -151.33268) (xy 367.794144 -151.294109) (xy 367.837753 -151.261413) (xy 367.885573 -151.235257)
			(xy 367.936629 -151.216173) (xy 367.98988 -151.20455) (xy 368.044245 -151.200625) (xy 368.098614 -151.204477)
			(xy 368.151881 -151.216029) (xy 368.202962 -151.235044) (xy 368.250817 -151.261137) (xy 368.29447 -151.293775)
			(xy 368.333034 -151.332294) (xy 368.365723 -151.375909) (xy 368.391871 -151.423733) (xy 368.410946 -151.474792)
			(xy 368.42256 -151.528046) (xy 368.424968 -151.555196) (xy 368.424968 -151.556212) (xy 368.426238 -151.568658)
			(xy 368.455194 -151.595328) (xy 369.117626 -151.595328) (xy 369.127073 -151.594843) (xy 369.144671 -151.587947)
			(xy 369.151916 -151.581866) (xy 369.16106 -151.573484) (xy 369.166809 -151.567162) (xy 369.174096 -151.551718)
			(xy 369.175284 -151.543258) (xy 369.175284 -151.541734) (xy 369.177853 -151.513242) (xy 369.190444 -151.457439)
			(xy 369.211226 -151.404141) (xy 369.239733 -151.354544) (xy 369.275326 -151.309759) (xy 369.317206 -151.27079)
			(xy 369.364435 -151.238511) (xy 369.415954 -151.213646) (xy 369.470609 -151.196751) (xy 369.527173 -151.188206)
			(xy 369.555776 -151.187658) (xy 369.55603 -151.187658) (xy 369.581353 -151.188091) (xy 369.631551 -151.194823)
			(xy 369.680421 -151.208125) (xy 369.727105 -151.227764) (xy 369.770787 -151.253397) (xy 369.79098 -151.268684)
			(xy 369.791234 -151.268938) (xy 369.798793 -151.27432) (xy 369.816503 -151.279809) (xy 369.825778 -151.279606)
			(xy 369.834414 -151.279098) (xy 369.851432 -151.271478) (xy 371.387624 -149.73554) (xy 371.394405 -149.728116)
			(xy 371.40201 -149.70952) (xy 371.402356 -149.699472) (xy 371.402356 -113.383314) (xy 371.402229 -113.377382)
			(xy 371.399536 -113.365829) (xy 371.397022 -113.360454) (xy 371.395114 -113.356917) (xy 371.390393 -113.350413)
			(xy 371.387624 -113.3475) (xy 369.57254 -111.53267) (xy 369.550012 -111.509502) (xy 369.50972 -111.458978)
			(xy 369.475337 -111.40426) (xy 369.447297 -111.346037) (xy 369.425953 -111.28504) (xy 369.411572 -111.222037)
			(xy 369.404335 -111.15782) (xy 369.403884 -111.125508) (xy 369.403884 -110.325662) (xy 369.403718 -110.319652)
			(xy 369.400896 -110.307969) (xy 369.398296 -110.302548) (xy 369.396454 -110.299075) (xy 369.391858 -110.2927)
			(xy 369.389152 -110.289848) (xy 368.977418 -109.878114) (xy 368.974567 -109.875408) (xy 368.968189 -109.870815)
			(xy 368.964718 -109.86897) (xy 368.95929 -109.866392) (xy 368.94761 -109.863579) (xy 368.941604 -109.863382)
			(xy 361.775502 -109.863382) (xy 361.765431 -109.863804) (xy 361.746824 -109.871516) (xy 361.739434 -109.878368)
			(xy 360.34853 -111.269272) (xy 360.341061 -111.277626) (xy 360.333568 -111.298715) (xy 360.334052 -111.309912)
			(xy 360.34218 -111.398812) (xy 360.35361 -111.41837) (xy 360.363008 -111.42472) (xy 360.384564 -111.440042)
			(xy 360.423638 -111.475683) (xy 360.457414 -111.516378) (xy 360.485246 -111.561349) (xy 360.506599 -111.609733)
			(xy 360.521065 -111.660603) (xy 360.528366 -111.712983) (xy 360.52887 -111.739426) (xy 360.528405 -111.766677)
			(xy 360.520645 -111.820623) (xy 360.505286 -111.872915) (xy 360.482642 -111.92249) (xy 360.453172 -111.968337)
			(xy 360.417478 -112.009523) (xy 360.376286 -112.045211) (xy 360.330433 -112.074672) (xy 360.280855 -112.097308)
			(xy 360.22856 -112.112658) (xy 360.174613 -112.120409) (xy 360.147362 -112.120934) (xy 360.120918 -112.12048)
			(xy 360.068539 -112.113169) (xy 360.017672 -112.098691) (xy 359.969293 -112.077324) (xy 359.92433 -112.049479)
			(xy 359.883645 -112.015689) (xy 359.848018 -111.976602) (xy 359.832656 -111.955072) (xy 359.826306 -111.945674)
			(xy 359.806748 -111.934244) (xy 359.717848 -111.926116) (xy 359.706659 -111.925642) (xy 359.685595 -111.933169)
			(xy 359.677208 -111.940594) (xy 359.077739 -112.540034) (xy 362.1057 -112.540034) (xy 362.109771 -112.484412)
			(xy 362.121897 -112.429975) (xy 362.14182 -112.377884) (xy 362.169116 -112.329249) (xy 362.203202 -112.285106)
			(xy 362.243351 -112.246397) (xy 362.288709 -112.213946) (xy 362.338309 -112.188445) (xy 362.391093 -112.170438)
			(xy 362.445936 -112.160308) (xy 362.50167 -112.158271) (xy 362.557107 -112.164371) (xy 362.611064 -112.178477)
			(xy 362.662393 -112.200289) (xy 362.709999 -112.229343) (xy 362.752867 -112.265018) (xy 362.790084 -112.306555)
			(xy 362.820857 -112.353068) (xy 362.844529 -112.403565) (xy 362.849823 -112.421162) (xy 364.10722 -112.421162)
			(xy 364.111291 -112.36554) (xy 364.123417 -112.311103) (xy 364.14334 -112.259012) (xy 364.170636 -112.210377)
			(xy 364.204722 -112.166234) (xy 364.244871 -112.127525) (xy 364.290229 -112.095074) (xy 364.339829 -112.069573)
			(xy 364.392613 -112.051566) (xy 364.447456 -112.041436) (xy 364.50319 -112.039399) (xy 364.558627 -112.045499)
			(xy 364.612584 -112.059605) (xy 364.663913 -112.081417) (xy 364.711519 -112.110471) (xy 364.754387 -112.146146)
			(xy 364.791604 -112.187683) (xy 364.822377 -112.234196) (xy 364.846049 -112.284693) (xy 364.862117 -112.3381)
			(xy 364.870237 -112.393276) (xy 364.870746 -112.421162) (xy 364.870237 -112.449048) (xy 364.862117 -112.504224)
			(xy 364.846049 -112.557631) (xy 364.822377 -112.608128) (xy 364.791604 -112.654641) (xy 364.754387 -112.696178)
			(xy 364.711519 -112.731853) (xy 364.663913 -112.760907) (xy 364.612584 -112.782719) (xy 364.558627 -112.796825)
			(xy 364.50319 -112.802925) (xy 364.447456 -112.800888) (xy 364.392613 -112.790758) (xy 364.339829 -112.772751)
			(xy 364.290229 -112.74725) (xy 364.244871 -112.714799) (xy 364.204722 -112.67609) (xy 364.170636 -112.631947)
			(xy 364.14334 -112.583312) (xy 364.123417 -112.531221) (xy 364.111291 -112.476784) (xy 364.10722 -112.421162)
			(xy 362.849823 -112.421162) (xy 362.860597 -112.456972) (xy 362.868717 -112.512148) (xy 362.869226 -112.540034)
			(xy 362.868717 -112.56792) (xy 362.860597 -112.623096) (xy 362.844529 -112.676503) (xy 362.820857 -112.727)
			(xy 362.790084 -112.773513) (xy 362.752867 -112.81505) (xy 362.709999 -112.850725) (xy 362.662393 -112.879779)
			(xy 362.611064 -112.901591) (xy 362.557107 -112.915697) (xy 362.50167 -112.921797) (xy 362.445936 -112.91976)
			(xy 362.391093 -112.90963) (xy 362.338309 -112.891623) (xy 362.288709 -112.866122) (xy 362.243351 -112.833671)
			(xy 362.203202 -112.794962) (xy 362.169116 -112.750819) (xy 362.14182 -112.702184) (xy 362.121897 -112.650093)
			(xy 362.109771 -112.595656) (xy 362.1057 -112.540034) (xy 359.077739 -112.540034) (xy 357.719281 -113.898426)
			(xy 359.753406 -113.898426) (xy 359.757477 -113.842804) (xy 359.769603 -113.788367) (xy 359.789526 -113.736276)
			(xy 359.816822 -113.687641) (xy 359.850908 -113.643498) (xy 359.891057 -113.604789) (xy 359.936415 -113.572338)
			(xy 359.986015 -113.546837) (xy 360.038799 -113.52883) (xy 360.093642 -113.5187) (xy 360.149376 -113.516663)
			(xy 360.204813 -113.522763) (xy 360.25877 -113.536869) (xy 360.310099 -113.558681) (xy 360.357705 -113.587735)
			(xy 360.400573 -113.62341) (xy 360.43779 -113.664947) (xy 360.468563 -113.71146) (xy 360.492235 -113.761957)
			(xy 360.508303 -113.815364) (xy 360.516423 -113.87054) (xy 360.516932 -113.898426) (xy 360.516423 -113.926312)
			(xy 360.508303 -113.981488) (xy 360.492235 -114.034895) (xy 360.468563 -114.085392) (xy 360.43779 -114.131905)
			(xy 360.400573 -114.173442) (xy 360.357705 -114.209117) (xy 360.310099 -114.238171) (xy 360.25877 -114.259983)
			(xy 360.204813 -114.274089) (xy 360.149376 -114.280189) (xy 360.093642 -114.278152) (xy 360.038799 -114.268022)
			(xy 359.986015 -114.250015) (xy 359.936415 -114.224514) (xy 359.891057 -114.192063) (xy 359.850908 -114.153354)
			(xy 359.816822 -114.109211) (xy 359.789526 -114.060576) (xy 359.769603 -114.008485) (xy 359.757477 -113.954048)
			(xy 359.753406 -113.898426) (xy 357.719281 -113.898426) (xy 354.634047 -116.98351) (xy 356.001572 -116.98351)
			(xy 356.005643 -116.927888) (xy 356.017769 -116.873451) (xy 356.037692 -116.82136) (xy 356.064988 -116.772725)
			(xy 356.099074 -116.728582) (xy 356.139223 -116.689873) (xy 356.184581 -116.657422) (xy 356.234181 -116.631921)
			(xy 356.286965 -116.613914) (xy 356.341808 -116.603784) (xy 356.397542 -116.601747) (xy 356.452979 -116.607847)
			(xy 356.506936 -116.621953) (xy 356.558265 -116.643765) (xy 356.604703 -116.672106) (xy 361.16895 -116.672106)
			(xy 361.169407 -116.644735) (xy 361.177225 -116.590555) (xy 361.192716 -116.538052) (xy 361.21556 -116.488305)
			(xy 361.245287 -116.442339) (xy 361.26293 -116.421408) (xy 361.263184 -116.421154) (xy 361.268752 -116.414055)
			(xy 361.27501 -116.397148) (xy 361.275376 -116.388134) (xy 361.275376 -116.321078) (xy 361.275035 -116.312059)
			(xy 361.268777 -116.295142) (xy 361.263184 -116.288058) (xy 361.26293 -116.288058) (xy 361.26293 -116.287804)
			(xy 361.245295 -116.266867) (xy 361.21557 -116.2209) (xy 361.192724 -116.171154) (xy 361.177227 -116.118653)
			(xy 361.169398 -116.064475) (xy 361.169397 -116.009734) (xy 361.177225 -115.955556) (xy 361.192721 -115.903054)
			(xy 361.215565 -115.853308) (xy 361.24529 -115.807341) (xy 361.26293 -115.786408) (xy 361.263184 -115.786154)
			(xy 361.268752 -115.779055) (xy 361.27501 -115.762148) (xy 361.275376 -115.753134) (xy 361.275376 -115.686078)
			(xy 361.275035 -115.677059) (xy 361.268777 -115.660142) (xy 361.263184 -115.653058) (xy 361.26293 -115.653058)
			(xy 361.26293 -115.652804) (xy 361.245284 -115.631877) (xy 361.215572 -115.585904) (xy 361.192737 -115.536155)
			(xy 361.177248 -115.483653) (xy 361.169422 -115.429476) (xy 361.16895 -115.402106) (xy 361.169483 -115.374857)
			(xy 361.177238 -115.320913) (xy 361.19259 -115.268622) (xy 361.215227 -115.219047) (xy 361.244689 -115.173199)
			(xy 361.280376 -115.13201) (xy 361.32156 -115.096318) (xy 361.367405 -115.06685) (xy 361.416977 -115.044207)
			(xy 361.469266 -115.028848) (xy 361.523209 -115.021087) (xy 361.550458 -115.020598) (xy 361.577827 -115.021089)
			(xy 361.632005 -115.028901) (xy 361.684508 -115.044384) (xy 361.734255 -115.06722) (xy 361.780223 -115.096939)
			(xy 361.801156 -115.114578) (xy 361.80141 -115.114832) (xy 361.808487 -115.120432) (xy 361.825411 -115.12667)
			(xy 361.83443 -115.127024) (xy 361.901486 -115.127024) (xy 361.910502 -115.126655) (xy 361.927418 -115.120415)
			(xy 361.934506 -115.114832) (xy 361.934506 -115.114578) (xy 361.93476 -115.114578) (xy 361.955694 -115.096941)
			(xy 362.001666 -115.067229) (xy 362.051413 -115.044393) (xy 362.103914 -115.028902) (xy 362.158089 -115.021073)
			(xy 362.185458 -115.020598) (xy 362.21271 -115.021094) (xy 362.26666 -115.028846) (xy 362.318958 -115.044197)
			(xy 362.368538 -115.066835) (xy 362.414392 -115.096299) (xy 362.455585 -115.131989) (xy 362.491279 -115.173179)
			(xy 362.520748 -115.21903) (xy 362.543391 -115.268608) (xy 362.558747 -115.320905) (xy 362.566503 -115.374854)
			(xy 362.566966 -115.402106) (xy 362.566512 -115.429477) (xy 362.558692 -115.483657) (xy 362.543201 -115.53616)
			(xy 362.520356 -115.585907) (xy 362.490629 -115.631873) (xy 362.472986 -115.652804) (xy 362.472732 -115.653058)
			(xy 362.467149 -115.660147) (xy 362.460902 -115.677062) (xy 362.46054 -115.686078) (xy 362.46054 -115.753134)
			(xy 362.460872 -115.762154) (xy 362.467136 -115.779071) (xy 362.472732 -115.786154) (xy 362.472986 -115.786154)
			(xy 362.472986 -115.786408) (xy 362.490632 -115.807336) (xy 362.520356 -115.853305) (xy 362.5432 -115.903052)
			(xy 362.558695 -115.955555) (xy 362.566523 -116.009734) (xy 362.566522 -116.064475) (xy 362.558693 -116.118654)
			(xy 362.543197 -116.171156) (xy 362.520351 -116.220903) (xy 362.490627 -116.266871) (xy 362.472986 -116.287804)
			(xy 362.472732 -116.288058) (xy 362.467149 -116.295147) (xy 362.460902 -116.312062) (xy 362.46054 -116.321078)
			(xy 362.46054 -116.388134) (xy 362.460872 -116.397154) (xy 362.467136 -116.414071) (xy 362.472732 -116.421154)
			(xy 362.472986 -116.421154) (xy 362.472986 -116.421408) (xy 362.49064 -116.442328) (xy 362.52035 -116.488304)
			(xy 362.543183 -116.538054) (xy 362.558671 -116.590558) (xy 362.566495 -116.644736) (xy 362.566966 -116.672106)
			(xy 362.566828 -116.680234) (xy 363.451138 -116.680234) (xy 363.455209 -116.624612) (xy 363.467335 -116.570175)
			(xy 363.487258 -116.518084) (xy 363.514554 -116.469449) (xy 363.54864 -116.425306) (xy 363.588789 -116.386597)
			(xy 363.634147 -116.354146) (xy 363.683747 -116.328645) (xy 363.736531 -116.310638) (xy 363.791374 -116.300508)
			(xy 363.847108 -116.298471) (xy 363.902545 -116.304571) (xy 363.956502 -116.318677) (xy 364.007831 -116.340489)
			(xy 364.055437 -116.369543) (xy 364.098305 -116.405218) (xy 364.135522 -116.446755) (xy 364.166295 -116.493268)
			(xy 364.189967 -116.543765) (xy 364.206035 -116.597172) (xy 364.214155 -116.652348) (xy 364.214664 -116.680234)
			(xy 364.214155 -116.70812) (xy 364.206035 -116.763296) (xy 364.189967 -116.816703) (xy 364.166295 -116.8672)
			(xy 364.135522 -116.913713) (xy 364.098305 -116.95525) (xy 364.055437 -116.990925) (xy 364.007831 -117.019979)
			(xy 363.956502 -117.041791) (xy 363.902545 -117.055897) (xy 363.847108 -117.061997) (xy 363.791374 -117.05996)
			(xy 363.736531 -117.04983) (xy 363.683747 -117.031823) (xy 363.634147 -117.006322) (xy 363.588789 -116.973871)
			(xy 363.54864 -116.935162) (xy 363.514554 -116.891019) (xy 363.487258 -116.842384) (xy 363.467335 -116.790293)
			(xy 363.455209 -116.735856) (xy 363.451138 -116.680234) (xy 362.566828 -116.680234) (xy 362.566514 -116.698663)
			(xy 362.559145 -116.751262) (xy 362.54455 -116.802331) (xy 362.5342 -116.826792) (xy 362.529851 -116.83816)
			(xy 362.531199 -116.862434) (xy 362.53674 -116.873274) (xy 362.578142 -116.944394) (xy 362.584859 -116.954477)
			(xy 362.605279 -116.967461) (xy 362.617258 -116.969286) (xy 362.64524 -116.972462) (xy 362.699904 -116.985999)
			(xy 362.751984 -117.007426) (xy 362.800347 -117.036278) (xy 362.843942 -117.071927) (xy 362.881822 -117.113598)
			(xy 362.913164 -117.160386) (xy 362.937286 -117.211274) (xy 362.953663 -117.265155) (xy 362.959105 -117.301772)
			(xy 364.598202 -117.301772) (xy 364.602273 -117.24615) (xy 364.614399 -117.191713) (xy 364.634322 -117.139622)
			(xy 364.661618 -117.090987) (xy 364.695704 -117.046844) (xy 364.735853 -117.008135) (xy 364.781211 -116.975684)
			(xy 364.830811 -116.950183) (xy 364.883595 -116.932176) (xy 364.938438 -116.922046) (xy 364.994172 -116.920009)
			(xy 365.049609 -116.926109) (xy 365.103566 -116.940215) (xy 365.154895 -116.962027) (xy 365.202501 -116.991081)
			(xy 365.245369 -117.026756) (xy 365.282586 -117.068293) (xy 365.313359 -117.114806) (xy 365.337031 -117.165303)
			(xy 365.353099 -117.21871) (xy 365.359118 -117.259608) (xy 365.477552 -117.259608) (xy 365.47801 -117.232237)
			(xy 365.485828 -117.178057) (xy 365.501318 -117.125554) (xy 365.524162 -117.075807) (xy 365.553889 -117.029841)
			(xy 365.571532 -117.00891) (xy 365.571786 -117.008656) (xy 365.577354 -117.001556) (xy 365.583612 -116.98465)
			(xy 365.583978 -116.975636) (xy 365.583978 -116.90858) (xy 365.583635 -116.899562) (xy 365.577378 -116.882644)
			(xy 365.571786 -116.87556) (xy 365.571532 -116.87556) (xy 365.571532 -116.875306) (xy 365.553899 -116.854367)
			(xy 365.524173 -116.8084) (xy 365.501327 -116.758655) (xy 365.48583 -116.706154) (xy 365.478001 -116.651976)
			(xy 365.478 -116.597236) (xy 365.485828 -116.543058) (xy 365.501323 -116.490556) (xy 365.524168 -116.44081)
			(xy 365.553892 -116.394843) (xy 365.571532 -116.37391) (xy 365.571786 -116.373656) (xy 365.577354 -116.366556)
			(xy 365.583612 -116.34965) (xy 365.583978 -116.340636) (xy 365.583978 -116.27358) (xy 365.583635 -116.264562)
			(xy 365.577378 -116.247644) (xy 365.571786 -116.24056) (xy 365.571532 -116.24056) (xy 365.571532 -116.240306)
			(xy 365.553887 -116.219378) (xy 365.524175 -116.173405) (xy 365.50134 -116.123656) (xy 365.48585 -116.071154)
			(xy 365.478024 -116.016978) (xy 365.477552 -115.989608) (xy 365.478085 -115.962359) (xy 365.485839 -115.908415)
			(xy 365.501192 -115.856123) (xy 365.523829 -115.806549) (xy 365.553291 -115.7607) (xy 365.588977 -115.719511)
			(xy 365.630162 -115.683819) (xy 365.676007 -115.654352) (xy 365.725578 -115.631708) (xy 365.777868 -115.61635)
			(xy 365.831811 -115.608589) (xy 365.85906 -115.6081) (xy 365.886429 -115.60859) (xy 365.940607 -115.616402)
			(xy 365.99311 -115.631885) (xy 366.042858 -115.654722) (xy 366.088825 -115.684441) (xy 366.109758 -115.70208)
			(xy 366.110012 -115.702334) (xy 366.117088 -115.707936) (xy 366.134013 -115.714172) (xy 366.143032 -115.714526)
			(xy 366.210088 -115.714526) (xy 366.219104 -115.714158) (xy 366.23602 -115.707917) (xy 366.243108 -115.702334)
			(xy 366.243108 -115.70208) (xy 366.243362 -115.70208) (xy 366.264295 -115.684442) (xy 366.310268 -115.654731)
			(xy 366.360015 -115.631895) (xy 366.412516 -115.616404) (xy 366.466691 -115.608575) (xy 366.49406 -115.6081)
			(xy 366.521312 -115.608593) (xy 366.575263 -115.616344) (xy 366.62756 -115.631696) (xy 366.677141 -115.654334)
			(xy 366.722995 -115.683799) (xy 366.764188 -115.719489) (xy 366.799882 -115.76068) (xy 366.829351 -115.806531)
			(xy 366.851993 -115.85611) (xy 366.867349 -115.908406) (xy 366.875105 -115.962356) (xy 366.875568 -115.989608)
			(xy 366.875114 -116.016979) (xy 366.867295 -116.071159) (xy 366.851803 -116.123662) (xy 366.828959 -116.173409)
			(xy 366.799231 -116.219375) (xy 366.781588 -116.240306) (xy 366.781334 -116.24056) (xy 366.77575 -116.247648)
			(xy 366.769504 -116.264564) (xy 366.769142 -116.27358) (xy 366.769142 -116.340636) (xy 366.769473 -116.349656)
			(xy 366.775737 -116.366573) (xy 366.781334 -116.373656) (xy 366.781588 -116.373656) (xy 366.781588 -116.37391)
			(xy 366.799236 -116.394837) (xy 366.828959 -116.440806) (xy 366.851803 -116.490553) (xy 366.867298 -116.543056)
			(xy 366.875126 -116.597235) (xy 366.875125 -116.651977) (xy 366.867296 -116.706156) (xy 366.851799 -116.758658)
			(xy 366.828953 -116.808405) (xy 366.799229 -116.854373) (xy 366.781588 -116.875306) (xy 366.781334 -116.87556)
			(xy 366.77575 -116.882648) (xy 366.769504 -116.899564) (xy 366.769142 -116.90858) (xy 366.769142 -116.975636)
			(xy 366.769473 -116.984656) (xy 366.775737 -117.001573) (xy 366.781334 -117.008656) (xy 366.781588 -117.008656)
			(xy 366.781588 -117.00891) (xy 366.799243 -117.029829) (xy 366.828953 -117.075805) (xy 366.851786 -117.125556)
			(xy 366.867273 -117.17806) (xy 366.875097 -117.232238) (xy 366.875568 -117.259608) (xy 366.875152 -117.286863)
			(xy 366.867393 -117.340818) (xy 366.852034 -117.393119) (xy 366.829387 -117.442702) (xy 366.799915 -117.488557)
			(xy 366.764216 -117.52975) (xy 366.723018 -117.565444) (xy 366.677159 -117.594911) (xy 366.627574 -117.617551)
			(xy 366.575271 -117.632903) (xy 366.521315 -117.640655) (xy 366.49406 -117.641116) (xy 366.46669 -117.640635)
			(xy 366.412511 -117.632824) (xy 366.360007 -117.61734) (xy 366.31026 -117.594501) (xy 366.264293 -117.564777)
			(xy 366.243362 -117.547136) (xy 366.243108 -117.546882) (xy 366.236025 -117.541291) (xy 366.219105 -117.535047)
			(xy 366.210088 -117.53469) (xy 366.143032 -117.53469) (xy 366.134017 -117.535064) (xy 366.1171 -117.5413)
			(xy 366.110012 -117.546882) (xy 366.110012 -117.547136) (xy 366.109758 -117.547136) (xy 366.08882 -117.564767)
			(xy 366.042848 -117.594479) (xy 365.993102 -117.617316) (xy 365.940603 -117.632809) (xy 365.886429 -117.64064)
			(xy 365.85906 -117.641116) (xy 365.831808 -117.640659) (xy 365.77786 -117.632898) (xy 365.725565 -117.617538)
			(xy 365.675988 -117.594893) (xy 365.630138 -117.565423) (xy 365.588949 -117.529729) (xy 365.553258 -117.488536)
			(xy 365.523792 -117.442684) (xy 365.501151 -117.393105) (xy 365.485796 -117.340809) (xy 365.478038 -117.28686)
			(xy 365.477552 -117.259608) (xy 365.359118 -117.259608) (xy 365.361219 -117.273886) (xy 365.361728 -117.301772)
			(xy 365.361219 -117.329658) (xy 365.353099 -117.384834) (xy 365.337031 -117.438241) (xy 365.313359 -117.488738)
			(xy 365.282586 -117.535251) (xy 365.245369 -117.576788) (xy 365.202501 -117.612463) (xy 365.154895 -117.641517)
			(xy 365.103566 -117.663329) (xy 365.049609 -117.677435) (xy 364.994172 -117.683535) (xy 364.938438 -117.681498)
			(xy 364.883595 -117.671368) (xy 364.830811 -117.653361) (xy 364.781211 -117.62786) (xy 364.735853 -117.595409)
			(xy 364.695704 -117.5567) (xy 364.661618 -117.512557) (xy 364.634322 -117.463922) (xy 364.614399 -117.411831)
			(xy 364.602273 -117.357394) (xy 364.598202 -117.301772) (xy 362.959105 -117.301772) (xy 362.961941 -117.320858)
			(xy 362.962444 -117.349016) (xy 362.961958 -117.376267) (xy 362.954202 -117.430215) (xy 362.938847 -117.48251)
			(xy 362.916205 -117.532087) (xy 362.886739 -117.577937) (xy 362.851048 -117.619128) (xy 362.809857 -117.654819)
			(xy 362.764007 -117.684285) (xy 362.71443 -117.706927) (xy 362.662135 -117.722282) (xy 362.608187 -117.730038)
			(xy 362.553685 -117.730038) (xy 362.499737 -117.722282) (xy 362.447442 -117.706927) (xy 362.397865 -117.684285)
			(xy 362.352015 -117.654819) (xy 362.310824 -117.619128) (xy 362.275133 -117.577937) (xy 362.245667 -117.532087)
			(xy 362.223025 -117.48251) (xy 362.20767 -117.430215) (xy 362.199914 -117.376267) (xy 362.199428 -117.349016)
			(xy 362.199888 -117.32246) (xy 362.207254 -117.26986) (xy 362.221846 -117.218791) (xy 362.232194 -117.19433)
			(xy 362.236529 -117.182958) (xy 362.235191 -117.158688) (xy 362.229654 -117.147848) (xy 362.188252 -117.076728)
			(xy 362.181509 -117.066666) (xy 362.161107 -117.053675) (xy 362.149136 -117.051836) (xy 362.119662 -117.048454)
			(xy 362.062193 -117.033737) (xy 362.007697 -117.010298) (xy 361.957487 -116.978703) (xy 361.93476 -116.959634)
			(xy 361.934506 -116.95938) (xy 361.927424 -116.953788) (xy 361.910504 -116.947545) (xy 361.901486 -116.947188)
			(xy 361.83443 -116.947188) (xy 361.825415 -116.947562) (xy 361.808498 -116.953798) (xy 361.80141 -116.95938)
			(xy 361.80141 -116.959634) (xy 361.801156 -116.959634) (xy 361.780218 -116.977266) (xy 361.734246 -117.006977)
			(xy 361.6845 -117.029814) (xy 361.632001 -117.045307) (xy 361.577827 -117.053138) (xy 361.550458 -117.053614)
			(xy 361.523206 -117.053161) (xy 361.469257 -117.045399) (xy 361.416962 -117.030039) (xy 361.367385 -117.007393)
			(xy 361.321536 -116.977923) (xy 361.280346 -116.942229) (xy 361.244655 -116.901036) (xy 361.215189 -116.855183)
			(xy 361.192548 -116.805604) (xy 361.177193 -116.753307) (xy 361.169436 -116.699358) (xy 361.16895 -116.672106)
			(xy 356.604703 -116.672106) (xy 356.605871 -116.672819) (xy 356.648739 -116.708494) (xy 356.685956 -116.750031)
			(xy 356.716729 -116.796544) (xy 356.740401 -116.847041) (xy 356.756469 -116.900448) (xy 356.764589 -116.955624)
			(xy 356.765098 -116.98351) (xy 356.764589 -117.011396) (xy 356.756469 -117.066572) (xy 356.740401 -117.119979)
			(xy 356.716729 -117.170476) (xy 356.685956 -117.216989) (xy 356.648739 -117.258526) (xy 356.605871 -117.294201)
			(xy 356.558265 -117.323255) (xy 356.54845 -117.327426) (xy 357.987344 -117.327426) (xy 357.991415 -117.271804)
			(xy 358.003541 -117.217367) (xy 358.023464 -117.165276) (xy 358.05076 -117.116641) (xy 358.084846 -117.072498)
			(xy 358.124995 -117.033789) (xy 358.170353 -117.001338) (xy 358.219953 -116.975837) (xy 358.272737 -116.95783)
			(xy 358.32758 -116.9477) (xy 358.383314 -116.945663) (xy 358.438751 -116.951763) (xy 358.492708 -116.965869)
			(xy 358.544037 -116.987681) (xy 358.591643 -117.016735) (xy 358.634511 -117.05241) (xy 358.671728 -117.093947)
			(xy 358.702501 -117.14046) (xy 358.726173 -117.190957) (xy 358.729022 -117.200426) (xy 360.019344 -117.200426)
			(xy 360.023415 -117.144804) (xy 360.035541 -117.090367) (xy 360.055464 -117.038276) (xy 360.08276 -116.989641)
			(xy 360.116846 -116.945498) (xy 360.156995 -116.906789) (xy 360.202353 -116.874338) (xy 360.251953 -116.848837)
			(xy 360.304737 -116.83083) (xy 360.35958 -116.8207) (xy 360.415314 -116.818663) (xy 360.470751 -116.824763)
			(xy 360.524708 -116.838869) (xy 360.576037 -116.860681) (xy 360.623643 -116.889735) (xy 360.666511 -116.92541)
			(xy 360.703728 -116.966947) (xy 360.734501 -117.01346) (xy 360.758173 -117.063957) (xy 360.774241 -117.117364)
			(xy 360.782361 -117.17254) (xy 360.78287 -117.200426) (xy 360.782361 -117.228312) (xy 360.774241 -117.283488)
			(xy 360.758173 -117.336895) (xy 360.734501 -117.387392) (xy 360.703728 -117.433905) (xy 360.666511 -117.475442)
			(xy 360.623643 -117.511117) (xy 360.576037 -117.540171) (xy 360.524708 -117.561983) (xy 360.470751 -117.576089)
			(xy 360.415314 -117.582189) (xy 360.35958 -117.580152) (xy 360.304737 -117.570022) (xy 360.251953 -117.552015)
			(xy 360.202353 -117.526514) (xy 360.156995 -117.494063) (xy 360.116846 -117.455354) (xy 360.08276 -117.411211)
			(xy 360.055464 -117.362576) (xy 360.035541 -117.310485) (xy 360.023415 -117.256048) (xy 360.019344 -117.200426)
			(xy 358.729022 -117.200426) (xy 358.742241 -117.244364) (xy 358.750361 -117.29954) (xy 358.75087 -117.327426)
			(xy 358.750361 -117.355312) (xy 358.742241 -117.410488) (xy 358.726173 -117.463895) (xy 358.702501 -117.514392)
			(xy 358.671728 -117.560905) (xy 358.634511 -117.602442) (xy 358.591643 -117.638117) (xy 358.544037 -117.667171)
			(xy 358.492708 -117.688983) (xy 358.438751 -117.703089) (xy 358.383314 -117.709189) (xy 358.32758 -117.707152)
			(xy 358.272737 -117.697022) (xy 358.219953 -117.679015) (xy 358.170353 -117.653514) (xy 358.124995 -117.621063)
			(xy 358.084846 -117.582354) (xy 358.05076 -117.538211) (xy 358.023464 -117.489576) (xy 358.003541 -117.437485)
			(xy 357.991415 -117.383048) (xy 357.987344 -117.327426) (xy 356.54845 -117.327426) (xy 356.506936 -117.345067)
			(xy 356.452979 -117.359173) (xy 356.397542 -117.365273) (xy 356.341808 -117.363236) (xy 356.286965 -117.353106)
			(xy 356.234181 -117.335099) (xy 356.184581 -117.309598) (xy 356.139223 -117.277147) (xy 356.099074 -117.238438)
			(xy 356.064988 -117.194295) (xy 356.037692 -117.14566) (xy 356.017769 -117.093569) (xy 356.005643 -117.039132)
			(xy 356.001572 -116.98351) (xy 354.634047 -116.98351) (xy 354.439982 -117.177566) (xy 354.433137 -117.184964)
			(xy 354.425414 -117.203563) (xy 354.424996 -117.213634) (xy 354.424996 -119.486426) (xy 357.987344 -119.486426)
			(xy 357.991415 -119.430804) (xy 358.003541 -119.376367) (xy 358.023464 -119.324276) (xy 358.05076 -119.275641)
			(xy 358.084846 -119.231498) (xy 358.124995 -119.192789) (xy 358.170353 -119.160338) (xy 358.219953 -119.134837)
			(xy 358.272737 -119.11683) (xy 358.32758 -119.1067) (xy 358.383314 -119.104663) (xy 358.438751 -119.110763)
			(xy 358.492708 -119.124869) (xy 358.544037 -119.146681) (xy 358.591643 -119.175735) (xy 358.634511 -119.21141)
			(xy 358.671728 -119.252947) (xy 358.702501 -119.29946) (xy 358.726173 -119.349957) (xy 358.727952 -119.35587)
			(xy 359.003344 -119.35587) (xy 359.007415 -119.300248) (xy 359.019541 -119.245811) (xy 359.039464 -119.19372)
			(xy 359.06676 -119.145085) (xy 359.100846 -119.100942) (xy 359.140995 -119.062233) (xy 359.186353 -119.029782)
			(xy 359.235953 -119.004281) (xy 359.288737 -118.986274) (xy 359.34358 -118.976144) (xy 359.399314 -118.974107)
			(xy 359.454751 -118.980207) (xy 359.508708 -118.994313) (xy 359.560037 -119.016125) (xy 359.607643 -119.045179)
			(xy 359.650511 -119.080854) (xy 359.687728 -119.122391) (xy 359.718501 -119.168904) (xy 359.742173 -119.219401)
			(xy 359.758241 -119.272808) (xy 359.766361 -119.327984) (xy 359.76687 -119.35587) (xy 360.019344 -119.35587)
			(xy 360.023415 -119.300248) (xy 360.035541 -119.245811) (xy 360.055464 -119.19372) (xy 360.08276 -119.145085)
			(xy 360.116846 -119.100942) (xy 360.156995 -119.062233) (xy 360.202353 -119.029782) (xy 360.251953 -119.004281)
			(xy 360.304737 -118.986274) (xy 360.35958 -118.976144) (xy 360.415314 -118.974107) (xy 360.470751 -118.980207)
			(xy 360.524708 -118.994313) (xy 360.576037 -119.016125) (xy 360.623643 -119.045179) (xy 360.666511 -119.080854)
			(xy 360.703728 -119.122391) (xy 360.734501 -119.168904) (xy 360.758173 -119.219401) (xy 360.774241 -119.272808)
			(xy 360.782361 -119.327984) (xy 360.78287 -119.35587) (xy 360.782361 -119.383756) (xy 360.781232 -119.39143)
			(xy 363.214918 -119.39143) (xy 363.218989 -119.335808) (xy 363.231115 -119.281371) (xy 363.251038 -119.22928)
			(xy 363.278334 -119.180645) (xy 363.31242 -119.136502) (xy 363.352569 -119.097793) (xy 363.397927 -119.065342)
			(xy 363.447527 -119.039841) (xy 363.500311 -119.021834) (xy 363.555154 -119.011704) (xy 363.610888 -119.009667)
			(xy 363.666325 -119.015767) (xy 363.720282 -119.029873) (xy 363.771611 -119.051685) (xy 363.819217 -119.080739)
			(xy 363.862085 -119.116414) (xy 363.899302 -119.157951) (xy 363.930075 -119.204464) (xy 363.953747 -119.254961)
			(xy 363.969815 -119.308368) (xy 363.977935 -119.363544) (xy 363.978444 -119.39143) (xy 363.977935 -119.419316)
			(xy 363.969815 -119.474492) (xy 363.953747 -119.527899) (xy 363.930075 -119.578396) (xy 363.899302 -119.624909)
			(xy 363.862085 -119.666446) (xy 363.819217 -119.702121) (xy 363.771611 -119.731175) (xy 363.720282 -119.752987)
			(xy 363.666325 -119.767093) (xy 363.610888 -119.773193) (xy 363.555154 -119.771156) (xy 363.500311 -119.761026)
			(xy 363.447527 -119.743019) (xy 363.397927 -119.717518) (xy 363.352569 -119.685067) (xy 363.31242 -119.646358)
			(xy 363.278334 -119.602215) (xy 363.251038 -119.55358) (xy 363.231115 -119.501489) (xy 363.218989 -119.447052)
			(xy 363.214918 -119.39143) (xy 360.781232 -119.39143) (xy 360.774241 -119.438932) (xy 360.758173 -119.492339)
			(xy 360.734501 -119.542836) (xy 360.703728 -119.589349) (xy 360.666511 -119.630886) (xy 360.623643 -119.666561)
			(xy 360.576037 -119.695615) (xy 360.524708 -119.717427) (xy 360.470751 -119.731533) (xy 360.415314 -119.737633)
			(xy 360.35958 -119.735596) (xy 360.304737 -119.725466) (xy 360.251953 -119.707459) (xy 360.202353 -119.681958)
			(xy 360.156995 -119.649507) (xy 360.116846 -119.610798) (xy 360.08276 -119.566655) (xy 360.055464 -119.51802)
			(xy 360.035541 -119.465929) (xy 360.023415 -119.411492) (xy 360.019344 -119.35587) (xy 359.76687 -119.35587)
			(xy 359.766361 -119.383756) (xy 359.758241 -119.438932) (xy 359.742173 -119.492339) (xy 359.718501 -119.542836)
			(xy 359.687728 -119.589349) (xy 359.650511 -119.630886) (xy 359.607643 -119.666561) (xy 359.560037 -119.695615)
			(xy 359.508708 -119.717427) (xy 359.454751 -119.731533) (xy 359.399314 -119.737633) (xy 359.34358 -119.735596)
			(xy 359.288737 -119.725466) (xy 359.235953 -119.707459) (xy 359.186353 -119.681958) (xy 359.140995 -119.649507)
			(xy 359.100846 -119.610798) (xy 359.06676 -119.566655) (xy 359.039464 -119.51802) (xy 359.019541 -119.465929)
			(xy 359.007415 -119.411492) (xy 359.003344 -119.35587) (xy 358.727952 -119.35587) (xy 358.742241 -119.403364)
			(xy 358.750361 -119.45854) (xy 358.75087 -119.486426) (xy 358.750361 -119.514312) (xy 358.742241 -119.569488)
			(xy 358.726173 -119.622895) (xy 358.702501 -119.673392) (xy 358.671728 -119.719905) (xy 358.634511 -119.761442)
			(xy 358.591643 -119.797117) (xy 358.544037 -119.826171) (xy 358.492708 -119.847983) (xy 358.438751 -119.862089)
			(xy 358.383314 -119.868189) (xy 358.32758 -119.866152) (xy 358.272737 -119.856022) (xy 358.219953 -119.838015)
			(xy 358.170353 -119.812514) (xy 358.124995 -119.780063) (xy 358.084846 -119.741354) (xy 358.05076 -119.697211)
			(xy 358.023464 -119.648576) (xy 358.003541 -119.596485) (xy 357.991415 -119.542048) (xy 357.987344 -119.486426)
			(xy 354.424996 -119.486426) (xy 354.424996 -121.57075) (xy 361.920028 -121.57075) (xy 361.920517 -121.54338)
			(xy 361.928328 -121.489202) (xy 361.943811 -121.436699) (xy 361.966648 -121.386952) (xy 361.996369 -121.340984)
			(xy 362.014008 -121.320052) (xy 362.014262 -121.319798) (xy 362.019863 -121.312722) (xy 362.026099 -121.295797)
			(xy 362.026454 -121.286778) (xy 362.026454 -121.219722) (xy 362.026096 -121.210705) (xy 362.01985 -121.193788)
			(xy 362.014262 -121.186702) (xy 362.014008 -121.186702) (xy 362.014008 -121.186448) (xy 361.996379 -121.165508)
			(xy 361.966666 -121.119537) (xy 361.943827 -121.069792) (xy 361.928334 -121.017293) (xy 361.920503 -120.963119)
			(xy 361.920028 -120.93575) (xy 361.920514 -120.908499) (xy 361.92827 -120.854551) (xy 361.943625 -120.802256)
			(xy 361.966267 -120.752679) (xy 361.995733 -120.706829) (xy 362.031424 -120.665638) (xy 362.072615 -120.629947)
			(xy 362.118465 -120.600481) (xy 362.168042 -120.577839) (xy 362.220337 -120.562484) (xy 362.274285 -120.554728)
			(xy 362.328787 -120.554728) (xy 362.382735 -120.562484) (xy 362.43503 -120.577839) (xy 362.484607 -120.600481)
			(xy 362.530457 -120.629947) (xy 362.571648 -120.665638) (xy 362.607339 -120.706829) (xy 362.636805 -120.752679)
			(xy 362.659447 -120.802256) (xy 362.674802 -120.854551) (xy 362.682558 -120.908499) (xy 362.683044 -120.93575)
			(xy 362.682562 -120.96312) (xy 362.67475 -121.017299) (xy 362.659266 -121.069802) (xy 362.636427 -121.119549)
			(xy 362.606705 -121.165516) (xy 362.589064 -121.186448) (xy 362.58881 -121.186702) (xy 362.583218 -121.193785)
			(xy 362.576974 -121.210704) (xy 362.576618 -121.219722) (xy 362.576618 -121.286778) (xy 362.576982 -121.295794)
			(xy 362.583224 -121.312711) (xy 362.58881 -121.319798) (xy 362.589064 -121.319798) (xy 362.589064 -121.320052)
			(xy 362.606688 -121.340996) (xy 362.636404 -121.386965) (xy 362.659243 -121.436709) (xy 362.674737 -121.489208)
			(xy 362.682569 -121.543382) (xy 362.683044 -121.57075) (xy 362.682558 -121.598001) (xy 362.674802 -121.651949)
			(xy 362.659447 -121.704244) (xy 362.636805 -121.753821) (xy 362.607339 -121.799671) (xy 362.571648 -121.840862)
			(xy 362.530457 -121.876553) (xy 362.484607 -121.906019) (xy 362.43503 -121.928661) (xy 362.382735 -121.944016)
			(xy 362.328787 -121.951772) (xy 362.274285 -121.951772) (xy 362.220337 -121.944016) (xy 362.168042 -121.928661)
			(xy 362.118465 -121.906019) (xy 362.072615 -121.876553) (xy 362.031424 -121.840862) (xy 361.995733 -121.799671)
			(xy 361.966267 -121.753821) (xy 361.943625 -121.704244) (xy 361.92827 -121.651949) (xy 361.920514 -121.598001)
			(xy 361.920028 -121.57075) (xy 354.424996 -121.57075) (xy 354.424996 -122.292618) (xy 358.080308 -122.292618)
			(xy 358.084379 -122.236996) (xy 358.096505 -122.182559) (xy 358.116428 -122.130468) (xy 358.143724 -122.081833)
			(xy 358.17781 -122.03769) (xy 358.217959 -121.998981) (xy 358.263317 -121.96653) (xy 358.312917 -121.941029)
			(xy 358.365701 -121.923022) (xy 358.420544 -121.912892) (xy 358.476278 -121.910855) (xy 358.531715 -121.916955)
			(xy 358.585672 -121.931061) (xy 358.637001 -121.952873) (xy 358.684607 -121.981927) (xy 358.727475 -122.017602)
			(xy 358.764692 -122.059139) (xy 358.795465 -122.105652) (xy 358.819137 -122.156149) (xy 358.835205 -122.209556)
			(xy 358.843325 -122.264732) (xy 358.843834 -122.292618) (xy 358.843325 -122.320504) (xy 358.835205 -122.37568)
			(xy 358.819137 -122.429087) (xy 358.8 -122.46991) (xy 359.237024 -122.46991) (xy 359.241095 -122.414288)
			(xy 359.253221 -122.359851) (xy 359.273144 -122.30776) (xy 359.30044 -122.259125) (xy 359.334526 -122.214982)
			(xy 359.374675 -122.176273) (xy 359.420033 -122.143822) (xy 359.469633 -122.118321) (xy 359.522417 -122.100314)
			(xy 359.57726 -122.090184) (xy 359.632994 -122.088147) (xy 359.688431 -122.094247) (xy 359.742388 -122.108353)
			(xy 359.793717 -122.130165) (xy 359.841323 -122.159219) (xy 359.884191 -122.194894) (xy 359.921408 -122.236431)
			(xy 359.952181 -122.282944) (xy 359.975853 -122.333441) (xy 359.991921 -122.386848) (xy 360.000041 -122.442024)
			(xy 360.00055 -122.46991) (xy 360.000041 -122.497796) (xy 359.991921 -122.552972) (xy 359.975853 -122.606379)
			(xy 359.952181 -122.656876) (xy 359.921408 -122.703389) (xy 359.884191 -122.744926) (xy 359.841323 -122.780601)
			(xy 359.793717 -122.809655) (xy 359.742388 -122.831467) (xy 359.688431 -122.845573) (xy 359.632994 -122.851673)
			(xy 359.57726 -122.849636) (xy 359.522417 -122.839506) (xy 359.469633 -122.821499) (xy 359.420033 -122.795998)
			(xy 359.374675 -122.763547) (xy 359.334526 -122.724838) (xy 359.30044 -122.680695) (xy 359.273144 -122.63206)
			(xy 359.253221 -122.579969) (xy 359.241095 -122.525532) (xy 359.237024 -122.46991) (xy 358.8 -122.46991)
			(xy 358.795465 -122.479584) (xy 358.764692 -122.526097) (xy 358.727475 -122.567634) (xy 358.684607 -122.603309)
			(xy 358.637001 -122.632363) (xy 358.585672 -122.654175) (xy 358.531715 -122.668281) (xy 358.476278 -122.674381)
			(xy 358.420544 -122.672344) (xy 358.365701 -122.662214) (xy 358.312917 -122.644207) (xy 358.263317 -122.618706)
			(xy 358.217959 -122.586255) (xy 358.17781 -122.547546) (xy 358.143724 -122.503403) (xy 358.116428 -122.454768)
			(xy 358.096505 -122.402677) (xy 358.084379 -122.34824) (xy 358.080308 -122.292618) (xy 354.424996 -122.292618)
			(xy 354.424996 -123.24975) (xy 360.21009 -123.24975) (xy 360.21009 -123.19525) (xy 360.217847 -123.141304)
			(xy 360.233201 -123.089011) (xy 360.255842 -123.039435) (xy 360.285307 -122.993586) (xy 360.320997 -122.952397)
			(xy 360.362186 -122.916707) (xy 360.408035 -122.887242) (xy 360.457611 -122.864601) (xy 360.509904 -122.849247)
			(xy 360.56385 -122.84149) (xy 360.5911 -122.841004) (xy 360.61813 -122.841499) (xy 360.671647 -122.849137)
			(xy 360.723549 -122.86426) (xy 360.772793 -122.886564) (xy 360.818392 -122.915602) (xy 360.85943 -122.950792)
			(xy 360.877612 -122.970798) (xy 360.877866 -122.971052) (xy 360.885307 -122.978703) (xy 360.904793 -122.987368)
			(xy 360.915458 -122.987816) (xy 361.003088 -122.988324) (xy 361.022646 -122.979688) (xy 361.030012 -122.971306)
			(xy 361.048173 -122.951583) (xy 361.089074 -122.916919) (xy 361.134429 -122.88833) (xy 361.183345 -122.866382)
			(xy 361.234854 -122.851506) (xy 361.287939 -122.843997) (xy 361.314746 -122.843544) (xy 361.342116 -122.844031)
			(xy 361.396294 -122.851842) (xy 361.448798 -122.867326) (xy 361.498545 -122.890163) (xy 361.544512 -122.919884)
			(xy 361.565444 -122.937524) (xy 361.565698 -122.937778) (xy 361.572774 -122.943379) (xy 361.589699 -122.949615)
			(xy 361.598718 -122.94997) (xy 361.665774 -122.94997) (xy 361.67479 -122.949607) (xy 361.691708 -122.943364)
			(xy 361.698794 -122.937778) (xy 361.698794 -122.937524) (xy 361.699048 -122.937524) (xy 361.719981 -122.919883)
			(xy 361.765949 -122.890159) (xy 361.815695 -122.867313) (xy 361.868197 -122.851817) (xy 361.922375 -122.843988)
			(xy 361.977117 -122.843988) (xy 362.031295 -122.851817) (xy 362.083797 -122.867313) (xy 362.133543 -122.890159)
			(xy 362.179511 -122.919883) (xy 362.200444 -122.937524) (xy 362.200698 -122.937778) (xy 362.207774 -122.943379)
			(xy 362.224699 -122.949615) (xy 362.233718 -122.94997) (xy 362.300774 -122.94997) (xy 362.30979 -122.949607)
			(xy 362.326708 -122.943364) (xy 362.333794 -122.937778) (xy 362.334302 -122.937524) (xy 362.347036 -122.92658)
			(xy 362.374128 -122.906738) (xy 362.388404 -122.8979) (xy 362.397294 -122.892566) (xy 362.409486 -122.875548)
			(xy 362.429806 -122.78233) (xy 362.425488 -122.761756) (xy 362.419646 -122.75312) (xy 362.403646 -122.729056)
			(xy 362.378305 -122.677124) (xy 362.36108 -122.621966) (xy 362.352364 -122.564842) (xy 362.351828 -122.53595)
			(xy 362.352314 -122.508699) (xy 362.36007 -122.454751) (xy 362.375425 -122.402456) (xy 362.398067 -122.352879)
			(xy 362.427533 -122.307029) (xy 362.463224 -122.265838) (xy 362.504415 -122.230147) (xy 362.550265 -122.200681)
			(xy 362.599842 -122.178039) (xy 362.652137 -122.162684) (xy 362.706085 -122.154928) (xy 362.760587 -122.154928)
			(xy 362.814535 -122.162684) (xy 362.86683 -122.178039) (xy 362.916407 -122.200681) (xy 362.962257 -122.230147)
			(xy 363.003448 -122.265838) (xy 363.039139 -122.307029) (xy 363.068605 -122.352879) (xy 363.091247 -122.402456)
			(xy 363.106602 -122.454751) (xy 363.114358 -122.508699) (xy 363.114844 -122.53595) (xy 363.114297 -122.56404)
			(xy 363.106078 -122.619614) (xy 363.089795 -122.673381) (xy 363.065801 -122.724178) (xy 363.034614 -122.770905)
			(xy 362.99691 -122.812552) (xy 362.953505 -122.848217) (xy 362.929678 -122.863102) (xy 362.920788 -122.868436)
			(xy 362.908596 -122.885454) (xy 362.888276 -122.978672) (xy 362.892594 -122.999246) (xy 362.898436 -123.007882)
			(xy 362.914435 -123.031947) (xy 362.939777 -123.083878) (xy 362.957002 -123.139036) (xy 362.965719 -123.19616)
			(xy 362.966254 -123.225052) (xy 362.9657 -123.252302) (xy 362.957951 -123.306247) (xy 362.942603 -123.35854)
			(xy 362.91997 -123.408117) (xy 362.890511 -123.453968) (xy 362.854827 -123.49516) (xy 362.813644 -123.530855)
			(xy 362.7678 -123.560325) (xy 362.718228 -123.58297) (xy 362.665939 -123.598331) (xy 362.611995 -123.606093)
			(xy 362.584746 -123.60656) (xy 362.557376 -123.606077) (xy 362.503198 -123.598265) (xy 362.450694 -123.58278)
			(xy 362.400947 -123.559942) (xy 362.35498 -123.53022) (xy 362.334048 -123.51258) (xy 362.333794 -123.512326)
			(xy 362.32672 -123.506722) (xy 362.309793 -123.500488) (xy 362.300774 -123.500134) (xy 362.233718 -123.500134)
			(xy 362.224701 -123.500492) (xy 362.207784 -123.506738) (xy 362.200698 -123.512326) (xy 362.200444 -123.51258)
			(xy 362.179511 -123.530221) (xy 362.133543 -123.559945) (xy 362.083797 -123.582791) (xy 362.031295 -123.598287)
			(xy 361.977117 -123.606116) (xy 361.922375 -123.606116) (xy 361.868197 -123.598287) (xy 361.815695 -123.582791)
			(xy 361.765949 -123.559945) (xy 361.719981 -123.530221) (xy 361.699048 -123.51258) (xy 361.698794 -123.512326)
			(xy 361.69172 -123.506722) (xy 361.674793 -123.500488) (xy 361.665774 -123.500134) (xy 361.598718 -123.500134)
			(xy 361.589701 -123.500492) (xy 361.572784 -123.506738) (xy 361.565698 -123.512326) (xy 361.565698 -123.51258)
			(xy 361.565444 -123.51258) (xy 361.544504 -123.530209) (xy 361.498533 -123.559923) (xy 361.448788 -123.582761)
			(xy 361.396289 -123.598255) (xy 361.342115 -123.606085) (xy 361.314746 -123.60656) (xy 361.287716 -123.60608)
			(xy 361.234199 -123.598436) (xy 361.182298 -123.583308) (xy 361.133054 -123.561001) (xy 361.087456 -123.531962)
			(xy 361.046417 -123.496772) (xy 361.028234 -123.476766) (xy 361.02798 -123.476512) (xy 361.020512 -123.468892)
			(xy 361.001047 -123.460207) (xy 360.990388 -123.459748) (xy 360.902758 -123.45924) (xy 360.8832 -123.467876)
			(xy 360.875834 -123.476258) (xy 360.857663 -123.495971) (xy 360.816763 -123.530634) (xy 360.771409 -123.559222)
			(xy 360.722496 -123.581172) (xy 360.67099 -123.596051) (xy 360.617906 -123.603564) (xy 360.5911 -123.60402)
			(xy 360.56385 -123.60351) (xy 360.509904 -123.595753) (xy 360.457611 -123.580399) (xy 360.408035 -123.557758)
			(xy 360.362186 -123.528293) (xy 360.320997 -123.492603) (xy 360.285307 -123.451414) (xy 360.255842 -123.405565)
			(xy 360.233201 -123.355989) (xy 360.217847 -123.303696) (xy 360.21009 -123.24975) (xy 354.424996 -123.24975)
			(xy 354.424996 -124.835666) (xy 354.424735 -124.854895) (xy 354.420284 -124.893095) (xy 354.416106 -124.911866)
			(xy 354.414836 -124.917708) (xy 354.414836 -125.288802) (xy 354.415852 -125.298454) (xy 354.41748 -125.305697)
			(xy 354.424324 -125.318864) (xy 354.429314 -125.324362) (xy 355.173534 -126.068582) (xy 355.179033 -126.07357)
			(xy 355.192199 -126.080415) (xy 355.199442 -126.082044) (xy 355.209094 -126.08306) (xy 355.759258 -126.08306)
			(xy 355.766624 -126.082552) (xy 356.987094 -124.862082) (xy 356.990396 -124.852176) (xy 356.998716 -124.826461)
			(xy 357.021601 -124.777497) (xy 357.051173 -124.732256) (xy 357.086837 -124.691646) (xy 357.127879 -124.656479)
			(xy 357.173477 -124.627462) (xy 357.222716 -124.605176) (xy 357.274609 -124.590067) (xy 357.328116 -124.582439)
			(xy 357.35514 -124.58192) (xy 357.382389 -124.582409) (xy 357.43633 -124.59017) (xy 357.488619 -124.605529)
			(xy 357.538189 -124.628173) (xy 357.584032 -124.657641) (xy 357.625216 -124.693333) (xy 357.6609 -124.734522)
			(xy 357.69036 -124.780371) (xy 357.712995 -124.829945) (xy 357.728344 -124.882236) (xy 357.736096 -124.936179)
			(xy 357.736648 -124.963428) (xy 357.736175 -124.990452) (xy 357.729664 -125.036072) (xy 359.186224 -125.036072)
			(xy 359.190295 -124.98045) (xy 359.202421 -124.926013) (xy 359.222344 -124.873922) (xy 359.24964 -124.825287)
			(xy 359.283726 -124.781144) (xy 359.323875 -124.742435) (xy 359.369233 -124.709984) (xy 359.418833 -124.684483)
			(xy 359.471617 -124.666476) (xy 359.52646 -124.656346) (xy 359.582194 -124.654309) (xy 359.637631 -124.660409)
			(xy 359.691588 -124.674515) (xy 359.742917 -124.696327) (xy 359.790523 -124.725381) (xy 359.833391 -124.761056)
			(xy 359.870608 -124.802593) (xy 359.901381 -124.849106) (xy 359.925053 -124.899603) (xy 359.941121 -124.95301)
			(xy 359.949241 -125.008186) (xy 359.94975 -125.036072) (xy 359.949241 -125.063958) (xy 359.941121 -125.119134)
			(xy 359.925053 -125.172541) (xy 359.901381 -125.223038) (xy 359.870608 -125.269551) (xy 359.833391 -125.311088)
			(xy 359.790523 -125.346763) (xy 359.742917 -125.375817) (xy 359.691588 -125.397629) (xy 359.669682 -125.403356)
			(xy 363.844332 -125.403356) (xy 363.844823 -125.375987) (xy 363.852634 -125.321808) (xy 363.868116 -125.269305)
			(xy 363.890953 -125.219558) (xy 363.920673 -125.17359) (xy 363.938312 -125.152658) (xy 363.938566 -125.152404)
			(xy 363.944165 -125.145326) (xy 363.950402 -125.128402) (xy 363.950758 -125.119384) (xy 363.950758 -125.052328)
			(xy 363.950397 -125.043311) (xy 363.944153 -125.026394) (xy 363.938566 -125.019308) (xy 363.938312 -125.019308)
			(xy 363.938312 -125.019054) (xy 363.920687 -124.998111) (xy 363.890972 -124.952141) (xy 363.868134 -124.902397)
			(xy 363.852639 -124.849898) (xy 363.844808 -124.795724) (xy 363.844332 -124.768356) (xy 363.844818 -124.741105)
			(xy 363.852574 -124.687157) (xy 363.867929 -124.634862) (xy 363.890571 -124.585285) (xy 363.920037 -124.539435)
			(xy 363.955728 -124.498244) (xy 363.996919 -124.462553) (xy 364.042769 -124.433087) (xy 364.092346 -124.410445)
			(xy 364.144641 -124.39509) (xy 364.198589 -124.387334) (xy 364.253091 -124.387334) (xy 364.307039 -124.39509)
			(xy 364.359334 -124.410445) (xy 364.408911 -124.433087) (xy 364.454761 -124.462553) (xy 364.495952 -124.498244)
			(xy 364.531643 -124.539435) (xy 364.561109 -124.585285) (xy 364.583751 -124.634862) (xy 364.599106 -124.687157)
			(xy 364.606862 -124.741105) (xy 364.607348 -124.768356) (xy 364.606869 -124.795726) (xy 364.599056 -124.849905)
			(xy 364.583571 -124.902408) (xy 364.560732 -124.952156) (xy 364.531009 -124.998122) (xy 364.513368 -125.019054)
			(xy 364.513114 -125.019308) (xy 364.507519 -125.026389) (xy 364.501277 -125.04331) (xy 364.500922 -125.052328)
			(xy 364.500922 -125.119384) (xy 364.501282 -125.128401) (xy 364.507527 -125.145318) (xy 364.513114 -125.152404)
			(xy 364.513368 -125.152404) (xy 364.513368 -125.152658) (xy 364.530996 -125.173599) (xy 364.560711 -125.219569)
			(xy 364.583549 -125.269314) (xy 364.599043 -125.321813) (xy 364.606873 -125.375987) (xy 364.607348 -125.403356)
			(xy 364.606862 -125.430607) (xy 364.599106 -125.484555) (xy 364.583751 -125.53685) (xy 364.561109 -125.586427)
			(xy 364.531643 -125.632277) (xy 364.495952 -125.673468) (xy 364.454761 -125.709159) (xy 364.408911 -125.738625)
			(xy 364.359334 -125.761267) (xy 364.307039 -125.776622) (xy 364.253091 -125.784378) (xy 364.198589 -125.784378)
			(xy 364.144641 -125.776622) (xy 364.092346 -125.761267) (xy 364.042769 -125.738625) (xy 363.996919 -125.709159)
			(xy 363.955728 -125.673468) (xy 363.920037 -125.632277) (xy 363.890571 -125.586427) (xy 363.867929 -125.53685)
			(xy 363.852574 -125.484555) (xy 363.844818 -125.430607) (xy 363.844332 -125.403356) (xy 359.669682 -125.403356)
			(xy 359.637631 -125.411735) (xy 359.582194 -125.417835) (xy 359.52646 -125.415798) (xy 359.471617 -125.405668)
			(xy 359.418833 -125.387661) (xy 359.369233 -125.36216) (xy 359.323875 -125.329709) (xy 359.283726 -125.291)
			(xy 359.24964 -125.246857) (xy 359.222344 -125.198222) (xy 359.202421 -125.146131) (xy 359.190295 -125.091694)
			(xy 359.186224 -125.036072) (xy 357.729664 -125.036072) (xy 357.728538 -125.043958) (xy 357.71342 -125.09585)
			(xy 357.691126 -125.145086) (xy 357.662101 -125.19068) (xy 357.626928 -125.231718) (xy 357.586311 -125.267376)
			(xy 357.541066 -125.296941) (xy 357.492098 -125.31982) (xy 357.466392 -125.328172) (xy 357.456486 -125.331474)
			(xy 357.330502 -125.457458) (xy 357.329861 -125.463356) (xy 357.331022 -125.475162) (xy 357.332788 -125.480826)
			(xy 357.345742 -125.518672) (xy 357.362506 -125.56744) (xy 357.364938 -125.573957) (xy 357.372799 -125.585427)
			(xy 357.378 -125.590046) (xy 357.383588 -125.594618) (xy 357.396542 -125.599952) (xy 357.403908 -125.600968)
			(xy 357.431157 -125.604964) (xy 357.484201 -125.619778) (xy 357.534562 -125.642067) (xy 357.581195 -125.671366)
			(xy 357.623129 -125.707067) (xy 357.659494 -125.748427) (xy 357.689532 -125.794587) (xy 357.712621 -125.844587)
			(xy 357.727524 -125.894846) (xy 359.386884 -125.894846) (xy 359.390955 -125.839224) (xy 359.403081 -125.784787)
			(xy 359.423004 -125.732696) (xy 359.4503 -125.684061) (xy 359.484386 -125.639918) (xy 359.524535 -125.601209)
			(xy 359.569893 -125.568758) (xy 359.619493 -125.543257) (xy 359.672277 -125.52525) (xy 359.72712 -125.51512)
			(xy 359.782854 -125.513083) (xy 359.838291 -125.519183) (xy 359.892248 -125.533289) (xy 359.943577 -125.555101)
			(xy 359.991183 -125.584155) (xy 360.034051 -125.61983) (xy 360.071268 -125.661367) (xy 360.102041 -125.70788)
			(xy 360.125713 -125.758377) (xy 360.141781 -125.811784) (xy 360.147949 -125.853698) (xy 364.784894 -125.853698)
			(xy 364.78536 -125.826328) (xy 364.793178 -125.772149) (xy 364.808667 -125.719646) (xy 364.831509 -125.669899)
			(xy 364.861233 -125.623932) (xy 364.878874 -125.603) (xy 364.879128 -125.602746) (xy 364.884705 -125.595653)
			(xy 364.890956 -125.578741) (xy 364.89132 -125.569726) (xy 364.89132 -125.50267) (xy 364.890973 -125.493652)
			(xy 364.884718 -125.476735) (xy 364.879128 -125.46965) (xy 364.878874 -125.46965) (xy 364.878874 -125.469396)
			(xy 364.861216 -125.44848) (xy 364.831507 -125.402502) (xy 364.808676 -125.352751) (xy 364.793189 -125.300247)
			(xy 364.785366 -125.246068) (xy 364.784894 -125.218698) (xy 364.78538 -125.191447) (xy 364.793136 -125.137499)
			(xy 364.808491 -125.085204) (xy 364.831133 -125.035627) (xy 364.860599 -124.989777) (xy 364.89629 -124.948586)
			(xy 364.937481 -124.912895) (xy 364.983331 -124.883429) (xy 365.032908 -124.860787) (xy 365.085203 -124.845432)
			(xy 365.139151 -124.837676) (xy 365.193653 -124.837676) (xy 365.247601 -124.845432) (xy 365.299896 -124.860787)
			(xy 365.349473 -124.883429) (xy 365.395323 -124.912895) (xy 365.436514 -124.948586) (xy 365.472205 -124.989777)
			(xy 365.501671 -125.035627) (xy 365.524313 -125.085204) (xy 365.539668 -125.137499) (xy 365.547424 -125.191447)
			(xy 365.54791 -125.218698) (xy 365.54744 -125.246068) (xy 365.539623 -125.300247) (xy 365.524135 -125.35275)
			(xy 365.501294 -125.402497) (xy 365.471571 -125.448464) (xy 365.45393 -125.469396) (xy 365.453676 -125.46965)
			(xy 365.448102 -125.476745) (xy 365.441848 -125.493655) (xy 365.441484 -125.50267) (xy 365.441484 -125.569726)
			(xy 365.441832 -125.578744) (xy 365.448086 -125.59566) (xy 365.453676 -125.602746) (xy 365.45393 -125.602746)
			(xy 365.45393 -125.603) (xy 365.471587 -125.623917) (xy 365.501295 -125.669895) (xy 365.524127 -125.719646)
			(xy 365.539614 -125.77215) (xy 365.547438 -125.826328) (xy 365.54791 -125.853698) (xy 365.547424 -125.880949)
			(xy 365.539668 -125.934897) (xy 365.524313 -125.987192) (xy 365.501671 -126.036769) (xy 365.472205 -126.082619)
			(xy 365.436514 -126.12381) (xy 365.395323 -126.159501) (xy 365.349473 -126.188967) (xy 365.299896 -126.211609)
			(xy 365.247601 -126.226964) (xy 365.193653 -126.23472) (xy 365.139151 -126.23472) (xy 365.085203 -126.226964)
			(xy 365.032908 -126.211609) (xy 364.983331 -126.188967) (xy 364.937481 -126.159501) (xy 364.89629 -126.12381)
			(xy 364.860599 -126.082619) (xy 364.831133 -126.036769) (xy 364.808491 -125.987192) (xy 364.793136 -125.934897)
			(xy 364.78538 -125.880949) (xy 364.784894 -125.853698) (xy 360.147949 -125.853698) (xy 360.149901 -125.86696)
			(xy 360.15041 -125.894846) (xy 360.149901 -125.922732) (xy 360.141781 -125.977908) (xy 360.125713 -126.031315)
			(xy 360.102041 -126.081812) (xy 360.071268 -126.128325) (xy 360.034051 -126.169862) (xy 359.991183 -126.205537)
			(xy 359.943577 -126.234591) (xy 359.892248 -126.256403) (xy 359.838291 -126.270509) (xy 359.782854 -126.276609)
			(xy 359.72712 -126.274572) (xy 359.672277 -126.264442) (xy 359.619493 -126.246435) (xy 359.569893 -126.220934)
			(xy 359.524535 -126.188483) (xy 359.484386 -126.149774) (xy 359.4503 -126.105631) (xy 359.423004 -126.056996)
			(xy 359.403081 -126.004905) (xy 359.390955 -125.950468) (xy 359.386884 -125.894846) (xy 357.727524 -125.894846)
			(xy 357.728278 -125.897388) (xy 357.73618 -125.951891) (xy 357.736648 -125.979428) (xy 357.73616 -126.006679)
			(xy 357.728401 -126.060626) (xy 357.713044 -126.112919) (xy 357.690401 -126.162496) (xy 357.660935 -126.208345)
			(xy 357.625244 -126.249536) (xy 357.584055 -126.285228) (xy 357.538206 -126.314696) (xy 357.488631 -126.337339)
			(xy 357.436338 -126.352698) (xy 357.382391 -126.360459) (xy 357.35514 -126.360936) (xy 357.327608 -126.360449)
			(xy 357.273116 -126.352527) (xy 357.220329 -126.336855) (xy 357.170342 -126.31376) (xy 357.124193 -126.28372)
			(xy 357.082841 -126.24736) (xy 357.047143 -126.205435) (xy 357.017841 -126.158814) (xy 356.995544 -126.108466)
			(xy 356.980715 -126.055436) (xy 356.97668 -126.028196) (xy 356.975664 -126.02083) (xy 356.97033 -126.007876)
			(xy 356.965758 -126.002288) (xy 356.961111 -125.99712) (xy 356.949643 -125.98928) (xy 356.943152 -125.986794)
			(xy 356.894384 -125.97003) (xy 356.856538 -125.957076) (xy 356.850876 -125.955302) (xy 356.83907 -125.954155)
			(xy 356.83317 -125.95479) (xy 356.257606 -126.530354) (xy 365.993426 -126.530354) (xy 365.993968 -126.50269)
			(xy 366.001961 -126.447942) (xy 366.017771 -126.39492) (xy 366.041069 -126.344736) (xy 366.071366 -126.298439)
			(xy 366.108028 -126.257001) (xy 366.150286 -126.221287) (xy 366.173512 -126.20625) (xy 366.183163 -126.199581)
			(xy 366.195622 -126.179744) (xy 366.197388 -126.16815) (xy 366.205262 -126.08814) (xy 366.205858 -126.076503)
			(xy 366.197802 -126.054668) (xy 366.189768 -126.04623) (xy 366.189514 -126.045976) (xy 366.170942 -126.027886)
			(xy 366.138362 -125.987557) (xy 366.111547 -125.943184) (xy 366.090993 -125.895587) (xy 366.077078 -125.845645)
			(xy 366.070059 -125.794277) (xy 366.069626 -125.768354) (xy 366.070035 -125.7411) (xy 366.077799 -125.687148)
			(xy 366.093161 -125.63485) (xy 366.11581 -125.58527) (xy 366.145285 -125.539418) (xy 366.180984 -125.498228)
			(xy 366.222182 -125.462537) (xy 366.26804 -125.433072) (xy 366.317625 -125.410433) (xy 366.369926 -125.395082)
			(xy 366.42388 -125.387329) (xy 366.451134 -125.386846) (xy 366.478505 -125.387281) (xy 366.532686 -125.395105)
			(xy 366.58519 -125.4106) (xy 366.634937 -125.433449) (xy 366.680902 -125.463181) (xy 366.701832 -125.480826)
			(xy 366.702086 -125.48108) (xy 366.709166 -125.486676) (xy 366.726088 -125.492915) (xy 366.735106 -125.493272)
			(xy 366.802162 -125.493272) (xy 366.811178 -125.492903) (xy 366.828095 -125.486664) (xy 366.835182 -125.48108)
			(xy 366.835182 -125.480826) (xy 366.835436 -125.480826) (xy 366.856385 -125.463207) (xy 366.902353 -125.433492)
			(xy 366.952096 -125.410651) (xy 367.004593 -125.395156) (xy 367.058766 -125.387322) (xy 367.086134 -125.386846)
			(xy 367.113384 -125.387346) (xy 367.167329 -125.395106) (xy 367.21962 -125.410463) (xy 367.269195 -125.433105)
			(xy 367.315043 -125.46257) (xy 367.356231 -125.49826) (xy 367.391922 -125.539448) (xy 367.421389 -125.585295)
			(xy 367.444033 -125.634868) (xy 367.459391 -125.687159) (xy 367.467153 -125.741104) (xy 367.467642 -125.768354)
			(xy 367.467113 -125.797271) (xy 367.458389 -125.854442) (xy 367.441135 -125.909642) (xy 367.415745 -125.961604)
			(xy 367.382803 -126.009138) (xy 367.343062 -126.051155) (xy 367.320576 -126.069344) (xy 367.311755 -126.076938)
			(xy 367.30158 -126.097849) (xy 367.301018 -126.109476) (xy 367.301018 -126.189232) (xy 367.301547 -126.200865)
			(xy 367.311742 -126.221775) (xy 367.320576 -126.229364) (xy 367.343037 -126.247581) (xy 367.382775 -126.289595)
			(xy 367.415717 -126.337124) (xy 367.44111 -126.38908) (xy 367.45837 -126.444274) (xy 367.467104 -126.501439)
			(xy 367.467642 -126.530354) (xy 367.467102 -126.557604) (xy 367.459352 -126.611551) (xy 367.447251 -126.652782)
			(xy 367.738914 -126.652782) (xy 367.739366 -126.625411) (xy 367.747187 -126.571231) (xy 367.762679 -126.518728)
			(xy 367.785524 -126.468981) (xy 367.815251 -126.423015) (xy 367.832894 -126.402084) (xy 367.833148 -126.40183)
			(xy 367.838734 -126.394743) (xy 367.84498 -126.377826) (xy 367.84534 -126.36881) (xy 367.84534 -126.301754)
			(xy 367.84497 -126.292738) (xy 367.838733 -126.27582) (xy 367.833148 -126.268734) (xy 367.832894 -126.268734)
			(xy 367.832894 -126.26848) (xy 367.815237 -126.247561) (xy 367.785515 -126.20159) (xy 367.762673 -126.151841)
			(xy 367.74718 -126.099337) (xy 367.739354 -126.045158) (xy 367.739355 -125.990415) (xy 367.747186 -125.936236)
			(xy 367.762683 -125.883733) (xy 367.785529 -125.833986) (xy 367.815253 -125.788017) (xy 367.832894 -125.767084)
			(xy 367.833148 -125.76683) (xy 367.838734 -125.759743) (xy 367.84498 -125.742826) (xy 367.84534 -125.73381)
			(xy 367.84534 -125.666754) (xy 367.84497 -125.657738) (xy 367.838733 -125.64082) (xy 367.833148 -125.633734)
			(xy 367.832894 -125.633734) (xy 367.832894 -125.63348) (xy 367.815237 -125.612561) (xy 367.785515 -125.56659)
			(xy 367.762673 -125.516841) (xy 367.74718 -125.464337) (xy 367.739354 -125.410158) (xy 367.739355 -125.355415)
			(xy 367.747186 -125.301236) (xy 367.762683 -125.248733) (xy 367.785529 -125.198986) (xy 367.815253 -125.153017)
			(xy 367.832894 -125.132084) (xy 367.833148 -125.13183) (xy 367.838734 -125.124743) (xy 367.84498 -125.107826)
			(xy 367.84534 -125.09881) (xy 367.84534 -125.031754) (xy 367.84497 -125.022738) (xy 367.838733 -125.00582)
			(xy 367.833148 -124.998734) (xy 367.832894 -124.998734) (xy 367.832894 -124.99848) (xy 367.815278 -124.977529)
			(xy 367.785563 -124.931562) (xy 367.762723 -124.881819) (xy 367.747226 -124.829322) (xy 367.739392 -124.77515)
			(xy 367.738914 -124.747782) (xy 367.7394 -124.720531) (xy 367.747156 -124.666583) (xy 367.762511 -124.614288)
			(xy 367.785153 -124.564711) (xy 367.814619 -124.518861) (xy 367.85031 -124.47767) (xy 367.891501 -124.441979)
			(xy 367.937351 -124.412513) (xy 367.986928 -124.389871) (xy 368.039223 -124.374516) (xy 368.093171 -124.36676)
			(xy 368.147673 -124.36676) (xy 368.201621 -124.374516) (xy 368.253916 -124.389871) (xy 368.303493 -124.412513)
			(xy 368.349343 -124.441979) (xy 368.390534 -124.47767) (xy 368.426225 -124.518861) (xy 368.455691 -124.564711)
			(xy 368.478333 -124.614288) (xy 368.493688 -124.666583) (xy 368.501444 -124.720531) (xy 368.50193 -124.747782)
			(xy 368.50147 -124.775153) (xy 368.493654 -124.829333) (xy 368.478164 -124.881837) (xy 368.45532 -124.931583)
			(xy 368.425593 -124.977549) (xy 368.40795 -124.99848) (xy 368.407696 -124.998734) (xy 368.40213 -125.005835)
			(xy 368.395871 -125.022741) (xy 368.395504 -125.031754) (xy 368.395504 -125.09881) (xy 368.395855 -125.107827)
			(xy 368.402107 -125.124744) (xy 368.407696 -125.13183) (xy 368.40795 -125.13183) (xy 368.40795 -125.132084)
			(xy 368.425574 -125.153031) (xy 368.455301 -125.198995) (xy 368.478149 -125.248739) (xy 368.493648 -125.301239)
			(xy 368.501479 -125.355416) (xy 368.50148 -125.410156) (xy 368.493654 -125.464334) (xy 368.478159 -125.516835)
			(xy 368.455314 -125.566581) (xy 368.42559 -125.612548) (xy 368.40795 -125.63348) (xy 368.407696 -125.633734)
			(xy 368.40213 -125.640835) (xy 368.395871 -125.657741) (xy 368.395504 -125.666754) (xy 368.395504 -125.73381)
			(xy 368.395855 -125.742827) (xy 368.402107 -125.759744) (xy 368.407696 -125.76683) (xy 368.40795 -125.76683)
			(xy 368.40795 -125.767084) (xy 368.425574 -125.788031) (xy 368.455301 -125.833995) (xy 368.478149 -125.883739)
			(xy 368.493648 -125.936239) (xy 368.501479 -125.990416) (xy 368.50148 -126.045156) (xy 368.493654 -126.099334)
			(xy 368.478159 -126.151835) (xy 368.455314 -126.201581) (xy 368.42559 -126.247548) (xy 368.40795 -126.26848)
			(xy 368.407696 -126.268734) (xy 368.40213 -126.275835) (xy 368.395871 -126.292741) (xy 368.395504 -126.301754)
			(xy 368.395504 -126.36881) (xy 368.395855 -126.377827) (xy 368.402107 -126.394744) (xy 368.407696 -126.40183)
			(xy 368.40795 -126.40183) (xy 368.40795 -126.402084) (xy 368.425587 -126.423018) (xy 368.455301 -126.468989)
			(xy 368.478138 -126.518736) (xy 368.493629 -126.571237) (xy 368.501457 -126.625413) (xy 368.50193 -126.652782)
			(xy 368.501444 -126.680033) (xy 368.493688 -126.733981) (xy 368.478333 -126.786276) (xy 368.455691 -126.835853)
			(xy 368.426225 -126.881703) (xy 368.390534 -126.922894) (xy 368.349343 -126.958585) (xy 368.303493 -126.988051)
			(xy 368.253916 -127.010693) (xy 368.201621 -127.026048) (xy 368.147673 -127.033804) (xy 368.093171 -127.033804)
			(xy 368.039223 -127.026048) (xy 367.986928 -127.010693) (xy 367.937351 -126.988051) (xy 367.891501 -126.958585)
			(xy 367.85031 -126.922894) (xy 367.814619 -126.881703) (xy 367.785153 -126.835853) (xy 367.762511 -126.786276)
			(xy 367.747156 -126.733981) (xy 367.7394 -126.680033) (xy 367.738914 -126.652782) (xy 367.447251 -126.652782)
			(xy 367.444004 -126.663845) (xy 367.421369 -126.713423) (xy 367.391909 -126.759274) (xy 367.356223 -126.800467)
			(xy 367.315038 -126.836161) (xy 367.269193 -126.865631) (xy 367.21962 -126.888276) (xy 367.167329 -126.903635)
			(xy 367.113384 -126.911396) (xy 367.086134 -126.911862) (xy 367.059818 -126.911451) (xy 367.007687 -126.904206)
			(xy 366.957042 -126.889877) (xy 366.908843 -126.868734) (xy 366.864001 -126.841177) (xy 366.823365 -126.807728)
			(xy 366.80521 -126.788672) (xy 366.797677 -126.781283) (xy 366.778406 -126.772749) (xy 366.767872 -126.772162)
			(xy 366.693196 -126.772162) (xy 366.682646 -126.772687) (xy 366.663352 -126.781226) (xy 366.655858 -126.788672)
			(xy 366.63771 -126.807736) (xy 366.59708 -126.841193) (xy 366.552238 -126.868752) (xy 366.504035 -126.889889)
			(xy 366.453386 -126.904204) (xy 366.401251 -126.911426) (xy 366.374934 -126.911862) (xy 366.34768 -126.911413)
			(xy 366.293726 -126.903659) (xy 366.241425 -126.888305) (xy 366.191842 -126.865663) (xy 366.145987 -126.836195)
			(xy 366.104792 -126.800499) (xy 366.069098 -126.759304) (xy 366.039631 -126.713447) (xy 366.01699 -126.663864)
			(xy 366.001638 -126.611562) (xy 365.993886 -126.557608) (xy 365.993426 -126.530354) (xy 356.257606 -126.530354)
			(xy 355.736652 -127.051308) (xy 359.044238 -127.051308) (xy 359.048309 -126.995686) (xy 359.060435 -126.941249)
			(xy 359.080358 -126.889158) (xy 359.107654 -126.840523) (xy 359.14174 -126.79638) (xy 359.181889 -126.757671)
			(xy 359.227247 -126.72522) (xy 359.276847 -126.699719) (xy 359.329631 -126.681712) (xy 359.384474 -126.671582)
			(xy 359.440208 -126.669545) (xy 359.495645 -126.675645) (xy 359.549602 -126.689751) (xy 359.600931 -126.711563)
			(xy 359.648537 -126.740617) (xy 359.691405 -126.776292) (xy 359.728622 -126.817829) (xy 359.759395 -126.864342)
			(xy 359.783067 -126.914839) (xy 359.799135 -126.968246) (xy 359.807255 -127.023422) (xy 359.807764 -127.051308)
			(xy 359.807255 -127.079194) (xy 359.799135 -127.13437) (xy 359.783067 -127.187777) (xy 359.759395 -127.238274)
			(xy 359.728622 -127.284787) (xy 359.691405 -127.326324) (xy 359.648537 -127.361999) (xy 359.600931 -127.391053)
			(xy 359.549602 -127.412865) (xy 359.495645 -127.426971) (xy 359.440208 -127.433071) (xy 359.384474 -127.431034)
			(xy 359.329631 -127.420904) (xy 359.276847 -127.402897) (xy 359.227247 -127.377396) (xy 359.181889 -127.344945)
			(xy 359.14174 -127.306236) (xy 359.107654 -127.262093) (xy 359.080358 -127.213458) (xy 359.060435 -127.161367)
			(xy 359.048309 -127.10693) (xy 359.044238 -127.051308) (xy 355.736652 -127.051308) (xy 355.51364 -127.27432)
			(xy 355.513132 -127.281178) (xy 355.513132 -128.252747) (xy 358.028528 -128.252747) (xy 358.028528 -128.198253)
			(xy 358.036283 -128.144313) (xy 358.051636 -128.092025) (xy 358.074274 -128.042455) (xy 358.103736 -127.996611)
			(xy 358.139422 -127.955426) (xy 358.180606 -127.919739) (xy 358.22645 -127.890277) (xy 358.27602 -127.867638)
			(xy 358.328307 -127.852285) (xy 358.382247 -127.844529) (xy 358.409494 -127.844042) (xy 358.436865 -127.844501)
			(xy 358.491044 -127.852319) (xy 358.543548 -127.867809) (xy 358.593295 -127.890653) (xy 358.639261 -127.92038)
			(xy 358.660192 -127.938022) (xy 358.660446 -127.938276) (xy 358.667537 -127.943855) (xy 358.684451 -127.950104)
			(xy 358.693466 -127.950468) (xy 358.760522 -127.950468) (xy 358.769541 -127.950129) (xy 358.786458 -127.94387)
			(xy 358.793542 -127.938276) (xy 358.793542 -127.938022) (xy 358.793796 -127.938022) (xy 358.814729 -127.920381)
			(xy 358.860697 -127.890657) (xy 358.910443 -127.867811) (xy 358.962945 -127.852315) (xy 359.017123 -127.844486)
			(xy 359.071865 -127.844486) (xy 359.126043 -127.852315) (xy 359.178545 -127.867811) (xy 359.228291 -127.890657)
			(xy 359.274259 -127.920381) (xy 359.295192 -127.938022) (xy 359.295446 -127.938276) (xy 359.302537 -127.943855)
			(xy 359.319451 -127.950104) (xy 359.328466 -127.950468) (xy 359.395522 -127.950468) (xy 359.404541 -127.950129)
			(xy 359.421458 -127.94387) (xy 359.428542 -127.938276) (xy 359.428542 -127.938022) (xy 359.428796 -127.938022)
			(xy 359.449722 -127.920375) (xy 359.495696 -127.890663) (xy 359.545445 -127.867829) (xy 359.597947 -127.85234)
			(xy 359.652124 -127.844514) (xy 359.679494 -127.844042) (xy 359.706751 -127.844405) (xy 359.760709 -127.852162)
			(xy 359.813015 -127.867519) (xy 359.862602 -127.890165) (xy 359.908462 -127.919636) (xy 359.949661 -127.955335)
			(xy 359.98536 -127.996533) (xy 360.014833 -128.042392) (xy 360.037478 -128.091979) (xy 360.052837 -128.144285)
			(xy 360.060595 -128.198243) (xy 360.060595 -128.252757) (xy 360.052837 -128.306715) (xy 360.037478 -128.359021)
			(xy 360.014833 -128.408608) (xy 359.98536 -128.454467) (xy 359.949661 -128.495665) (xy 359.908462 -128.531364)
			(xy 359.862602 -128.560835) (xy 359.813015 -128.583481) (xy 359.760709 -128.598838) (xy 359.706751 -128.606595)
			(xy 359.679494 -128.607058) (xy 359.652123 -128.606606) (xy 359.597943 -128.598786) (xy 359.545439 -128.583294)
			(xy 359.495693 -128.560449) (xy 359.449727 -128.530721) (xy 359.428796 -128.513078) (xy 359.428542 -128.512824)
			(xy 359.421454 -128.50724) (xy 359.404538 -128.500994) (xy 359.395522 -128.500632) (xy 359.328466 -128.500632)
			(xy 359.319447 -128.500966) (xy 359.302529 -128.507229) (xy 359.295446 -128.512824) (xy 359.295192 -128.513078)
			(xy 359.274259 -128.530719) (xy 359.228291 -128.560443) (xy 359.178545 -128.583289) (xy 359.126043 -128.598785)
			(xy 359.071865 -128.606614) (xy 359.017123 -128.606614) (xy 358.962945 -128.598785) (xy 358.910443 -128.583289)
			(xy 358.860697 -128.560443) (xy 358.814729 -128.530719) (xy 358.793796 -128.513078) (xy 358.793542 -128.512824)
			(xy 358.786454 -128.50724) (xy 358.769538 -128.500994) (xy 358.760522 -128.500632) (xy 358.693466 -128.500632)
			(xy 358.684447 -128.500966) (xy 358.667529 -128.507229) (xy 358.660446 -128.512824) (xy 358.660446 -128.513078)
			(xy 358.660192 -128.513078) (xy 358.639271 -128.530731) (xy 358.593295 -128.560441) (xy 358.543545 -128.583275)
			(xy 358.491042 -128.598763) (xy 358.436864 -128.606587) (xy 358.409494 -128.607058) (xy 358.382247 -128.606471)
			(xy 358.328307 -128.598715) (xy 358.27602 -128.583362) (xy 358.22645 -128.560723) (xy 358.180606 -128.531261)
			(xy 358.139422 -128.495574) (xy 358.103736 -128.454389) (xy 358.074274 -128.408545) (xy 358.051636 -128.358975)
			(xy 358.036283 -128.306687) (xy 358.028528 -128.252747) (xy 355.513132 -128.252747) (xy 355.513132 -131.316222)
			(xy 355.512635 -131.341512) (xy 355.504724 -131.391468) (xy 355.489101 -131.439574) (xy 355.485239 -131.447157)
			(xy 358.013409 -131.447157) (xy 358.013409 -131.392643) (xy 358.021167 -131.338685) (xy 358.036525 -131.28638)
			(xy 358.059171 -131.236794) (xy 358.088644 -131.190935) (xy 358.124342 -131.149737) (xy 358.165541 -131.114039)
			(xy 358.211401 -131.084567) (xy 358.260988 -131.061923) (xy 358.313293 -131.046565) (xy 358.367251 -131.038808)
			(xy 358.394508 -131.038346) (xy 358.421879 -131.038796) (xy 358.476059 -131.046616) (xy 358.528563 -131.062108)
			(xy 358.57831 -131.084954) (xy 358.624275 -131.114683) (xy 358.645206 -131.132326) (xy 358.64546 -131.13258)
			(xy 358.652547 -131.138165) (xy 358.669464 -131.144411) (xy 358.67848 -131.144772) (xy 358.745536 -131.144772)
			(xy 358.754555 -131.144438) (xy 358.771472 -131.138175) (xy 358.778556 -131.13258) (xy 358.778556 -131.132326)
			(xy 358.77881 -131.132326) (xy 358.799743 -131.114685) (xy 358.845711 -131.084961) (xy 358.895457 -131.062115)
			(xy 358.947959 -131.046619) (xy 359.002137 -131.03879) (xy 359.056879 -131.03879) (xy 359.111057 -131.046619)
			(xy 359.163559 -131.062115) (xy 359.213305 -131.084961) (xy 359.259273 -131.114685) (xy 359.280206 -131.132326)
			(xy 359.28046 -131.13258) (xy 359.287547 -131.138165) (xy 359.304464 -131.144411) (xy 359.31348 -131.144772)
			(xy 359.380536 -131.144772) (xy 359.389555 -131.144438) (xy 359.406472 -131.138175) (xy 359.413556 -131.13258)
			(xy 359.413556 -131.132326) (xy 359.41381 -131.132326) (xy 359.434731 -131.114673) (xy 359.480706 -131.084962)
			(xy 359.530457 -131.062129) (xy 359.58296 -131.046641) (xy 359.637138 -131.038817) (xy 359.664508 -131.038346)
			(xy 359.691756 -131.038925) (xy 359.745696 -131.046681) (xy 359.797983 -131.062035) (xy 359.847553 -131.084674)
			(xy 359.893397 -131.114137) (xy 359.934582 -131.149824) (xy 359.970268 -131.191009) (xy 359.99973 -131.236854)
			(xy 360.022368 -131.286424) (xy 360.037721 -131.338712) (xy 360.045476 -131.392652) (xy 360.045476 -131.447148)
			(xy 360.037721 -131.501088) (xy 360.022368 -131.553376) (xy 359.99973 -131.602946) (xy 359.970268 -131.648791)
			(xy 359.934582 -131.689976) (xy 359.893397 -131.725663) (xy 359.847553 -131.755126) (xy 359.797983 -131.777765)
			(xy 359.745696 -131.793119) (xy 359.691756 -131.800875) (xy 359.664508 -131.801362) (xy 359.637137 -131.800901)
			(xy 359.582958 -131.793083) (xy 359.530454 -131.777593) (xy 359.480708 -131.75475) (xy 359.434741 -131.725024)
			(xy 359.41381 -131.707382) (xy 359.413556 -131.707128) (xy 359.406464 -131.70155) (xy 359.389551 -131.6953)
			(xy 359.380536 -131.694936) (xy 359.31348 -131.694936) (xy 359.304461 -131.695276) (xy 359.287544 -131.701534)
			(xy 359.28046 -131.707128) (xy 359.280206 -131.707382) (xy 359.259273 -131.725023) (xy 359.213305 -131.754747)
			(xy 359.163559 -131.777593) (xy 359.111057 -131.793089) (xy 359.056879 -131.800918) (xy 359.002137 -131.800918)
			(xy 358.947959 -131.793089) (xy 358.895457 -131.777593) (xy 358.845711 -131.754747) (xy 358.799743 -131.725023)
			(xy 358.77881 -131.707382) (xy 358.778556 -131.707128) (xy 358.771464 -131.70155) (xy 358.754551 -131.6953)
			(xy 358.745536 -131.694936) (xy 358.67848 -131.694936) (xy 358.669461 -131.695276) (xy 358.652544 -131.701534)
			(xy 358.64546 -131.707128) (xy 358.64546 -131.707382) (xy 358.645206 -131.707382) (xy 358.62428 -131.725029)
			(xy 358.578306 -131.75474) (xy 358.528557 -131.777575) (xy 358.476055 -131.793064) (xy 358.421878 -131.80089)
			(xy 358.394508 -131.801362) (xy 358.367251 -131.800992) (xy 358.313293 -131.793235) (xy 358.260988 -131.777877)
			(xy 358.211401 -131.755233) (xy 358.165541 -131.725761) (xy 358.124342 -131.690063) (xy 358.088644 -131.648865)
			(xy 358.059171 -131.603006) (xy 358.036525 -131.55342) (xy 358.021167 -131.501115) (xy 358.013409 -131.447157)
			(xy 355.485239 -131.447157) (xy 355.466148 -131.484646) (xy 355.436432 -131.525575) (xy 355.418898 -131.543806)
			(xy 354.791772 -132.170678) (xy 354.720652 -132.241798) (xy 354.716069 -132.246746) (xy 354.709386 -132.258453)
			(xy 354.707444 -132.264912) (xy 354.70592 -132.274056) (xy 354.70592 -133.443726) (xy 359.422954 -133.443726)
			(xy 359.423421 -133.417412) (xy 359.430654 -133.365283) (xy 359.444972 -133.314639) (xy 359.466104 -133.26644)
			(xy 359.493651 -133.221596) (xy 359.527091 -133.180958) (xy 359.546144 -133.162802) (xy 359.553538 -133.155274)
			(xy 359.562069 -133.135999) (xy 359.562654 -133.125464) (xy 359.562654 -133.050788) (xy 359.562158 -133.040234)
			(xy 359.553601 -133.020938) (xy 359.546144 -133.01345) (xy 359.527061 -132.995323) (xy 359.493608 -132.954686)
			(xy 359.466054 -132.909839) (xy 359.444921 -132.861633) (xy 359.430609 -132.810981) (xy 359.42339 -132.758844)
			(xy 359.422954 -132.732526) (xy 359.42344 -132.705275) (xy 359.431196 -132.651327) (xy 359.446551 -132.599032)
			(xy 359.469193 -132.549455) (xy 359.498659 -132.503605) (xy 359.53435 -132.462414) (xy 359.575541 -132.426723)
			(xy 359.621391 -132.397257) (xy 359.670968 -132.374615) (xy 359.723263 -132.35926) (xy 359.777211 -132.351504)
			(xy 359.831713 -132.351504) (xy 359.885661 -132.35926) (xy 359.937956 -132.374615) (xy 359.987533 -132.397257)
			(xy 360.033383 -132.426723) (xy 360.074574 -132.462414) (xy 360.110265 -132.503605) (xy 360.139731 -132.549455)
			(xy 360.162373 -132.599032) (xy 360.177728 -132.651327) (xy 360.185484 -132.705275) (xy 360.18597 -132.732526)
			(xy 360.185529 -132.758841) (xy 360.17829 -132.810971) (xy 360.163967 -132.861615) (xy 360.142829 -132.909814)
			(xy 360.115278 -132.954657) (xy 360.081834 -132.995295) (xy 360.06278 -133.01345) (xy 360.055351 -133.020948)
			(xy 360.046843 -133.040246) (xy 360.04627 -133.050788) (xy 360.04627 -133.125464) (xy 360.046814 -133.136012)
			(xy 360.05534 -133.155307) (xy 360.06278 -133.162802) (xy 360.081826 -133.180968) (xy 360.115285 -133.221595)
			(xy 360.142845 -133.266433) (xy 360.163986 -133.314632) (xy 360.178305 -133.365278) (xy 360.185531 -133.41741)
			(xy 360.18597 -133.443726) (xy 360.185484 -133.470977) (xy 360.177728 -133.524925) (xy 360.162373 -133.57722)
			(xy 360.139731 -133.626797) (xy 360.110265 -133.672647) (xy 360.074574 -133.713838) (xy 360.033383 -133.749529)
			(xy 359.987533 -133.778995) (xy 359.937956 -133.801637) (xy 359.885661 -133.816992) (xy 359.831713 -133.824748)
			(xy 359.777211 -133.824748) (xy 359.723263 -133.816992) (xy 359.670968 -133.801637) (xy 359.621391 -133.778995)
			(xy 359.575541 -133.749529) (xy 359.53435 -133.713838) (xy 359.498659 -133.672647) (xy 359.469193 -133.626797)
			(xy 359.446551 -133.57722) (xy 359.431196 -133.524925) (xy 359.42344 -133.470977) (xy 359.422954 -133.443726)
			(xy 354.70592 -133.443726) (xy 354.70592 -133.561836) (xy 354.706408 -133.571282) (xy 354.713312 -133.588873)
			(xy 354.719382 -133.596126) (xy 354.784914 -133.655816) (xy 354.786692 -133.65734) (xy 354.807012 -133.663944)
			(xy 354.817934 -133.662928) (xy 354.827938 -133.661954) (xy 354.848015 -133.660937) (xy 354.858066 -133.660896)
			(xy 354.88532 -133.661357) (xy 354.939274 -133.66911) (xy 354.991576 -133.684463) (xy 355.041159 -133.707103)
			(xy 355.087016 -133.73657) (xy 355.128213 -133.772263) (xy 355.16391 -133.813456) (xy 355.19338 -133.859311)
			(xy 355.216025 -133.908893) (xy 355.231383 -133.961193) (xy 355.239141 -134.015146) (xy 355.239141 -134.069654)
			(xy 355.231383 -134.123607) (xy 355.216025 -134.175907) (xy 355.19338 -134.225489) (xy 355.16391 -134.271344)
			(xy 355.128213 -134.312537) (xy 355.087016 -134.34823) (xy 355.041159 -134.377697) (xy 354.991576 -134.400337)
			(xy 354.939274 -134.41569) (xy 354.88532 -134.423443) (xy 354.858066 -134.423912) (xy 354.848015 -134.423867)
			(xy 354.827938 -134.422851) (xy 354.817934 -134.42188) (xy 354.807012 -134.420864) (xy 354.786692 -134.427468)
			(xy 354.784914 -134.428992) (xy 354.719382 -134.488682) (xy 354.713225 -134.495885) (xy 354.706295 -134.513505)
			(xy 354.70592 -134.522972) (xy 354.70592 -135.142051) (xy 357.66197 -135.142051) (xy 357.66197 -135.087549)
			(xy 357.669726 -135.033603) (xy 357.68508 -134.981309) (xy 357.707719 -134.931733) (xy 357.737184 -134.885883)
			(xy 357.772873 -134.844693) (xy 357.814061 -134.809) (xy 357.859908 -134.779533) (xy 357.909483 -134.756889)
			(xy 357.961776 -134.741532) (xy 358.015721 -134.733772) (xy 358.042972 -134.733284) (xy 358.07189 -134.73379)
			(xy 358.129063 -134.742517) (xy 358.184263 -134.759776) (xy 358.236226 -134.785169) (xy 358.283759 -134.818117)
			(xy 358.325774 -134.857862) (xy 358.343962 -134.88035) (xy 358.351755 -134.889337) (xy 358.37322 -134.899526)
			(xy 358.38511 -134.899908) (xy 358.478582 -134.897876) (xy 358.499918 -134.8867) (xy 358.506776 -134.876794)
			(xy 358.522175 -134.855885) (xy 358.557753 -134.818058) (xy 358.598132 -134.785406) (xy 358.642566 -134.758531)
			(xy 358.690235 -134.737931) (xy 358.740256 -134.723985) (xy 358.791707 -134.716952) (xy 358.817672 -134.71652)
			(xy 358.845042 -134.716998) (xy 358.899221 -134.724812) (xy 358.951724 -134.740298) (xy 359.001471 -134.763137)
			(xy 359.047438 -134.79286) (xy 359.06837 -134.8105) (xy 359.068624 -134.810754) (xy 359.075695 -134.816363)
			(xy 359.092624 -134.822595) (xy 359.101644 -134.822946) (xy 359.1687 -134.822946) (xy 359.177718 -134.822601)
			(xy 359.194636 -134.816346) (xy 359.20172 -134.810754) (xy 359.20172 -134.8105) (xy 359.201974 -134.8105)
			(xy 359.222907 -134.792859) (xy 359.268875 -134.763135) (xy 359.318621 -134.740289) (xy 359.371123 -134.724793)
			(xy 359.425301 -134.716964) (xy 359.480043 -134.716964) (xy 359.534221 -134.724793) (xy 359.586723 -134.740289)
			(xy 359.636469 -134.763135) (xy 359.682437 -134.792859) (xy 359.70337 -134.8105) (xy 359.703624 -134.810754)
			(xy 359.710695 -134.816363) (xy 359.727624 -134.822595) (xy 359.736644 -134.822946) (xy 359.8037 -134.822946)
			(xy 359.812718 -134.822601) (xy 359.829636 -134.816346) (xy 359.83672 -134.810754) (xy 359.837228 -134.8105)
			(xy 359.849966 -134.79956) (xy 359.877055 -134.779716) (xy 359.89133 -134.770876) (xy 359.90022 -134.765542)
			(xy 359.912412 -134.748524) (xy 359.932732 -134.655306) (xy 359.928414 -134.634732) (xy 359.922572 -134.626096)
			(xy 359.906565 -134.602037) (xy 359.881225 -134.550103) (xy 359.864001 -134.494944) (xy 359.855288 -134.437819)
			(xy 359.854754 -134.408926) (xy 359.85524 -134.381675) (xy 359.862996 -134.327727) (xy 359.878351 -134.275432)
			(xy 359.900993 -134.225855) (xy 359.930459 -134.180005) (xy 359.96615 -134.138814) (xy 360.007341 -134.103123)
			(xy 360.053191 -134.073657) (xy 360.102768 -134.051015) (xy 360.155063 -134.03566) (xy 360.209011 -134.027904)
			(xy 360.263513 -134.027904) (xy 360.317461 -134.03566) (xy 360.369756 -134.051015) (xy 360.419333 -134.073657)
			(xy 360.465183 -134.103123) (xy 360.506374 -134.138814) (xy 360.542065 -134.180005) (xy 360.571531 -134.225855)
			(xy 360.594173 -134.275432) (xy 360.609528 -134.327727) (xy 360.617284 -134.381675) (xy 360.61777 -134.408926)
			(xy 360.617319 -134.437019) (xy 360.609086 -134.492599) (xy 360.592789 -134.546371) (xy 360.56878 -134.597169)
			(xy 360.537578 -134.643895) (xy 360.499859 -134.685539) (xy 360.456438 -134.721198) (xy 360.432604 -134.736078)
			(xy 360.423714 -134.741412) (xy 360.411522 -134.75843) (xy 360.391202 -134.851648) (xy 360.39552 -134.872222)
			(xy 360.401362 -134.880858) (xy 360.417342 -134.904935) (xy 360.44269 -134.956861) (xy 360.459922 -135.012015)
			(xy 360.468643 -135.069137) (xy 360.46918 -135.098028) (xy 360.468748 -135.125281) (xy 360.460987 -135.179232)
			(xy 360.445627 -135.23153) (xy 360.422981 -135.281109) (xy 360.393509 -135.326961) (xy 360.357812 -135.368151)
			(xy 360.316616 -135.403842) (xy 360.27076 -135.433307) (xy 360.221177 -135.455947) (xy 360.168878 -135.471299)
			(xy 360.114925 -135.479052) (xy 360.087672 -135.479536) (xy 360.0603 -135.479102) (xy 360.006119 -135.471279)
			(xy 359.953615 -135.455783) (xy 359.903869 -135.432934) (xy 359.857904 -135.403201) (xy 359.836974 -135.385556)
			(xy 359.83672 -135.385302) (xy 359.829632 -135.379718) (xy 359.812716 -135.37347) (xy 359.8037 -135.37311)
			(xy 359.736644 -135.37311) (xy 359.727629 -135.373486) (xy 359.710712 -135.37972) (xy 359.703624 -135.385302)
			(xy 359.703624 -135.385556) (xy 359.70337 -135.385556) (xy 359.682437 -135.403197) (xy 359.636469 -135.432921)
			(xy 359.586723 -135.455767) (xy 359.534221 -135.471263) (xy 359.480043 -135.479092) (xy 359.425301 -135.479092)
			(xy 359.371123 -135.471263) (xy 359.318621 -135.455767) (xy 359.268875 -135.432921) (xy 359.222907 -135.403197)
			(xy 359.201974 -135.385556) (xy 359.20172 -135.385302) (xy 359.194632 -135.379718) (xy 359.177716 -135.37347)
			(xy 359.1687 -135.37311) (xy 359.101644 -135.37311) (xy 359.092629 -135.373486) (xy 359.075712 -135.37972)
			(xy 359.068624 -135.385302) (xy 359.068624 -135.385556) (xy 359.06837 -135.385556) (xy 359.047417 -135.403169)
			(xy 359.00145 -135.432886) (xy 358.951708 -135.455728) (xy 358.899212 -135.471225) (xy 358.84504 -135.479059)
			(xy 358.817672 -135.479536) (xy 358.788756 -135.47899) (xy 358.731585 -135.47027) (xy 358.676386 -135.453019)
			(xy 358.624423 -135.427633) (xy 358.576889 -135.394693) (xy 358.534872 -135.354954) (xy 358.516682 -135.33247)
			(xy 358.508866 -135.323507) (xy 358.487419 -135.313305) (xy 358.475534 -135.312912) (xy 358.382062 -135.314944)
			(xy 358.360726 -135.32612) (xy 358.353868 -135.336026) (xy 358.338447 -135.356919) (xy 358.302873 -135.394745)
			(xy 358.262497 -135.427398) (xy 358.218066 -135.454275) (xy 358.170402 -135.474878) (xy 358.120383 -135.488827)
			(xy 358.068936 -135.495865) (xy 358.042972 -135.4963) (xy 358.015721 -135.495828) (xy 357.961776 -135.488068)
			(xy 357.909483 -135.472711) (xy 357.859908 -135.450067) (xy 357.814061 -135.4206) (xy 357.772873 -135.384907)
			(xy 357.737184 -135.343717) (xy 357.707719 -135.297867) (xy 357.68508 -135.248291) (xy 357.669726 -135.195997)
			(xy 357.66197 -135.142051) (xy 354.70592 -135.142051) (xy 354.70592 -135.689594) (xy 355.583234 -135.689594)
			(xy 355.587305 -135.633972) (xy 355.599431 -135.579535) (xy 355.619354 -135.527444) (xy 355.64665 -135.478809)
			(xy 355.680736 -135.434666) (xy 355.720885 -135.395957) (xy 355.766243 -135.363506) (xy 355.815843 -135.338005)
			(xy 355.868627 -135.319998) (xy 355.92347 -135.309868) (xy 355.979204 -135.307831) (xy 356.034641 -135.313931)
			(xy 356.088598 -135.328037) (xy 356.139927 -135.349849) (xy 356.187533 -135.378903) (xy 356.230401 -135.414578)
			(xy 356.267618 -135.456115) (xy 356.298391 -135.502628) (xy 356.322063 -135.553125) (xy 356.338131 -135.606532)
			(xy 356.346251 -135.661708) (xy 356.34676 -135.689594) (xy 356.346251 -135.71748) (xy 356.338131 -135.772656)
			(xy 356.322063 -135.826063) (xy 356.302926 -135.866886) (xy 356.73995 -135.866886) (xy 356.744021 -135.811264)
			(xy 356.756147 -135.756827) (xy 356.77607 -135.704736) (xy 356.803366 -135.656101) (xy 356.837452 -135.611958)
			(xy 356.877601 -135.573249) (xy 356.922959 -135.540798) (xy 356.972559 -135.515297) (xy 357.025343 -135.49729)
			(xy 357.080186 -135.48716) (xy 357.13592 -135.485123) (xy 357.191357 -135.491223) (xy 357.245314 -135.505329)
			(xy 357.296643 -135.527141) (xy 357.344249 -135.556195) (xy 357.387117 -135.59187) (xy 357.424334 -135.633407)
			(xy 357.455107 -135.67992) (xy 357.478779 -135.730417) (xy 357.494847 -135.783824) (xy 357.502967 -135.839)
			(xy 357.503476 -135.866886) (xy 357.502967 -135.894772) (xy 357.494847 -135.949948) (xy 357.478779 -136.003355)
			(xy 357.455107 -136.053852) (xy 357.424334 -136.100365) (xy 357.387117 -136.141902) (xy 357.344249 -136.177577)
			(xy 357.296643 -136.206631) (xy 357.245314 -136.228443) (xy 357.191357 -136.242549) (xy 357.13592 -136.248649)
			(xy 357.080186 -136.246612) (xy 357.025343 -136.236482) (xy 356.972559 -136.218475) (xy 356.922959 -136.192974)
			(xy 356.877601 -136.160523) (xy 356.837452 -136.121814) (xy 356.803366 -136.077671) (xy 356.77607 -136.029036)
			(xy 356.756147 -135.976945) (xy 356.744021 -135.922508) (xy 356.73995 -135.866886) (xy 356.302926 -135.866886)
			(xy 356.298391 -135.87656) (xy 356.267618 -135.923073) (xy 356.230401 -135.96461) (xy 356.187533 -136.000285)
			(xy 356.139927 -136.029339) (xy 356.088598 -136.051151) (xy 356.034641 -136.065257) (xy 355.979204 -136.071357)
			(xy 355.92347 -136.06932) (xy 355.868627 -136.05919) (xy 355.815843 -136.041183) (xy 355.766243 -136.015682)
			(xy 355.720885 -135.983231) (xy 355.680736 -135.944522) (xy 355.64665 -135.900379) (xy 355.619354 -135.851744)
			(xy 355.599431 -135.799653) (xy 355.587305 -135.745216) (xy 355.583234 -135.689594) (xy 354.70592 -135.689594)
			(xy 354.70592 -137.386314) (xy 354.706198 -137.393663) (xy 354.710453 -137.407734) (xy 354.714302 -137.414)
			(xy 354.717858 -137.419334) (xy 354.746958 -137.44829) (xy 356.645208 -137.44829) (xy 356.649279 -137.392668)
			(xy 356.661405 -137.338231) (xy 356.681328 -137.28614) (xy 356.708624 -137.237505) (xy 356.74271 -137.193362)
			(xy 356.782859 -137.154653) (xy 356.828217 -137.122202) (xy 356.877817 -137.096701) (xy 356.930601 -137.078694)
			(xy 356.985444 -137.068564) (xy 357.041178 -137.066527) (xy 357.096615 -137.072627) (xy 357.150572 -137.086733)
			(xy 357.201901 -137.108545) (xy 357.249507 -137.137599) (xy 357.292375 -137.173274) (xy 357.329592 -137.214811)
			(xy 357.360365 -137.261324) (xy 357.3674 -137.276332) (xy 361.347258 -137.276332) (xy 361.347662 -137.250016)
			(xy 361.354907 -137.197884) (xy 361.369237 -137.147239) (xy 361.390382 -137.09904) (xy 361.41794 -137.054198)
			(xy 361.451391 -137.013562) (xy 361.470448 -136.995408) (xy 361.47784 -136.987878) (xy 361.486372 -136.968605)
			(xy 361.486958 -136.95807) (xy 361.486958 -136.883394) (xy 361.486458 -136.872841) (xy 361.477904 -136.853545)
			(xy 361.470448 -136.846056) (xy 361.451368 -136.827925) (xy 361.417915 -136.787289) (xy 361.390361 -136.742443)
			(xy 361.369227 -136.694238) (xy 361.354914 -136.643586) (xy 361.347694 -136.591449) (xy 361.347258 -136.565132)
			(xy 361.347744 -136.537881) (xy 361.3555 -136.483933) (xy 361.370855 -136.431638) (xy 361.393497 -136.382061)
			(xy 361.422963 -136.336211) (xy 361.458654 -136.29502) (xy 361.499845 -136.259329) (xy 361.545695 -136.229863)
			(xy 361.595272 -136.207221) (xy 361.647567 -136.191866) (xy 361.701515 -136.18411) (xy 361.756017 -136.18411)
			(xy 361.809965 -136.191866) (xy 361.86226 -136.207221) (xy 361.911837 -136.229863) (xy 361.957687 -136.259329)
			(xy 361.998878 -136.29502) (xy 362.034569 -136.336211) (xy 362.064035 -136.382061) (xy 362.086677 -136.431638)
			(xy 362.102032 -136.483933) (xy 362.109788 -136.537881) (xy 362.110274 -136.565132) (xy 362.109836 -136.591447)
			(xy 362.102596 -136.643577) (xy 362.088272 -136.694221) (xy 362.067134 -136.74242) (xy 362.039582 -136.787263)
			(xy 362.006138 -136.827901) (xy 361.987084 -136.846056) (xy 361.979697 -136.85359) (xy 361.971165 -136.872861)
			(xy 361.970574 -136.883394) (xy 361.970574 -136.95807) (xy 361.971114 -136.968618) (xy 361.979642 -136.987913)
			(xy 361.987084 -136.995408) (xy 362.006133 -137.01357) (xy 362.039592 -137.054198) (xy 362.067152 -137.099037)
			(xy 362.088292 -137.147236) (xy 362.10261 -137.197883) (xy 362.109835 -137.250016) (xy 362.110274 -137.276332)
			(xy 362.109788 -137.303583) (xy 362.102032 -137.357531) (xy 362.086677 -137.409826) (xy 362.064035 -137.459403)
			(xy 362.034569 -137.505253) (xy 361.998878 -137.546444) (xy 361.957687 -137.582135) (xy 361.911837 -137.611601)
			(xy 361.86226 -137.634243) (xy 361.809965 -137.649598) (xy 361.756017 -137.657354) (xy 361.701515 -137.657354)
			(xy 361.647567 -137.649598) (xy 361.595272 -137.634243) (xy 361.545695 -137.611601) (xy 361.499845 -137.582135)
			(xy 361.458654 -137.546444) (xy 361.422963 -137.505253) (xy 361.393497 -137.459403) (xy 361.370855 -137.409826)
			(xy 361.3555 -137.357531) (xy 361.347744 -137.303583) (xy 361.347258 -137.276332) (xy 357.3674 -137.276332)
			(xy 357.384037 -137.311821) (xy 357.400105 -137.365228) (xy 357.408225 -137.420404) (xy 357.408734 -137.44829)
			(xy 357.408225 -137.476176) (xy 357.400105 -137.531352) (xy 357.384037 -137.584759) (xy 357.360365 -137.635256)
			(xy 357.329592 -137.681769) (xy 357.292375 -137.723306) (xy 357.288328 -137.726674) (xy 362.28782 -137.726674)
			(xy 362.288266 -137.699303) (xy 362.296088 -137.645123) (xy 362.311581 -137.592619) (xy 362.334428 -137.542873)
			(xy 362.364157 -137.496907) (xy 362.3818 -137.475976) (xy 362.382054 -137.475722) (xy 362.387644 -137.468638)
			(xy 362.393887 -137.451719) (xy 362.394246 -137.442702) (xy 362.394246 -137.375646) (xy 362.393879 -137.36663)
			(xy 362.38764 -137.349712) (xy 362.382054 -137.342626) (xy 362.3818 -137.342626) (xy 362.3818 -137.342372)
			(xy 362.364181 -137.321424) (xy 362.334466 -137.275455) (xy 362.311626 -137.225712) (xy 362.296131 -137.173215)
			(xy 362.288297 -137.119042) (xy 362.28782 -137.091674) (xy 362.288306 -137.064423) (xy 362.296062 -137.010475)
			(xy 362.311417 -136.95818) (xy 362.334059 -136.908603) (xy 362.363525 -136.862753) (xy 362.399216 -136.821562)
			(xy 362.440407 -136.785871) (xy 362.486257 -136.756405) (xy 362.535834 -136.733763) (xy 362.588129 -136.718408)
			(xy 362.642077 -136.710652) (xy 362.696579 -136.710652) (xy 362.750527 -136.718408) (xy 362.802822 -136.733763)
			(xy 362.852399 -136.756405) (xy 362.898249 -136.785871) (xy 362.93944 -136.821562) (xy 362.975131 -136.862753)
			(xy 363.004597 -136.908603) (xy 363.027239 -136.95818) (xy 363.042594 -137.010475) (xy 363.05035 -137.064423)
			(xy 363.050836 -137.091674) (xy 363.05037 -137.119044) (xy 363.042555 -137.173224) (xy 363.027066 -137.225728)
			(xy 363.004224 -137.275475) (xy 362.974498 -137.321441) (xy 362.956856 -137.342372) (xy 362.956602 -137.342626)
			(xy 362.95104 -137.34973) (xy 362.944779 -137.366633) (xy 362.94441 -137.375646) (xy 362.94441 -137.442702)
			(xy 362.944764 -137.451719) (xy 362.951013 -137.468636) (xy 362.956602 -137.475722) (xy 362.956856 -137.475722)
			(xy 362.956856 -137.475976) (xy 362.97449 -137.496912) (xy 363.004205 -137.542883) (xy 363.027042 -137.592629)
			(xy 363.042534 -137.64513) (xy 363.050362 -137.699305) (xy 363.050836 -137.726674) (xy 363.05035 -137.753925)
			(xy 363.042594 -137.807873) (xy 363.027239 -137.860168) (xy 363.004597 -137.909745) (xy 362.975131 -137.955595)
			(xy 362.93944 -137.996786) (xy 362.898249 -138.032477) (xy 362.852399 -138.061943) (xy 362.802822 -138.084585)
			(xy 362.750527 -138.09994) (xy 362.696579 -138.107696) (xy 362.642077 -138.107696) (xy 362.588129 -138.09994)
			(xy 362.535834 -138.084585) (xy 362.486257 -138.061943) (xy 362.440407 -138.032477) (xy 362.399216 -137.996786)
			(xy 362.363525 -137.955595) (xy 362.334059 -137.909745) (xy 362.311417 -137.860168) (xy 362.296062 -137.807873)
			(xy 362.288306 -137.753925) (xy 362.28782 -137.726674) (xy 357.288328 -137.726674) (xy 357.249507 -137.758981)
			(xy 357.201901 -137.788035) (xy 357.150572 -137.809847) (xy 357.096615 -137.823953) (xy 357.041178 -137.830053)
			(xy 356.985444 -137.828016) (xy 356.930601 -137.817886) (xy 356.877817 -137.799879) (xy 356.828217 -137.774378)
			(xy 356.782859 -137.741927) (xy 356.74271 -137.703218) (xy 356.708624 -137.659075) (xy 356.681328 -137.61044)
			(xy 356.661405 -137.558349) (xy 356.649279 -137.503912) (xy 356.645208 -137.44829) (xy 354.746958 -137.44829)
			(xy 354.820474 -137.521442) (xy 354.82276 -137.52322) (xy 355.088952 -137.52322) (xy 355.115038 -137.52371)
			(xy 355.166566 -137.531883) (xy 355.216179 -137.548021) (xy 355.262655 -137.571724) (xy 355.304849 -137.602409)
			(xy 355.323648 -137.620502) (xy 355.934772 -138.231626) (xy 355.950686 -138.248077) (xy 355.978299 -138.284581)
			(xy 356.000628 -138.324536) (xy 356.017248 -138.367183) (xy 356.02291 -138.38936) (xy 356.024688 -138.396472)
			(xy 356.028482 -138.40333) (xy 363.496352 -138.40333) (xy 363.496863 -138.375665) (xy 363.50486 -138.320914)
			(xy 363.520675 -138.267892) (xy 363.543977 -138.217707) (xy 363.574279 -138.171411) (xy 363.610946 -138.129973)
			(xy 363.65321 -138.094262) (xy 363.676438 -138.079226) (xy 363.686103 -138.072575) (xy 363.698554 -138.052724)
			(xy 363.700314 -138.041126) (xy 363.708188 -137.961116) (xy 363.708791 -137.949479) (xy 363.700729 -137.927644)
			(xy 363.692694 -137.919206) (xy 363.69244 -137.918952) (xy 363.673861 -137.900869) (xy 363.641281 -137.860538)
			(xy 363.614466 -137.816165) (xy 363.593913 -137.768567) (xy 363.58 -137.718622) (xy 363.572983 -137.667253)
			(xy 363.572552 -137.64133) (xy 363.573106 -137.614081) (xy 363.580857 -137.560138) (xy 363.596207 -137.507847)
			(xy 363.618841 -137.458273) (xy 363.648301 -137.412424) (xy 363.683985 -137.371235) (xy 363.725168 -137.335543)
			(xy 363.771011 -137.306075) (xy 363.820582 -137.283431) (xy 363.87287 -137.268072) (xy 363.926811 -137.260311)
			(xy 363.95406 -137.259822) (xy 363.98143 -137.260306) (xy 364.035608 -137.268119) (xy 364.088111 -137.283603)
			(xy 364.137858 -137.306441) (xy 364.183826 -137.336162) (xy 364.204758 -137.353802) (xy 364.205012 -137.354056)
			(xy 364.212086 -137.35966) (xy 364.229013 -137.365895) (xy 364.238032 -137.366248) (xy 364.305088 -137.366248)
			(xy 364.314106 -137.365896) (xy 364.331023 -137.359646) (xy 364.338108 -137.354056) (xy 364.338108 -137.353802)
			(xy 364.338362 -137.353802) (xy 364.359298 -137.336168) (xy 364.40527 -137.306455) (xy 364.455016 -137.283618)
			(xy 364.507516 -137.268126) (xy 364.561691 -137.260297) (xy 364.58906 -137.259822) (xy 364.616313 -137.260293)
			(xy 364.670265 -137.268045) (xy 364.722565 -137.283397) (xy 364.772147 -137.306037) (xy 364.818002 -137.335504)
			(xy 364.859196 -137.371197) (xy 364.89489 -137.41239) (xy 364.924358 -137.458244) (xy 364.946999 -137.507826)
			(xy 364.962353 -137.560125) (xy 364.970107 -137.614077) (xy 364.970568 -137.64133) (xy 364.970012 -137.670246)
			(xy 364.961292 -137.727416) (xy 364.944043 -137.782614) (xy 364.918658 -137.834576) (xy 364.885721 -137.882111)
			(xy 364.845985 -137.924129) (xy 364.823502 -137.94232) (xy 364.814696 -137.949929) (xy 364.804512 -137.970828)
			(xy 364.803944 -137.982452) (xy 364.803944 -138.062208) (xy 364.804478 -138.073841) (xy 364.814669 -138.094751)
			(xy 364.823502 -138.10234) (xy 364.846005 -138.120508) (xy 364.885739 -138.162533) (xy 364.918676 -138.210072)
			(xy 364.944061 -138.262038) (xy 364.961312 -138.31724) (xy 364.970036 -138.374413) (xy 364.970568 -138.40333)
			(xy 364.970173 -138.430585) (xy 364.962411 -138.484541) (xy 364.950305 -138.525758) (xy 365.24184 -138.525758)
			(xy 365.24233 -138.498389) (xy 365.250141 -138.44421) (xy 365.265624 -138.391707) (xy 365.28846 -138.34196)
			(xy 365.318181 -138.295992) (xy 365.33582 -138.27506) (xy 365.336074 -138.274806) (xy 365.341673 -138.267728)
			(xy 365.34791 -138.250804) (xy 365.348266 -138.241786) (xy 365.348266 -138.17473) (xy 365.347902 -138.165714)
			(xy 365.34166 -138.148796) (xy 365.336074 -138.14171) (xy 365.33582 -138.14171) (xy 365.33582 -138.141456)
			(xy 365.318138 -138.120556) (xy 365.288416 -138.074583) (xy 365.265573 -138.024831) (xy 365.250081 -137.972324)
			(xy 365.242256 -137.918141) (xy 365.242261 -137.863396) (xy 365.250094 -137.809214) (xy 365.265596 -137.75671)
			(xy 365.288446 -137.706962) (xy 365.318177 -137.660993) (xy 365.33582 -137.64006) (xy 365.336074 -137.639806)
			(xy 365.341673 -137.632728) (xy 365.34791 -137.615804) (xy 365.348266 -137.606786) (xy 365.348266 -137.53973)
			(xy 365.347902 -137.530714) (xy 365.34166 -137.513796) (xy 365.336074 -137.50671) (xy 365.33582 -137.50671)
			(xy 365.33582 -137.506456) (xy 365.318138 -137.485556) (xy 365.288416 -137.439583) (xy 365.265573 -137.389831)
			(xy 365.250081 -137.337324) (xy 365.242256 -137.283141) (xy 365.242261 -137.228396) (xy 365.250094 -137.174214)
			(xy 365.265596 -137.12171) (xy 365.288446 -137.071962) (xy 365.318177 -137.025993) (xy 365.33582 -137.00506)
			(xy 365.336074 -137.004806) (xy 365.341673 -136.997728) (xy 365.34791 -136.980804) (xy 365.348266 -136.971786)
			(xy 365.348266 -136.90473) (xy 365.347902 -136.895714) (xy 365.34166 -136.878796) (xy 365.336074 -136.87171)
			(xy 365.33582 -136.87171) (xy 365.33582 -136.871456) (xy 365.318197 -136.850511) (xy 365.288482 -136.804542)
			(xy 365.265643 -136.754798) (xy 365.250148 -136.7023) (xy 365.242316 -136.648126) (xy 365.24184 -136.620758)
			(xy 365.242326 -136.593507) (xy 365.250082 -136.539559) (xy 365.265437 -136.487264) (xy 365.288079 -136.437687)
			(xy 365.317545 -136.391837) (xy 365.353236 -136.350646) (xy 365.394427 -136.314955) (xy 365.440277 -136.285489)
			(xy 365.489854 -136.262847) (xy 365.542149 -136.247492) (xy 365.596097 -136.239736) (xy 365.650599 -136.239736)
			(xy 365.704547 -136.247492) (xy 365.756842 -136.262847) (xy 365.806419 -136.285489) (xy 365.852269 -136.314955)
			(xy 365.89346 -136.350646) (xy 365.929151 -136.391837) (xy 365.958617 -136.437687) (xy 365.981259 -136.487264)
			(xy 365.996614 -136.539559) (xy 366.00437 -136.593507) (xy 366.004856 -136.620758) (xy 366.004376 -136.648128)
			(xy 365.996563 -136.702307) (xy 365.981078 -136.75481) (xy 365.958239 -136.804557) (xy 365.928517 -136.850524)
			(xy 365.910876 -136.871456) (xy 365.910622 -136.87171) (xy 365.905016 -136.878783) (xy 365.898783 -136.89571)
			(xy 365.89843 -136.90473) (xy 365.89843 -136.971786) (xy 365.898787 -136.980803) (xy 365.905034 -136.99772)
			(xy 365.910622 -137.004806) (xy 365.910876 -137.004806) (xy 365.910876 -137.00506) (xy 365.928475 -137.026026)
			(xy 365.958202 -137.071988) (xy 365.981049 -137.121729) (xy 365.996549 -137.174226) (xy 366.004381 -137.2284)
			(xy 366.004386 -137.283137) (xy 365.996562 -137.337312) (xy 365.981072 -137.389812) (xy 365.958232 -137.439556)
			(xy 365.928514 -137.485523) (xy 365.910876 -137.506456) (xy 365.910622 -137.50671) (xy 365.905016 -137.513783)
			(xy 365.898783 -137.53071) (xy 365.89843 -137.53973) (xy 365.89843 -137.606786) (xy 365.898787 -137.615803)
			(xy 365.905034 -137.63272) (xy 365.910622 -137.639806) (xy 365.910876 -137.639806) (xy 365.910876 -137.64006)
			(xy 365.928475 -137.661026) (xy 365.958202 -137.706988) (xy 365.981049 -137.756729) (xy 365.996549 -137.809226)
			(xy 366.004381 -137.8634) (xy 366.004386 -137.918137) (xy 365.996562 -137.972312) (xy 365.981072 -138.024812)
			(xy 365.958232 -138.074556) (xy 365.928514 -138.120523) (xy 365.910876 -138.141456) (xy 365.910622 -138.14171)
			(xy 365.905016 -138.148783) (xy 365.898783 -138.16571) (xy 365.89843 -138.17473) (xy 365.89843 -138.241786)
			(xy 365.898787 -138.250803) (xy 365.905034 -138.26772) (xy 365.910622 -138.274806) (xy 365.910876 -138.274806)
			(xy 365.910876 -138.27506) (xy 365.928506 -138.295999) (xy 365.95822 -138.34197) (xy 365.981058 -138.391715)
			(xy 365.996551 -138.444215) (xy 366.004381 -138.498389) (xy 366.004856 -138.525758) (xy 366.004277 -138.554944)
			(xy 365.995383 -138.612636) (xy 365.977812 -138.668301) (xy 365.951974 -138.720644) (xy 365.918469 -138.768444)
			(xy 365.87808 -138.810588) (xy 365.85525 -138.82878) (xy 365.846159 -138.836456) (xy 365.835688 -138.857787)
			(xy 365.835184 -138.869674) (xy 365.835946 -138.950954) (xy 365.836649 -138.962668) (xy 365.847243 -138.983581)
			(xy 365.856266 -138.991086) (xy 365.856774 -138.991594) (xy 365.88065 -139.010644) (xy 365.880904 -139.010898)
			(xy 365.887985 -139.016492) (xy 365.904906 -139.022734) (xy 365.913924 -139.02309) (xy 365.98098 -139.02309)
			(xy 365.989996 -139.022726) (xy 366.006913 -139.016484) (xy 366.014 -139.010898) (xy 366.014 -139.010644)
			(xy 366.014254 -139.010644) (xy 366.035187 -138.993003) (xy 366.081155 -138.963279) (xy 366.130901 -138.940433)
			(xy 366.183403 -138.924937) (xy 366.237581 -138.917108) (xy 366.292323 -138.917108) (xy 366.346501 -138.924937)
			(xy 366.399003 -138.940433) (xy 366.448749 -138.963279) (xy 366.494717 -138.993003) (xy 366.51565 -139.010644)
			(xy 366.515904 -139.010898) (xy 366.522985 -139.016492) (xy 366.539906 -139.022734) (xy 366.548924 -139.02309)
			(xy 366.61598 -139.02309) (xy 366.624996 -139.022726) (xy 366.641913 -139.016484) (xy 366.649 -139.010898)
			(xy 366.649 -139.010644) (xy 366.649254 -139.010644) (xy 366.670187 -138.993003) (xy 366.716155 -138.963279)
			(xy 366.765901 -138.940433) (xy 366.818403 -138.924937) (xy 366.872581 -138.917108) (xy 366.927323 -138.917108)
			(xy 366.981501 -138.924937) (xy 367.034003 -138.940433) (xy 367.083749 -138.963279) (xy 367.129717 -138.993003)
			(xy 367.15065 -139.010644) (xy 367.150904 -139.010898) (xy 367.157985 -139.016492) (xy 367.174906 -139.022734)
			(xy 367.183924 -139.02309) (xy 367.25098 -139.02309) (xy 367.259996 -139.022726) (xy 367.276913 -139.016484)
			(xy 367.284 -139.010898) (xy 367.284 -139.010644) (xy 367.284254 -139.010644) (xy 367.305198 -138.99302)
			(xy 367.351167 -138.963304) (xy 367.400911 -138.940465) (xy 367.45341 -138.92497) (xy 367.507584 -138.917139)
			(xy 367.534952 -138.916664) (xy 367.562205 -138.91718) (xy 367.616157 -138.924931) (xy 367.668457 -138.940282)
			(xy 367.71804 -138.96292) (xy 367.763895 -138.992384) (xy 367.805091 -139.028075) (xy 367.840787 -139.069266)
			(xy 367.870257 -139.115118) (xy 367.892902 -139.164698) (xy 367.908259 -139.216996) (xy 367.916017 -139.270947)
			(xy 367.916017 -139.325453) (xy 367.908259 -139.379404) (xy 367.892902 -139.431702) (xy 367.870257 -139.481282)
			(xy 367.840787 -139.527134) (xy 367.805091 -139.568325) (xy 367.763895 -139.604016) (xy 367.71804 -139.63348)
			(xy 367.668457 -139.656118) (xy 367.616157 -139.671469) (xy 367.562205 -139.67922) (xy 367.534952 -139.67968)
			(xy 367.507583 -139.679188) (xy 367.453404 -139.671377) (xy 367.400901 -139.655895) (xy 367.351154 -139.633058)
			(xy 367.305186 -139.603339) (xy 367.284254 -139.5857) (xy 367.284 -139.585446) (xy 367.276922 -139.579847)
			(xy 367.259999 -139.573609) (xy 367.25098 -139.573254) (xy 367.183924 -139.573254) (xy 367.174907 -139.573611)
			(xy 367.157989 -139.579857) (xy 367.150904 -139.585446) (xy 367.150904 -139.5857) (xy 367.15065 -139.5857)
			(xy 367.129717 -139.603341) (xy 367.083749 -139.633065) (xy 367.034003 -139.655911) (xy 366.981501 -139.671407)
			(xy 366.927323 -139.679236) (xy 366.872581 -139.679236) (xy 366.818403 -139.671407) (xy 366.765901 -139.655911)
			(xy 366.716155 -139.633065) (xy 366.670187 -139.603341) (xy 366.649254 -139.5857) (xy 366.649 -139.585446)
			(xy 366.641922 -139.579847) (xy 366.624999 -139.573609) (xy 366.61598 -139.573254) (xy 366.548924 -139.573254)
			(xy 366.539907 -139.573611) (xy 366.522989 -139.579857) (xy 366.515904 -139.585446) (xy 366.515904 -139.5857)
			(xy 366.51565 -139.5857) (xy 366.494717 -139.603341) (xy 366.448749 -139.633065) (xy 366.399003 -139.655911)
			(xy 366.346501 -139.671407) (xy 366.292323 -139.679236) (xy 366.237581 -139.679236) (xy 366.183403 -139.671407)
			(xy 366.130901 -139.655911) (xy 366.081155 -139.633065) (xy 366.035187 -139.603341) (xy 366.014254 -139.5857)
			(xy 366.014 -139.585446) (xy 366.006922 -139.579847) (xy 365.989999 -139.573609) (xy 365.98098 -139.573254)
			(xy 365.913924 -139.573254) (xy 365.904907 -139.573611) (xy 365.887989 -139.579857) (xy 365.880904 -139.585446)
			(xy 365.880904 -139.5857) (xy 365.88065 -139.5857) (xy 365.85971 -139.603329) (xy 365.813739 -139.633042)
			(xy 365.763994 -139.65588) (xy 365.711495 -139.671374) (xy 365.657321 -139.679205) (xy 365.629952 -139.67968)
			(xy 365.602698 -139.679267) (xy 365.548747 -139.671503) (xy 365.496449 -139.65614) (xy 365.446869 -139.633492)
			(xy 365.401018 -139.604018) (xy 365.359828 -139.568319) (xy 365.324137 -139.527121) (xy 365.294672 -139.481264)
			(xy 365.272033 -139.43168) (xy 365.256681 -139.379379) (xy 365.248928 -139.325426) (xy 365.248444 -139.298172)
			(xy 365.248973 -139.268984) (xy 365.257877 -139.21129) (xy 365.275458 -139.155623) (xy 365.301306 -139.103281)
			(xy 365.334819 -139.055482) (xy 365.375216 -139.013341) (xy 365.39805 -138.99515) (xy 365.407128 -138.98746)
			(xy 365.417605 -138.96614) (xy 365.418116 -138.954256) (xy 365.417354 -138.872976) (xy 365.416635 -138.861264)
			(xy 365.406052 -138.840351) (xy 365.397034 -138.832844) (xy 365.397034 -138.83259) (xy 365.396526 -138.83259)
			(xy 365.372936 -138.814499) (xy 365.331183 -138.772183) (xy 365.296507 -138.723897) (xy 365.269751 -138.670812)
			(xy 365.251562 -138.614216) (xy 365.242384 -138.555482) (xy 365.24184 -138.525758) (xy 364.950305 -138.525758)
			(xy 364.947049 -138.536843) (xy 364.9244 -138.586426) (xy 364.894925 -138.63228) (xy 364.859224 -138.673474)
			(xy 364.818024 -138.709167) (xy 364.772164 -138.738634) (xy 364.722577 -138.761273) (xy 364.670272 -138.776626)
			(xy 364.616316 -138.784378) (xy 364.58906 -138.784838) (xy 364.562744 -138.784417) (xy 364.510613 -138.777175)
			(xy 364.459969 -138.762849) (xy 364.411769 -138.741708) (xy 364.366927 -138.714152) (xy 364.32629 -138.680704)
			(xy 364.308136 -138.661648) (xy 364.300596 -138.654267) (xy 364.28133 -138.645729) (xy 364.270798 -138.645138)
			(xy 364.196122 -138.645138) (xy 364.18557 -138.645654) (xy 364.166274 -138.654197) (xy 364.158784 -138.661648)
			(xy 364.140639 -138.680713) (xy 364.100006 -138.714168) (xy 364.055163 -138.741724) (xy 364.00696 -138.762861)
			(xy 363.956312 -138.777176) (xy 363.904177 -138.7844) (xy 363.87786 -138.784838) (xy 363.850609 -138.784359)
			(xy 363.796663 -138.776598) (xy 363.74437 -138.76124) (xy 363.694794 -138.738596) (xy 363.648946 -138.709128)
			(xy 363.607757 -138.673436) (xy 363.572066 -138.632246) (xy 363.542599 -138.586397) (xy 363.519957 -138.536821)
			(xy 363.5046 -138.484527) (xy 363.49684 -138.430581) (xy 363.496352 -138.40333) (xy 356.028482 -138.40333)
			(xy 356.031292 -138.40841) (xy 356.083108 -138.460226) (xy 356.099437 -138.477148) (xy 356.127465 -138.514908)
			(xy 356.149677 -138.556356) (xy 356.158038 -138.578336) (xy 356.166941 -138.604824) (xy 356.17652 -138.659872)
			(xy 356.177088 -138.68781) (xy 356.177088 -138.824462) (xy 356.661972 -138.824462) (xy 356.666043 -138.76884)
			(xy 356.678169 -138.714403) (xy 356.698092 -138.662312) (xy 356.725388 -138.613677) (xy 356.759474 -138.569534)
			(xy 356.799623 -138.530825) (xy 356.844981 -138.498374) (xy 356.894581 -138.472873) (xy 356.947365 -138.454866)
			(xy 357.002208 -138.444736) (xy 357.057942 -138.442699) (xy 357.113379 -138.448799) (xy 357.167336 -138.462905)
			(xy 357.218665 -138.484717) (xy 357.266271 -138.513771) (xy 357.309139 -138.549446) (xy 357.346356 -138.590983)
			(xy 357.377129 -138.637496) (xy 357.400801 -138.687993) (xy 357.416869 -138.7414) (xy 357.424989 -138.796576)
			(xy 357.425498 -138.824462) (xy 357.424989 -138.852348) (xy 357.416869 -138.907524) (xy 357.400801 -138.960931)
			(xy 357.377129 -139.011428) (xy 357.346356 -139.057941) (xy 357.309139 -139.099478) (xy 357.266271 -139.135153)
			(xy 357.218665 -139.164207) (xy 357.167336 -139.186019) (xy 357.113379 -139.200125) (xy 357.057942 -139.206225)
			(xy 357.002208 -139.204188) (xy 356.947365 -139.194058) (xy 356.894581 -139.176051) (xy 356.844981 -139.15055)
			(xy 356.799623 -139.118099) (xy 356.759474 -139.07939) (xy 356.725388 -139.035247) (xy 356.698092 -138.986612)
			(xy 356.678169 -138.934521) (xy 356.666043 -138.880084) (xy 356.661972 -138.824462) (xy 356.177088 -138.824462)
			(xy 356.177088 -140.392404) (xy 356.667814 -140.392404) (xy 356.671885 -140.336782) (xy 356.684011 -140.282345)
			(xy 356.703934 -140.230254) (xy 356.73123 -140.181619) (xy 356.765316 -140.137476) (xy 356.805465 -140.098767)
			(xy 356.850823 -140.066316) (xy 356.900423 -140.040815) (xy 356.953207 -140.022808) (xy 357.00805 -140.012678)
			(xy 357.063784 -140.010641) (xy 357.119221 -140.016741) (xy 357.173178 -140.030847) (xy 357.224507 -140.052659)
			(xy 357.272113 -140.081713) (xy 357.314981 -140.117388) (xy 357.352198 -140.158925) (xy 357.382971 -140.205438)
			(xy 357.406643 -140.255935) (xy 357.422711 -140.309342) (xy 357.430831 -140.364518) (xy 357.43134 -140.392404)
			(xy 357.430831 -140.42029) (xy 357.422711 -140.475466) (xy 357.406643 -140.528873) (xy 357.382971 -140.57937)
			(xy 357.352198 -140.625883) (xy 357.314981 -140.66742) (xy 357.272113 -140.703095) (xy 357.224507 -140.732149)
			(xy 357.173178 -140.753961) (xy 357.119221 -140.768067) (xy 357.063784 -140.774167) (xy 357.00805 -140.77213)
			(xy 356.953207 -140.762) (xy 356.900423 -140.743993) (xy 356.850823 -140.718492) (xy 356.805465 -140.686041)
			(xy 356.765316 -140.647332) (xy 356.73123 -140.603189) (xy 356.703934 -140.554554) (xy 356.684011 -140.502463)
			(xy 356.671885 -140.448026) (xy 356.667814 -140.392404) (xy 356.177088 -140.392404) (xy 356.177088 -141.046551)
			(xy 359.055154 -141.046551) (xy 359.055154 -140.992049) (xy 359.06291 -140.938101) (xy 359.078264 -140.885806)
			(xy 359.100904 -140.836228) (xy 359.130368 -140.790377) (xy 359.166058 -140.749185) (xy 359.207246 -140.713491)
			(xy 359.253095 -140.684022) (xy 359.30267 -140.661377) (xy 359.354964 -140.646018) (xy 359.408911 -140.638256)
			(xy 359.436162 -140.637768) (xy 359.462477 -140.638204) (xy 359.514606 -140.645447) (xy 359.565249 -140.659773)
			(xy 359.613448 -140.680911) (xy 359.658291 -140.708462) (xy 359.69893 -140.741905) (xy 359.717086 -140.760958)
			(xy 359.724617 -140.768349) (xy 359.74389 -140.776881) (xy 359.754424 -140.777468) (xy 359.8291 -140.777468)
			(xy 359.839653 -140.776962) (xy 359.858948 -140.768412) (xy 359.866438 -140.760958) (xy 359.884574 -140.741883)
			(xy 359.925209 -140.708429) (xy 359.970053 -140.680874) (xy 360.018258 -140.659739) (xy 360.068908 -140.645426)
			(xy 360.121045 -140.638205) (xy 360.147362 -140.637768) (xy 360.174615 -140.638277) (xy 360.228567 -140.646029)
			(xy 360.280866 -140.661381) (xy 360.330447 -140.684019) (xy 360.376302 -140.713485) (xy 360.417497 -140.749176)
			(xy 360.453193 -140.790367) (xy 360.482662 -140.836219) (xy 360.505306 -140.885799) (xy 360.520663 -140.938096)
			(xy 360.528421 -140.992047) (xy 360.528421 -141.046553) (xy 360.520663 -141.100504) (xy 360.505306 -141.152801)
			(xy 360.482662 -141.202381) (xy 360.453193 -141.248233) (xy 360.417497 -141.289424) (xy 360.376302 -141.325115)
			(xy 360.330447 -141.354581) (xy 360.280866 -141.377219) (xy 360.228567 -141.392571) (xy 360.174615 -141.400323)
			(xy 360.147362 -141.400784) (xy 360.121047 -141.400347) (xy 360.068917 -141.393107) (xy 360.018273 -141.378782)
			(xy 359.970074 -141.357644) (xy 359.925232 -141.330092) (xy 359.884594 -141.296648) (xy 359.866438 -141.277594)
			(xy 359.858905 -141.270206) (xy 359.839634 -141.261674) (xy 359.8291 -141.261084) (xy 359.754424 -141.261084)
			(xy 359.743875 -141.261618) (xy 359.72458 -141.27015) (xy 359.717086 -141.277594) (xy 359.698929 -141.296648)
			(xy 359.6583 -141.330106) (xy 359.61346 -141.357665) (xy 359.565259 -141.378804) (xy 359.514612 -141.393121)
			(xy 359.462478 -141.400346) (xy 359.436162 -141.400784) (xy 359.408911 -141.400344) (xy 359.354964 -141.392582)
			(xy 359.30267 -141.377223) (xy 359.253095 -141.354578) (xy 359.207246 -141.325109) (xy 359.166058 -141.289415)
			(xy 359.130368 -141.248223) (xy 359.100904 -141.202372) (xy 359.078264 -141.152794) (xy 359.06291 -141.100499)
			(xy 359.055154 -141.046551) (xy 356.177088 -141.046551) (xy 356.177088 -143.078551) (xy 359.055154 -143.078551)
			(xy 359.055154 -143.024049) (xy 359.06291 -142.970101) (xy 359.078264 -142.917806) (xy 359.100904 -142.868228)
			(xy 359.130368 -142.822377) (xy 359.166058 -142.781185) (xy 359.207246 -142.745491) (xy 359.253095 -142.716022)
			(xy 359.30267 -142.693377) (xy 359.354964 -142.678018) (xy 359.408911 -142.670256) (xy 359.436162 -142.669768)
			(xy 359.462477 -142.670204) (xy 359.514606 -142.677447) (xy 359.565249 -142.691773) (xy 359.613448 -142.712911)
			(xy 359.658291 -142.740462) (xy 359.69893 -142.773905) (xy 359.717086 -142.792958) (xy 359.724617 -142.800349)
			(xy 359.74389 -142.808881) (xy 359.754424 -142.809468) (xy 359.8291 -142.809468) (xy 359.839653 -142.808962)
			(xy 359.858948 -142.800412) (xy 359.866438 -142.792958) (xy 359.884574 -142.773883) (xy 359.925209 -142.740429)
			(xy 359.970053 -142.712874) (xy 360.018258 -142.691739) (xy 360.068908 -142.677426) (xy 360.121045 -142.670205)
			(xy 360.147362 -142.669768) (xy 360.174615 -142.670277) (xy 360.228567 -142.678029) (xy 360.280866 -142.693381)
			(xy 360.330447 -142.716019) (xy 360.376302 -142.745485) (xy 360.417497 -142.781176) (xy 360.453193 -142.822367)
			(xy 360.482662 -142.868219) (xy 360.505306 -142.917799) (xy 360.520663 -142.970096) (xy 360.528421 -143.024047)
			(xy 360.528421 -143.078553) (xy 360.520663 -143.132504) (xy 360.505306 -143.184801) (xy 360.482662 -143.234381)
			(xy 360.453193 -143.280233) (xy 360.417497 -143.321424) (xy 360.376302 -143.357115) (xy 360.330447 -143.386581)
			(xy 360.280866 -143.409219) (xy 360.228567 -143.424571) (xy 360.174615 -143.432323) (xy 360.147362 -143.432784)
			(xy 360.121047 -143.432347) (xy 360.068917 -143.425107) (xy 360.018273 -143.410782) (xy 359.970074 -143.389644)
			(xy 359.925232 -143.362092) (xy 359.884594 -143.328648) (xy 359.866438 -143.309594) (xy 359.858905 -143.302206)
			(xy 359.839634 -143.293674) (xy 359.8291 -143.293084) (xy 359.754424 -143.293084) (xy 359.743875 -143.293618)
			(xy 359.72458 -143.30215) (xy 359.717086 -143.309594) (xy 359.698929 -143.328648) (xy 359.6583 -143.362106)
			(xy 359.61346 -143.389665) (xy 359.565259 -143.410804) (xy 359.514612 -143.425121) (xy 359.462478 -143.432346)
			(xy 359.436162 -143.432784) (xy 359.408911 -143.432344) (xy 359.354964 -143.424582) (xy 359.30267 -143.409223)
			(xy 359.253095 -143.386578) (xy 359.207246 -143.357109) (xy 359.166058 -143.321415) (xy 359.130368 -143.280223)
			(xy 359.100904 -143.234372) (xy 359.078264 -143.184794) (xy 359.06291 -143.132499) (xy 359.055154 -143.078551)
			(xy 356.177088 -143.078551) (xy 356.177088 -143.237712) (xy 356.176535 -143.265652) (xy 356.166958 -143.320703)
			(xy 356.158038 -143.347186) (xy 356.149644 -143.369149) (xy 356.127406 -143.410575) (xy 356.09939 -143.448333)
			(xy 356.083108 -143.465296) (xy 355.581833 -143.966438) (xy 367.764314 -143.966438) (xy 367.764725 -143.940462)
			(xy 367.771775 -143.88899) (xy 367.785751 -143.838952) (xy 367.806392 -143.791277) (xy 367.833317 -143.746846)
			(xy 367.866026 -143.706483) (xy 367.903914 -143.670936) (xy 367.924842 -143.655542) (xy 367.934333 -143.64791)
			(xy 367.945478 -143.626298) (xy 367.946178 -143.61414) (xy 367.946178 -143.531336) (xy 367.945487 -143.519174)
			(xy 367.934347 -143.497553) (xy 367.924842 -143.489934) (xy 367.903923 -143.474532) (xy 367.866046 -143.438979)
			(xy 367.833346 -143.398614) (xy 367.806428 -143.354184) (xy 367.785789 -143.306512) (xy 367.771812 -143.256479)
			(xy 367.764756 -143.205012) (xy 367.764314 -143.179038) (xy 367.764823 -143.150299) (xy 367.773453 -143.093472)
			(xy 367.790508 -143.038582) (xy 367.815602 -142.98687) (xy 367.848168 -142.939508) (xy 367.867438 -142.91818)
			(xy 367.874042 -142.911322) (xy 367.881154 -142.893288) (xy 367.881154 -142.804388) (xy 367.874042 -142.786354)
			(xy 367.867438 -142.779496) (xy 367.848204 -142.758137) (xy 367.815637 -142.71078) (xy 367.790542 -142.659074)
			(xy 367.773488 -142.604188) (xy 367.764862 -142.547365) (xy 367.764858 -142.489891) (xy 367.773476 -142.433066)
			(xy 367.790522 -142.378178) (xy 367.815609 -142.326468) (xy 367.848169 -142.279106) (xy 367.867438 -142.25778)
			(xy 367.874042 -142.250922) (xy 367.881154 -142.232888) (xy 367.881154 -142.143988) (xy 367.874042 -142.125954)
			(xy 367.867438 -142.119096) (xy 367.848204 -142.097737) (xy 367.815637 -142.05038) (xy 367.790542 -141.998674)
			(xy 367.773488 -141.943788) (xy 367.764862 -141.886965) (xy 367.764858 -141.829491) (xy 367.773476 -141.772666)
			(xy 367.790522 -141.717778) (xy 367.815609 -141.666068) (xy 367.848169 -141.618706) (xy 367.867438 -141.59738)
			(xy 367.874042 -141.590522) (xy 367.881154 -141.572488) (xy 367.881154 -141.483588) (xy 367.874042 -141.465554)
			(xy 367.867438 -141.458696) (xy 367.848204 -141.437337) (xy 367.815637 -141.38998) (xy 367.790542 -141.338274)
			(xy 367.773488 -141.283388) (xy 367.764862 -141.226565) (xy 367.764858 -141.169091) (xy 367.773476 -141.112266)
			(xy 367.790522 -141.057378) (xy 367.815609 -141.005668) (xy 367.848169 -140.958306) (xy 367.867438 -140.93698)
			(xy 367.874042 -140.930122) (xy 367.881154 -140.912088) (xy 367.881154 -140.823188) (xy 367.874042 -140.805154)
			(xy 367.867438 -140.798296) (xy 367.848185 -140.776953) (xy 367.815617 -140.729596) (xy 367.790521 -140.677888)
			(xy 367.773466 -140.623001) (xy 367.764838 -140.566176) (xy 367.764314 -140.537438) (xy 367.7648 -140.510187)
			(xy 367.772556 -140.456239) (xy 367.787911 -140.403944) (xy 367.810553 -140.354367) (xy 367.840019 -140.308517)
			(xy 367.87571 -140.267326) (xy 367.916901 -140.231635) (xy 367.962751 -140.202169) (xy 368.012328 -140.179527)
			(xy 368.064623 -140.164172) (xy 368.118571 -140.156416) (xy 368.173073 -140.156416) (xy 368.227021 -140.164172)
			(xy 368.279316 -140.179527) (xy 368.328893 -140.202169) (xy 368.374743 -140.231635) (xy 368.415934 -140.267326)
			(xy 368.451625 -140.308517) (xy 368.481091 -140.354367) (xy 368.503733 -140.403944) (xy 368.519088 -140.456239)
			(xy 368.526844 -140.510187) (xy 368.52733 -140.537438) (xy 368.526821 -140.566177) (xy 368.518194 -140.623005)
			(xy 368.50114 -140.677896) (xy 368.476045 -140.729607) (xy 368.443478 -140.776969) (xy 368.424206 -140.798296)
			(xy 368.417602 -140.805154) (xy 368.41049 -140.823188) (xy 368.41049 -140.912088) (xy 368.417602 -140.930122)
			(xy 368.424206 -140.93698) (xy 368.443513 -140.958275) (xy 368.476075 -141.005644) (xy 368.501162 -141.057361)
			(xy 368.518208 -141.112256) (xy 368.526826 -141.169087) (xy 368.526822 -141.226568) (xy 368.518195 -141.283398)
			(xy 368.501142 -141.338291) (xy 368.476047 -141.390004) (xy 368.443478 -141.437368) (xy 368.424206 -141.458696)
			(xy 368.417602 -141.465554) (xy 368.41049 -141.483588) (xy 368.41049 -141.572488) (xy 368.417602 -141.590522)
			(xy 368.424206 -141.59738) (xy 368.443513 -141.618675) (xy 368.476075 -141.666044) (xy 368.501162 -141.717761)
			(xy 368.518208 -141.772656) (xy 368.526826 -141.829487) (xy 368.526822 -141.886968) (xy 368.518195 -141.943798)
			(xy 368.501142 -141.998691) (xy 368.476047 -142.050404) (xy 368.443478 -142.097768) (xy 368.424206 -142.119096)
			(xy 368.417602 -142.125954) (xy 368.41049 -142.143988) (xy 368.41049 -142.232888) (xy 368.417602 -142.250922)
			(xy 368.424206 -142.25778) (xy 368.443513 -142.279075) (xy 368.476075 -142.326444) (xy 368.501162 -142.378161)
			(xy 368.518208 -142.433056) (xy 368.526826 -142.489887) (xy 368.526822 -142.547368) (xy 368.518195 -142.604198)
			(xy 368.501142 -142.659091) (xy 368.476047 -142.710804) (xy 368.443478 -142.758168) (xy 368.424206 -142.779496)
			(xy 368.417602 -142.786354) (xy 368.41049 -142.804388) (xy 368.41049 -142.893288) (xy 368.417602 -142.911322)
			(xy 368.424206 -142.91818) (xy 368.443485 -142.9395) (xy 368.476052 -142.986863) (xy 368.501144 -143.038576)
			(xy 368.518192 -143.093469) (xy 368.526811 -143.150298) (xy 368.52733 -143.179038) (xy 368.526925 -143.205015)
			(xy 368.519876 -143.256488) (xy 368.505902 -143.306526) (xy 368.48526 -143.354203) (xy 368.458334 -143.398634)
			(xy 368.425622 -143.438996) (xy 368.387731 -143.474541) (xy 368.366802 -143.489934) (xy 368.35733 -143.497587)
			(xy 368.346173 -143.519183) (xy 368.345466 -143.531336) (xy 368.345466 -143.61414) (xy 368.346155 -143.626303)
			(xy 368.357295 -143.647925) (xy 368.366802 -143.655542) (xy 368.38772 -143.670946) (xy 368.425594 -143.7065)
			(xy 368.458293 -143.746865) (xy 368.485211 -143.791295) (xy 368.50585 -143.838967) (xy 368.519828 -143.888998)
			(xy 368.526887 -143.940464) (xy 368.52733 -143.966438) (xy 368.526844 -143.993689) (xy 368.519088 -144.047637)
			(xy 368.503733 -144.099932) (xy 368.481091 -144.149509) (xy 368.451625 -144.195359) (xy 368.415934 -144.23655)
			(xy 368.374743 -144.272241) (xy 368.328893 -144.301707) (xy 368.279316 -144.324349) (xy 368.227021 -144.339704)
			(xy 368.173073 -144.34746) (xy 368.118571 -144.34746) (xy 368.064623 -144.339704) (xy 368.012328 -144.324349)
			(xy 367.962751 -144.301707) (xy 367.916901 -144.272241) (xy 367.87571 -144.23655) (xy 367.840019 -144.195359)
			(xy 367.810553 -144.149509) (xy 367.787911 -144.099932) (xy 367.772556 -144.047637) (xy 367.7648 -143.993689)
			(xy 367.764314 -143.966438) (xy 355.581833 -143.966438) (xy 355.124512 -144.423638) (xy 355.067108 -144.481042)
			(xy 355.06032 -144.488463) (xy 355.052704 -144.50706) (xy 355.052376 -144.51711) (xy 355.052376 -145.110551)
			(xy 359.055154 -145.110551) (xy 359.055154 -145.056049) (xy 359.06291 -145.002101) (xy 359.078264 -144.949806)
			(xy 359.100904 -144.900228) (xy 359.130368 -144.854377) (xy 359.166058 -144.813185) (xy 359.207246 -144.777491)
			(xy 359.253095 -144.748022) (xy 359.30267 -144.725377) (xy 359.354964 -144.710018) (xy 359.408911 -144.702256)
			(xy 359.436162 -144.701768) (xy 359.462477 -144.702204) (xy 359.514606 -144.709447) (xy 359.565249 -144.723773)
			(xy 359.613448 -144.744911) (xy 359.658291 -144.772462) (xy 359.69893 -144.805905) (xy 359.717086 -144.824958)
			(xy 359.724617 -144.832349) (xy 359.74389 -144.840881) (xy 359.754424 -144.841468) (xy 359.8291 -144.841468)
			(xy 359.839653 -144.840962) (xy 359.858948 -144.832412) (xy 359.866438 -144.824958) (xy 359.884574 -144.805883)
			(xy 359.925209 -144.772429) (xy 359.970053 -144.744874) (xy 360.018258 -144.723739) (xy 360.068908 -144.709426)
			(xy 360.121045 -144.702205) (xy 360.147362 -144.701768) (xy 360.174615 -144.702277) (xy 360.228567 -144.710029)
			(xy 360.280866 -144.725381) (xy 360.330447 -144.748019) (xy 360.376302 -144.777485) (xy 360.417497 -144.813176)
			(xy 360.453193 -144.854367) (xy 360.482662 -144.900219) (xy 360.505306 -144.949799) (xy 360.506611 -144.954244)
			(xy 366.239044 -144.954244) (xy 366.239619 -144.926996) (xy 366.247368 -144.873054) (xy 366.262715 -144.820764)
			(xy 366.285348 -144.77119) (xy 366.314805 -144.725342) (xy 366.350487 -144.684152) (xy 366.391668 -144.64846)
			(xy 366.437509 -144.618992) (xy 366.487078 -144.596348) (xy 366.539364 -144.580988) (xy 366.593304 -144.573226)
			(xy 366.620552 -144.572736) (xy 366.649326 -144.573259) (xy 366.706221 -144.581909) (xy 366.761172 -144.599005)
			(xy 366.812932 -144.624159) (xy 366.860328 -144.656801) (xy 366.881664 -144.676114) (xy 366.889538 -144.68348)
			(xy 366.90935 -144.690592) (xy 367.005616 -144.683226) (xy 367.024412 -144.67332) (xy 367.031016 -144.664938)
			(xy 367.049197 -144.642716) (xy 367.091141 -144.603508) (xy 367.138486 -144.571026) (xy 367.190162 -144.546004)
			(xy 367.245004 -144.529006) (xy 367.301774 -144.520416) (xy 367.330482 -144.519904) (xy 367.357735 -144.520372)
			(xy 367.411686 -144.528127) (xy 367.463985 -144.543481) (xy 367.513566 -144.566123) (xy 367.559419 -144.59559)
			(xy 367.600613 -144.631283) (xy 367.636307 -144.672476) (xy 367.665775 -144.718329) (xy 367.688417 -144.76791)
			(xy 367.703772 -144.820208) (xy 367.711527 -144.874159) (xy 367.71199 -144.901412) (xy 367.711543 -144.928315)
			(xy 367.703969 -144.981586) (xy 367.688988 -145.033265) (xy 367.666895 -145.082327) (xy 367.63813 -145.127799)
			(xy 367.603263 -145.16878) (xy 367.562985 -145.204457) (xy 367.540794 -145.219674) (xy 367.529872 -145.226786)
			(xy 367.517934 -145.249646) (xy 367.519966 -145.361914) (xy 367.53292 -145.384266) (xy 367.544096 -145.391124)
			(xy 367.567696 -145.406048) (xy 367.610649 -145.441726) (xy 367.647942 -145.483283) (xy 367.67878 -145.529833)
			(xy 367.702504 -145.58038) (xy 367.718606 -145.633846) (xy 367.726744 -145.689087) (xy 367.72723 -145.717006)
			(xy 367.726776 -145.744) (xy 367.719169 -145.797448) (xy 367.704107 -145.849292) (xy 367.681891 -145.898496)
			(xy 367.652965 -145.94408) (xy 367.63579 -145.96491) (xy 367.628678 -145.973038) (xy 367.622582 -145.993612)
			(xy 367.633504 -146.078956) (xy 367.635295 -146.089496) (xy 367.646338 -146.107781) (xy 367.65484 -146.114262)
			(xy 367.676045 -146.12965) (xy 367.714499 -146.165231) (xy 367.74772 -146.205741) (xy 367.775082 -146.250419)
			(xy 367.79607 -146.298421) (xy 367.810288 -146.348845) (xy 367.817469 -146.400741) (xy 367.817908 -146.426936)
			(xy 367.817422 -146.454187) (xy 367.809666 -146.508135) (xy 367.794311 -146.56043) (xy 367.771669 -146.610007)
			(xy 367.742203 -146.655857) (xy 367.706512 -146.697048) (xy 367.665321 -146.732739) (xy 367.619471 -146.762205)
			(xy 367.569894 -146.784847) (xy 367.517599 -146.800202) (xy 367.463651 -146.807958) (xy 367.409149 -146.807958)
			(xy 367.355201 -146.800202) (xy 367.302906 -146.784847) (xy 367.253329 -146.762205) (xy 367.207479 -146.732739)
			(xy 367.166288 -146.697048) (xy 367.130597 -146.655857) (xy 367.101131 -146.610007) (xy 367.078489 -146.56043)
			(xy 367.063134 -146.508135) (xy 367.055378 -146.454187) (xy 367.054892 -146.426936) (xy 367.055365 -146.399943)
			(xy 367.062967 -146.346495) (xy 367.078024 -146.294651) (xy 367.100235 -146.245447) (xy 367.129158 -146.199862)
			(xy 367.146332 -146.179032) (xy 367.153444 -146.170904) (xy 367.15954 -146.15033) (xy 367.148618 -146.064986)
			(xy 367.146848 -146.054441) (xy 367.135789 -146.036159) (xy 367.127282 -146.02968) (xy 367.102981 -146.012068)
			(xy 367.059722 -145.970472) (xy 367.041176 -145.946876) (xy 367.035334 -145.939002) (xy 367.017808 -145.928588)
			(xy 366.927384 -145.91538) (xy 366.90808 -145.920206) (xy 366.900206 -145.926048) (xy 366.899952 -145.926048)
			(xy 366.87521 -145.943554) (xy 366.821357 -145.971357) (xy 366.763784 -145.990292) (xy 366.703941 -145.999884)
			(xy 366.673638 -146.00047) (xy 366.646384 -146.000009) (xy 366.592431 -145.992256) (xy 366.540131 -145.976903)
			(xy 366.490549 -145.954262) (xy 366.444693 -145.924795) (xy 366.403499 -145.889101) (xy 366.367805 -145.847907)
			(xy 366.338338 -145.802051) (xy 366.315697 -145.752469) (xy 366.300344 -145.700169) (xy 366.292591 -145.646216)
			(xy 366.29213 -145.618962) (xy 366.292566 -145.592928) (xy 366.299657 -145.541345) (xy 366.31369 -145.491203)
			(xy 366.334403 -145.443433) (xy 366.361413 -145.398918) (xy 366.377474 -145.378424) (xy 366.383214 -145.370666)
			(xy 366.388956 -145.352256) (xy 366.38865 -145.34261) (xy 366.3823 -145.262854) (xy 366.373664 -145.245074)
			(xy 366.366298 -145.238724) (xy 366.346658 -145.220536) (xy 366.312132 -145.179632) (xy 366.28366 -145.134305)
			(xy 366.261801 -145.085445) (xy 366.246983 -145.034009) (xy 366.239498 -144.981008) (xy 366.239044 -144.954244)
			(xy 360.506611 -144.954244) (xy 360.520663 -145.002096) (xy 360.528421 -145.056047) (xy 360.528421 -145.110553)
			(xy 360.520663 -145.164504) (xy 360.505306 -145.216801) (xy 360.482662 -145.266381) (xy 360.453193 -145.312233)
			(xy 360.417497 -145.353424) (xy 360.376302 -145.389115) (xy 360.330447 -145.418581) (xy 360.280866 -145.441219)
			(xy 360.228567 -145.456571) (xy 360.174615 -145.464323) (xy 360.147362 -145.464784) (xy 360.121047 -145.464347)
			(xy 360.068917 -145.457107) (xy 360.018273 -145.442782) (xy 359.970074 -145.421644) (xy 359.925232 -145.394092)
			(xy 359.884594 -145.360648) (xy 359.866438 -145.341594) (xy 359.858905 -145.334206) (xy 359.839634 -145.325674)
			(xy 359.8291 -145.325084) (xy 359.754424 -145.325084) (xy 359.743875 -145.325618) (xy 359.72458 -145.33415)
			(xy 359.717086 -145.341594) (xy 359.698929 -145.360648) (xy 359.6583 -145.394106) (xy 359.61346 -145.421665)
			(xy 359.565259 -145.442804) (xy 359.514612 -145.457121) (xy 359.462478 -145.464346) (xy 359.436162 -145.464784)
			(xy 359.408911 -145.464344) (xy 359.354964 -145.456582) (xy 359.30267 -145.441223) (xy 359.253095 -145.418578)
			(xy 359.207246 -145.389109) (xy 359.166058 -145.353415) (xy 359.130368 -145.312223) (xy 359.100904 -145.266372)
			(xy 359.078264 -145.216794) (xy 359.06291 -145.164499) (xy 359.055154 -145.110551) (xy 355.052376 -145.110551)
			(xy 355.052376 -146.91487) (xy 367.916204 -146.91487) (xy 367.920275 -146.859248) (xy 367.932401 -146.804811)
			(xy 367.952324 -146.75272) (xy 367.97962 -146.704085) (xy 368.013706 -146.659942) (xy 368.053855 -146.621233)
			(xy 368.099213 -146.588782) (xy 368.148813 -146.563281) (xy 368.201597 -146.545274) (xy 368.25644 -146.535144)
			(xy 368.312174 -146.533107) (xy 368.367611 -146.539207) (xy 368.421568 -146.553313) (xy 368.472897 -146.575125)
			(xy 368.520503 -146.604179) (xy 368.563371 -146.639854) (xy 368.600588 -146.681391) (xy 368.631361 -146.727904)
			(xy 368.655033 -146.778401) (xy 368.671101 -146.831808) (xy 368.679221 -146.886984) (xy 368.67973 -146.91487)
			(xy 368.679221 -146.942756) (xy 368.671101 -146.997932) (xy 368.655033 -147.051339) (xy 368.649827 -147.062444)
			(xy 369.294408 -147.062444) (xy 369.298479 -147.006822) (xy 369.310605 -146.952385) (xy 369.330528 -146.900294)
			(xy 369.357824 -146.851659) (xy 369.39191 -146.807516) (xy 369.432059 -146.768807) (xy 369.477417 -146.736356)
			(xy 369.527017 -146.710855) (xy 369.579801 -146.692848) (xy 369.634644 -146.682718) (xy 369.690378 -146.680681)
			(xy 369.745815 -146.686781) (xy 369.799772 -146.700887) (xy 369.851101 -146.722699) (xy 369.898707 -146.751753)
			(xy 369.941575 -146.787428) (xy 369.978792 -146.828965) (xy 370.009565 -146.875478) (xy 370.033237 -146.925975)
			(xy 370.049305 -146.979382) (xy 370.057425 -147.034558) (xy 370.057934 -147.062444) (xy 370.057425 -147.09033)
			(xy 370.049305 -147.145506) (xy 370.033237 -147.198913) (xy 370.009565 -147.24941) (xy 369.978792 -147.295923)
			(xy 369.941575 -147.33746) (xy 369.898707 -147.373135) (xy 369.851101 -147.402189) (xy 369.799772 -147.424001)
			(xy 369.745815 -147.438107) (xy 369.690378 -147.444207) (xy 369.634644 -147.44217) (xy 369.579801 -147.43204)
			(xy 369.527017 -147.414033) (xy 369.477417 -147.388532) (xy 369.432059 -147.356081) (xy 369.39191 -147.317372)
			(xy 369.357824 -147.273229) (xy 369.330528 -147.224594) (xy 369.310605 -147.172503) (xy 369.298479 -147.118066)
			(xy 369.294408 -147.062444) (xy 368.649827 -147.062444) (xy 368.631361 -147.101836) (xy 368.600588 -147.148349)
			(xy 368.563371 -147.189886) (xy 368.520503 -147.225561) (xy 368.472897 -147.254615) (xy 368.421568 -147.276427)
			(xy 368.367611 -147.290533) (xy 368.312174 -147.296633) (xy 368.25644 -147.294596) (xy 368.201597 -147.284466)
			(xy 368.148813 -147.266459) (xy 368.099213 -147.240958) (xy 368.053855 -147.208507) (xy 368.013706 -147.169798)
			(xy 367.97962 -147.125655) (xy 367.952324 -147.07702) (xy 367.932401 -147.024929) (xy 367.920275 -146.970492)
			(xy 367.916204 -146.91487) (xy 355.052376 -146.91487) (xy 355.052376 -147.657656) (xy 359.450543 -147.657656)
			(xy 359.450543 -147.603144) (xy 359.458301 -147.549188) (xy 359.47366 -147.496885) (xy 359.496306 -147.447301)
			(xy 359.525779 -147.401445) (xy 359.561478 -147.360249) (xy 359.602677 -147.324555) (xy 359.648536 -147.295087)
			(xy 359.698123 -147.272446) (xy 359.750427 -147.257093) (xy 359.804384 -147.24934) (xy 359.83164 -147.24888)
			(xy 359.857955 -147.249327) (xy 359.910084 -147.256567) (xy 359.960727 -147.270891) (xy 360.008925 -147.292027)
			(xy 360.053768 -147.319576) (xy 360.094408 -147.353017) (xy 360.112564 -147.37207) (xy 360.120101 -147.379453)
			(xy 360.139369 -147.387989) (xy 360.149902 -147.38858) (xy 360.224578 -147.38858) (xy 360.235129 -147.388058)
			(xy 360.254424 -147.379519) (xy 360.261916 -147.37207) (xy 360.281736 -147.351282) (xy 360.326508 -147.315307)
			(xy 360.376166 -147.286447) (xy 360.429588 -147.265354) (xy 360.485567 -147.252505) (xy 360.54284 -147.24819)
			(xy 360.600113 -147.252505) (xy 360.656092 -147.265354) (xy 360.709514 -147.286447) (xy 360.759172 -147.315307)
			(xy 360.803944 -147.351282) (xy 360.823764 -147.37207) (xy 360.831301 -147.379453) (xy 360.850569 -147.387989)
			(xy 360.861102 -147.38858) (xy 360.935778 -147.38858) (xy 360.946329 -147.388058) (xy 360.965624 -147.379519)
			(xy 360.973116 -147.37207) (xy 360.991265 -147.353008) (xy 361.031897 -147.319553) (xy 361.076739 -147.291995)
			(xy 361.124941 -147.270858) (xy 361.175589 -147.256542) (xy 361.227724 -147.249318) (xy 361.25404 -147.24888)
			(xy 361.281288 -147.249393) (xy 361.33523 -147.257154) (xy 361.387518 -147.272512) (xy 361.437089 -147.295155)
			(xy 361.482933 -147.324621) (xy 361.524117 -147.360311) (xy 361.559803 -147.401499) (xy 361.589265 -147.447346)
			(xy 361.611902 -147.496919) (xy 361.627255 -147.549209) (xy 361.63501 -147.603151) (xy 361.63501 -147.657649)
			(xy 361.627255 -147.711591) (xy 361.611902 -147.763881) (xy 361.589265 -147.813454) (xy 361.559803 -147.859301)
			(xy 361.524117 -147.900489) (xy 361.482933 -147.936179) (xy 361.437089 -147.965645) (xy 361.387518 -147.988288)
			(xy 361.33523 -148.003646) (xy 361.281288 -148.011407) (xy 361.25404 -148.011896) (xy 361.227725 -148.01147)
			(xy 361.175594 -148.004227) (xy 361.124951 -147.9899) (xy 361.076752 -147.968759) (xy 361.031909 -147.941206)
			(xy 360.991271 -147.907761) (xy 360.973116 -147.888706) (xy 360.965589 -147.88131) (xy 360.946313 -147.872782)
			(xy 360.935778 -147.872196) (xy 360.861102 -147.872196) (xy 360.850551 -147.872714) (xy 360.831256 -147.881257)
			(xy 360.823764 -147.888706) (xy 360.803944 -147.909494) (xy 360.759172 -147.945469) (xy 360.709514 -147.974329)
			(xy 360.656092 -147.995422) (xy 360.600113 -148.008271) (xy 360.54284 -148.012586) (xy 360.485567 -148.008271)
			(xy 360.429588 -147.995422) (xy 360.376166 -147.974329) (xy 360.326508 -147.945469) (xy 360.281736 -147.909494)
			(xy 360.261916 -147.888706) (xy 360.254389 -147.88131) (xy 360.235113 -147.872782) (xy 360.224578 -147.872196)
			(xy 360.149902 -147.872196) (xy 360.139351 -147.872714) (xy 360.120056 -147.881257) (xy 360.112564 -147.888706)
			(xy 360.09442 -147.907773) (xy 360.053788 -147.941229) (xy 360.008945 -147.968786) (xy 359.960742 -147.989923)
			(xy 359.910092 -148.004237) (xy 359.857957 -148.011459) (xy 359.83164 -148.011896) (xy 359.804384 -148.01146)
			(xy 359.750427 -148.003707) (xy 359.698123 -147.988354) (xy 359.648536 -147.965713) (xy 359.602677 -147.936245)
			(xy 359.561478 -147.900551) (xy 359.525779 -147.859355) (xy 359.496306 -147.813499) (xy 359.47366 -147.763915)
			(xy 359.458301 -147.711612) (xy 359.450543 -147.657656) (xy 355.052376 -147.657656) (xy 355.052376 -148.017738)
			(xy 364.277654 -148.017738) (xy 364.281725 -147.962116) (xy 364.293851 -147.907679) (xy 364.313774 -147.855588)
			(xy 364.34107 -147.806953) (xy 364.375156 -147.76281) (xy 364.415305 -147.724101) (xy 364.460663 -147.69165)
			(xy 364.510263 -147.666149) (xy 364.563047 -147.648142) (xy 364.61789 -147.638012) (xy 364.673624 -147.635975)
			(xy 364.729061 -147.642075) (xy 364.783018 -147.656181) (xy 364.834347 -147.677993) (xy 364.881953 -147.707047)
			(xy 364.923216 -147.741386) (xy 370.18163 -147.741386) (xy 370.185701 -147.685764) (xy 370.197827 -147.631327)
			(xy 370.21775 -147.579236) (xy 370.245046 -147.530601) (xy 370.279132 -147.486458) (xy 370.319281 -147.447749)
			(xy 370.364639 -147.415298) (xy 370.414239 -147.389797) (xy 370.467023 -147.37179) (xy 370.521866 -147.36166)
			(xy 370.5776 -147.359623) (xy 370.633037 -147.365723) (xy 370.686994 -147.379829) (xy 370.738323 -147.401641)
			(xy 370.785929 -147.430695) (xy 370.828797 -147.46637) (xy 370.866014 -147.507907) (xy 370.896787 -147.55442)
			(xy 370.920459 -147.604917) (xy 370.936527 -147.658324) (xy 370.944647 -147.7135) (xy 370.945156 -147.741386)
			(xy 370.944647 -147.769272) (xy 370.936527 -147.824448) (xy 370.920459 -147.877855) (xy 370.896787 -147.928352)
			(xy 370.866014 -147.974865) (xy 370.828797 -148.016402) (xy 370.785929 -148.052077) (xy 370.738323 -148.081131)
			(xy 370.686994 -148.102943) (xy 370.633037 -148.117049) (xy 370.5776 -148.123149) (xy 370.521866 -148.121112)
			(xy 370.467023 -148.110982) (xy 370.414239 -148.092975) (xy 370.364639 -148.067474) (xy 370.319281 -148.035023)
			(xy 370.279132 -147.996314) (xy 370.245046 -147.952171) (xy 370.21775 -147.903536) (xy 370.197827 -147.851445)
			(xy 370.185701 -147.797008) (xy 370.18163 -147.741386) (xy 364.923216 -147.741386) (xy 364.924821 -147.742722)
			(xy 364.962038 -147.784259) (xy 364.992811 -147.830772) (xy 365.016483 -147.881269) (xy 365.032551 -147.934676)
			(xy 365.040671 -147.989852) (xy 365.04118 -148.017738) (xy 365.040671 -148.045624) (xy 365.032551 -148.1008)
			(xy 365.016483 -148.154207) (xy 364.992811 -148.204704) (xy 364.962038 -148.251217) (xy 364.924821 -148.292754)
			(xy 364.881953 -148.328429) (xy 364.834347 -148.357483) (xy 364.783018 -148.379295) (xy 364.729061 -148.393401)
			(xy 364.673624 -148.399501) (xy 364.61789 -148.397464) (xy 364.563047 -148.387334) (xy 364.510263 -148.369327)
			(xy 364.460663 -148.343826) (xy 364.415305 -148.311375) (xy 364.375156 -148.272666) (xy 364.34107 -148.228523)
			(xy 364.313774 -148.179888) (xy 364.293851 -148.127797) (xy 364.281725 -148.07336) (xy 364.277654 -148.017738)
			(xy 355.052376 -148.017738) (xy 355.052376 -150.195854) (xy 359.450565 -150.195854) (xy 359.450565 -150.141346)
			(xy 359.458323 -150.087393) (xy 359.473681 -150.035093) (xy 359.496326 -149.985512) (xy 359.525797 -149.939658)
			(xy 359.561494 -149.898465) (xy 359.60269 -149.862773) (xy 359.648547 -149.833307) (xy 359.698131 -149.810667)
			(xy 359.750432 -149.795315) (xy 359.804386 -149.787563) (xy 359.83164 -149.787102) (xy 359.857955 -149.787542)
			(xy 359.910085 -149.794782) (xy 359.960728 -149.809107) (xy 360.008927 -149.830244) (xy 360.05377 -149.857795)
			(xy 360.094408 -149.891238) (xy 360.112564 -149.910292) (xy 360.120098 -149.917679) (xy 360.139369 -149.926212)
			(xy 360.149902 -149.926802) (xy 360.224578 -149.926802) (xy 360.235128 -149.926274) (xy 360.254423 -149.917738)
			(xy 360.261916 -149.910292) (xy 360.281736 -149.889504) (xy 360.326508 -149.853529) (xy 360.376166 -149.824669)
			(xy 360.429588 -149.803576) (xy 360.485567 -149.790727) (xy 360.54284 -149.786412) (xy 360.600113 -149.790727)
			(xy 360.656092 -149.803576) (xy 360.709514 -149.824669) (xy 360.759172 -149.853529) (xy 360.803944 -149.889504)
			(xy 360.823764 -149.910292) (xy 360.831298 -149.917679) (xy 360.850569 -149.926212) (xy 360.861102 -149.926802)
			(xy 360.935778 -149.926802) (xy 360.946328 -149.926274) (xy 360.965623 -149.917738) (xy 360.973116 -149.910292)
			(xy 360.991269 -149.891234) (xy 361.0319 -149.857778) (xy 361.07674 -149.830219) (xy 361.124942 -149.809081)
			(xy 361.175589 -149.794764) (xy 361.227724 -149.78754) (xy 361.25404 -149.787102) (xy 361.28129 -149.787571)
			(xy 361.335235 -149.795332) (xy 361.387526 -149.810691) (xy 361.4371 -149.833335) (xy 361.482946 -149.862803)
			(xy 361.524133 -149.898495) (xy 361.559821 -149.939686) (xy 361.589284 -149.985535) (xy 361.611923 -150.035111)
			(xy 361.627277 -150.087404) (xy 361.6311 -150.114) (xy 363.091982 -150.114) (xy 363.096053 -150.058378)
			(xy 363.108179 -150.003941) (xy 363.128102 -149.95185) (xy 363.155398 -149.903215) (xy 363.189484 -149.859072)
			(xy 363.229633 -149.820363) (xy 363.274991 -149.787912) (xy 363.324591 -149.762411) (xy 363.377375 -149.744404)
			(xy 363.432218 -149.734274) (xy 363.487952 -149.732237) (xy 363.543389 -149.738337) (xy 363.597346 -149.752443)
			(xy 363.648675 -149.774255) (xy 363.696281 -149.803309) (xy 363.739149 -149.838984) (xy 363.776366 -149.880521)
			(xy 363.807139 -149.927034) (xy 363.830811 -149.977531) (xy 363.846879 -150.030938) (xy 363.851664 -150.063454)
			(xy 364.138208 -150.063454) (xy 364.142279 -150.007832) (xy 364.154405 -149.953395) (xy 364.174328 -149.901304)
			(xy 364.201624 -149.852669) (xy 364.23571 -149.808526) (xy 364.275859 -149.769817) (xy 364.321217 -149.737366)
			(xy 364.370817 -149.711865) (xy 364.423601 -149.693858) (xy 364.478444 -149.683728) (xy 364.534178 -149.681691)
			(xy 364.589615 -149.687791) (xy 364.643572 -149.701897) (xy 364.694901 -149.723709) (xy 364.742507 -149.752763)
			(xy 364.785375 -149.788438) (xy 364.822592 -149.829975) (xy 364.853365 -149.876488) (xy 364.877037 -149.926985)
			(xy 364.893105 -149.980392) (xy 364.901225 -150.035568) (xy 364.901734 -150.063454) (xy 364.901225 -150.09134)
			(xy 364.893105 -150.146516) (xy 364.877037 -150.199923) (xy 364.853365 -150.25042) (xy 364.822592 -150.296933)
			(xy 364.785375 -150.33847) (xy 364.742507 -150.374145) (xy 364.694901 -150.403199) (xy 364.643572 -150.425011)
			(xy 364.589615 -150.439117) (xy 364.534178 -150.445217) (xy 364.478444 -150.44318) (xy 364.423601 -150.43305)
			(xy 364.370817 -150.415043) (xy 364.321217 -150.389542) (xy 364.275859 -150.357091) (xy 364.23571 -150.318382)
			(xy 364.201624 -150.274239) (xy 364.174328 -150.225604) (xy 364.154405 -150.173513) (xy 364.142279 -150.119076)
			(xy 364.138208 -150.063454) (xy 363.851664 -150.063454) (xy 363.854999 -150.086114) (xy 363.855508 -150.114)
			(xy 363.854999 -150.141886) (xy 363.846879 -150.197062) (xy 363.830811 -150.250469) (xy 363.807139 -150.300966)
			(xy 363.776366 -150.347479) (xy 363.739149 -150.389016) (xy 363.696281 -150.424691) (xy 363.648675 -150.453745)
			(xy 363.597346 -150.475557) (xy 363.543389 -150.489663) (xy 363.487952 -150.495763) (xy 363.432218 -150.493726)
			(xy 363.377375 -150.483596) (xy 363.324591 -150.465589) (xy 363.274991 -150.440088) (xy 363.229633 -150.407637)
			(xy 363.189484 -150.368928) (xy 363.155398 -150.324785) (xy 363.128102 -150.27615) (xy 363.108179 -150.224059)
			(xy 363.096053 -150.169622) (xy 363.091982 -150.114) (xy 361.6311 -150.114) (xy 361.635032 -150.14135)
			(xy 361.635032 -150.19585) (xy 361.627277 -150.249796) (xy 361.611923 -150.302089) (xy 361.589284 -150.351665)
			(xy 361.559821 -150.397514) (xy 361.524133 -150.438705) (xy 361.482946 -150.474397) (xy 361.4371 -150.503865)
			(xy 361.387526 -150.526509) (xy 361.335235 -150.541868) (xy 361.28129 -150.549629) (xy 361.25404 -150.550118)
			(xy 361.227725 -150.549685) (xy 361.175595 -150.542442) (xy 361.124952 -150.528116) (xy 361.076753 -150.506977)
			(xy 361.031911 -150.479425) (xy 360.991272 -150.445982) (xy 360.973116 -150.426928) (xy 360.965587 -150.419535)
			(xy 360.946313 -150.411005) (xy 360.935778 -150.410418) (xy 360.861102 -150.410418) (xy 360.85055 -150.410929)
			(xy 360.831255 -150.419477) (xy 360.823764 -150.426928) (xy 360.803944 -150.447716) (xy 360.759172 -150.483691)
			(xy 360.709514 -150.512551) (xy 360.656092 -150.533644) (xy 360.600113 -150.546493) (xy 360.54284 -150.550808)
			(xy 360.485567 -150.546493) (xy 360.429588 -150.533644) (xy 360.376166 -150.512551) (xy 360.326508 -150.483691)
			(xy 360.281736 -150.447716) (xy 360.261916 -150.426928) (xy 360.254387 -150.419535) (xy 360.235113 -150.411005)
			(xy 360.224578 -150.410418) (xy 360.149902 -150.410418) (xy 360.13935 -150.410929) (xy 360.120055 -150.419477)
			(xy 360.112564 -150.426928) (xy 360.094424 -150.445999) (xy 360.053791 -150.479454) (xy 360.008947 -150.50701)
			(xy 359.960743 -150.528146) (xy 359.910093 -150.54246) (xy 359.857957 -150.549681) (xy 359.83164 -150.550118)
			(xy 359.804386 -150.549637) (xy 359.750432 -150.541885) (xy 359.698131 -150.526533) (xy 359.648547 -150.503893)
			(xy 359.60269 -150.474427) (xy 359.561494 -150.438735) (xy 359.525797 -150.397542) (xy 359.496326 -150.351688)
			(xy 359.473681 -150.302107) (xy 359.458323 -150.249807) (xy 359.450565 -150.195854) (xy 355.052376 -150.195854)
			(xy 355.052376 -155.212034) (xy 355.569264 -155.212034) (xy 355.573335 -155.156412) (xy 355.585461 -155.101975)
			(xy 355.605384 -155.049884) (xy 355.63268 -155.001249) (xy 355.666766 -154.957106) (xy 355.706915 -154.918397)
			(xy 355.752273 -154.885946) (xy 355.801873 -154.860445) (xy 355.854657 -154.842438) (xy 355.9095 -154.832308)
			(xy 355.965234 -154.830271) (xy 356.020671 -154.836371) (xy 356.074628 -154.850477) (xy 356.125957 -154.872289)
			(xy 356.173563 -154.901343) (xy 356.216431 -154.937018) (xy 356.253648 -154.978555) (xy 356.284421 -155.025068)
			(xy 356.308093 -155.075565) (xy 356.309184 -155.079192) (xy 358.16997 -155.079192) (xy 358.174041 -155.02357)
			(xy 358.186167 -154.969133) (xy 358.20609 -154.917042) (xy 358.233386 -154.868407) (xy 358.267472 -154.824264)
			(xy 358.307621 -154.785555) (xy 358.352979 -154.753104) (xy 358.402579 -154.727603) (xy 358.455363 -154.709596)
			(xy 358.510206 -154.699466) (xy 358.56594 -154.697429) (xy 358.621377 -154.703529) (xy 358.675334 -154.717635)
			(xy 358.726663 -154.739447) (xy 358.774269 -154.768501) (xy 358.817137 -154.804176) (xy 358.854354 -154.845713)
			(xy 358.885127 -154.892226) (xy 358.908799 -154.942723) (xy 358.924867 -154.99613) (xy 358.932987 -155.051306)
			(xy 358.933496 -155.079192) (xy 358.933431 -155.082748) (xy 359.49382 -155.082748) (xy 359.494246 -155.056433)
			(xy 359.501489 -155.004302) (xy 359.515815 -154.953658) (xy 359.536956 -154.905459) (xy 359.564509 -154.860617)
			(xy 359.597955 -154.819979) (xy 359.61701 -154.801824) (xy 359.624405 -154.794297) (xy 359.632933 -154.775021)
			(xy 359.63352 -154.764486) (xy 359.63352 -154.68981) (xy 359.632993 -154.67926) (xy 359.624456 -154.659965)
			(xy 359.61701 -154.652472) (xy 359.59795 -154.634321) (xy 359.564493 -154.593691) (xy 359.536934 -154.548849)
			(xy 359.515796 -154.500648) (xy 359.50148 -154.449999) (xy 359.494257 -154.397864) (xy 359.49382 -154.371548)
			(xy 359.4943 -154.344295) (xy 359.502051 -154.290343) (xy 359.517403 -154.238044) (xy 359.540042 -154.188462)
			(xy 359.569507 -154.142607) (xy 359.605199 -154.101414) (xy 359.646391 -154.065719) (xy 359.692245 -154.036251)
			(xy 359.741825 -154.01361) (xy 359.794124 -153.998255) (xy 359.848075 -153.990501) (xy 359.875328 -153.99004)
			(xy 359.901643 -153.990476) (xy 359.953774 -153.997715) (xy 360.004417 -154.01204) (xy 360.052617 -154.033178)
			(xy 360.097459 -154.06073) (xy 360.138097 -154.094175) (xy 360.156252 -154.11323) (xy 360.163762 -154.120646)
			(xy 360.18305 -154.129165) (xy 360.19359 -154.12974) (xy 360.268266 -154.12974) (xy 360.278813 -154.129194)
			(xy 360.298108 -154.12067) (xy 360.305604 -154.11323) (xy 360.325424 -154.092442) (xy 360.370196 -154.056467)
			(xy 360.419854 -154.027607) (xy 360.473276 -154.006514) (xy 360.529255 -153.993665) (xy 360.586528 -153.98935)
			(xy 360.643801 -153.993665) (xy 360.69978 -154.006514) (xy 360.753202 -154.027607) (xy 360.80286 -154.056467)
			(xy 360.847632 -154.092442) (xy 360.867452 -154.11323) (xy 360.874962 -154.120646) (xy 360.89425 -154.129165)
			(xy 360.90479 -154.12974) (xy 360.979466 -154.12974) (xy 360.990013 -154.129194) (xy 361.009308 -154.12067)
			(xy 361.016804 -154.11323) (xy 361.036624 -154.092442) (xy 361.081396 -154.056467) (xy 361.131054 -154.027607)
			(xy 361.184476 -154.006514) (xy 361.240455 -153.993665) (xy 361.297728 -153.98935) (xy 361.355001 -153.993665)
			(xy 361.41098 -154.006514) (xy 361.464402 -154.027607) (xy 361.51406 -154.056467) (xy 361.558832 -154.092442)
			(xy 361.578652 -154.11323) (xy 361.586162 -154.120646) (xy 361.60545 -154.129165) (xy 361.61599 -154.12974)
			(xy 361.690666 -154.12974) (xy 361.701213 -154.129194) (xy 361.720508 -154.12067) (xy 361.728004 -154.11323)
			(xy 361.746171 -154.094185) (xy 361.786797 -154.060726) (xy 361.831635 -154.033165) (xy 361.879834 -154.012024)
			(xy 361.93048 -153.997705) (xy 361.982612 -153.990479) (xy 362.008928 -153.99004) (xy 362.036184 -153.990429)
			(xy 362.09014 -153.998191) (xy 362.142442 -154.013553) (xy 362.192026 -154.036202) (xy 362.237881 -154.065678)
			(xy 362.279075 -154.101379) (xy 362.314768 -154.14258) (xy 362.344234 -154.188441) (xy 362.366874 -154.238029)
			(xy 362.382225 -154.290334) (xy 362.389976 -154.344292) (xy 362.390436 -154.371548) (xy 362.389989 -154.397863)
			(xy 362.382748 -154.449991) (xy 362.368424 -154.500634) (xy 362.347288 -154.548833) (xy 362.319739 -154.593676)
			(xy 362.286298 -154.634315) (xy 362.267246 -154.652472) (xy 362.259862 -154.660008) (xy 362.251326 -154.679277)
			(xy 362.250736 -154.68981) (xy 362.250736 -154.764486) (xy 362.251248 -154.775038) (xy 362.259794 -154.794334)
			(xy 362.267246 -154.801824) (xy 362.286315 -154.819966) (xy 362.319769 -154.8606) (xy 362.347325 -154.905443)
			(xy 362.368461 -154.953646) (xy 362.382776 -155.004296) (xy 362.389998 -155.056431) (xy 362.390436 -155.082748)
			(xy 362.389967 -155.109999) (xy 362.382205 -155.163946) (xy 362.366845 -155.216239) (xy 362.3442 -155.265815)
			(xy 362.314731 -155.311664) (xy 362.279038 -155.352853) (xy 362.237848 -155.388543) (xy 362.191997 -155.41801)
			(xy 362.142421 -155.440652) (xy 362.090126 -155.456009) (xy 362.036179 -155.463768) (xy 362.008928 -155.464256)
			(xy 361.982612 -155.463851) (xy 361.93048 -155.456605) (xy 361.879836 -155.442275) (xy 361.831636 -155.421131)
			(xy 361.786795 -155.393573) (xy 361.746158 -155.360123) (xy 361.728004 -155.341066) (xy 361.720474 -155.333674)
			(xy 361.701201 -155.325142) (xy 361.690666 -155.324556) (xy 361.61599 -155.324556) (xy 361.60544 -155.325079)
			(xy 361.586146 -155.33362) (xy 361.578652 -155.341066) (xy 361.558832 -155.361854) (xy 361.51406 -155.397829)
			(xy 361.464402 -155.426689) (xy 361.41098 -155.447782) (xy 361.355001 -155.460631) (xy 361.297728 -155.464946)
			(xy 361.240455 -155.460631) (xy 361.184476 -155.447782) (xy 361.131054 -155.426689) (xy 361.081396 -155.397829)
			(xy 361.036624 -155.361854) (xy 361.016804 -155.341066) (xy 361.009274 -155.333674) (xy 360.990001 -155.325142)
			(xy 360.979466 -155.324556) (xy 360.90479 -155.324556) (xy 360.89424 -155.325079) (xy 360.874946 -155.33362)
			(xy 360.867452 -155.341066) (xy 360.847632 -155.361854) (xy 360.80286 -155.397829) (xy 360.753202 -155.426689)
			(xy 360.69978 -155.447782) (xy 360.643801 -155.460631) (xy 360.586528 -155.464946) (xy 360.529255 -155.460631)
			(xy 360.473276 -155.447782) (xy 360.419854 -155.426689) (xy 360.370196 -155.397829) (xy 360.325424 -155.361854)
			(xy 360.305604 -155.341066) (xy 360.298074 -155.333674) (xy 360.278801 -155.325142) (xy 360.268266 -155.324556)
			(xy 360.19359 -155.324556) (xy 360.18304 -155.325079) (xy 360.163746 -155.33362) (xy 360.156252 -155.341066)
			(xy 360.138126 -155.36015) (xy 360.097488 -155.393602) (xy 360.052641 -155.421156) (xy 360.004435 -155.442289)
			(xy 359.953783 -155.456601) (xy 359.901646 -155.46382) (xy 359.875328 -155.464256) (xy 359.84808 -155.463696)
			(xy 359.794137 -155.455944) (xy 359.741847 -155.440595) (xy 359.692273 -155.417961) (xy 359.646425 -155.388502)
			(xy 359.605235 -155.352818) (xy 359.569544 -155.311636) (xy 359.540076 -155.265794) (xy 359.517431 -155.216225)
			(xy 359.502072 -155.163937) (xy 359.49431 -155.109996) (xy 359.49382 -155.082748) (xy 358.933431 -155.082748)
			(xy 358.932987 -155.107078) (xy 358.924867 -155.162254) (xy 358.908799 -155.215661) (xy 358.885127 -155.266158)
			(xy 358.854354 -155.312671) (xy 358.817137 -155.354208) (xy 358.774269 -155.389883) (xy 358.726663 -155.418937)
			(xy 358.675334 -155.440749) (xy 358.621377 -155.454855) (xy 358.56594 -155.460955) (xy 358.510206 -155.458918)
			(xy 358.455363 -155.448788) (xy 358.402579 -155.430781) (xy 358.352979 -155.40528) (xy 358.307621 -155.372829)
			(xy 358.267472 -155.33412) (xy 358.233386 -155.289977) (xy 358.20609 -155.241342) (xy 358.186167 -155.189251)
			(xy 358.174041 -155.134814) (xy 358.16997 -155.079192) (xy 356.309184 -155.079192) (xy 356.324161 -155.128972)
			(xy 356.332281 -155.184148) (xy 356.33279 -155.212034) (xy 356.332281 -155.23992) (xy 356.324161 -155.295096)
			(xy 356.308093 -155.348503) (xy 356.284421 -155.399) (xy 356.253648 -155.445513) (xy 356.216431 -155.48705)
			(xy 356.173563 -155.522725) (xy 356.125957 -155.551779) (xy 356.074628 -155.573591) (xy 356.020671 -155.587697)
			(xy 355.965234 -155.593797) (xy 355.9095 -155.59176) (xy 355.854657 -155.58163) (xy 355.801873 -155.563623)
			(xy 355.752273 -155.538122) (xy 355.706915 -155.505671) (xy 355.666766 -155.466962) (xy 355.63268 -155.422819)
			(xy 355.605384 -155.374184) (xy 355.585461 -155.322093) (xy 355.573335 -155.267656) (xy 355.569264 -155.212034)
			(xy 355.052376 -155.212034) (xy 355.052376 -156.69387) (xy 357.187498 -156.69387) (xy 357.191569 -156.638248)
			(xy 357.203695 -156.583811) (xy 357.223618 -156.53172) (xy 357.250914 -156.483085) (xy 357.285 -156.438942)
			(xy 357.325149 -156.400233) (xy 357.370507 -156.367782) (xy 357.420107 -156.342281) (xy 357.472891 -156.324274)
			(xy 357.527734 -156.314144) (xy 357.583468 -156.312107) (xy 357.638905 -156.318207) (xy 357.692862 -156.332313)
			(xy 357.744191 -156.354125) (xy 357.791797 -156.383179) (xy 357.834665 -156.418854) (xy 357.871882 -156.460391)
			(xy 357.902655 -156.506904) (xy 357.926327 -156.557401) (xy 357.942395 -156.610808) (xy 357.950515 -156.665984)
			(xy 357.951024 -156.69387) (xy 357.950515 -156.721756) (xy 357.942395 -156.776932) (xy 357.926327 -156.830339)
			(xy 357.902655 -156.880836) (xy 357.871882 -156.927349) (xy 357.834665 -156.968886) (xy 357.791797 -157.004561)
			(xy 357.744191 -157.033615) (xy 357.692862 -157.055427) (xy 357.638905 -157.069533) (xy 357.583468 -157.075633)
			(xy 357.527734 -157.073596) (xy 357.472891 -157.063466) (xy 357.420107 -157.045459) (xy 357.370507 -157.019958)
			(xy 357.325149 -156.987507) (xy 357.285 -156.948798) (xy 357.250914 -156.904655) (xy 357.223618 -156.85602)
			(xy 357.203695 -156.803929) (xy 357.191569 -156.749492) (xy 357.187498 -156.69387) (xy 355.052376 -156.69387)
			(xy 355.052376 -157.418278) (xy 355.052722 -157.427011) (xy 355.058595 -157.443458) (xy 355.06969 -157.456945)
			(xy 355.077014 -157.461712) (xy 355.092508 -157.47111) (xy 355.096052 -157.472955) (xy 355.103582 -157.475626)
			(xy 355.107494 -157.476444) (xy 355.116638 -157.477206) (xy 355.144832 -157.477206) (xy 355.155754 -157.474666)
			(xy 355.161596 -157.471872) (xy 355.188228 -157.459139) (xy 355.244447 -157.441144) (xy 355.30277 -157.432043)
			(xy 355.332284 -157.431486) (xy 355.359538 -157.431948) (xy 355.413492 -157.439704) (xy 355.465792 -157.455058)
			(xy 355.515375 -157.4777) (xy 355.561231 -157.507168) (xy 355.602426 -157.542863) (xy 355.638122 -157.584056)
			(xy 355.667592 -157.629911) (xy 355.675805 -157.647894) (xy 359.313988 -157.647894) (xy 359.314524 -157.621251)
			(xy 359.323048 -157.568653) (xy 359.339905 -157.518105) (xy 359.364658 -157.470919) (xy 359.396665 -157.428318)
			(xy 359.435096 -157.391409) (xy 359.456736 -157.37586) (xy 359.468026 -157.367502) (xy 359.485877 -157.345826)
			(xy 359.497157 -157.320111) (xy 359.501013 -157.292297) (xy 359.497155 -157.264483) (xy 359.485874 -157.238768)
			(xy 359.468021 -157.217094) (xy 359.456736 -157.208728) (xy 359.435134 -157.193132) (xy 359.396719 -157.156218)
			(xy 359.364719 -157.113623) (xy 359.339961 -157.066449) (xy 359.323086 -157.015916) (xy 359.31453 -156.963332)
			(xy 359.313988 -156.936694) (xy 359.314498 -156.910707) (xy 359.322628 -156.859372) (xy 359.338689 -156.809942)
			(xy 359.362285 -156.763632) (xy 359.392835 -156.721584) (xy 359.429586 -156.684833) (xy 359.471634 -156.654283)
			(xy 359.517944 -156.630687) (xy 359.567374 -156.614626) (xy 359.618709 -156.606496) (xy 359.670683 -156.606496)
			(xy 359.722018 -156.614626) (xy 359.771448 -156.630687) (xy 359.817758 -156.654283) (xy 359.859806 -156.684833)
			(xy 359.896557 -156.721584) (xy 359.927107 -156.763632) (xy 359.950703 -156.809942) (xy 359.966764 -156.859372)
			(xy 359.974894 -156.910707) (xy 359.975404 -156.936694) (xy 359.974862 -156.963336) (xy 359.96634 -157.015935)
			(xy 359.949485 -157.066483) (xy 359.924733 -157.113669) (xy 359.892726 -157.15627) (xy 359.854296 -157.193179)
			(xy 359.832656 -157.208728) (xy 359.821379 -157.217101) (xy 359.803529 -157.238774) (xy 359.79225 -157.264486)
			(xy 359.788392 -157.292297) (xy 359.792248 -157.320108) (xy 359.803525 -157.34582) (xy 359.821374 -157.367494)
			(xy 359.832656 -157.37586) (xy 359.854251 -157.391466) (xy 359.892666 -157.428378) (xy 359.924667 -157.47097)
			(xy 359.949427 -157.518142) (xy 359.966303 -157.568674) (xy 359.974861 -157.621257) (xy 359.975404 -157.647894)
			(xy 360.21391 -157.647894) (xy 360.214437 -157.621251) (xy 360.222961 -157.568652) (xy 360.239819 -157.518103)
			(xy 360.264574 -157.470917) (xy 360.296583 -157.428317) (xy 360.335017 -157.391408) (xy 360.356658 -157.37586)
			(xy 360.367946 -157.3675) (xy 360.385793 -157.345824) (xy 360.39707 -157.320109) (xy 360.400926 -157.292297)
			(xy 360.397068 -157.264484) (xy 360.38579 -157.23877) (xy 360.367941 -157.217095) (xy 360.356658 -157.208728)
			(xy 360.335061 -157.193125) (xy 360.296645 -157.156214) (xy 360.264643 -157.11362) (xy 360.239884 -157.066447)
			(xy 360.223009 -157.015915) (xy 360.214452 -156.963332) (xy 360.21391 -156.936694) (xy 360.21442 -156.910707)
			(xy 360.22255 -156.859372) (xy 360.238611 -156.809942) (xy 360.262207 -156.763632) (xy 360.292757 -156.721584)
			(xy 360.329508 -156.684833) (xy 360.371556 -156.654283) (xy 360.417866 -156.630687) (xy 360.467296 -156.614626)
			(xy 360.518631 -156.606496) (xy 360.570605 -156.606496) (xy 360.62194 -156.614626) (xy 360.67137 -156.630687)
			(xy 360.71768 -156.654283) (xy 360.759728 -156.684833) (xy 360.796479 -156.721584) (xy 360.827029 -156.763632)
			(xy 360.850625 -156.809942) (xy 360.866686 -156.859372) (xy 360.874816 -156.910707) (xy 360.875326 -156.936694)
			(xy 360.874817 -156.963338) (xy 360.866294 -157.01594) (xy 360.849434 -157.06649) (xy 360.824675 -157.113677)
			(xy 360.792661 -157.156276) (xy 360.754222 -157.193182) (xy 360.732578 -157.208728) (xy 360.721299 -157.2171)
			(xy 360.703445 -157.238772) (xy 360.692163 -157.264484) (xy 360.688305 -157.292297) (xy 360.692161 -157.320109)
			(xy 360.703441 -157.345823) (xy 360.721294 -157.367495) (xy 360.732578 -157.37586) (xy 360.754178 -157.391459)
			(xy 360.792592 -157.428373) (xy 360.824592 -157.470967) (xy 360.84935 -157.518141) (xy 360.866226 -157.568673)
			(xy 360.874783 -157.621256) (xy 360.875326 -157.647894) (xy 361.113832 -157.647894) (xy 361.11435 -157.62125)
			(xy 361.122874 -157.56865) (xy 361.139734 -157.518101) (xy 361.16449 -157.470914) (xy 361.196502 -157.428315)
			(xy 361.234937 -157.391407) (xy 361.25658 -157.37586) (xy 361.267875 -157.367505) (xy 361.285736 -157.345832)
			(xy 361.297022 -157.320115) (xy 361.300881 -157.292297) (xy 361.29702 -157.264479) (xy 361.285732 -157.238762)
			(xy 361.26787 -157.217091) (xy 361.25658 -157.208728) (xy 361.234987 -157.193119) (xy 361.19657 -157.156209)
			(xy 361.164567 -157.113617) (xy 361.139808 -157.066446) (xy 361.122931 -157.015915) (xy 361.114374 -156.963331)
			(xy 361.113832 -156.936694) (xy 361.114342 -156.910707) (xy 361.122472 -156.859372) (xy 361.138533 -156.809942)
			(xy 361.162129 -156.763632) (xy 361.192679 -156.721584) (xy 361.22943 -156.684833) (xy 361.271478 -156.654283)
			(xy 361.317788 -156.630687) (xy 361.367218 -156.614626) (xy 361.418553 -156.606496) (xy 361.470527 -156.606496)
			(xy 361.521862 -156.614626) (xy 361.571292 -156.630687) (xy 361.617602 -156.654283) (xy 361.65965 -156.684833)
			(xy 361.696401 -156.721584) (xy 361.726951 -156.763632) (xy 361.750547 -156.809942) (xy 361.766608 -156.859372)
			(xy 361.774738 -156.910707) (xy 361.775248 -156.936694) (xy 361.77473 -156.963338) (xy 361.766207 -157.015938)
			(xy 361.749348 -157.066488) (xy 361.724592 -157.113675) (xy 361.69258 -157.156274) (xy 361.654143 -157.193181)
			(xy 361.6325 -157.208728) (xy 361.621219 -157.217099) (xy 361.603362 -157.23877) (xy 361.592077 -157.264483)
			(xy 361.588218 -157.292297) (xy 361.592075 -157.320111) (xy 361.603358 -157.345825) (xy 361.621214 -157.367496)
			(xy 361.6325 -157.37586) (xy 361.654083 -157.391483) (xy 361.692501 -157.428389) (xy 361.724506 -157.470977)
			(xy 361.749267 -157.518147) (xy 361.766146 -157.568676) (xy 361.774705 -157.621257) (xy 361.775248 -157.647894)
			(xy 362.014008 -157.647894) (xy 362.014536 -157.621251) (xy 362.02306 -157.568652) (xy 362.039918 -157.518103)
			(xy 362.064672 -157.470917) (xy 362.096682 -157.428317) (xy 362.135115 -157.391408) (xy 362.156756 -157.37586)
			(xy 362.168044 -157.367501) (xy 362.185892 -157.345824) (xy 362.197169 -157.320109) (xy 362.201024 -157.292297)
			(xy 362.197167 -157.264484) (xy 362.185888 -157.23877) (xy 362.168039 -157.217095) (xy 362.156756 -157.208728)
			(xy 362.135158 -157.193126) (xy 362.096742 -157.156214) (xy 362.064741 -157.113621) (xy 362.039982 -157.066448)
			(xy 362.023107 -157.015916) (xy 362.01455 -156.963332) (xy 362.014008 -156.936694) (xy 362.014518 -156.910707)
			(xy 362.022648 -156.859372) (xy 362.038709 -156.809942) (xy 362.062305 -156.763632) (xy 362.092855 -156.721584)
			(xy 362.129606 -156.684833) (xy 362.171654 -156.654283) (xy 362.217964 -156.630687) (xy 362.267394 -156.614626)
			(xy 362.318729 -156.606496) (xy 362.370703 -156.606496) (xy 362.422038 -156.614626) (xy 362.471468 -156.630687)
			(xy 362.517778 -156.654283) (xy 362.559826 -156.684833) (xy 362.596577 -156.721584) (xy 362.627127 -156.763632)
			(xy 362.650723 -156.809942) (xy 362.666784 -156.859372) (xy 362.674914 -156.910707) (xy 362.675424 -156.936694)
			(xy 362.674916 -156.963338) (xy 362.666392 -157.01594) (xy 362.649532 -157.06649) (xy 362.624774 -157.113677)
			(xy 362.59276 -157.156276) (xy 362.55432 -157.193182) (xy 362.532676 -157.208728) (xy 362.521397 -157.2171)
			(xy 362.503544 -157.238772) (xy 362.492262 -157.264484) (xy 362.488404 -157.292297) (xy 362.49226 -157.320109)
			(xy 362.50354 -157.345822) (xy 362.521392 -157.367495) (xy 362.532676 -157.37586) (xy 362.554275 -157.39146)
			(xy 362.592689 -157.428374) (xy 362.624689 -157.470968) (xy 362.649448 -157.518141) (xy 362.666324 -157.568673)
			(xy 362.674881 -157.621256) (xy 362.675383 -157.645862) (xy 363.629448 -157.645862) (xy 363.629875 -157.619546)
			(xy 363.637116 -157.567416) (xy 363.651442 -157.516771) (xy 363.672582 -157.468572) (xy 363.700136 -157.42373)
			(xy 363.733582 -157.383093) (xy 363.752638 -157.364938) (xy 363.760016 -157.357396) (xy 363.768556 -157.338132)
			(xy 363.769148 -157.3276) (xy 363.769148 -157.252924) (xy 363.768605 -157.242376) (xy 363.760078 -157.223082)
			(xy 363.752638 -157.215586) (xy 363.733571 -157.197442) (xy 363.700117 -157.156809) (xy 363.672561 -157.111965)
			(xy 363.651425 -157.063763) (xy 363.63711 -157.013114) (xy 363.629886 -156.960979) (xy 363.629448 -156.934662)
			(xy 363.629934 -156.907411) (xy 363.63769 -156.853463) (xy 363.653045 -156.801168) (xy 363.675687 -156.751591)
			(xy 363.705153 -156.705741) (xy 363.740844 -156.66455) (xy 363.782035 -156.628859) (xy 363.827885 -156.599393)
			(xy 363.877462 -156.576751) (xy 363.929757 -156.561396) (xy 363.983705 -156.55364) (xy 364.038207 -156.55364)
			(xy 364.092155 -156.561396) (xy 364.14445 -156.576751) (xy 364.194027 -156.599393) (xy 364.239877 -156.628859)
			(xy 364.258622 -156.645101) (xy 365.614017 -156.645101) (xy 365.618332 -156.587828) (xy 365.631182 -156.531849)
			(xy 365.652276 -156.478427) (xy 365.681137 -156.428769) (xy 365.717113 -156.383997) (xy 365.737902 -156.364178)
			(xy 365.745315 -156.356667) (xy 365.753833 -156.337379) (xy 365.754412 -156.32684) (xy 365.754412 -156.252164)
			(xy 365.753858 -156.241617) (xy 365.74534 -156.222322) (xy 365.737902 -156.214826) (xy 365.718866 -156.19665)
			(xy 365.685407 -156.156025) (xy 365.657846 -156.111189) (xy 365.636704 -156.062992) (xy 365.622382 -156.012348)
			(xy 365.615153 -155.960217) (xy 365.614712 -155.933902) (xy 365.615198 -155.906651) (xy 365.622954 -155.852703)
			(xy 365.638309 -155.800408) (xy 365.660951 -155.750831) (xy 365.690417 -155.704981) (xy 365.726108 -155.66379)
			(xy 365.767299 -155.628099) (xy 365.813149 -155.598633) (xy 365.862726 -155.575991) (xy 365.915021 -155.560636)
			(xy 365.968969 -155.55288) (xy 366.023471 -155.55288) (xy 366.077419 -155.560636) (xy 366.129714 -155.575991)
			(xy 366.179291 -155.598633) (xy 366.225141 -155.628099) (xy 366.266332 -155.66379) (xy 366.302023 -155.704981)
			(xy 366.331489 -155.750831) (xy 366.354131 -155.800408) (xy 366.369486 -155.852703) (xy 366.377242 -155.906651)
			(xy 366.377728 -155.933902) (xy 366.377253 -155.960216) (xy 366.370018 -156.012343) (xy 366.3557 -156.062986)
			(xy 366.334569 -156.111184) (xy 366.307025 -156.156028) (xy 366.273588 -156.196669) (xy 366.254538 -156.214826)
			(xy 366.247129 -156.222341) (xy 366.238608 -156.241626) (xy 366.238028 -156.252164) (xy 366.238028 -156.32684)
			(xy 366.238568 -156.337389) (xy 366.247095 -156.356685) (xy 366.254538 -156.364178) (xy 366.275327 -156.383996)
			(xy 366.3113 -156.42877) (xy 366.340158 -156.478428) (xy 366.36125 -156.53185) (xy 366.374098 -156.587829)
			(xy 366.378413 -156.645101) (xy 366.374098 -156.702374) (xy 366.372962 -156.707322) (xy 368.679825 -156.707322)
			(xy 368.684137 -156.650052) (xy 368.696983 -156.594076) (xy 368.718071 -156.540656) (xy 368.746926 -156.491)
			(xy 368.782897 -156.446228) (xy 368.803682 -156.426408) (xy 368.811079 -156.418883) (xy 368.819607 -156.399606)
			(xy 368.820192 -156.38907) (xy 368.820192 -156.314394) (xy 368.819682 -156.303842) (xy 368.811133 -156.284547)
			(xy 368.803682 -156.277056) (xy 368.784609 -156.258918) (xy 368.751154 -156.218284) (xy 368.723598 -156.17344)
			(xy 368.702462 -156.125236) (xy 368.688149 -156.074586) (xy 368.680928 -156.022449) (xy 368.680492 -155.996132)
			(xy 368.680978 -155.968881) (xy 368.688734 -155.914933) (xy 368.704089 -155.862638) (xy 368.726731 -155.813061)
			(xy 368.756197 -155.767211) (xy 368.791888 -155.72602) (xy 368.833079 -155.690329) (xy 368.878929 -155.660863)
			(xy 368.928506 -155.638221) (xy 368.980801 -155.622866) (xy 369.034749 -155.61511) (xy 369.089251 -155.61511)
			(xy 369.143199 -155.622866) (xy 369.195494 -155.638221) (xy 369.245071 -155.660863) (xy 369.290921 -155.690329)
			(xy 369.332112 -155.72602) (xy 369.367803 -155.767211) (xy 369.397269 -155.813061) (xy 369.419911 -155.862638)
			(xy 369.435266 -155.914933) (xy 369.443022 -155.968881) (xy 369.443508 -155.996132) (xy 369.443059 -156.022447)
			(xy 369.43582 -156.074576) (xy 369.421497 -156.125219) (xy 369.400361 -156.173418) (xy 369.372812 -156.218261)
			(xy 369.339371 -156.2589) (xy 369.320318 -156.277056) (xy 369.312936 -156.284594) (xy 369.3044 -156.303862)
			(xy 369.303808 -156.314394) (xy 369.303808 -156.38907) (xy 369.304337 -156.39962) (xy 369.312872 -156.418915)
			(xy 369.320318 -156.426408) (xy 369.341138 -156.446196) (xy 369.377113 -156.490973) (xy 369.405971 -156.540635)
			(xy 369.427062 -156.594062) (xy 369.439909 -156.650045) (xy 369.444222 -156.707322) (xy 369.439903 -156.764598)
			(xy 369.427049 -156.82058) (xy 369.405952 -156.874004) (xy 369.377088 -156.923663) (xy 369.341108 -156.968436)
			(xy 369.320318 -156.988256) (xy 369.312936 -156.995794) (xy 369.3044 -157.015062) (xy 369.303808 -157.025594)
			(xy 369.303808 -157.10027) (xy 369.304337 -157.11082) (xy 369.312872 -157.130115) (xy 369.320318 -157.137608)
			(xy 369.339374 -157.155763) (xy 369.37283 -157.196393) (xy 369.400389 -157.241234) (xy 369.421527 -157.289435)
			(xy 369.435844 -157.340082) (xy 369.443069 -157.392216) (xy 369.443508 -157.418532) (xy 369.443022 -157.445783)
			(xy 369.435266 -157.499731) (xy 369.419911 -157.552026) (xy 369.397269 -157.601603) (xy 369.367803 -157.647453)
			(xy 369.332112 -157.688644) (xy 369.290921 -157.724335) (xy 369.245071 -157.753801) (xy 369.195494 -157.776443)
			(xy 369.143199 -157.791798) (xy 369.089251 -157.799554) (xy 369.034749 -157.799554) (xy 368.980801 -157.791798)
			(xy 368.928506 -157.776443) (xy 368.878929 -157.753801) (xy 368.833079 -157.724335) (xy 368.791888 -157.688644)
			(xy 368.756197 -157.647453) (xy 368.726731 -157.601603) (xy 368.704089 -157.552026) (xy 368.688734 -157.499731)
			(xy 368.680978 -157.445783) (xy 368.680492 -157.418532) (xy 368.680917 -157.392217) (xy 368.688161 -157.340086)
			(xy 368.702488 -157.289443) (xy 368.723629 -157.241244) (xy 368.751182 -157.196402) (xy 368.784627 -157.155764)
			(xy 368.803682 -157.137608) (xy 368.811079 -157.130083) (xy 368.819607 -157.110806) (xy 368.820192 -157.10027)
			(xy 368.820192 -157.025594) (xy 368.819682 -157.015042) (xy 368.811133 -156.995747) (xy 368.803682 -156.988256)
			(xy 368.782926 -156.968404) (xy 368.746951 -156.923636) (xy 368.71809 -156.873983) (xy 368.696996 -156.820566)
			(xy 368.684144 -156.764591) (xy 368.679825 -156.707322) (xy 366.372962 -156.707322) (xy 366.361249 -156.758353)
			(xy 366.340157 -156.811774) (xy 366.311299 -156.861432) (xy 366.275325 -156.906205) (xy 366.254538 -156.926026)
			(xy 366.247129 -156.933541) (xy 366.238608 -156.952826) (xy 366.238028 -156.963364) (xy 366.238028 -157.03804)
			(xy 366.238568 -157.048589) (xy 366.247095 -157.067885) (xy 366.254538 -157.075378) (xy 366.273583 -157.093544)
			(xy 366.30704 -157.134172) (xy 366.334599 -157.179011) (xy 366.355739 -157.227209) (xy 366.370059 -157.277854)
			(xy 366.377287 -157.329987) (xy 366.377728 -157.356302) (xy 366.377242 -157.383553) (xy 366.369486 -157.437501)
			(xy 366.354131 -157.489796) (xy 366.331489 -157.539373) (xy 366.302023 -157.585223) (xy 366.266332 -157.626414)
			(xy 366.225141 -157.662105) (xy 366.179291 -157.691571) (xy 366.129714 -157.714213) (xy 366.077419 -157.729568)
			(xy 366.023471 -157.737324) (xy 365.968969 -157.737324) (xy 365.915021 -157.729568) (xy 365.862726 -157.714213)
			(xy 365.813149 -157.691571) (xy 365.767299 -157.662105) (xy 365.726108 -157.626414) (xy 365.690417 -157.585223)
			(xy 365.660951 -157.539373) (xy 365.638309 -157.489796) (xy 365.622954 -157.437501) (xy 365.615198 -157.383553)
			(xy 365.614712 -157.356302) (xy 365.615177 -157.329988) (xy 365.622412 -157.277859) (xy 365.636731 -157.227216)
			(xy 365.657864 -157.179017) (xy 365.685411 -157.134174) (xy 365.71885 -157.093534) (xy 365.737902 -157.075378)
			(xy 365.745315 -157.067867) (xy 365.753833 -157.048579) (xy 365.754412 -157.03804) (xy 365.754412 -156.963364)
			(xy 365.753858 -156.952817) (xy 365.74534 -156.933522) (xy 365.737902 -156.926026) (xy 365.717115 -156.906205)
			(xy 365.681138 -156.861433) (xy 365.652277 -156.811776) (xy 365.631183 -156.758354) (xy 365.618333 -156.702374)
			(xy 365.614017 -156.645101) (xy 364.258622 -156.645101) (xy 364.281068 -156.66455) (xy 364.316759 -156.705741)
			(xy 364.346225 -156.751591) (xy 364.368867 -156.801168) (xy 364.384222 -156.853463) (xy 364.391978 -156.907411)
			(xy 364.392464 -156.934662) (xy 364.392049 -156.960978) (xy 364.384805 -157.013109) (xy 364.370477 -157.063753)
			(xy 364.349334 -157.111952) (xy 364.321778 -157.156794) (xy 364.28833 -157.197431) (xy 364.269274 -157.215586)
			(xy 364.261887 -157.223121) (xy 364.253352 -157.24239) (xy 364.252764 -157.252924) (xy 364.252764 -157.3276)
			(xy 364.25329 -157.33815) (xy 364.261829 -157.357444) (xy 364.269274 -157.364938) (xy 364.288336 -157.383087)
			(xy 364.321794 -157.423718) (xy 364.349352 -157.468559) (xy 364.37049 -157.516761) (xy 364.384805 -157.56741)
			(xy 364.392027 -157.619545) (xy 364.392464 -157.645862) (xy 364.391978 -157.673113) (xy 364.384222 -157.727061)
			(xy 364.368867 -157.779356) (xy 364.346225 -157.828933) (xy 364.316759 -157.874783) (xy 364.281068 -157.915974)
			(xy 364.239877 -157.951665) (xy 364.194027 -157.981131) (xy 364.14445 -158.003773) (xy 364.092155 -158.019128)
			(xy 364.038207 -158.026884) (xy 363.983705 -158.026884) (xy 363.929757 -158.019128) (xy 363.877462 -158.003773)
			(xy 363.827885 -157.981131) (xy 363.782035 -157.951665) (xy 363.740844 -157.915974) (xy 363.705153 -157.874783)
			(xy 363.675687 -157.828933) (xy 363.653045 -157.779356) (xy 363.63769 -157.727061) (xy 363.629934 -157.673113)
			(xy 363.629448 -157.645862) (xy 362.675383 -157.645862) (xy 362.675424 -157.647894) (xy 362.674914 -157.673881)
			(xy 362.666784 -157.725216) (xy 362.650723 -157.774646) (xy 362.627127 -157.820956) (xy 362.596577 -157.863004)
			(xy 362.559826 -157.899755) (xy 362.517778 -157.930305) (xy 362.471468 -157.953901) (xy 362.422038 -157.969962)
			(xy 362.370703 -157.978092) (xy 362.318729 -157.978092) (xy 362.267394 -157.969962) (xy 362.217964 -157.953901)
			(xy 362.171654 -157.930305) (xy 362.129606 -157.899755) (xy 362.092855 -157.863004) (xy 362.062305 -157.820956)
			(xy 362.038709 -157.774646) (xy 362.022648 -157.725216) (xy 362.014518 -157.673881) (xy 362.014008 -157.647894)
			(xy 361.775248 -157.647894) (xy 361.774738 -157.673881) (xy 361.766608 -157.725216) (xy 361.750547 -157.774646)
			(xy 361.726951 -157.820956) (xy 361.696401 -157.863004) (xy 361.65965 -157.899755) (xy 361.617602 -157.930305)
			(xy 361.571292 -157.953901) (xy 361.521862 -157.969962) (xy 361.470527 -157.978092) (xy 361.418553 -157.978092)
			(xy 361.367218 -157.969962) (xy 361.317788 -157.953901) (xy 361.271478 -157.930305) (xy 361.22943 -157.899755)
			(xy 361.192679 -157.863004) (xy 361.162129 -157.820956) (xy 361.138533 -157.774646) (xy 361.122472 -157.725216)
			(xy 361.114342 -157.673881) (xy 361.113832 -157.647894) (xy 360.875326 -157.647894) (xy 360.874816 -157.673881)
			(xy 360.866686 -157.725216) (xy 360.850625 -157.774646) (xy 360.827029 -157.820956) (xy 360.796479 -157.863004)
			(xy 360.759728 -157.899755) (xy 360.71768 -157.930305) (xy 360.67137 -157.953901) (xy 360.62194 -157.969962)
			(xy 360.570605 -157.978092) (xy 360.518631 -157.978092) (xy 360.467296 -157.969962) (xy 360.417866 -157.953901)
			(xy 360.371556 -157.930305) (xy 360.329508 -157.899755) (xy 360.292757 -157.863004) (xy 360.262207 -157.820956)
			(xy 360.238611 -157.774646) (xy 360.22255 -157.725216) (xy 360.21442 -157.673881) (xy 360.21391 -157.647894)
			(xy 359.975404 -157.647894) (xy 359.974894 -157.673881) (xy 359.966764 -157.725216) (xy 359.950703 -157.774646)
			(xy 359.927107 -157.820956) (xy 359.896557 -157.863004) (xy 359.859806 -157.899755) (xy 359.817758 -157.930305)
			(xy 359.771448 -157.953901) (xy 359.722018 -157.969962) (xy 359.670683 -157.978092) (xy 359.618709 -157.978092)
			(xy 359.567374 -157.969962) (xy 359.517944 -157.953901) (xy 359.471634 -157.930305) (xy 359.429586 -157.899755)
			(xy 359.392835 -157.863004) (xy 359.362285 -157.820956) (xy 359.338689 -157.774646) (xy 359.322628 -157.725216)
			(xy 359.314498 -157.673881) (xy 359.313988 -157.647894) (xy 355.675805 -157.647894) (xy 355.690236 -157.679493)
			(xy 355.705593 -157.731793) (xy 355.713351 -157.785746) (xy 355.713351 -157.840254) (xy 355.705593 -157.894207)
			(xy 355.690236 -157.946507) (xy 355.667592 -157.996089) (xy 355.638122 -158.041944) (xy 355.622138 -158.06039)
			(xy 357.139746 -158.06039) (xy 357.143817 -158.004768) (xy 357.155943 -157.950331) (xy 357.175866 -157.89824)
			(xy 357.203162 -157.849605) (xy 357.237248 -157.805462) (xy 357.277397 -157.766753) (xy 357.322755 -157.734302)
			(xy 357.372355 -157.708801) (xy 357.425139 -157.690794) (xy 357.479982 -157.680664) (xy 357.535716 -157.678627)
			(xy 357.591153 -157.684727) (xy 357.64511 -157.698833) (xy 357.696439 -157.720645) (xy 357.744045 -157.749699)
			(xy 357.786913 -157.785374) (xy 357.82413 -157.826911) (xy 357.854903 -157.873424) (xy 357.878575 -157.923921)
			(xy 357.894643 -157.977328) (xy 357.902763 -158.032504) (xy 357.903272 -158.06039) (xy 357.902763 -158.088276)
			(xy 357.894643 -158.143452) (xy 357.878575 -158.196859) (xy 357.854903 -158.247356) (xy 357.82413 -158.293869)
			(xy 357.786913 -158.335406) (xy 357.744045 -158.371081) (xy 357.696439 -158.400135) (xy 357.64511 -158.421947)
			(xy 357.591153 -158.436053) (xy 357.535716 -158.442153) (xy 357.479982 -158.440116) (xy 357.425139 -158.429986)
			(xy 357.372355 -158.411979) (xy 357.322755 -158.386478) (xy 357.277397 -158.354027) (xy 357.237248 -158.315318)
			(xy 357.203162 -158.271175) (xy 357.175866 -158.22254) (xy 357.155943 -158.170449) (xy 357.143817 -158.116012)
			(xy 357.139746 -158.06039) (xy 355.622138 -158.06039) (xy 355.602426 -158.083137) (xy 355.561231 -158.118832)
			(xy 355.515375 -158.1483) (xy 355.465792 -158.170942) (xy 355.413492 -158.186296) (xy 355.359538 -158.194052)
			(xy 355.332284 -158.194502) (xy 355.300816 -158.193857) (xy 355.238732 -158.183528) (xy 355.179186 -158.163151)
			(xy 355.151182 -158.148782) (xy 355.150928 -158.148782) (xy 355.144947 -158.145808) (xy 355.131954 -158.142726)
			(xy 355.125274 -158.142686) (xy 355.112574 -158.14294) (xy 355.077014 -158.164276) (xy 355.069725 -158.169084)
			(xy 355.058657 -158.182574) (xy 355.052733 -158.198987) (xy 355.052376 -158.20771) (xy 355.052376 -158.434278)
			(xy 355.052722 -158.443011) (xy 355.058595 -158.459458) (xy 355.06969 -158.472945) (xy 355.077014 -158.477712)
			(xy 355.092508 -158.48711) (xy 355.096052 -158.488955) (xy 355.103582 -158.491626) (xy 355.107494 -158.492444)
			(xy 355.116638 -158.493206) (xy 355.144832 -158.493206) (xy 355.155754 -158.490666) (xy 355.161596 -158.487872)
			(xy 355.188228 -158.475139) (xy 355.244447 -158.457144) (xy 355.30277 -158.448043) (xy 355.332284 -158.447486)
			(xy 355.359538 -158.447948) (xy 355.413492 -158.455704) (xy 355.465792 -158.471058) (xy 355.515375 -158.4937)
			(xy 355.561231 -158.523168) (xy 355.602426 -158.558863) (xy 355.638122 -158.600056) (xy 355.667592 -158.645911)
			(xy 355.690236 -158.695493) (xy 355.705593 -158.747793) (xy 355.706385 -158.753302) (xy 364.816642 -158.753302)
			(xy 364.820713 -158.69768) (xy 364.832839 -158.643243) (xy 364.852762 -158.591152) (xy 364.880058 -158.542517)
			(xy 364.914144 -158.498374) (xy 364.954293 -158.459665) (xy 364.999651 -158.427214) (xy 365.049251 -158.401713)
			(xy 365.102035 -158.383706) (xy 365.156878 -158.373576) (xy 365.212612 -158.371539) (xy 365.268049 -158.377639)
			(xy 365.322006 -158.391745) (xy 365.373335 -158.413557) (xy 365.420941 -158.442611) (xy 365.463809 -158.478286)
			(xy 365.501026 -158.519823) (xy 365.531799 -158.566336) (xy 365.555471 -158.616833) (xy 365.571539 -158.67024)
			(xy 365.579659 -158.725416) (xy 365.580168 -158.753302) (xy 365.579659 -158.781188) (xy 365.571539 -158.836364)
			(xy 365.555471 -158.889771) (xy 365.531799 -158.940268) (xy 365.501026 -158.986781) (xy 365.463809 -159.028318)
			(xy 365.420941 -159.063993) (xy 365.373335 -159.093047) (xy 365.322006 -159.114859) (xy 365.268049 -159.128965)
			(xy 365.212612 -159.135065) (xy 365.156878 -159.133028) (xy 365.102035 -159.122898) (xy 365.049251 -159.104891)
			(xy 364.999651 -159.07939) (xy 364.954293 -159.046939) (xy 364.914144 -159.00823) (xy 364.880058 -158.964087)
			(xy 364.852762 -158.915452) (xy 364.832839 -158.863361) (xy 364.820713 -158.808924) (xy 364.816642 -158.753302)
			(xy 355.706385 -158.753302) (xy 355.713351 -158.801746) (xy 355.713351 -158.856254) (xy 355.705593 -158.910207)
			(xy 355.690236 -158.962507) (xy 355.667592 -159.012089) (xy 355.638122 -159.057944) (xy 355.602426 -159.099137)
			(xy 355.561231 -159.134832) (xy 355.515375 -159.1643) (xy 355.465792 -159.186942) (xy 355.413492 -159.202296)
			(xy 355.359538 -159.210052) (xy 355.332284 -159.210502) (xy 355.300816 -159.209857) (xy 355.238732 -159.199528)
			(xy 355.179186 -159.179151) (xy 355.151182 -159.164782) (xy 355.150928 -159.164782) (xy 355.144947 -159.161808)
			(xy 355.131954 -159.158726) (xy 355.125274 -159.158686) (xy 355.112574 -159.15894) (xy 355.077014 -159.180276)
			(xy 355.069725 -159.185084) (xy 355.058657 -159.198574) (xy 355.052733 -159.214987) (xy 355.052376 -159.22371)
			(xy 355.052376 -159.439102) (xy 357.208072 -159.439102) (xy 357.212143 -159.38348) (xy 357.224269 -159.329043)
			(xy 357.244192 -159.276952) (xy 357.271488 -159.228317) (xy 357.305574 -159.184174) (xy 357.345723 -159.145465)
			(xy 357.391081 -159.113014) (xy 357.440681 -159.087513) (xy 357.493465 -159.069506) (xy 357.548308 -159.059376)
			(xy 357.604042 -159.057339) (xy 357.659479 -159.063439) (xy 357.713436 -159.077545) (xy 357.764765 -159.099357)
			(xy 357.812371 -159.128411) (xy 357.855239 -159.164086) (xy 357.892456 -159.205623) (xy 357.923229 -159.252136)
			(xy 357.946901 -159.302633) (xy 357.962969 -159.35604) (xy 357.971089 -159.411216) (xy 357.971598 -159.439102)
			(xy 357.971089 -159.466988) (xy 357.962969 -159.522164) (xy 357.960066 -159.531812) (xy 360.41279 -159.531812)
			(xy 360.416861 -159.47619) (xy 360.428987 -159.421753) (xy 360.44891 -159.369662) (xy 360.476206 -159.321027)
			(xy 360.510292 -159.276884) (xy 360.550441 -159.238175) (xy 360.595799 -159.205724) (xy 360.645399 -159.180223)
			(xy 360.698183 -159.162216) (xy 360.753026 -159.152086) (xy 360.80876 -159.150049) (xy 360.864197 -159.156149)
			(xy 360.918154 -159.170255) (xy 360.969483 -159.192067) (xy 361.017089 -159.221121) (xy 361.059957 -159.256796)
			(xy 361.097174 -159.298333) (xy 361.127947 -159.344846) (xy 361.151619 -159.395343) (xy 361.167687 -159.44875)
			(xy 361.171463 -159.474408) (xy 362.882432 -159.474408) (xy 362.886503 -159.418786) (xy 362.898629 -159.364349)
			(xy 362.918552 -159.312258) (xy 362.945848 -159.263623) (xy 362.979934 -159.21948) (xy 363.020083 -159.180771)
			(xy 363.065441 -159.14832) (xy 363.115041 -159.122819) (xy 363.167825 -159.104812) (xy 363.222668 -159.094682)
			(xy 363.278402 -159.092645) (xy 363.333839 -159.098745) (xy 363.387796 -159.112851) (xy 363.439125 -159.134663)
			(xy 363.486731 -159.163717) (xy 363.529599 -159.199392) (xy 363.566816 -159.240929) (xy 363.597589 -159.287442)
			(xy 363.621261 -159.337939) (xy 363.637329 -159.391346) (xy 363.645449 -159.446522) (xy 363.645958 -159.474408)
			(xy 363.645449 -159.502294) (xy 363.637329 -159.55747) (xy 363.621261 -159.610877) (xy 363.597589 -159.661374)
			(xy 363.566816 -159.707887) (xy 363.529599 -159.749424) (xy 363.486731 -159.785099) (xy 363.439125 -159.814153)
			(xy 363.387796 -159.835965) (xy 363.333839 -159.850071) (xy 363.278402 -159.856171) (xy 363.222668 -159.854134)
			(xy 363.167825 -159.844004) (xy 363.115041 -159.825997) (xy 363.065441 -159.800496) (xy 363.020083 -159.768045)
			(xy 362.979934 -159.729336) (xy 362.945848 -159.685193) (xy 362.918552 -159.636558) (xy 362.898629 -159.584467)
			(xy 362.886503 -159.53003) (xy 362.882432 -159.474408) (xy 361.171463 -159.474408) (xy 361.175807 -159.503926)
			(xy 361.176316 -159.531812) (xy 361.175807 -159.559698) (xy 361.167687 -159.614874) (xy 361.151619 -159.668281)
			(xy 361.127947 -159.718778) (xy 361.097174 -159.765291) (xy 361.059957 -159.806828) (xy 361.017089 -159.842503)
			(xy 360.969483 -159.871557) (xy 360.918154 -159.893369) (xy 360.864197 -159.907475) (xy 360.80876 -159.913575)
			(xy 360.753026 -159.911538) (xy 360.698183 -159.901408) (xy 360.645399 -159.883401) (xy 360.595799 -159.8579)
			(xy 360.550441 -159.825449) (xy 360.510292 -159.78674) (xy 360.476206 -159.742597) (xy 360.44891 -159.693962)
			(xy 360.428987 -159.641871) (xy 360.416861 -159.587434) (xy 360.41279 -159.531812) (xy 357.960066 -159.531812)
			(xy 357.946901 -159.575571) (xy 357.923229 -159.626068) (xy 357.892456 -159.672581) (xy 357.855239 -159.714118)
			(xy 357.812371 -159.749793) (xy 357.764765 -159.778847) (xy 357.713436 -159.800659) (xy 357.659479 -159.814765)
			(xy 357.604042 -159.820865) (xy 357.548308 -159.818828) (xy 357.493465 -159.808698) (xy 357.440681 -159.790691)
			(xy 357.391081 -159.76519) (xy 357.345723 -159.732739) (xy 357.305574 -159.69403) (xy 357.271488 -159.649887)
			(xy 357.244192 -159.601252) (xy 357.224269 -159.549161) (xy 357.212143 -159.494724) (xy 357.208072 -159.439102)
			(xy 355.052376 -159.439102) (xy 355.052376 -159.450278) (xy 355.052722 -159.459011) (xy 355.058595 -159.475458)
			(xy 355.06969 -159.488945) (xy 355.077014 -159.493712) (xy 355.092508 -159.50311) (xy 355.096052 -159.504955)
			(xy 355.103582 -159.507626) (xy 355.107494 -159.508444) (xy 355.116638 -159.509206) (xy 355.144832 -159.509206)
			(xy 355.155754 -159.506666) (xy 355.161596 -159.503872) (xy 355.188228 -159.491139) (xy 355.244447 -159.473144)
			(xy 355.30277 -159.464043) (xy 355.332284 -159.463486) (xy 355.359538 -159.463948) (xy 355.413491 -159.471703)
			(xy 355.465791 -159.487058) (xy 355.515373 -159.509699) (xy 355.561229 -159.539167) (xy 355.602424 -159.57486)
			(xy 355.63812 -159.616053) (xy 355.66759 -159.661907) (xy 355.690234 -159.711489) (xy 355.705592 -159.763788)
			(xy 355.71335 -159.81774) (xy 355.713792 -159.844994) (xy 355.713334 -159.87185) (xy 355.705801 -159.925031)
			(xy 355.690883 -159.976629) (xy 355.668875 -160.025625) (xy 355.640212 -160.071049) (xy 355.605461 -160.112004)
			(xy 355.565309 -160.14768) (xy 355.520549 -160.17737) (xy 355.472068 -160.20049) (xy 355.446584 -160.208976)
			(xy 355.44633 -160.208976) (xy 355.443536 -160.209992) (xy 355.438273 -160.212158) (xy 355.428783 -160.218434)
			(xy 355.42474 -160.222438) (xy 355.424486 -160.222692) (xy 355.42122 -160.226221) (xy 355.415975 -160.234278)
			(xy 355.414072 -160.238694) (xy 355.41204 -160.245552) (xy 355.39426 -160.316672) (xy 355.39426 -160.31718)
			(xy 355.391212 -160.330388) (xy 355.389506 -160.338976) (xy 355.391314 -160.356379) (xy 355.394768 -160.364424)
			(xy 355.397308 -160.368742) (xy 355.40061 -160.373822) (xy 355.992684 -160.965896) (xy 357.23779 -160.965896)
			(xy 357.241861 -160.910274) (xy 357.253987 -160.855837) (xy 357.27391 -160.803746) (xy 357.301206 -160.755111)
			(xy 357.335292 -160.710968) (xy 357.375441 -160.672259) (xy 357.420799 -160.639808) (xy 357.470399 -160.614307)
			(xy 357.523183 -160.5963) (xy 357.578026 -160.58617) (xy 357.63376 -160.584133) (xy 357.689197 -160.590233)
			(xy 357.743154 -160.604339) (xy 357.794483 -160.626151) (xy 357.842089 -160.655205) (xy 357.884957 -160.69088)
			(xy 357.922174 -160.732417) (xy 357.952947 -160.77893) (xy 357.976619 -160.829427) (xy 357.992687 -160.882834)
			(xy 358.000807 -160.93801) (xy 358.001279 -160.963864) (xy 358.62971 -160.963864) (xy 358.633781 -160.908242)
			(xy 358.645907 -160.853805) (xy 358.66583 -160.801714) (xy 358.693126 -160.753079) (xy 358.727212 -160.708936)
			(xy 358.767361 -160.670227) (xy 358.812719 -160.637776) (xy 358.862319 -160.612275) (xy 358.915103 -160.594268)
			(xy 358.969946 -160.584138) (xy 359.02568 -160.582101) (xy 359.081117 -160.588201) (xy 359.135074 -160.602307)
			(xy 359.186403 -160.624119) (xy 359.234009 -160.653173) (xy 359.276877 -160.688848) (xy 359.314094 -160.730385)
			(xy 359.344867 -160.776898) (xy 359.368539 -160.827395) (xy 359.384607 -160.880802) (xy 359.392727 -160.935978)
			(xy 359.393236 -160.963864) (xy 359.393143 -160.968944) (xy 359.901488 -160.968944) (xy 359.905559 -160.913322)
			(xy 359.917685 -160.858885) (xy 359.937608 -160.806794) (xy 359.964904 -160.758159) (xy 359.99899 -160.714016)
			(xy 360.039139 -160.675307) (xy 360.084497 -160.642856) (xy 360.134097 -160.617355) (xy 360.186881 -160.599348)
			(xy 360.241724 -160.589218) (xy 360.297458 -160.587181) (xy 360.352895 -160.593281) (xy 360.406852 -160.607387)
			(xy 360.458181 -160.629199) (xy 360.505787 -160.658253) (xy 360.548655 -160.693928) (xy 360.585872 -160.735465)
			(xy 360.616645 -160.781978) (xy 360.640317 -160.832475) (xy 360.656385 -160.885882) (xy 360.658778 -160.902142)
			(xy 361.68279 -160.902142) (xy 361.686861 -160.84652) (xy 361.698987 -160.792083) (xy 361.71891 -160.739992)
			(xy 361.746206 -160.691357) (xy 361.780292 -160.647214) (xy 361.820441 -160.608505) (xy 361.865799 -160.576054)
			(xy 361.915399 -160.550553) (xy 361.968183 -160.532546) (xy 362.023026 -160.522416) (xy 362.07876 -160.520379)
			(xy 362.134197 -160.526479) (xy 362.188154 -160.540585) (xy 362.239483 -160.562397) (xy 362.287089 -160.591451)
			(xy 362.329957 -160.627126) (xy 362.367174 -160.668663) (xy 362.397947 -160.715176) (xy 362.421619 -160.765673)
			(xy 362.437687 -160.81908) (xy 362.445807 -160.874256) (xy 362.446316 -160.902142) (xy 362.445807 -160.930028)
			(xy 362.437687 -160.985204) (xy 362.421619 -161.038611) (xy 362.397947 -161.089108) (xy 362.367174 -161.135621)
			(xy 362.329957 -161.177158) (xy 362.287089 -161.212833) (xy 362.239483 -161.241887) (xy 362.188154 -161.263699)
			(xy 362.134197 -161.277805) (xy 362.07876 -161.283905) (xy 362.023026 -161.281868) (xy 361.968183 -161.271738)
			(xy 361.915399 -161.253731) (xy 361.865799 -161.22823) (xy 361.820441 -161.195779) (xy 361.780292 -161.15707)
			(xy 361.746206 -161.112927) (xy 361.71891 -161.064292) (xy 361.698987 -161.012201) (xy 361.686861 -160.957764)
			(xy 361.68279 -160.902142) (xy 360.658778 -160.902142) (xy 360.664505 -160.941058) (xy 360.665014 -160.968944)
			(xy 360.664505 -160.99683) (xy 360.656385 -161.052006) (xy 360.640317 -161.105413) (xy 360.616645 -161.15591)
			(xy 360.585872 -161.202423) (xy 360.548655 -161.24396) (xy 360.505787 -161.279635) (xy 360.458181 -161.308689)
			(xy 360.406852 -161.330501) (xy 360.352895 -161.344607) (xy 360.297458 -161.350707) (xy 360.241724 -161.34867)
			(xy 360.186881 -161.33854) (xy 360.134097 -161.320533) (xy 360.084497 -161.295032) (xy 360.039139 -161.262581)
			(xy 359.99899 -161.223872) (xy 359.964904 -161.179729) (xy 359.937608 -161.131094) (xy 359.917685 -161.079003)
			(xy 359.905559 -161.024566) (xy 359.901488 -160.968944) (xy 359.393143 -160.968944) (xy 359.392727 -160.99175)
			(xy 359.384607 -161.046926) (xy 359.368539 -161.100333) (xy 359.344867 -161.15083) (xy 359.314094 -161.197343)
			(xy 359.276877 -161.23888) (xy 359.234009 -161.274555) (xy 359.186403 -161.303609) (xy 359.135074 -161.325421)
			(xy 359.081117 -161.339527) (xy 359.02568 -161.345627) (xy 358.969946 -161.34359) (xy 358.915103 -161.33346)
			(xy 358.862319 -161.315453) (xy 358.812719 -161.289952) (xy 358.767361 -161.257501) (xy 358.727212 -161.218792)
			(xy 358.693126 -161.174649) (xy 358.66583 -161.126014) (xy 358.645907 -161.073923) (xy 358.633781 -161.019486)
			(xy 358.62971 -160.963864) (xy 358.001279 -160.963864) (xy 358.001316 -160.965896) (xy 358.000807 -160.993782)
			(xy 357.992687 -161.048958) (xy 357.976619 -161.102365) (xy 357.952947 -161.152862) (xy 357.922174 -161.199375)
			(xy 357.884957 -161.240912) (xy 357.842089 -161.276587) (xy 357.794483 -161.305641) (xy 357.743154 -161.327453)
			(xy 357.689197 -161.341559) (xy 357.63376 -161.347659) (xy 357.578026 -161.345622) (xy 357.523183 -161.335492)
			(xy 357.470399 -161.317485) (xy 357.420799 -161.291984) (xy 357.375441 -161.259533) (xy 357.335292 -161.220824)
			(xy 357.301206 -161.176681) (xy 357.27391 -161.128046) (xy 357.253987 -161.075955) (xy 357.241861 -161.021518)
			(xy 357.23779 -160.965896) (xy 355.992684 -160.965896) (xy 357.238808 -162.21202) (xy 357.241602 -162.21456)
			(xy 357.246712 -162.218528) (xy 357.258407 -162.224048) (xy 357.264716 -162.225482) (xy 357.274114 -162.226244)
			(xy 357.816912 -162.226244) (xy 357.84466 -162.22685) (xy 357.899322 -162.236434) (xy 357.925624 -162.245294)
			(xy 357.94759 -162.253683) (xy 357.989024 -162.275911) (xy 358.026792 -162.303919) (xy 358.043734 -162.320224)
			(xy 358.321102 -162.597592) (xy 358.338653 -162.615809) (xy 358.36838 -162.656734) (xy 358.391335 -162.701809)
			(xy 358.40695 -162.749921) (xy 358.414842 -162.799884) (xy 358.415336 -162.825176) (xy 358.415336 -163.063936)
			(xy 358.41559 -163.068508) (xy 358.416617 -163.076571) (xy 358.423094 -163.091468) (xy 358.42829 -163.097718)
			(xy 358.434386 -163.104068) (xy 358.4448 -163.111942) (xy 358.44734 -163.113466) (xy 358.449394 -163.114736)
			(xy 364.34979 -163.114736) (xy 364.353861 -163.059114) (xy 364.365987 -163.004677) (xy 364.38591 -162.952586)
			(xy 364.413206 -162.903951) (xy 364.447292 -162.859808) (xy 364.487441 -162.821099) (xy 364.532799 -162.788648)
			(xy 364.582399 -162.763147) (xy 364.635183 -162.74514) (xy 364.690026 -162.73501) (xy 364.74576 -162.732973)
			(xy 364.801197 -162.739073) (xy 364.855154 -162.753179) (xy 364.906483 -162.774991) (xy 364.954089 -162.804045)
			(xy 364.996957 -162.83972) (xy 365.034174 -162.881257) (xy 365.064947 -162.92777) (xy 365.088619 -162.978267)
			(xy 365.104687 -163.031674) (xy 365.112807 -163.08685) (xy 365.113316 -163.114736) (xy 365.112807 -163.142622)
			(xy 365.104687 -163.197798) (xy 365.088619 -163.251205) (xy 365.064947 -163.301702) (xy 365.034174 -163.348215)
			(xy 364.996957 -163.389752) (xy 364.954089 -163.425427) (xy 364.906483 -163.454481) (xy 364.855154 -163.476293)
			(xy 364.801197 -163.490399) (xy 364.74576 -163.496499) (xy 364.690026 -163.494462) (xy 364.635183 -163.484332)
			(xy 364.582399 -163.466325) (xy 364.532799 -163.440824) (xy 364.487441 -163.408373) (xy 364.447292 -163.369664)
			(xy 364.413206 -163.325521) (xy 364.38591 -163.276886) (xy 364.365987 -163.224795) (xy 364.353861 -163.170358)
			(xy 364.34979 -163.114736) (xy 358.449394 -163.114736) (xy 358.464244 -163.12392) (xy 358.495575 -163.148377)
			(xy 358.509824 -163.162234) (xy 359.83672 -164.488876) (xy 359.837228 -164.489384) (xy 359.842976 -164.494584)
			(xy 359.856808 -164.501567) (xy 359.864406 -164.5031) (xy 359.872788 -164.503862) (xy 371.10162 -164.503862)
		)
		(stroke
			(width 0)
			(type solid)
		)
		(fill yes)
		(layer "In5.Cu")
		(net "GND")
	)
	(gr_poly
		(pts
			(xy 102.620826 -134.51459) (xy 102.630894 -134.514162) (xy 102.649491 -134.50644) (xy 102.656894 -134.499604)
			(xy 104.063038 -133.09346) (xy 104.070436 -133.086613) (xy 104.089035 -133.078883) (xy 104.099106 -133.078474)
			(xy 118.90121 -133.078474) (xy 118.911279 -133.078048) (xy 118.929878 -133.070329) (xy 118.937278 -133.063488)
			(xy 119.09933 -132.901436) (xy 119.106174 -132.894038) (xy 119.113896 -132.875438) (xy 119.114316 -132.865368)
			(xy 119.114316 -131.701794) (xy 119.113841 -131.691827) (xy 119.10627 -131.673385) (xy 119.099584 -131.66598)
			(xy 119.041418 -131.607814) (xy 119.023384 -131.600194) (xy 119.01297 -131.600194) (xy 118.985754 -131.599658)
			(xy 118.931887 -131.591818) (xy 118.879682 -131.5764) (xy 118.830198 -131.553718) (xy 118.784441 -131.524233)
			(xy 118.74334 -131.488543) (xy 118.707729 -131.447374) (xy 118.678331 -131.40156) (xy 118.655744 -131.352033)
			(xy 118.640427 -131.299799) (xy 118.632689 -131.245917) (xy 118.632689 -131.191483) (xy 118.640427 -131.137601)
			(xy 118.655744 -131.085367) (xy 118.678331 -131.03584) (xy 118.707729 -130.990026) (xy 118.74334 -130.948857)
			(xy 118.784441 -130.913167) (xy 118.830198 -130.883682) (xy 118.879682 -130.861) (xy 118.931887 -130.845582)
			(xy 118.985754 -130.837742) (xy 119.01297 -130.837178) (xy 119.023384 -130.837178) (xy 119.041418 -130.829558)
			(xy 119.099584 -130.771392) (xy 119.106269 -130.763983) (xy 119.113851 -130.745546) (xy 119.114316 -130.735578)
			(xy 119.114316 -127.399034) (xy 119.11383 -127.389072) (xy 119.106244 -127.370646) (xy 119.099584 -127.36322)
			(xy 119.041418 -127.305054) (xy 119.023384 -127.297434) (xy 119.01297 -127.297434) (xy 118.985751 -127.296898)
			(xy 118.931879 -127.289057) (xy 118.879668 -127.273638) (xy 118.830179 -127.250954) (xy 118.784417 -127.221466)
			(xy 118.743311 -127.185772) (xy 118.707696 -127.144598) (xy 118.678296 -127.09878) (xy 118.655706 -127.049247)
			(xy 118.640387 -126.997007) (xy 118.632649 -126.94312) (xy 118.632649 -126.88868) (xy 118.640387 -126.834793)
			(xy 118.655706 -126.782553) (xy 118.678296 -126.73302) (xy 118.707696 -126.687202) (xy 118.743311 -126.646028)
			(xy 118.784417 -126.610335) (xy 118.830179 -126.580846) (xy 118.879668 -126.558162) (xy 118.931879 -126.542743)
			(xy 118.985751 -126.534902) (xy 119.01297 -126.534418) (xy 119.023384 -126.534418) (xy 119.041418 -126.526798)
			(xy 119.099584 -126.468632) (xy 119.106275 -126.461225) (xy 119.113871 -126.442789) (xy 119.114316 -126.432818)
			(xy 119.114316 -126.383034) (xy 119.11383 -126.373072) (xy 119.106244 -126.354646) (xy 119.099584 -126.34722)
			(xy 119.041418 -126.289054) (xy 119.023384 -126.281434) (xy 119.01297 -126.281434) (xy 118.985751 -126.280898)
			(xy 118.931879 -126.273057) (xy 118.879668 -126.257638) (xy 118.830179 -126.234954) (xy 118.784417 -126.205466)
			(xy 118.743311 -126.169772) (xy 118.707696 -126.128598) (xy 118.678296 -126.08278) (xy 118.655706 -126.033247)
			(xy 118.640387 -125.981007) (xy 118.632649 -125.92712) (xy 118.632649 -125.87268) (xy 118.640387 -125.818793)
			(xy 118.655706 -125.766553) (xy 118.678296 -125.71702) (xy 118.707696 -125.671202) (xy 118.743311 -125.630028)
			(xy 118.784417 -125.594335) (xy 118.830179 -125.564846) (xy 118.879668 -125.542162) (xy 118.931879 -125.526743)
			(xy 118.985751 -125.518902) (xy 119.01297 -125.518418) (xy 119.023384 -125.518418) (xy 119.041418 -125.510798)
			(xy 119.099584 -125.452632) (xy 119.106275 -125.445225) (xy 119.113871 -125.426789) (xy 119.114316 -125.416818)
			(xy 119.114316 -121.488454) (xy 119.113679 -121.475942) (xy 119.101973 -121.453823) (xy 119.091964 -121.44629)
			(xy 119.0117 -121.392188) (xy 118.986808 -121.389394) (xy 118.975124 -121.39422) (xy 118.952504 -121.402851)
			(xy 118.905631 -121.414972) (xy 118.8576 -121.421056) (xy 118.833392 -121.421398) (xy 118.804476 -121.420863)
			(xy 118.747305 -121.412135) (xy 118.692106 -121.39488) (xy 118.640144 -121.369494) (xy 118.592606 -121.336556)
			(xy 118.550584 -121.296823) (xy 118.532402 -121.274332) (xy 118.524863 -121.265541) (xy 118.50409 -121.255362)
			(xy 118.492524 -121.254774) (xy 118.41226 -121.254774) (xy 118.400703 -121.25539) (xy 118.379944 -121.265571)
			(xy 118.372382 -121.274332) (xy 118.354192 -121.296817) (xy 118.312174 -121.336556) (xy 118.26464 -121.369499)
			(xy 118.212678 -121.39489) (xy 118.15748 -121.412147) (xy 118.100309 -121.420874) (xy 118.071392 -121.421398)
			(xy 118.044142 -121.420911) (xy 117.990196 -121.413154) (xy 117.937904 -121.397799) (xy 117.888329 -121.375158)
			(xy 117.842481 -121.345692) (xy 117.801293 -121.310001) (xy 117.765603 -121.268812) (xy 117.736139 -121.222964)
			(xy 117.713499 -121.173388) (xy 117.698144 -121.121096) (xy 117.690388 -121.06715) (xy 117.690388 -121.01265)
			(xy 117.698144 -120.958704) (xy 117.713499 -120.906412) (xy 117.736139 -120.856836) (xy 117.765603 -120.810988)
			(xy 117.801293 -120.769799) (xy 117.842481 -120.734108) (xy 117.888329 -120.704642) (xy 117.937904 -120.682001)
			(xy 117.990196 -120.666646) (xy 118.044142 -120.658889) (xy 118.071392 -120.658382) (xy 118.100309 -120.658915)
			(xy 118.157481 -120.667641) (xy 118.212682 -120.684894) (xy 118.264648 -120.710278) (xy 118.312188 -120.743213)
			(xy 118.354214 -120.782945) (xy 118.372382 -120.805448) (xy 118.379926 -120.81423) (xy 118.400697 -120.824399)
			(xy 118.41226 -120.825006) (xy 118.492524 -120.825006) (xy 118.504082 -120.824393) (xy 118.524843 -120.814213)
			(xy 118.532402 -120.805448) (xy 118.550592 -120.782964) (xy 118.592609 -120.743226) (xy 118.640143 -120.710287)
			(xy 118.692106 -120.684902) (xy 118.747305 -120.667653) (xy 118.804476 -120.658935) (xy 118.833392 -120.658382)
			(xy 118.857599 -120.658742) (xy 118.905627 -120.664831) (xy 118.952502 -120.676938) (xy 118.975124 -120.68556)
			(xy 118.986808 -120.690386) (xy 119.0117 -120.687592) (xy 119.091964 -120.63349) (xy 119.101984 -120.625961)
			(xy 119.113708 -120.603844) (xy 119.114316 -120.591326) (xy 119.114316 -118.448328) (xy 119.113673 -118.435819)
			(xy 119.101961 -118.41371) (xy 119.091964 -118.406164) (xy 119.0117 -118.352062) (xy 118.986808 -118.349268)
			(xy 118.975124 -118.354094) (xy 118.952504 -118.362726) (xy 118.905631 -118.374848) (xy 118.8576 -118.380932)
			(xy 118.833392 -118.381272) (xy 118.804476 -118.380737) (xy 118.747306 -118.372009) (xy 118.692108 -118.354753)
			(xy 118.640146 -118.329365) (xy 118.592611 -118.296426) (xy 118.55059 -118.256692) (xy 118.532402 -118.234206)
			(xy 118.524861 -118.225419) (xy 118.504089 -118.215245) (xy 118.492524 -118.214648) (xy 118.41226 -118.214648)
			(xy 118.400706 -118.215266) (xy 118.379957 -118.225458) (xy 118.372382 -118.234206) (xy 118.354192 -118.256692)
			(xy 118.312176 -118.296434) (xy 118.264642 -118.329379) (xy 118.21268 -118.354772) (xy 118.157481 -118.37203)
			(xy 118.100309 -118.380758) (xy 118.071392 -118.381272) (xy 118.044144 -118.380785) (xy 117.990202 -118.373029)
			(xy 117.937913 -118.357674) (xy 117.888342 -118.335035) (xy 117.842497 -118.305571) (xy 117.801311 -118.269883)
			(xy 117.765624 -118.228697) (xy 117.736161 -118.182851) (xy 117.713523 -118.133279) (xy 117.69817 -118.08099)
			(xy 117.690414 -118.027048) (xy 117.690414 -117.972552) (xy 117.69817 -117.91861) (xy 117.713523 -117.866321)
			(xy 117.736161 -117.816749) (xy 117.765624 -117.770903) (xy 117.801311 -117.729717) (xy 117.842497 -117.694029)
			(xy 117.888342 -117.664565) (xy 117.937913 -117.641926) (xy 117.990202 -117.626571) (xy 118.044144 -117.618815)
			(xy 118.071392 -117.618256) (xy 118.100308 -117.61879) (xy 118.157479 -117.627516) (xy 118.212678 -117.644771)
			(xy 118.26464 -117.670159) (xy 118.312176 -117.703099) (xy 118.354196 -117.742834) (xy 118.372382 -117.765322)
			(xy 118.379924 -117.774108) (xy 118.400696 -117.784282) (xy 118.41226 -117.78488) (xy 118.492524 -117.78488)
			(xy 118.504081 -117.784266) (xy 118.524839 -117.774082) (xy 118.532402 -117.765322) (xy 118.550593 -117.742839)
			(xy 118.59261 -117.703104) (xy 118.640145 -117.670167) (xy 118.692108 -117.644784) (xy 118.747306 -117.627536)
			(xy 118.804476 -117.618819) (xy 118.833392 -117.618256) (xy 118.857599 -117.618616) (xy 118.905627 -117.624705)
			(xy 118.952503 -117.636811) (xy 118.975124 -117.645434) (xy 118.986808 -117.65026) (xy 119.0117 -117.647466)
			(xy 119.091964 -117.593364) (xy 119.101979 -117.585833) (xy 119.113693 -117.563716) (xy 119.114316 -117.5512)
			(xy 119.114316 -103.46944) (xy 119.113882 -103.459374) (xy 119.106155 -103.440784) (xy 119.09933 -103.433372)
			(xy 113.656618 -97.99066) (xy 113.638504 -97.97188) (xy 113.607817 -97.929684) (xy 113.584116 -97.883203)
			(xy 113.567984 -97.833584) (xy 113.559821 -97.782052) (xy 113.559336 -97.755964) (xy 113.559336 -97.385886)
			(xy 113.556542 -97.373948) (xy 113.553748 -97.36836) (xy 113.539915 -97.340832) (xy 113.520341 -97.282418)
			(xy 113.510416 -97.221617) (xy 113.509806 -97.190814) (xy 113.510309 -97.162651) (xy 113.518585 -97.106935)
			(xy 113.534959 -97.053041) (xy 113.559076 -97.002139) (xy 113.590412 -96.955333) (xy 113.628286 -96.913641)
			(xy 113.64976 -96.895412) (xy 113.658904 -96.888046) (xy 113.66881 -96.86671) (xy 113.66627 -96.763078)
			(xy 113.655602 -96.742504) (xy 113.646204 -96.735392) (xy 113.622799 -96.717247) (xy 113.581356 -96.674946)
			(xy 113.546939 -96.626755) (xy 113.520372 -96.573829) (xy 113.502293 -96.517438) (xy 113.493134 -96.458931)
			(xy 113.492534 -96.429322) (xy 113.49302 -96.402071) (xy 113.500776 -96.348123) (xy 113.516131 -96.295828)
			(xy 113.538773 -96.246251) (xy 113.568239 -96.200401) (xy 113.60393 -96.15921) (xy 113.645121 -96.123519)
			(xy 113.690971 -96.094053) (xy 113.740548 -96.071411) (xy 113.792843 -96.056056) (xy 113.846791 -96.0483)
			(xy 113.901293 -96.0483) (xy 113.955241 -96.056056) (xy 114.007536 -96.071411) (xy 114.057113 -96.094053)
			(xy 114.102963 -96.123519) (xy 114.144154 -96.15921) (xy 114.179845 -96.200401) (xy 114.209311 -96.246251)
			(xy 114.231953 -96.295828) (xy 114.247308 -96.348123) (xy 114.255064 -96.402071) (xy 114.25555 -96.429322)
			(xy 114.255044 -96.457484) (xy 114.246763 -96.513195) (xy 114.230384 -96.567085) (xy 114.206262 -96.617982)
			(xy 114.174922 -96.664781) (xy 114.137044 -96.706465) (xy 114.115596 -96.724724) (xy 114.106452 -96.73209)
			(xy 114.096546 -96.753426) (xy 114.099086 -96.857058) (xy 114.109754 -96.877632) (xy 114.119152 -96.884744)
			(xy 114.142562 -96.902887) (xy 114.184017 -96.945184) (xy 114.218446 -96.993373) (xy 114.245025 -97.046298)
			(xy 114.263116 -97.102692) (xy 114.272286 -97.161202) (xy 114.272822 -97.190814) (xy 114.272209 -97.221615)
			(xy 114.262269 -97.282412) (xy 114.242697 -97.340824) (xy 114.22888 -97.36836) (xy 114.226086 -97.373948)
			(xy 114.223292 -97.385886) (xy 114.223292 -97.597468) (xy 114.223778 -97.60743) (xy 114.231366 -97.625855)
			(xy 114.238024 -97.633282) (xy 117.970808 -101.36632) (xy 117.97825 -101.373017) (xy 117.996748 -101.38062)
			(xy 118.016748 -101.380601) (xy 118.02618 -101.377242) (xy 118.040658 -101.371146) (xy 118.057676 -101.346)
			(xy 118.057676 -99.270312) (xy 118.05714 -99.260324) (xy 118.049427 -99.241891) (xy 118.04269 -99.234498)
			(xy 117.94363 -99.135438) (xy 117.93679 -99.128038) (xy 117.929074 -99.109439) (xy 117.928644 -99.09937)
			(xy 117.928644 -94.973648) (xy 117.92821 -94.963583) (xy 117.920476 -94.944998) (xy 117.913658 -94.93758)
			(xy 116.347494 -93.371416) (xy 116.340438 -93.364862) (xy 116.322808 -93.357154) (xy 116.303577 -93.35654)
			(xy 116.294408 -93.359478) (xy 116.193824 -93.395546) (xy 116.176044 -93.418406) (xy 116.17452 -93.433392)
			(xy 116.171287 -93.461332) (xy 116.15766 -93.5159) (xy 116.136169 -93.567877) (xy 116.107281 -93.616135)
			(xy 116.07162 -93.659629) (xy 116.029961 -93.697416) (xy 115.983205 -93.728678) (xy 115.932367 -93.752737)
			(xy 115.878547 -93.769071) (xy 115.822912 -93.777327) (xy 115.79479 -93.777816) (xy 115.767539 -93.77733)
			(xy 115.713592 -93.769572) (xy 115.661298 -93.754216) (xy 115.611721 -93.731574) (xy 115.565872 -93.702108)
			(xy 115.524682 -93.666417) (xy 115.488991 -93.625227) (xy 115.459525 -93.579377) (xy 115.436883 -93.5298)
			(xy 115.421528 -93.477506) (xy 115.41377 -93.423559) (xy 115.413282 -93.396308) (xy 115.413783 -93.368187)
			(xy 115.422039 -93.312554) (xy 115.438373 -93.258736) (xy 115.462431 -93.207899) (xy 115.493691 -93.161144)
			(xy 115.531478 -93.119486) (xy 115.57497 -93.083827) (xy 115.623227 -93.054939) (xy 115.675201 -93.033449)
			(xy 115.729768 -93.019822) (xy 115.757706 -93.016578) (xy 115.772692 -93.015054) (xy 115.795552 -92.997274)
			(xy 115.83162 -92.89669) (xy 115.834452 -92.887504) (xy 115.83381 -92.868305) (xy 115.826198 -92.850668)
			(xy 115.819682 -92.843604) (xy 115.64112 -92.665042) (xy 115.633719 -92.658203) (xy 115.61512 -92.650492)
			(xy 115.605052 -92.650056) (xy 99.631754 -92.650056) (xy 99.621755 -92.650544) (xy 99.603268 -92.658173)
			(xy 99.589077 -92.672264) (xy 99.584764 -92.681298) (xy 99.578668 -92.695776) (xy 99.584764 -92.725748)
			(xy 99.842828 -92.983558) (xy 99.864824 -93.006285) (xy 99.903291 -93.056492) (xy 99.934874 -93.11129)
			(xy 99.959034 -93.169743) (xy 99.975357 -93.230849) (xy 99.983563 -93.293563) (xy 99.984052 -93.325188)
			(xy 99.984052 -93.447362) (xy 104.346754 -93.447362) (xy 104.350825 -93.39174) (xy 104.362951 -93.337303)
			(xy 104.382874 -93.285212) (xy 104.41017 -93.236577) (xy 104.444256 -93.192434) (xy 104.484405 -93.153725)
			(xy 104.529763 -93.121274) (xy 104.579363 -93.095773) (xy 104.632147 -93.077766) (xy 104.68699 -93.067636)
			(xy 104.742724 -93.065599) (xy 104.798161 -93.071699) (xy 104.852118 -93.085805) (xy 104.903447 -93.107617)
			(xy 104.951053 -93.136671) (xy 104.993921 -93.172346) (xy 105.031138 -93.213883) (xy 105.061911 -93.260396)
			(xy 105.085583 -93.310893) (xy 105.101651 -93.3643) (xy 105.109771 -93.419476) (xy 105.110076 -93.436186)
			(xy 106.40517 -93.436186) (xy 106.409241 -93.380564) (xy 106.421367 -93.326127) (xy 106.44129 -93.274036)
			(xy 106.468586 -93.225401) (xy 106.502672 -93.181258) (xy 106.542821 -93.142549) (xy 106.588179 -93.110098)
			(xy 106.637779 -93.084597) (xy 106.690563 -93.06659) (xy 106.745406 -93.05646) (xy 106.80114 -93.054423)
			(xy 106.856577 -93.060523) (xy 106.910534 -93.074629) (xy 106.961863 -93.096441) (xy 107.009469 -93.125495)
			(xy 107.052337 -93.16117) (xy 107.089554 -93.202707) (xy 107.120327 -93.24922) (xy 107.143999 -93.299717)
			(xy 107.160067 -93.353124) (xy 107.168187 -93.4083) (xy 107.168696 -93.436186) (xy 107.168187 -93.464072)
			(xy 107.160067 -93.519248) (xy 107.143999 -93.572655) (xy 107.120327 -93.623152) (xy 107.089554 -93.669665)
			(xy 107.052337 -93.711202) (xy 107.009469 -93.746877) (xy 106.961863 -93.775931) (xy 106.910534 -93.797743)
			(xy 106.856577 -93.811849) (xy 106.80114 -93.817949) (xy 106.745406 -93.815912) (xy 106.690563 -93.805782)
			(xy 106.637779 -93.787775) (xy 106.588179 -93.762274) (xy 106.542821 -93.729823) (xy 106.502672 -93.691114)
			(xy 106.468586 -93.646971) (xy 106.44129 -93.598336) (xy 106.421367 -93.546245) (xy 106.409241 -93.491808)
			(xy 106.40517 -93.436186) (xy 105.110076 -93.436186) (xy 105.11028 -93.447362) (xy 105.109771 -93.475248)
			(xy 105.101651 -93.530424) (xy 105.085583 -93.583831) (xy 105.061911 -93.634328) (xy 105.031138 -93.680841)
			(xy 104.993921 -93.722378) (xy 104.951053 -93.758053) (xy 104.903447 -93.787107) (xy 104.852118 -93.808919)
			(xy 104.798161 -93.823025) (xy 104.742724 -93.829125) (xy 104.68699 -93.827088) (xy 104.632147 -93.816958)
			(xy 104.579363 -93.798951) (xy 104.529763 -93.77345) (xy 104.484405 -93.740999) (xy 104.444256 -93.70229)
			(xy 104.41017 -93.658147) (xy 104.382874 -93.609512) (xy 104.362951 -93.557421) (xy 104.350825 -93.502984)
			(xy 104.346754 -93.447362) (xy 99.984052 -93.447362) (xy 99.984052 -94.088485) (xy 109.149614 -94.088485)
			(xy 109.149614 -94.028515) (xy 109.157442 -93.969058) (xy 109.172963 -93.911131) (xy 109.195912 -93.855726)
			(xy 109.225897 -93.80379) (xy 109.262405 -93.756213) (xy 109.30481 -93.713807) (xy 109.352387 -93.6773)
			(xy 109.404322 -93.647314) (xy 109.459727 -93.624364) (xy 109.517654 -93.608843) (xy 109.577111 -93.601014)
			(xy 109.607096 -93.600524) (xy 110.470696 -93.600524) (xy 110.500681 -93.601021) (xy 110.560138 -93.608848)
			(xy 110.618064 -93.624369) (xy 110.673469 -93.647318) (xy 110.725405 -93.677303) (xy 110.772982 -93.71381)
			(xy 110.815388 -93.756215) (xy 110.851895 -93.803792) (xy 110.88188 -93.855727) (xy 110.90483 -93.911132)
			(xy 110.920351 -93.969058) (xy 110.928179 -94.028515) (xy 110.928179 -94.088485) (xy 110.920351 -94.147942)
			(xy 110.90483 -94.205868) (xy 110.88188 -94.261273) (xy 110.851895 -94.313208) (xy 110.815388 -94.360785)
			(xy 110.772982 -94.40319) (xy 110.725405 -94.439697) (xy 110.673469 -94.469682) (xy 110.618064 -94.492631)
			(xy 110.584158 -94.501716) (xy 114.13439 -94.501716) (xy 114.138461 -94.446094) (xy 114.150587 -94.391657)
			(xy 114.17051 -94.339566) (xy 114.197806 -94.290931) (xy 114.231892 -94.246788) (xy 114.272041 -94.208079)
			(xy 114.317399 -94.175628) (xy 114.366999 -94.150127) (xy 114.419783 -94.13212) (xy 114.474626 -94.12199)
			(xy 114.53036 -94.119953) (xy 114.585797 -94.126053) (xy 114.639754 -94.140159) (xy 114.691083 -94.161971)
			(xy 114.738689 -94.191025) (xy 114.781557 -94.2267) (xy 114.818774 -94.268237) (xy 114.849547 -94.31475)
			(xy 114.873219 -94.365247) (xy 114.889287 -94.418654) (xy 114.897407 -94.47383) (xy 114.897916 -94.501716)
			(xy 114.897407 -94.529602) (xy 114.889287 -94.584778) (xy 114.873219 -94.638185) (xy 114.849547 -94.688682)
			(xy 114.818774 -94.735195) (xy 114.781557 -94.776732) (xy 114.738689 -94.812407) (xy 114.691083 -94.841461)
			(xy 114.639754 -94.863273) (xy 114.585797 -94.877379) (xy 114.53036 -94.883479) (xy 114.474626 -94.881442)
			(xy 114.419783 -94.871312) (xy 114.366999 -94.853305) (xy 114.317399 -94.827804) (xy 114.272041 -94.795353)
			(xy 114.231892 -94.756644) (xy 114.197806 -94.712501) (xy 114.17051 -94.663866) (xy 114.150587 -94.611775)
			(xy 114.138461 -94.557338) (xy 114.13439 -94.501716) (xy 110.584158 -94.501716) (xy 110.560138 -94.508152)
			(xy 110.500681 -94.515979) (xy 110.470696 -94.516448) (xy 109.607096 -94.516448) (xy 109.577111 -94.515986)
			(xy 109.517654 -94.508157) (xy 109.459727 -94.492636) (xy 109.404322 -94.469686) (xy 109.352387 -94.4397)
			(xy 109.30481 -94.403193) (xy 109.262405 -94.360787) (xy 109.225897 -94.31321) (xy 109.195912 -94.261274)
			(xy 109.172963 -94.205869) (xy 109.157442 -94.147942) (xy 109.149614 -94.088485) (xy 99.984052 -94.088485)
			(xy 99.984052 -95.905574) (xy 99.983544 -95.930466) (xy 99.983036 -95.941642) (xy 99.991164 -95.962216)
			(xy 100.063554 -96.030796) (xy 100.084636 -96.037908) (xy 100.095812 -96.036638) (xy 100.105879 -96.03566)
			(xy 100.126083 -96.034643) (xy 100.136198 -96.034606) (xy 100.16345 -96.035069) (xy 100.217399 -96.042826)
			(xy 100.269695 -96.058181) (xy 100.319274 -96.080822) (xy 100.365126 -96.110289) (xy 100.406317 -96.145982)
			(xy 100.442009 -96.187173) (xy 100.471477 -96.233024) (xy 100.494118 -96.282603) (xy 100.509474 -96.334899)
			(xy 100.517231 -96.388848) (xy 100.517231 -96.443352) (xy 100.509474 -96.497301) (xy 100.494118 -96.549597)
			(xy 100.471477 -96.599176) (xy 100.442009 -96.645027) (xy 100.406317 -96.686218) (xy 100.365126 -96.721911)
			(xy 100.319274 -96.751378) (xy 100.269695 -96.774019) (xy 100.217399 -96.789374) (xy 100.16345 -96.797131)
			(xy 100.136198 -96.797622) (xy 100.108321 -96.797114) (xy 100.053162 -96.788999) (xy 99.999771 -96.772942)
			(xy 99.949285 -96.749284) (xy 99.902781 -96.718531) (xy 99.861248 -96.681336) (xy 99.825571 -96.638492)
			(xy 99.79651 -96.590912) (xy 99.774683 -96.539609) (xy 99.760556 -96.485675) (xy 99.756976 -96.458024)
			(xy 99.755706 -96.446848) (xy 99.744276 -96.428052) (xy 99.661726 -96.371918) (xy 99.639882 -96.368362)
			(xy 99.629214 -96.37141) (xy 99.597821 -96.379427) (xy 99.533595 -96.387968) (xy 99.501198 -96.388428)
			(xy 99.469583 -96.387933) (xy 99.406895 -96.37968) (xy 99.34582 -96.363314) (xy 99.287403 -96.339116)
			(xy 99.232646 -96.3075) (xy 99.182483 -96.269007) (xy 99.137774 -96.224296) (xy 99.099284 -96.174131)
			(xy 99.067672 -96.119371) (xy 99.043477 -96.060954) (xy 99.027115 -95.999878) (xy 99.018865 -95.937189)
			(xy 99.018344 -95.905574) (xy 99.018344 -93.546168) (xy 99.017799 -93.536184) (xy 99.010071 -93.517766)
			(xy 99.003358 -93.510354) (xy 98.157792 -92.665042) (xy 98.150448 -92.658228) (xy 98.131986 -92.650492)
			(xy 98.121978 -92.650056) (xy 85.52307 -92.650056) (xy 85.513003 -92.650486) (xy 85.494412 -92.658214)
			(xy 85.487002 -92.665042) (xy 83.579208 -94.572836) (xy 88.806526 -94.572836) (xy 88.810597 -94.517214)
			(xy 88.822723 -94.462777) (xy 88.842646 -94.410686) (xy 88.869942 -94.362051) (xy 88.904028 -94.317908)
			(xy 88.944177 -94.279199) (xy 88.989535 -94.246748) (xy 89.039135 -94.221247) (xy 89.091919 -94.20324)
			(xy 89.146762 -94.19311) (xy 89.202496 -94.191073) (xy 89.257933 -94.197173) (xy 89.31189 -94.211279)
			(xy 89.363219 -94.233091) (xy 89.38968 -94.24924) (xy 95.43618 -94.24924) (xy 95.440251 -94.193618)
			(xy 95.452377 -94.139181) (xy 95.4723 -94.08709) (xy 95.499596 -94.038455) (xy 95.533682 -93.994312)
			(xy 95.573831 -93.955603) (xy 95.619189 -93.923152) (xy 95.668789 -93.897651) (xy 95.721573 -93.879644)
			(xy 95.776416 -93.869514) (xy 95.83215 -93.867477) (xy 95.887587 -93.873577) (xy 95.941544 -93.887683)
			(xy 95.992873 -93.909495) (xy 96.040479 -93.938549) (xy 96.083347 -93.974224) (xy 96.120564 -94.015761)
			(xy 96.151337 -94.062274) (xy 96.175009 -94.112771) (xy 96.191077 -94.166178) (xy 96.199197 -94.221354)
			(xy 96.199706 -94.24924) (xy 96.199632 -94.253304) (xy 96.45218 -94.253304) (xy 96.456251 -94.197682)
			(xy 96.468377 -94.143245) (xy 96.4883 -94.091154) (xy 96.515596 -94.042519) (xy 96.549682 -93.998376)
			(xy 96.589831 -93.959667) (xy 96.635189 -93.927216) (xy 96.684789 -93.901715) (xy 96.737573 -93.883708)
			(xy 96.792416 -93.873578) (xy 96.84815 -93.871541) (xy 96.903587 -93.877641) (xy 96.957544 -93.891747)
			(xy 97.008873 -93.913559) (xy 97.056479 -93.942613) (xy 97.099347 -93.978288) (xy 97.136564 -94.019825)
			(xy 97.167337 -94.066338) (xy 97.191009 -94.116835) (xy 97.207077 -94.170242) (xy 97.215197 -94.225418)
			(xy 97.215706 -94.253304) (xy 97.215197 -94.28119) (xy 97.207077 -94.336366) (xy 97.191009 -94.389773)
			(xy 97.167337 -94.44027) (xy 97.136564 -94.486783) (xy 97.099347 -94.52832) (xy 97.056479 -94.563995)
			(xy 97.008873 -94.593049) (xy 96.957544 -94.614861) (xy 96.903587 -94.628967) (xy 96.84815 -94.635067)
			(xy 96.792416 -94.63303) (xy 96.737573 -94.6229) (xy 96.684789 -94.604893) (xy 96.635189 -94.579392)
			(xy 96.589831 -94.546941) (xy 96.549682 -94.508232) (xy 96.515596 -94.464089) (xy 96.4883 -94.415454)
			(xy 96.468377 -94.363363) (xy 96.456251 -94.308926) (xy 96.45218 -94.253304) (xy 96.199632 -94.253304)
			(xy 96.199197 -94.277126) (xy 96.191077 -94.332302) (xy 96.175009 -94.385709) (xy 96.151337 -94.436206)
			(xy 96.120564 -94.482719) (xy 96.083347 -94.524256) (xy 96.040479 -94.559931) (xy 95.992873 -94.588985)
			(xy 95.941544 -94.610797) (xy 95.887587 -94.624903) (xy 95.83215 -94.631003) (xy 95.776416 -94.628966)
			(xy 95.721573 -94.618836) (xy 95.668789 -94.600829) (xy 95.619189 -94.575328) (xy 95.573831 -94.542877)
			(xy 95.533682 -94.504168) (xy 95.499596 -94.460025) (xy 95.4723 -94.41139) (xy 95.452377 -94.359299)
			(xy 95.440251 -94.304862) (xy 95.43618 -94.24924) (xy 89.38968 -94.24924) (xy 89.410825 -94.262145)
			(xy 89.453693 -94.29782) (xy 89.49091 -94.339357) (xy 89.521683 -94.38587) (xy 89.545355 -94.436367)
			(xy 89.561423 -94.489774) (xy 89.569543 -94.54495) (xy 89.570052 -94.572836) (xy 89.569543 -94.600722)
			(xy 89.561423 -94.655898) (xy 89.545355 -94.709305) (xy 89.521683 -94.759802) (xy 89.49091 -94.806315)
			(xy 89.453693 -94.847852) (xy 89.410825 -94.883527) (xy 89.363219 -94.912581) (xy 89.31189 -94.934393)
			(xy 89.257933 -94.948499) (xy 89.202496 -94.954599) (xy 89.146762 -94.952562) (xy 89.091919 -94.942432)
			(xy 89.039135 -94.924425) (xy 88.989535 -94.898924) (xy 88.944177 -94.866473) (xy 88.904028 -94.827764)
			(xy 88.869942 -94.783621) (xy 88.842646 -94.734986) (xy 88.822723 -94.682895) (xy 88.810597 -94.628458)
			(xy 88.806526 -94.572836) (xy 83.579208 -94.572836) (xy 83.166712 -94.985332) (xy 83.160032 -94.992743)
			(xy 83.152459 -95.011179) (xy 83.15198 -95.021146) (xy 83.15198 -95.801942) (xy 88.641426 -95.801942)
			(xy 88.645497 -95.74632) (xy 88.657623 -95.691883) (xy 88.677546 -95.639792) (xy 88.704842 -95.591157)
			(xy 88.738928 -95.547014) (xy 88.779077 -95.508305) (xy 88.824435 -95.475854) (xy 88.874035 -95.450353)
			(xy 88.926819 -95.432346) (xy 88.981662 -95.422216) (xy 89.037396 -95.420179) (xy 89.092833 -95.426279)
			(xy 89.14679 -95.440385) (xy 89.198119 -95.462197) (xy 89.245725 -95.491251) (xy 89.288593 -95.526926)
			(xy 89.32581 -95.568463) (xy 89.356583 -95.614976) (xy 89.380255 -95.665473) (xy 89.396323 -95.71888)
			(xy 89.404443 -95.774056) (xy 89.404952 -95.801942) (xy 90.674696 -95.801942) (xy 90.678767 -95.74632)
			(xy 90.690893 -95.691883) (xy 90.710816 -95.639792) (xy 90.738112 -95.591157) (xy 90.772198 -95.547014)
			(xy 90.812347 -95.508305) (xy 90.857705 -95.475854) (xy 90.907305 -95.450353) (xy 90.960089 -95.432346)
			(xy 91.014932 -95.422216) (xy 91.070666 -95.420179) (xy 91.126103 -95.426279) (xy 91.18006 -95.440385)
			(xy 91.231389 -95.462197) (xy 91.278995 -95.491251) (xy 91.321863 -95.526926) (xy 91.35908 -95.568463)
			(xy 91.389853 -95.614976) (xy 91.413525 -95.665473) (xy 91.429593 -95.71888) (xy 91.437713 -95.774056)
			(xy 91.438222 -95.801942) (xy 92.715586 -95.801942) (xy 92.719657 -95.74632) (xy 92.731783 -95.691883)
			(xy 92.751706 -95.639792) (xy 92.779002 -95.591157) (xy 92.813088 -95.547014) (xy 92.853237 -95.508305)
			(xy 92.898595 -95.475854) (xy 92.948195 -95.450353) (xy 93.000979 -95.432346) (xy 93.055822 -95.422216)
			(xy 93.111556 -95.420179) (xy 93.166993 -95.426279) (xy 93.22095 -95.440385) (xy 93.272279 -95.462197)
			(xy 93.319885 -95.491251) (xy 93.362753 -95.526926) (xy 93.39997 -95.568463) (xy 93.430743 -95.614976)
			(xy 93.454415 -95.665473) (xy 93.470483 -95.71888) (xy 93.478603 -95.774056) (xy 93.479112 -95.801942)
			(xy 93.721426 -95.801942) (xy 93.725497 -95.74632) (xy 93.737623 -95.691883) (xy 93.757546 -95.639792)
			(xy 93.784842 -95.591157) (xy 93.818928 -95.547014) (xy 93.859077 -95.508305) (xy 93.904435 -95.475854)
			(xy 93.954035 -95.450353) (xy 94.006819 -95.432346) (xy 94.061662 -95.422216) (xy 94.117396 -95.420179)
			(xy 94.172833 -95.426279) (xy 94.22679 -95.440385) (xy 94.278119 -95.462197) (xy 94.325725 -95.491251)
			(xy 94.368593 -95.526926) (xy 94.40581 -95.568463) (xy 94.436583 -95.614976) (xy 94.460255 -95.665473)
			(xy 94.476323 -95.71888) (xy 94.484443 -95.774056) (xy 94.484952 -95.801942) (xy 94.484443 -95.829828)
			(xy 94.476323 -95.885004) (xy 94.460255 -95.938411) (xy 94.436583 -95.988908) (xy 94.40581 -96.035421)
			(xy 94.368593 -96.076958) (xy 94.325725 -96.112633) (xy 94.278119 -96.141687) (xy 94.22679 -96.163499)
			(xy 94.172833 -96.177605) (xy 94.117396 -96.183705) (xy 94.061662 -96.181668) (xy 94.006819 -96.171538)
			(xy 93.954035 -96.153531) (xy 93.904435 -96.12803) (xy 93.859077 -96.095579) (xy 93.818928 -96.05687)
			(xy 93.784842 -96.012727) (xy 93.757546 -95.964092) (xy 93.737623 -95.912001) (xy 93.725497 -95.857564)
			(xy 93.721426 -95.801942) (xy 93.479112 -95.801942) (xy 93.478603 -95.829828) (xy 93.470483 -95.885004)
			(xy 93.454415 -95.938411) (xy 93.430743 -95.988908) (xy 93.39997 -96.035421) (xy 93.362753 -96.076958)
			(xy 93.319885 -96.112633) (xy 93.272279 -96.141687) (xy 93.22095 -96.163499) (xy 93.166993 -96.177605)
			(xy 93.111556 -96.183705) (xy 93.055822 -96.181668) (xy 93.000979 -96.171538) (xy 92.948195 -96.153531)
			(xy 92.898595 -96.12803) (xy 92.853237 -96.095579) (xy 92.813088 -96.05687) (xy 92.779002 -96.012727)
			(xy 92.751706 -95.964092) (xy 92.731783 -95.912001) (xy 92.719657 -95.857564) (xy 92.715586 -95.801942)
			(xy 91.438222 -95.801942) (xy 91.437713 -95.829828) (xy 91.429593 -95.885004) (xy 91.413525 -95.938411)
			(xy 91.389853 -95.988908) (xy 91.35908 -96.035421) (xy 91.321863 -96.076958) (xy 91.278995 -96.112633)
			(xy 91.231389 -96.141687) (xy 91.18006 -96.163499) (xy 91.126103 -96.177605) (xy 91.070666 -96.183705)
			(xy 91.014932 -96.181668) (xy 90.960089 -96.171538) (xy 90.907305 -96.153531) (xy 90.857705 -96.12803)
			(xy 90.812347 -96.095579) (xy 90.772198 -96.05687) (xy 90.738112 -96.012727) (xy 90.710816 -95.964092)
			(xy 90.690893 -95.912001) (xy 90.678767 -95.857564) (xy 90.674696 -95.801942) (xy 89.404952 -95.801942)
			(xy 89.404443 -95.829828) (xy 89.396323 -95.885004) (xy 89.380255 -95.938411) (xy 89.356583 -95.988908)
			(xy 89.32581 -96.035421) (xy 89.288593 -96.076958) (xy 89.245725 -96.112633) (xy 89.198119 -96.141687)
			(xy 89.14679 -96.163499) (xy 89.092833 -96.177605) (xy 89.037396 -96.183705) (xy 88.981662 -96.181668)
			(xy 88.926819 -96.171538) (xy 88.874035 -96.153531) (xy 88.824435 -96.12803) (xy 88.779077 -96.095579)
			(xy 88.738928 -96.05687) (xy 88.704842 -96.012727) (xy 88.677546 -95.964092) (xy 88.657623 -95.912001)
			(xy 88.645497 -95.857564) (xy 88.641426 -95.801942) (xy 83.15198 -95.801942) (xy 83.15198 -96.374966)
			(xy 94.427038 -96.374966) (xy 94.431109 -96.319344) (xy 94.443235 -96.264907) (xy 94.463158 -96.212816)
			(xy 94.490454 -96.164181) (xy 94.52454 -96.120038) (xy 94.564689 -96.081329) (xy 94.610047 -96.048878)
			(xy 94.659647 -96.023377) (xy 94.712431 -96.00537) (xy 94.767274 -95.99524) (xy 94.823008 -95.993203)
			(xy 94.878445 -95.999303) (xy 94.932402 -96.013409) (xy 94.983731 -96.035221) (xy 95.031337 -96.064275)
			(xy 95.074205 -96.09995) (xy 95.111422 -96.141487) (xy 95.142195 -96.188) (xy 95.165867 -96.238497)
			(xy 95.180866 -96.288352) (xy 95.852232 -96.288352) (xy 95.856303 -96.23273) (xy 95.868429 -96.178293)
			(xy 95.888352 -96.126202) (xy 95.915648 -96.077567) (xy 95.949734 -96.033424) (xy 95.989883 -95.994715)
			(xy 96.035241 -95.962264) (xy 96.084841 -95.936763) (xy 96.137625 -95.918756) (xy 96.192468 -95.908626)
			(xy 96.248202 -95.906589) (xy 96.303639 -95.912689) (xy 96.357596 -95.926795) (xy 96.408925 -95.948607)
			(xy 96.456531 -95.977661) (xy 96.499399 -96.013336) (xy 96.536616 -96.054873) (xy 96.567389 -96.101386)
			(xy 96.591061 -96.151883) (xy 96.607129 -96.20529) (xy 96.615249 -96.260466) (xy 96.61548 -96.273112)
			(xy 97.197924 -96.273112) (xy 97.201995 -96.21749) (xy 97.214121 -96.163053) (xy 97.234044 -96.110962)
			(xy 97.26134 -96.062327) (xy 97.295426 -96.018184) (xy 97.335575 -95.979475) (xy 97.380933 -95.947024)
			(xy 97.430533 -95.921523) (xy 97.483317 -95.903516) (xy 97.53816 -95.893386) (xy 97.593894 -95.891349)
			(xy 97.649331 -95.897449) (xy 97.703288 -95.911555) (xy 97.754617 -95.933367) (xy 97.802223 -95.962421)
			(xy 97.845091 -95.998096) (xy 97.882308 -96.039633) (xy 97.913081 -96.086146) (xy 97.936753 -96.136643)
			(xy 97.952821 -96.19005) (xy 97.960941 -96.245226) (xy 97.96145 -96.273112) (xy 97.960941 -96.300998)
			(xy 97.952821 -96.356174) (xy 97.936753 -96.409581) (xy 97.913081 -96.460078) (xy 97.882308 -96.506591)
			(xy 97.845091 -96.548128) (xy 97.802223 -96.583803) (xy 97.754617 -96.612857) (xy 97.703288 -96.634669)
			(xy 97.649331 -96.648775) (xy 97.593894 -96.654875) (xy 97.53816 -96.652838) (xy 97.483317 -96.642708)
			(xy 97.430533 -96.624701) (xy 97.380933 -96.5992) (xy 97.335575 -96.566749) (xy 97.295426 -96.52804)
			(xy 97.26134 -96.483897) (xy 97.234044 -96.435262) (xy 97.214121 -96.383171) (xy 97.201995 -96.328734)
			(xy 97.197924 -96.273112) (xy 96.61548 -96.273112) (xy 96.615758 -96.288352) (xy 96.615249 -96.316238)
			(xy 96.607129 -96.371414) (xy 96.591061 -96.424821) (xy 96.567389 -96.475318) (xy 96.536616 -96.521831)
			(xy 96.499399 -96.563368) (xy 96.456531 -96.599043) (xy 96.408925 -96.628097) (xy 96.357596 -96.649909)
			(xy 96.303639 -96.664015) (xy 96.248202 -96.670115) (xy 96.192468 -96.668078) (xy 96.137625 -96.657948)
			(xy 96.084841 -96.639941) (xy 96.035241 -96.61444) (xy 95.989883 -96.581989) (xy 95.949734 -96.54328)
			(xy 95.915648 -96.499137) (xy 95.888352 -96.450502) (xy 95.868429 -96.398411) (xy 95.856303 -96.343974)
			(xy 95.852232 -96.288352) (xy 95.180866 -96.288352) (xy 95.181935 -96.291904) (xy 95.190055 -96.34708)
			(xy 95.190564 -96.374966) (xy 95.190055 -96.402852) (xy 95.181935 -96.458028) (xy 95.165867 -96.511435)
			(xy 95.142195 -96.561932) (xy 95.111422 -96.608445) (xy 95.074205 -96.649982) (xy 95.031337 -96.685657)
			(xy 94.983731 -96.714711) (xy 94.932402 -96.736523) (xy 94.878445 -96.750629) (xy 94.823008 -96.756729)
			(xy 94.767274 -96.754692) (xy 94.712431 -96.744562) (xy 94.659647 -96.726555) (xy 94.610047 -96.701054)
			(xy 94.564689 -96.668603) (xy 94.52454 -96.629894) (xy 94.490454 -96.585751) (xy 94.463158 -96.537116)
			(xy 94.443235 -96.485025) (xy 94.431109 -96.430588) (xy 94.427038 -96.374966) (xy 83.15198 -96.374966)
			(xy 83.15198 -97.953576) (xy 88.342976 -97.953576) (xy 88.347047 -97.897954) (xy 88.359173 -97.843517)
			(xy 88.379096 -97.791426) (xy 88.406392 -97.742791) (xy 88.440478 -97.698648) (xy 88.480627 -97.659939)
			(xy 88.525985 -97.627488) (xy 88.575585 -97.601987) (xy 88.628369 -97.58398) (xy 88.683212 -97.57385)
			(xy 88.738946 -97.571813) (xy 88.794383 -97.577913) (xy 88.84834 -97.592019) (xy 88.899669 -97.613831)
			(xy 88.947275 -97.642885) (xy 88.990143 -97.67856) (xy 89.02736 -97.720097) (xy 89.058133 -97.76661)
			(xy 89.081805 -97.817107) (xy 89.083049 -97.821242) (xy 89.657426 -97.821242) (xy 89.661497 -97.76562)
			(xy 89.673623 -97.711183) (xy 89.693546 -97.659092) (xy 89.720842 -97.610457) (xy 89.754928 -97.566314)
			(xy 89.795077 -97.527605) (xy 89.840435 -97.495154) (xy 89.890035 -97.469653) (xy 89.942819 -97.451646)
			(xy 89.997662 -97.441516) (xy 90.053396 -97.439479) (xy 90.108833 -97.445579) (xy 90.16279 -97.459685)
			(xy 90.214119 -97.481497) (xy 90.261725 -97.510551) (xy 90.304593 -97.546226) (xy 90.34181 -97.587763)
			(xy 90.372583 -97.634276) (xy 90.396255 -97.684773) (xy 90.412323 -97.73818) (xy 90.420443 -97.793356)
			(xy 90.420952 -97.821242) (xy 90.420455 -97.848452) (xy 90.928397 -97.848452) (xy 90.928397 -97.793948)
			(xy 90.936155 -97.739999) (xy 90.951511 -97.687704) (xy 90.974154 -97.638126) (xy 91.003623 -97.592276)
			(xy 91.039318 -97.551087) (xy 91.080511 -97.515397) (xy 91.126365 -97.485933) (xy 91.175945 -97.463296)
			(xy 91.228242 -97.447945) (xy 91.282192 -97.440194) (xy 91.309444 -97.439734) (xy 91.33836 -97.44028)
			(xy 91.395531 -97.449001) (xy 91.450729 -97.466253) (xy 91.502692 -97.491639) (xy 91.550226 -97.524579)
			(xy 91.592244 -97.564316) (xy 91.610434 -97.5868) (xy 91.617985 -97.595573) (xy 91.638752 -97.60575)
			(xy 91.650312 -97.606358) (xy 91.730576 -97.606358) (xy 91.742144 -97.605788) (xy 91.762916 -97.595595)
			(xy 91.770454 -97.5868) (xy 91.788671 -97.564339) (xy 91.830685 -97.524602) (xy 91.878215 -97.49166)
			(xy 91.930171 -97.466268) (xy 91.985364 -97.449007) (xy 92.04253 -97.440272) (xy 92.071444 -97.439734)
			(xy 92.098696 -97.440139) (xy 92.152645 -97.447901) (xy 92.20494 -97.463262) (xy 92.254517 -97.485908)
			(xy 92.300367 -97.515379) (xy 92.341557 -97.551074) (xy 92.377248 -97.592268) (xy 92.406713 -97.638121)
			(xy 92.429353 -97.687701) (xy 92.444708 -97.739998) (xy 92.452464 -97.793948) (xy 92.452464 -97.821242)
			(xy 92.705426 -97.821242) (xy 92.709497 -97.76562) (xy 92.721623 -97.711183) (xy 92.741546 -97.659092)
			(xy 92.768842 -97.610457) (xy 92.802928 -97.566314) (xy 92.843077 -97.527605) (xy 92.888435 -97.495154)
			(xy 92.938035 -97.469653) (xy 92.990819 -97.451646) (xy 93.045662 -97.441516) (xy 93.101396 -97.439479)
			(xy 93.156833 -97.445579) (xy 93.21079 -97.459685) (xy 93.262119 -97.481497) (xy 93.309725 -97.510551)
			(xy 93.352593 -97.546226) (xy 93.38981 -97.587763) (xy 93.420583 -97.634276) (xy 93.444255 -97.684773)
			(xy 93.460323 -97.73818) (xy 93.468443 -97.793356) (xy 93.468952 -97.821242) (xy 93.468443 -97.849128)
			(xy 93.460323 -97.904304) (xy 93.444255 -97.957711) (xy 93.420583 -98.008208) (xy 93.38981 -98.054721)
			(xy 93.352593 -98.096258) (xy 93.309725 -98.131933) (xy 93.262119 -98.160987) (xy 93.21079 -98.182799)
			(xy 93.156833 -98.196905) (xy 93.101396 -98.203005) (xy 93.045662 -98.200968) (xy 92.990819 -98.190838)
			(xy 92.938035 -98.172831) (xy 92.888435 -98.14733) (xy 92.843077 -98.114879) (xy 92.802928 -98.07617)
			(xy 92.768842 -98.032027) (xy 92.741546 -97.983392) (xy 92.721623 -97.931301) (xy 92.709497 -97.876864)
			(xy 92.705426 -97.821242) (xy 92.452464 -97.821242) (xy 92.452464 -97.848452) (xy 92.444708 -97.902402)
			(xy 92.429353 -97.954699) (xy 92.406713 -98.004279) (xy 92.377248 -98.050132) (xy 92.341557 -98.091326)
			(xy 92.300367 -98.127021) (xy 92.254517 -98.156492) (xy 92.20494 -98.179138) (xy 92.152645 -98.194499)
			(xy 92.098696 -98.202261) (xy 92.071444 -98.20275) (xy 92.042527 -98.202219) (xy 91.985356 -98.193495)
			(xy 91.930156 -98.176241) (xy 91.878194 -98.150852) (xy 91.83066 -98.11791) (xy 91.788644 -98.078169)
			(xy 91.770454 -98.055684) (xy 91.762911 -98.046903) (xy 91.742138 -98.03673) (xy 91.730576 -98.036126)
			(xy 91.650312 -98.036126) (xy 91.638744 -98.036694) (xy 91.617972 -98.04689) (xy 91.610434 -98.055684)
			(xy 91.59222 -98.078148) (xy 91.550205 -98.117885) (xy 91.502675 -98.150827) (xy 91.450719 -98.176219)
			(xy 91.395525 -98.193479) (xy 91.338359 -98.202213) (xy 91.309444 -98.20275) (xy 91.282192 -98.202206)
			(xy 91.228242 -98.194455) (xy 91.175945 -98.179104) (xy 91.126365 -98.156467) (xy 91.080511 -98.127003)
			(xy 91.039318 -98.091313) (xy 91.003623 -98.050124) (xy 90.974154 -98.004274) (xy 90.951511 -97.954696)
			(xy 90.936155 -97.902401) (xy 90.928397 -97.848452) (xy 90.420455 -97.848452) (xy 90.420443 -97.849128)
			(xy 90.412323 -97.904304) (xy 90.396255 -97.957711) (xy 90.372583 -98.008208) (xy 90.34181 -98.054721)
			(xy 90.304593 -98.096258) (xy 90.261725 -98.131933) (xy 90.214119 -98.160987) (xy 90.16279 -98.182799)
			(xy 90.108833 -98.196905) (xy 90.053396 -98.203005) (xy 89.997662 -98.200968) (xy 89.942819 -98.190838)
			(xy 89.890035 -98.172831) (xy 89.840435 -98.14733) (xy 89.795077 -98.114879) (xy 89.754928 -98.07617)
			(xy 89.720842 -98.032027) (xy 89.693546 -97.983392) (xy 89.673623 -97.931301) (xy 89.661497 -97.876864)
			(xy 89.657426 -97.821242) (xy 89.083049 -97.821242) (xy 89.097873 -97.870514) (xy 89.105993 -97.92569)
			(xy 89.106502 -97.953576) (xy 89.105993 -97.981462) (xy 89.097873 -98.036638) (xy 89.081805 -98.090045)
			(xy 89.058133 -98.140542) (xy 89.02736 -98.187055) (xy 88.990143 -98.228592) (xy 88.947275 -98.264267)
			(xy 88.899669 -98.293321) (xy 88.84834 -98.315133) (xy 88.794383 -98.329239) (xy 88.738946 -98.335339)
			(xy 88.683212 -98.333302) (xy 88.628369 -98.323172) (xy 88.575585 -98.305165) (xy 88.525985 -98.279664)
			(xy 88.480627 -98.247213) (xy 88.440478 -98.208504) (xy 88.406392 -98.164361) (xy 88.379096 -98.115726)
			(xy 88.359173 -98.063635) (xy 88.347047 -98.009198) (xy 88.342976 -97.953576) (xy 83.15198 -97.953576)
			(xy 83.15198 -98.759518) (xy 99.171252 -98.759518) (xy 99.171716 -98.732148) (xy 99.179532 -98.677968)
			(xy 99.195021 -98.625464) (xy 99.217864 -98.575717) (xy 99.24759 -98.529751) (xy 99.265232 -98.50882)
			(xy 99.271328 -98.501708) (xy 99.277678 -98.48469) (xy 99.277678 -98.399346) (xy 99.271328 -98.382328)
			(xy 99.265232 -98.375216) (xy 99.247609 -98.354269) (xy 99.217883 -98.308304) (xy 99.195036 -98.25856)
			(xy 99.179538 -98.20606) (xy 99.171708 -98.151883) (xy 99.171706 -98.097144) (xy 99.179532 -98.042966)
			(xy 99.195027 -97.990465) (xy 99.21787 -97.94072) (xy 99.247592 -97.894753) (xy 99.265232 -97.87382)
			(xy 99.271328 -97.866708) (xy 99.277678 -97.84969) (xy 99.277678 -97.764346) (xy 99.271328 -97.747328)
			(xy 99.265232 -97.740216) (xy 99.247592 -97.719285) (xy 99.217879 -97.673312) (xy 99.195043 -97.623565)
			(xy 99.179552 -97.571063) (xy 99.171725 -97.516887) (xy 99.171252 -97.489518) (xy 99.171738 -97.462267)
			(xy 99.179494 -97.408319) (xy 99.194849 -97.356024) (xy 99.217491 -97.306447) (xy 99.246957 -97.260597)
			(xy 99.282648 -97.219406) (xy 99.323839 -97.183715) (xy 99.369689 -97.154249) (xy 99.419266 -97.131607)
			(xy 99.471561 -97.116252) (xy 99.525509 -97.108496) (xy 99.580011 -97.108496) (xy 99.633959 -97.116252)
			(xy 99.686254 -97.131607) (xy 99.735831 -97.154249) (xy 99.781681 -97.183715) (xy 99.822872 -97.219406)
			(xy 99.858563 -97.260597) (xy 99.888029 -97.306447) (xy 99.910671 -97.356024) (xy 99.926026 -97.408319)
			(xy 99.933782 -97.462267) (xy 99.934268 -97.489518) (xy 99.93382 -97.516889) (xy 99.925999 -97.571069)
			(xy 99.910506 -97.623573) (xy 99.88766 -97.673319) (xy 99.857931 -97.719285) (xy 99.840288 -97.740216)
			(xy 99.834192 -97.747328) (xy 99.827842 -97.764346) (xy 99.827842 -97.84969) (xy 99.834192 -97.866708)
			(xy 99.840288 -97.87382) (xy 99.857946 -97.894739) (xy 99.887669 -97.940709) (xy 99.910512 -97.990458)
			(xy 99.926006 -98.042962) (xy 99.933833 -98.097142) (xy 99.933831 -98.151885) (xy 99.926 -98.206064)
			(xy 99.910502 -98.258567) (xy 99.887656 -98.308314) (xy 99.857929 -98.354283) (xy 99.840288 -98.375216)
			(xy 99.834192 -98.382328) (xy 99.827842 -98.399346) (xy 99.827842 -98.48469) (xy 99.834192 -98.501708)
			(xy 99.83577 -98.503549) (xy 100.826086 -98.503549) (xy 100.826086 -98.449051) (xy 100.833841 -98.395108)
			(xy 100.849194 -98.342817) (xy 100.871832 -98.293244) (xy 100.901294 -98.247396) (xy 100.936981 -98.206207)
			(xy 100.978165 -98.170517) (xy 101.02401 -98.14105) (xy 101.073582 -98.118407) (xy 101.125871 -98.103049)
			(xy 101.179813 -98.095288) (xy 101.207062 -98.0948) (xy 101.233379 -98.095232) (xy 101.285514 -98.102456)
			(xy 101.336162 -98.116774) (xy 101.384364 -98.137912) (xy 101.429206 -98.165471) (xy 101.469837 -98.198928)
			(xy 101.487986 -98.21799) (xy 101.495512 -98.225386) (xy 101.514789 -98.233914) (xy 101.525324 -98.2345)
			(xy 101.6 -98.2345) (xy 101.610551 -98.233985) (xy 101.629847 -98.22544) (xy 101.637338 -98.21799)
			(xy 101.655452 -98.19889) (xy 101.696077 -98.165414) (xy 101.740922 -98.137847) (xy 101.789134 -98.116712)
			(xy 101.839795 -98.102412) (xy 101.891941 -98.095218) (xy 101.918262 -98.0948) (xy 101.945517 -98.095245)
			(xy 101.999473 -98.102998) (xy 102.051777 -98.118351) (xy 102.101363 -98.140991) (xy 102.147222 -98.170459)
			(xy 102.18842 -98.206153) (xy 102.224118 -98.247348) (xy 102.25359 -98.293204) (xy 102.273298 -98.336354)
			(xy 102.849426 -98.336354) (xy 102.849917 -98.308985) (xy 102.857728 -98.254806) (xy 102.873211 -98.202303)
			(xy 102.896047 -98.152556) (xy 102.925767 -98.106588) (xy 102.943406 -98.085656) (xy 102.949502 -98.078544)
			(xy 102.955852 -98.061526) (xy 102.955852 -97.976182) (xy 102.949502 -97.959164) (xy 102.943406 -97.952052)
			(xy 102.925721 -97.931155) (xy 102.896 -97.885181) (xy 102.873158 -97.835428) (xy 102.857667 -97.782921)
			(xy 102.849843 -97.728738) (xy 102.849848 -97.673993) (xy 102.857681 -97.619811) (xy 102.873183 -97.567307)
			(xy 102.896033 -97.517558) (xy 102.925763 -97.471589) (xy 102.943406 -97.450656) (xy 102.949502 -97.443544)
			(xy 102.955852 -97.426526) (xy 102.955852 -97.341182) (xy 102.949502 -97.324164) (xy 102.943406 -97.317052)
			(xy 102.925779 -97.29611) (xy 102.896065 -97.25014) (xy 102.873227 -97.200395) (xy 102.857733 -97.147897)
			(xy 102.849902 -97.093723) (xy 102.849426 -97.066354) (xy 102.849912 -97.039103) (xy 102.857668 -96.985155)
			(xy 102.873023 -96.93286) (xy 102.895665 -96.883283) (xy 102.925131 -96.837433) (xy 102.960822 -96.796242)
			(xy 103.002013 -96.760551) (xy 103.047863 -96.731085) (xy 103.09744 -96.708443) (xy 103.149735 -96.693088)
			(xy 103.203683 -96.685332) (xy 103.258185 -96.685332) (xy 103.312133 -96.693088) (xy 103.364428 -96.708443)
			(xy 103.414005 -96.731085) (xy 103.459855 -96.760551) (xy 103.501046 -96.796242) (xy 103.536737 -96.837433)
			(xy 103.566203 -96.883283) (xy 103.588845 -96.93286) (xy 103.6042 -96.985155) (xy 103.611956 -97.039103)
			(xy 103.612442 -97.066354) (xy 103.611963 -97.093724) (xy 103.604151 -97.147903) (xy 103.588665 -97.200407)
			(xy 103.565826 -97.250154) (xy 103.536103 -97.296121) (xy 103.518462 -97.317052) (xy 103.512366 -97.324164)
			(xy 103.506016 -97.341182) (xy 103.506016 -97.426526) (xy 103.512366 -97.443544) (xy 103.518462 -97.450656)
			(xy 103.536058 -97.471625) (xy 103.565786 -97.517586) (xy 103.588634 -97.567326) (xy 103.604135 -97.619823)
			(xy 103.611968 -97.673997) (xy 103.611973 -97.728734) (xy 103.604149 -97.782909) (xy 103.588659 -97.835409)
			(xy 103.565819 -97.885153) (xy 103.5361 -97.93112) (xy 103.518462 -97.952052) (xy 103.512366 -97.959164)
			(xy 103.506016 -97.976182) (xy 103.506016 -98.061526) (xy 103.512366 -98.078544) (xy 103.518462 -98.085656)
			(xy 103.536088 -98.106599) (xy 103.565803 -98.152568) (xy 103.588642 -98.202313) (xy 103.604136 -98.254811)
			(xy 103.611967 -98.308985) (xy 103.612442 -98.336354) (xy 103.612175 -98.35134) (xy 106.04373 -98.35134)
			(xy 106.044212 -98.32397) (xy 106.052025 -98.269792) (xy 106.06751 -98.217288) (xy 106.090348 -98.167541)
			(xy 106.12007 -98.121574) (xy 106.13771 -98.100642) (xy 106.143806 -98.09353) (xy 106.150156 -98.076512)
			(xy 106.150156 -97.991168) (xy 106.143806 -97.97415) (xy 106.13771 -97.967038) (xy 106.120109 -97.946073)
			(xy 106.090384 -97.900111) (xy 106.067537 -97.850369) (xy 106.052039 -97.797872) (xy 106.044207 -97.743699)
			(xy 106.044202 -97.688962) (xy 106.052026 -97.634786) (xy 106.067516 -97.582287) (xy 106.090355 -97.532542)
			(xy 106.120073 -97.486575) (xy 106.13771 -97.465642) (xy 106.143806 -97.45853) (xy 106.150156 -97.441512)
			(xy 106.150156 -97.356168) (xy 106.143806 -97.33915) (xy 106.13771 -97.332038) (xy 106.120077 -97.311101)
			(xy 106.090364 -97.26513) (xy 106.067527 -97.215384) (xy 106.052034 -97.162884) (xy 106.044205 -97.108709)
			(xy 106.04373 -97.08134) (xy 106.044216 -97.054089) (xy 106.051972 -97.000141) (xy 106.067327 -96.947846)
			(xy 106.089969 -96.898269) (xy 106.119435 -96.852419) (xy 106.155126 -96.811228) (xy 106.196317 -96.775537)
			(xy 106.242167 -96.746071) (xy 106.291744 -96.723429) (xy 106.344039 -96.708074) (xy 106.397987 -96.700318)
			(xy 106.452489 -96.700318) (xy 106.506437 -96.708074) (xy 106.558732 -96.723429) (xy 106.608309 -96.746071)
			(xy 106.654159 -96.775537) (xy 106.69535 -96.811228) (xy 106.731041 -96.852419) (xy 106.760507 -96.898269)
			(xy 106.783149 -96.947846) (xy 106.798504 -97.000141) (xy 106.80626 -97.054089) (xy 106.806746 -97.08134)
			(xy 106.806258 -97.10871) (xy 106.798447 -97.162888) (xy 106.782964 -97.215392) (xy 106.760127 -97.265139)
			(xy 106.730406 -97.311106) (xy 106.712766 -97.332038) (xy 106.70667 -97.33915) (xy 106.70032 -97.356168)
			(xy 106.70032 -97.441512) (xy 106.70667 -97.45853) (xy 106.712766 -97.465642) (xy 106.730446 -97.486543)
			(xy 106.76017 -97.532516) (xy 106.783013 -97.582268) (xy 106.798507 -97.634774) (xy 106.806332 -97.688958)
			(xy 106.806327 -97.743703) (xy 106.798494 -97.797884) (xy 106.782992 -97.850389) (xy 106.760141 -97.900137)
			(xy 106.73041 -97.946105) (xy 106.712766 -97.967038) (xy 106.70667 -97.97415) (xy 106.70032 -97.991168)
			(xy 106.70032 -98.076512) (xy 106.70667 -98.09353) (xy 106.712766 -98.100642) (xy 106.730386 -98.121589)
			(xy 106.760102 -98.167558) (xy 106.782942 -98.217301) (xy 106.798437 -98.269799) (xy 106.80627 -98.323972)
			(xy 106.806746 -98.35134) (xy 106.80626 -98.378591) (xy 106.798504 -98.432539) (xy 106.783149 -98.484834)
			(xy 106.760507 -98.534411) (xy 106.731041 -98.580261) (xy 106.69535 -98.621452) (xy 106.654159 -98.657143)
			(xy 106.608309 -98.686609) (xy 106.558732 -98.709251) (xy 106.506437 -98.724606) (xy 106.452489 -98.732362)
			(xy 106.397987 -98.732362) (xy 106.344039 -98.724606) (xy 106.291744 -98.709251) (xy 106.242167 -98.686609)
			(xy 106.196317 -98.657143) (xy 106.155126 -98.621452) (xy 106.119435 -98.580261) (xy 106.089969 -98.534411)
			(xy 106.067327 -98.484834) (xy 106.051972 -98.432539) (xy 106.044216 -98.378591) (xy 106.04373 -98.35134)
			(xy 103.612175 -98.35134) (xy 103.611956 -98.363605) (xy 103.6042 -98.417553) (xy 103.588845 -98.469848)
			(xy 103.566203 -98.519425) (xy 103.536737 -98.565275) (xy 103.501046 -98.606466) (xy 103.459855 -98.642157)
			(xy 103.414005 -98.671623) (xy 103.364428 -98.694265) (xy 103.312133 -98.70962) (xy 103.258185 -98.717376)
			(xy 103.203683 -98.717376) (xy 103.149735 -98.70962) (xy 103.09744 -98.694265) (xy 103.047863 -98.671623)
			(xy 103.002013 -98.642157) (xy 102.960822 -98.606466) (xy 102.925131 -98.565275) (xy 102.895665 -98.519425)
			(xy 102.873023 -98.469848) (xy 102.857668 -98.417553) (xy 102.849912 -98.363605) (xy 102.849426 -98.336354)
			(xy 102.273298 -98.336354) (xy 102.276236 -98.342787) (xy 102.291594 -98.395089) (xy 102.299353 -98.449045)
			(xy 102.299353 -98.503555) (xy 102.291594 -98.557511) (xy 102.276236 -98.609813) (xy 102.25359 -98.659396)
			(xy 102.224118 -98.705252) (xy 102.18842 -98.746447) (xy 102.147222 -98.782141) (xy 102.101363 -98.811609)
			(xy 102.051777 -98.834249) (xy 101.999473 -98.849602) (xy 101.945517 -98.857355) (xy 101.918262 -98.857816)
			(xy 101.891946 -98.857363) (xy 101.839812 -98.850142) (xy 101.789164 -98.835829) (xy 101.740962 -98.814694)
			(xy 101.69612 -98.787139) (xy 101.655488 -98.753686) (xy 101.637338 -98.734626) (xy 101.629801 -98.727243)
			(xy 101.610533 -98.718707) (xy 101.6 -98.718116) (xy 101.525324 -98.718116) (xy 101.514774 -98.71864)
			(xy 101.495478 -98.727178) (xy 101.487986 -98.734626) (xy 101.469844 -98.753698) (xy 101.429226 -98.78718)
			(xy 101.384388 -98.814753) (xy 101.336182 -98.835893) (xy 101.285525 -98.850198) (xy 101.233381 -98.857396)
			(xy 101.207062 -98.857816) (xy 101.179813 -98.857312) (xy 101.125871 -98.849551) (xy 101.073582 -98.834193)
			(xy 101.02401 -98.81155) (xy 100.978165 -98.782083) (xy 100.936981 -98.746393) (xy 100.901294 -98.705204)
			(xy 100.871832 -98.659356) (xy 100.849194 -98.609783) (xy 100.833841 -98.557492) (xy 100.826086 -98.503549)
			(xy 99.83577 -98.503549) (xy 99.840288 -98.50882) (xy 99.851239 -98.521616) (xy 99.87108 -98.548835)
			(xy 99.879912 -98.563176) (xy 99.885246 -98.57232) (xy 99.902264 -98.584512) (xy 99.995482 -98.604578)
			(xy 100.016056 -98.600514) (xy 100.024692 -98.594418) (xy 100.048758 -98.578421) (xy 100.100688 -98.553077)
			(xy 100.155846 -98.535851) (xy 100.21297 -98.527135) (xy 100.241862 -98.5266) (xy 100.269117 -98.527045)
			(xy 100.323073 -98.534798) (xy 100.375377 -98.550151) (xy 100.424963 -98.572791) (xy 100.470822 -98.602259)
			(xy 100.51202 -98.637953) (xy 100.547718 -98.679148) (xy 100.57719 -98.725004) (xy 100.599836 -98.774587)
			(xy 100.615194 -98.826889) (xy 100.622953 -98.880845) (xy 100.622953 -98.935355) (xy 100.615194 -98.989311)
			(xy 100.599836 -99.041613) (xy 100.57719 -99.091196) (xy 100.547718 -99.137052) (xy 100.51202 -99.178247)
			(xy 100.470822 -99.213941) (xy 100.424963 -99.243409) (xy 100.375377 -99.266049) (xy 100.323073 -99.281402)
			(xy 100.269117 -99.289155) (xy 100.241862 -99.289616) (xy 100.213769 -99.289152) (xy 100.158191 -99.28092)
			(xy 100.104421 -99.264623) (xy 100.053623 -99.240615) (xy 100.006897 -99.209416) (xy 99.965253 -99.171699)
			(xy 99.929592 -99.128282) (xy 99.91471 -99.10445) (xy 99.909376 -99.095306) (xy 99.892358 -99.083114)
			(xy 99.79914 -99.063048) (xy 99.778566 -99.067112) (xy 99.76993 -99.073208) (xy 99.74586 -99.089198)
			(xy 99.693931 -99.114543) (xy 99.638775 -99.131771) (xy 99.581652 -99.14049) (xy 99.55276 -99.141026)
			(xy 99.525509 -99.140559) (xy 99.471561 -99.132798) (xy 99.419267 -99.117439) (xy 99.369691 -99.094794)
			(xy 99.323842 -99.065325) (xy 99.282652 -99.029632) (xy 99.246961 -98.988441) (xy 99.217495 -98.94259)
			(xy 99.194854 -98.893012) (xy 99.179497 -98.840717) (xy 99.171739 -98.786769) (xy 99.171252 -98.759518)
			(xy 83.15198 -98.759518) (xy 83.15198 -99.449382) (xy 87.906096 -99.449382) (xy 87.910167 -99.39376)
			(xy 87.922293 -99.339323) (xy 87.942216 -99.287232) (xy 87.969512 -99.238597) (xy 88.003598 -99.194454)
			(xy 88.043747 -99.155745) (xy 88.089105 -99.123294) (xy 88.138705 -99.097793) (xy 88.191489 -99.079786)
			(xy 88.246332 -99.069656) (xy 88.302066 -99.067619) (xy 88.357503 -99.073719) (xy 88.41146 -99.087825)
			(xy 88.462789 -99.109637) (xy 88.510395 -99.138691) (xy 88.553263 -99.174366) (xy 88.59048 -99.215903)
			(xy 88.621253 -99.262416) (xy 88.644925 -99.312913) (xy 88.660993 -99.36632) (xy 88.669113 -99.421496)
			(xy 88.669622 -99.449382) (xy 88.669455 -99.458526) (xy 93.638622 -99.458526) (xy 93.642693 -99.402904)
			(xy 93.654819 -99.348467) (xy 93.674742 -99.296376) (xy 93.702038 -99.247741) (xy 93.736124 -99.203598)
			(xy 93.776273 -99.164889) (xy 93.821631 -99.132438) (xy 93.871231 -99.106937) (xy 93.924015 -99.08893)
			(xy 93.978858 -99.0788) (xy 94.034592 -99.076763) (xy 94.090029 -99.082863) (xy 94.143986 -99.096969)
			(xy 94.195315 -99.118781) (xy 94.242921 -99.147835) (xy 94.285789 -99.18351) (xy 94.323006 -99.225047)
			(xy 94.353779 -99.27156) (xy 94.377451 -99.322057) (xy 94.393519 -99.375464) (xy 94.401639 -99.43064)
			(xy 94.402148 -99.458526) (xy 94.401639 -99.486412) (xy 94.393519 -99.541588) (xy 94.377451 -99.594995)
			(xy 94.353779 -99.645492) (xy 94.323006 -99.692005) (xy 94.285789 -99.733542) (xy 94.242921 -99.769217)
			(xy 94.195315 -99.798271) (xy 94.143986 -99.820083) (xy 94.090029 -99.834189) (xy 94.034592 -99.840289)
			(xy 93.978858 -99.838252) (xy 93.924015 -99.828122) (xy 93.871231 -99.810115) (xy 93.821631 -99.784614)
			(xy 93.776273 -99.752163) (xy 93.736124 -99.713454) (xy 93.702038 -99.669311) (xy 93.674742 -99.620676)
			(xy 93.654819 -99.568585) (xy 93.642693 -99.514148) (xy 93.638622 -99.458526) (xy 88.669455 -99.458526)
			(xy 88.669113 -99.477268) (xy 88.660993 -99.532444) (xy 88.644925 -99.585851) (xy 88.621253 -99.636348)
			(xy 88.59048 -99.682861) (xy 88.553263 -99.724398) (xy 88.510395 -99.760073) (xy 88.462789 -99.789127)
			(xy 88.41146 -99.810939) (xy 88.357503 -99.825045) (xy 88.302066 -99.831145) (xy 88.246332 -99.829108)
			(xy 88.191489 -99.818978) (xy 88.138705 -99.800971) (xy 88.089105 -99.77547) (xy 88.043747 -99.743019)
			(xy 88.003598 -99.70431) (xy 87.969512 -99.660167) (xy 87.942216 -99.611532) (xy 87.922293 -99.559441)
			(xy 87.910167 -99.505004) (xy 87.906096 -99.449382) (xy 83.15198 -99.449382) (xy 83.15198 -101.189848)
			(xy 96.99349 -101.189848) (xy 96.99349 -101.135352) (xy 97.001245 -101.08141) (xy 97.016598 -101.02912)
			(xy 97.039235 -100.979547) (xy 97.068696 -100.933701) (xy 97.104382 -100.892513) (xy 97.145565 -100.856822)
			(xy 97.191409 -100.827356) (xy 97.240979 -100.804713) (xy 97.293266 -100.789355) (xy 97.347208 -100.781593)
			(xy 97.374456 -100.781104) (xy 97.401825 -100.781595) (xy 97.456003 -100.789407) (xy 97.508506 -100.80489)
			(xy 97.558254 -100.827726) (xy 97.604221 -100.857445) (xy 97.625154 -100.875084) (xy 97.632266 -100.88118)
			(xy 97.649284 -100.88753) (xy 97.734628 -100.88753) (xy 97.751646 -100.88118) (xy 97.758758 -100.875084)
			(xy 97.779693 -100.857449) (xy 97.825665 -100.827737) (xy 97.875412 -100.8049) (xy 97.927912 -100.789408)
			(xy 97.982087 -100.781579) (xy 98.009456 -100.781104) (xy 98.036712 -100.78154) (xy 98.090669 -100.789292)
			(xy 98.142974 -100.804645) (xy 98.192561 -100.827285) (xy 98.238422 -100.856753) (xy 98.279621 -100.892448)
			(xy 98.31532 -100.933643) (xy 98.344793 -100.9795) (xy 98.36744 -101.029085) (xy 98.382799 -101.081388)
			(xy 98.390557 -101.135344) (xy 98.390557 -101.189856) (xy 98.382799 -101.243812) (xy 98.36744 -101.296115)
			(xy 98.344793 -101.3457) (xy 98.31532 -101.391557) (xy 98.279621 -101.432752) (xy 98.238422 -101.468447)
			(xy 98.192561 -101.497915) (xy 98.142974 -101.520555) (xy 98.090669 -101.535908) (xy 98.036712 -101.54366)
			(xy 98.009456 -101.54412) (xy 97.982086 -101.543641) (xy 97.927907 -101.535829) (xy 97.875403 -101.520344)
			(xy 97.825656 -101.497505) (xy 97.779689 -101.467781) (xy 97.758758 -101.45014) (xy 97.751646 -101.444044)
			(xy 97.734628 -101.437694) (xy 97.649284 -101.437694) (xy 97.632266 -101.444044) (xy 97.625154 -101.45014)
			(xy 97.604218 -101.467774) (xy 97.558246 -101.497485) (xy 97.508499 -101.520322) (xy 97.455999 -101.535814)
			(xy 97.401825 -101.543645) (xy 97.374456 -101.54412) (xy 97.347208 -101.543607) (xy 97.293266 -101.535845)
			(xy 97.240979 -101.520487) (xy 97.191409 -101.497844) (xy 97.145565 -101.468378) (xy 97.104382 -101.432687)
			(xy 97.068696 -101.391499) (xy 97.039235 -101.345653) (xy 97.016598 -101.29608) (xy 97.001245 -101.24379)
			(xy 96.99349 -101.189848) (xy 83.15198 -101.189848) (xy 83.15198 -101.579172) (xy 87.770714 -101.579172)
			(xy 87.774785 -101.52355) (xy 87.786911 -101.469113) (xy 87.806834 -101.417022) (xy 87.83413 -101.368387)
			(xy 87.868216 -101.324244) (xy 87.908365 -101.285535) (xy 87.953723 -101.253084) (xy 88.003323 -101.227583)
			(xy 88.056107 -101.209576) (xy 88.11095 -101.199446) (xy 88.166684 -101.197409) (xy 88.222121 -101.203509)
			(xy 88.276078 -101.217615) (xy 88.327407 -101.239427) (xy 88.375013 -101.268481) (xy 88.417881 -101.304156)
			(xy 88.455098 -101.345693) (xy 88.485871 -101.392206) (xy 88.509543 -101.442703) (xy 88.525611 -101.49611)
			(xy 88.533731 -101.551286) (xy 88.53424 -101.579172) (xy 88.533731 -101.607058) (xy 88.525611 -101.662234)
			(xy 88.509543 -101.715641) (xy 88.485871 -101.766138) (xy 88.455098 -101.812651) (xy 88.417881 -101.854188)
			(xy 88.397963 -101.870764) (xy 93.23908 -101.870764) (xy 93.243151 -101.815142) (xy 93.255277 -101.760705)
			(xy 93.2752 -101.708614) (xy 93.302496 -101.659979) (xy 93.336582 -101.615836) (xy 93.376731 -101.577127)
			(xy 93.422089 -101.544676) (xy 93.471689 -101.519175) (xy 93.524473 -101.501168) (xy 93.579316 -101.491038)
			(xy 93.63505 -101.489001) (xy 93.690487 -101.495101) (xy 93.744444 -101.509207) (xy 93.795773 -101.531019)
			(xy 93.843379 -101.560073) (xy 93.886247 -101.595748) (xy 93.923464 -101.637285) (xy 93.954237 -101.683798)
			(xy 93.977909 -101.734295) (xy 93.993977 -101.787702) (xy 94.002097 -101.842878) (xy 94.002606 -101.870764)
			(xy 94.002097 -101.89865) (xy 93.993977 -101.953826) (xy 93.977909 -102.007233) (xy 93.954237 -102.05773)
			(xy 93.923464 -102.104243) (xy 93.899978 -102.130455) (xy 96.543029 -102.130455) (xy 96.543029 -102.075945)
			(xy 96.550787 -102.021989) (xy 96.566145 -101.969686) (xy 96.58879 -101.920102) (xy 96.618261 -101.874245)
			(xy 96.653959 -101.833049) (xy 96.695156 -101.797353) (xy 96.741014 -101.767883) (xy 96.790599 -101.74524)
			(xy 96.842902 -101.729884) (xy 96.896859 -101.722128) (xy 96.924114 -101.721666) (xy 96.951485 -101.722108)
			(xy 97.005666 -101.729929) (xy 97.05817 -101.745423) (xy 97.107917 -101.76827) (xy 97.153882 -101.798001)
			(xy 97.174812 -101.815646) (xy 97.181924 -101.821742) (xy 97.198942 -101.828092) (xy 97.284286 -101.828092)
			(xy 97.301304 -101.821742) (xy 97.308416 -101.815646) (xy 97.329375 -101.79804) (xy 97.37534 -101.768322)
			(xy 97.42508 -101.745479) (xy 97.477575 -101.72998) (xy 97.531747 -101.722144) (xy 97.559114 -101.721666)
			(xy 97.586363 -101.722205) (xy 97.640305 -101.729963) (xy 97.692595 -101.745318) (xy 97.742167 -101.767958)
			(xy 97.788012 -101.797423) (xy 97.829198 -101.833112) (xy 97.864885 -101.874299) (xy 97.894348 -101.920146)
			(xy 97.916987 -101.969719) (xy 97.93234 -102.022009) (xy 97.940096 -102.075951) (xy 97.940096 -102.130449)
			(xy 97.93234 -102.184391) (xy 97.916987 -102.236681) (xy 97.894348 -102.286254) (xy 97.864885 -102.332101)
			(xy 97.829198 -102.373288) (xy 97.788012 -102.408977) (xy 97.742167 -102.438442) (xy 97.692595 -102.461082)
			(xy 97.640305 -102.476437) (xy 97.586363 -102.484195) (xy 97.559114 -102.484682) (xy 97.531744 -102.484212)
			(xy 97.477565 -102.476396) (xy 97.425062 -102.460908) (xy 97.375315 -102.438067) (xy 97.329348 -102.408343)
			(xy 97.308416 -102.390702) (xy 97.301304 -102.384606) (xy 97.284286 -102.378256) (xy 97.198942 -102.378256)
			(xy 97.181924 -102.384606) (xy 97.174812 -102.390702) (xy 97.153886 -102.408349) (xy 97.107912 -102.43806)
			(xy 97.058163 -102.460894) (xy 97.005661 -102.476383) (xy 96.951484 -102.484209) (xy 96.924114 -102.484682)
			(xy 96.896859 -102.484272) (xy 96.842902 -102.476516) (xy 96.790599 -102.46116) (xy 96.741014 -102.438517)
			(xy 96.695156 -102.409047) (xy 96.653959 -102.373351) (xy 96.618261 -102.332155) (xy 96.58879 -102.286298)
			(xy 96.566145 -102.236714) (xy 96.550787 -102.184411) (xy 96.543029 -102.130455) (xy 93.899978 -102.130455)
			(xy 93.886247 -102.14578) (xy 93.843379 -102.181455) (xy 93.795773 -102.210509) (xy 93.744444 -102.232321)
			(xy 93.690487 -102.246427) (xy 93.63505 -102.252527) (xy 93.579316 -102.25049) (xy 93.524473 -102.24036)
			(xy 93.471689 -102.222353) (xy 93.422089 -102.196852) (xy 93.376731 -102.164401) (xy 93.336582 -102.125692)
			(xy 93.302496 -102.081549) (xy 93.2752 -102.032914) (xy 93.255277 -101.980823) (xy 93.243151 -101.926386)
			(xy 93.23908 -101.870764) (xy 88.397963 -101.870764) (xy 88.375013 -101.889863) (xy 88.327407 -101.918917)
			(xy 88.276078 -101.940729) (xy 88.222121 -101.954835) (xy 88.166684 -101.960935) (xy 88.11095 -101.958898)
			(xy 88.056107 -101.948768) (xy 88.003323 -101.930761) (xy 87.953723 -101.90526) (xy 87.908365 -101.872809)
			(xy 87.868216 -101.8341) (xy 87.83413 -101.789957) (xy 87.806834 -101.741322) (xy 87.786911 -101.689231)
			(xy 87.774785 -101.634794) (xy 87.770714 -101.579172) (xy 83.15198 -101.579172) (xy 83.15198 -103.13924)
			(xy 89.507058 -103.13924) (xy 89.511129 -103.083618) (xy 89.523255 -103.029181) (xy 89.543178 -102.97709)
			(xy 89.570474 -102.928455) (xy 89.60456 -102.884312) (xy 89.644709 -102.845603) (xy 89.690067 -102.813152)
			(xy 89.739667 -102.787651) (xy 89.792451 -102.769644) (xy 89.847294 -102.759514) (xy 89.903028 -102.757477)
			(xy 89.958465 -102.763577) (xy 90.012422 -102.777683) (xy 90.063751 -102.799495) (xy 90.111357 -102.828549)
			(xy 90.154225 -102.864224) (xy 90.191442 -102.905761) (xy 90.222215 -102.952274) (xy 90.245887 -103.002771)
			(xy 90.261955 -103.056178) (xy 90.270075 -103.111354) (xy 90.270584 -103.13924) (xy 90.270075 -103.167126)
			(xy 90.261955 -103.222302) (xy 90.245887 -103.275709) (xy 90.222215 -103.326206) (xy 90.191442 -103.372719)
			(xy 90.154225 -103.414256) (xy 90.111357 -103.449931) (xy 90.063751 -103.478985) (xy 90.012422 -103.500797)
			(xy 89.958465 -103.514903) (xy 89.903028 -103.521003) (xy 89.847294 -103.518966) (xy 89.792451 -103.508836)
			(xy 89.739667 -103.490829) (xy 89.690067 -103.465328) (xy 89.644709 -103.432877) (xy 89.60456 -103.394168)
			(xy 89.570474 -103.350025) (xy 89.543178 -103.30139) (xy 89.523255 -103.249299) (xy 89.511129 -103.194862)
			(xy 89.507058 -103.13924) (xy 83.15198 -103.13924) (xy 83.15198 -104.674924) (xy 88.559384 -104.674924)
			(xy 88.563455 -104.619302) (xy 88.575581 -104.564865) (xy 88.595504 -104.512774) (xy 88.6228 -104.464139)
			(xy 88.656886 -104.419996) (xy 88.697035 -104.381287) (xy 88.742393 -104.348836) (xy 88.791993 -104.323335)
			(xy 88.844777 -104.305328) (xy 88.89962 -104.295198) (xy 88.955354 -104.293161) (xy 89.010791 -104.299261)
			(xy 89.064748 -104.313367) (xy 89.116077 -104.335179) (xy 89.163683 -104.364233) (xy 89.206551 -104.399908)
			(xy 89.243768 -104.441445) (xy 89.274541 -104.487958) (xy 89.298213 -104.538455) (xy 89.314281 -104.591862)
			(xy 89.322401 -104.647038) (xy 89.32291 -104.674924) (xy 89.322401 -104.70281) (xy 89.314281 -104.757986)
			(xy 89.298213 -104.811393) (xy 89.274541 -104.86189) (xy 89.243768 -104.908403) (xy 89.206551 -104.94994)
			(xy 89.163683 -104.985615) (xy 89.116077 -105.014669) (xy 89.064748 -105.036481) (xy 89.010791 -105.050587)
			(xy 88.955354 -105.056687) (xy 88.89962 -105.05465) (xy 88.844777 -105.04452) (xy 88.791993 -105.026513)
			(xy 88.742393 -105.001012) (xy 88.697035 -104.968561) (xy 88.656886 -104.929852) (xy 88.6228 -104.885709)
			(xy 88.595504 -104.837074) (xy 88.575581 -104.784983) (xy 88.563455 -104.730546) (xy 88.559384 -104.674924)
			(xy 83.15198 -104.674924) (xy 83.15198 -107.210352) (xy 85.74278 -107.210352) (xy 85.74328 -107.181612)
			(xy 85.751909 -107.124784) (xy 85.768965 -107.069893) (xy 85.794062 -107.018182) (xy 85.826631 -106.97082)
			(xy 85.845904 -106.949494) (xy 85.852508 -106.942382) (xy 85.85962 -106.924856) (xy 85.85962 -106.835448)
			(xy 85.852508 -106.817922) (xy 85.845904 -106.81081) (xy 85.826587 -106.789524) (xy 85.794025 -106.742154)
			(xy 85.768937 -106.690435) (xy 85.751891 -106.635539) (xy 85.743274 -106.578706) (xy 85.743279 -106.521224)
			(xy 85.751907 -106.464393) (xy 85.768963 -106.409499) (xy 85.79406 -106.357785) (xy 85.826631 -106.310421)
			(xy 85.845904 -106.289094) (xy 85.852508 -106.281982) (xy 85.85962 -106.264456) (xy 85.85962 -106.175048)
			(xy 85.852508 -106.157522) (xy 85.845904 -106.15041) (xy 85.826622 -106.129093) (xy 85.794055 -106.081729)
			(xy 85.768963 -106.030015) (xy 85.751916 -105.975122) (xy 85.743298 -105.918292) (xy 85.74278 -105.889552)
			(xy 85.743266 -105.862301) (xy 85.751022 -105.808353) (xy 85.766377 -105.756058) (xy 85.789019 -105.706481)
			(xy 85.818485 -105.660631) (xy 85.854176 -105.61944) (xy 85.895367 -105.583749) (xy 85.941217 -105.554283)
			(xy 85.990794 -105.531641) (xy 86.043089 -105.516286) (xy 86.097037 -105.50853) (xy 86.151539 -105.50853)
			(xy 86.205487 -105.516286) (xy 86.257782 -105.531641) (xy 86.307359 -105.554283) (xy 86.353209 -105.583749)
			(xy 86.3944 -105.61944) (xy 86.430091 -105.660631) (xy 86.459557 -105.706481) (xy 86.482199 -105.756058)
			(xy 86.497554 -105.808353) (xy 86.50531 -105.862301) (xy 86.505796 -105.889552) (xy 86.505305 -105.918292)
			(xy 86.496675 -105.975121) (xy 86.479617 -106.030012) (xy 86.454518 -106.081723) (xy 86.421946 -106.129084)
			(xy 86.402672 -106.15041) (xy 86.396068 -106.157522) (xy 86.388956 -106.175048) (xy 86.388956 -106.264456)
			(xy 86.396068 -106.281982) (xy 86.402672 -106.289094) (xy 86.421895 -106.310462) (xy 86.454463 -106.357817)
			(xy 86.479557 -106.409522) (xy 86.496611 -106.464407) (xy 86.505238 -106.521229) (xy 86.505243 -106.578702)
			(xy 86.496626 -106.635525) (xy 86.479583 -106.690412) (xy 86.454498 -106.742122) (xy 86.421939 -106.789483)
			(xy 86.402672 -106.81081) (xy 86.396068 -106.817922) (xy 86.388956 -106.835448) (xy 86.388956 -106.924856)
			(xy 86.396068 -106.942382) (xy 86.402672 -106.949494) (xy 86.421969 -106.970798) (xy 86.454531 -107.018167)
			(xy 86.473954 -107.058206) (xy 89.573862 -107.058206) (xy 89.5744 -107.029468) (xy 89.58302 -106.972641)
			(xy 89.600068 -106.917751) (xy 89.625156 -106.866039) (xy 89.657717 -106.818676) (xy 89.676986 -106.797348)
			(xy 89.68359 -106.790236) (xy 89.690702 -106.77271) (xy 89.690702 -106.683302) (xy 89.68359 -106.665776)
			(xy 89.676986 -106.658664) (xy 89.657723 -106.637331) (xy 89.625161 -106.589969) (xy 89.600071 -106.538258)
			(xy 89.583023 -106.483368) (xy 89.5744 -106.426542) (xy 89.5744 -106.369066) (xy 89.583021 -106.31224)
			(xy 89.600068 -106.257351) (xy 89.625156 -106.205639) (xy 89.657717 -106.158276) (xy 89.676986 -106.136948)
			(xy 89.68359 -106.129836) (xy 89.690702 -106.11231) (xy 89.690702 -106.022902) (xy 89.68359 -106.005376)
			(xy 89.676986 -105.998264) (xy 89.657726 -105.976927) (xy 89.625156 -105.929569) (xy 89.600061 -105.87786)
			(xy 89.583008 -105.822971) (xy 89.574384 -105.766145) (xy 89.573862 -105.737406) (xy 89.574348 -105.710155)
			(xy 89.582104 -105.656207) (xy 89.597459 -105.603912) (xy 89.620101 -105.554335) (xy 89.649567 -105.508485)
			(xy 89.685258 -105.467294) (xy 89.726449 -105.431603) (xy 89.772299 -105.402137) (xy 89.821876 -105.379495)
			(xy 89.874171 -105.36414) (xy 89.928119 -105.356384) (xy 89.982621 -105.356384) (xy 90.036569 -105.36414)
			(xy 90.088864 -105.379495) (xy 90.138441 -105.402137) (xy 90.184291 -105.431603) (xy 90.225482 -105.467294)
			(xy 90.261173 -105.508485) (xy 90.290639 -105.554335) (xy 90.313281 -105.603912) (xy 90.328636 -105.656207)
			(xy 90.336392 -105.710155) (xy 90.336878 -105.737406) (xy 90.336337 -105.766144) (xy 90.327715 -105.82297)
			(xy 90.310668 -105.877859) (xy 90.285581 -105.929571) (xy 90.253022 -105.976936) (xy 90.233754 -105.998264)
			(xy 90.22715 -106.005376) (xy 90.220038 -106.022902) (xy 90.220038 -106.11231) (xy 90.22715 -106.129836)
			(xy 90.233754 -106.136948) (xy 90.253032 -106.158269) (xy 90.285599 -106.205632) (xy 90.310691 -106.257344)
			(xy 90.327742 -106.312236) (xy 90.336365 -106.369065) (xy 90.336364 -106.426544) (xy 90.32774 -106.483372)
			(xy 90.310688 -106.538264) (xy 90.285594 -106.589976) (xy 90.253026 -106.637338) (xy 90.233754 -106.658664)
			(xy 90.22715 -106.665776) (xy 90.220038 -106.683302) (xy 90.220038 -106.77271) (xy 90.22715 -106.790236)
			(xy 90.233754 -106.797348) (xy 90.253026 -106.818674) (xy 90.285593 -106.866036) (xy 90.310685 -106.917748)
			(xy 90.327735 -106.972639) (xy 90.336357 -107.029467) (xy 90.336878 -107.058206) (xy 90.336392 -107.085457)
			(xy 90.328636 -107.139405) (xy 90.313281 -107.1917) (xy 90.290639 -107.241277) (xy 90.261173 -107.287127)
			(xy 90.225482 -107.328318) (xy 90.184291 -107.364009) (xy 90.138441 -107.393475) (xy 90.088864 -107.416117)
			(xy 90.036569 -107.431472) (xy 89.982621 -107.439228) (xy 89.928119 -107.439228) (xy 89.874171 -107.431472)
			(xy 89.821876 -107.416117) (xy 89.772299 -107.393475) (xy 89.726449 -107.364009) (xy 89.685258 -107.328318)
			(xy 89.649567 -107.287127) (xy 89.620101 -107.241277) (xy 89.597459 -107.1917) (xy 89.582104 -107.139405)
			(xy 89.574348 -107.085457) (xy 89.573862 -107.058206) (xy 86.473954 -107.058206) (xy 86.479619 -107.069884)
			(xy 86.496663 -107.12478) (xy 86.505279 -107.181611) (xy 86.505796 -107.210352) (xy 86.50531 -107.237603)
			(xy 86.497554 -107.291551) (xy 86.482199 -107.343846) (xy 86.459557 -107.393423) (xy 86.430091 -107.439273)
			(xy 86.3944 -107.480464) (xy 86.353209 -107.516155) (xy 86.307359 -107.545621) (xy 86.257782 -107.568263)
			(xy 86.205487 -107.583618) (xy 86.151539 -107.591374) (xy 86.097037 -107.591374) (xy 86.043089 -107.583618)
			(xy 85.990794 -107.568263) (xy 85.941217 -107.545621) (xy 85.895367 -107.516155) (xy 85.854176 -107.480464)
			(xy 85.818485 -107.439273) (xy 85.789019 -107.393423) (xy 85.766377 -107.343846) (xy 85.751022 -107.291551)
			(xy 85.743266 -107.237603) (xy 85.74278 -107.210352) (xy 83.15198 -107.210352) (xy 83.15198 -108.379006)
			(xy 90.462862 -108.379006) (xy 90.4634 -108.350268) (xy 90.47202 -108.293441) (xy 90.489068 -108.238551)
			(xy 90.514156 -108.186839) (xy 90.546717 -108.139476) (xy 90.565986 -108.118148) (xy 90.57259 -108.111036)
			(xy 90.579702 -108.09351) (xy 90.579702 -108.004102) (xy 90.57259 -107.986576) (xy 90.565986 -107.979464)
			(xy 90.546723 -107.958131) (xy 90.514161 -107.910769) (xy 90.489071 -107.859058) (xy 90.472023 -107.804168)
			(xy 90.4634 -107.747342) (xy 90.4634 -107.689866) (xy 90.472021 -107.63304) (xy 90.489068 -107.578151)
			(xy 90.514156 -107.526439) (xy 90.546717 -107.479076) (xy 90.565986 -107.457748) (xy 90.57259 -107.450636)
			(xy 90.579702 -107.43311) (xy 90.579702 -107.343702) (xy 90.57259 -107.326176) (xy 90.565986 -107.319064)
			(xy 90.546723 -107.297731) (xy 90.514161 -107.250369) (xy 90.489071 -107.198658) (xy 90.472023 -107.143768)
			(xy 90.4634 -107.086942) (xy 90.4634 -107.029466) (xy 90.472021 -106.97264) (xy 90.489068 -106.917751)
			(xy 90.514156 -106.866039) (xy 90.546717 -106.818676) (xy 90.565986 -106.797348) (xy 90.57259 -106.790236)
			(xy 90.579702 -106.77271) (xy 90.579702 -106.683302) (xy 90.57259 -106.665776) (xy 90.565986 -106.658664)
			(xy 90.546723 -106.637331) (xy 90.514161 -106.589969) (xy 90.489071 -106.538258) (xy 90.472023 -106.483368)
			(xy 90.4634 -106.426542) (xy 90.4634 -106.369066) (xy 90.472021 -106.31224) (xy 90.489068 -106.257351)
			(xy 90.514156 -106.205639) (xy 90.546717 -106.158276) (xy 90.565986 -106.136948) (xy 90.57259 -106.129836)
			(xy 90.579702 -106.11231) (xy 90.579702 -106.022902) (xy 90.57259 -106.005376) (xy 90.565986 -105.998264)
			(xy 90.546723 -105.976931) (xy 90.514161 -105.929569) (xy 90.489071 -105.877858) (xy 90.472023 -105.822968)
			(xy 90.4634 -105.766142) (xy 90.4634 -105.708666) (xy 90.472021 -105.65184) (xy 90.489068 -105.596951)
			(xy 90.514156 -105.545239) (xy 90.546717 -105.497876) (xy 90.565986 -105.476548) (xy 90.57259 -105.469436)
			(xy 90.579702 -105.45191) (xy 90.579702 -105.362502) (xy 90.57259 -105.344976) (xy 90.565986 -105.337864)
			(xy 90.546723 -105.316531) (xy 90.514161 -105.269169) (xy 90.489071 -105.217458) (xy 90.472023 -105.162568)
			(xy 90.4634 -105.105742) (xy 90.4634 -105.048266) (xy 90.472021 -104.99144) (xy 90.489068 -104.936551)
			(xy 90.514156 -104.884839) (xy 90.546717 -104.837476) (xy 90.565986 -104.816148) (xy 90.57259 -104.809036)
			(xy 90.579702 -104.79151) (xy 90.579702 -104.702102) (xy 90.57259 -104.684576) (xy 90.565986 -104.677464)
			(xy 90.546723 -104.656131) (xy 90.514161 -104.608769) (xy 90.489071 -104.557058) (xy 90.472023 -104.502168)
			(xy 90.4634 -104.445342) (xy 90.4634 -104.387866) (xy 90.472021 -104.33104) (xy 90.489068 -104.276151)
			(xy 90.514156 -104.224439) (xy 90.546717 -104.177076) (xy 90.565986 -104.155748) (xy 90.57259 -104.148636)
			(xy 90.579702 -104.13111) (xy 90.579702 -104.041702) (xy 90.57259 -104.024176) (xy 90.565986 -104.017064)
			(xy 90.546723 -103.995731) (xy 90.514161 -103.948369) (xy 90.489071 -103.896658) (xy 90.472023 -103.841768)
			(xy 90.4634 -103.784942) (xy 90.4634 -103.727466) (xy 90.472021 -103.67064) (xy 90.489068 -103.615751)
			(xy 90.514156 -103.564039) (xy 90.546717 -103.516676) (xy 90.565986 -103.495348) (xy 90.57259 -103.488236)
			(xy 90.579702 -103.47071) (xy 90.579702 -103.381302) (xy 90.57259 -103.363776) (xy 90.565986 -103.356664)
			(xy 90.546726 -103.335327) (xy 90.514156 -103.287969) (xy 90.489061 -103.23626) (xy 90.472008 -103.181371)
			(xy 90.463384 -103.124545) (xy 90.462862 -103.095806) (xy 90.463323 -103.068599) (xy 90.471046 -103.014737)
			(xy 90.486351 -102.962521) (xy 90.508926 -102.913012) (xy 90.538312 -102.867217) (xy 90.573912 -102.826066)
			(xy 90.615003 -102.790397) (xy 90.637614 -102.775258) (xy 90.645996 -102.76967) (xy 90.657426 -102.753668)
			(xy 90.677746 -102.665022) (xy 90.674444 -102.645464) (xy 90.669364 -102.636828) (xy 90.656104 -102.61431)
			(xy 90.635237 -102.5664) (xy 90.621091 -102.516093) (xy 90.613931 -102.464328) (xy 90.613484 -102.4382)
			(xy 90.61397 -102.410949) (xy 90.621726 -102.357001) (xy 90.637081 -102.304706) (xy 90.659723 -102.255129)
			(xy 90.689189 -102.209279) (xy 90.72488 -102.168088) (xy 90.766071 -102.132397) (xy 90.811921 -102.102931)
			(xy 90.861498 -102.080289) (xy 90.913793 -102.064934) (xy 90.967741 -102.057178) (xy 91.022243 -102.057178)
			(xy 91.076191 -102.064934) (xy 91.128486 -102.080289) (xy 91.178063 -102.102931) (xy 91.223913 -102.132397)
			(xy 91.265104 -102.168088) (xy 91.300795 -102.209279) (xy 91.330261 -102.255129) (xy 91.352903 -102.304706)
			(xy 91.368258 -102.357001) (xy 91.376014 -102.410949) (xy 91.3765 -102.4382) (xy 91.376061 -102.465408)
			(xy 91.368336 -102.519271) (xy 91.353029 -102.571489) (xy 91.330451 -102.620999) (xy 91.301061 -102.666794)
			(xy 91.265456 -102.707943) (xy 91.224361 -102.743611) (xy 91.201748 -102.758748) (xy 91.193366 -102.764336)
			(xy 91.181936 -102.780338) (xy 91.161616 -102.868984) (xy 91.164918 -102.888542) (xy 91.169998 -102.897178)
			(xy 91.183216 -102.919719) (xy 91.204095 -102.967621) (xy 91.218252 -103.01792) (xy 91.225425 -103.069679)
			(xy 91.225878 -103.095806) (xy 91.225337 -103.124544) (xy 91.216715 -103.18137) (xy 91.199668 -103.236259)
			(xy 91.174581 -103.287971) (xy 91.142022 -103.335336) (xy 91.122754 -103.356664) (xy 91.11615 -103.363776)
			(xy 91.109038 -103.381302) (xy 91.109038 -103.47071) (xy 91.11615 -103.488236) (xy 91.122754 -103.495348)
			(xy 91.142032 -103.516669) (xy 91.174599 -103.564032) (xy 91.199691 -103.615744) (xy 91.216742 -103.670636)
			(xy 91.225365 -103.727465) (xy 91.225364 -103.784944) (xy 91.21674 -103.841772) (xy 91.199688 -103.896664)
			(xy 91.174594 -103.948376) (xy 91.142026 -103.995738) (xy 91.122754 -104.017064) (xy 91.117329 -104.022906)
			(xy 95.86595 -104.022906) (xy 95.866345 -103.996588) (xy 95.873574 -103.944451) (xy 95.887898 -103.893801)
			(xy 95.909043 -103.845599) (xy 95.93661 -103.800758) (xy 95.970074 -103.76013) (xy 95.98914 -103.741982)
			(xy 95.996543 -103.734461) (xy 96.005069 -103.715181) (xy 96.00565 -103.704644) (xy 96.00565 -103.629968)
			(xy 96.005083 -103.619423) (xy 95.996573 -103.600128) (xy 95.98914 -103.59263) (xy 95.970083 -103.574473)
			(xy 95.936601 -103.533858) (xy 95.909027 -103.489023) (xy 95.887884 -103.440819) (xy 95.873575 -103.390165)
			(xy 95.866373 -103.338024) (xy 95.86595 -103.311706) (xy 95.866483 -103.284457) (xy 95.874238 -103.230513)
			(xy 95.88959 -103.178222) (xy 95.912227 -103.128647) (xy 95.941689 -103.082799) (xy 95.977376 -103.04161)
			(xy 96.01856 -103.005918) (xy 96.064405 -102.97645) (xy 96.113977 -102.953807) (xy 96.166266 -102.938448)
			(xy 96.220209 -102.930687) (xy 96.247458 -102.930198) (xy 96.275122 -102.930744) (xy 96.329869 -102.938737)
			(xy 96.38289 -102.954548) (xy 96.433074 -102.977846) (xy 96.47937 -103.008142) (xy 96.520809 -103.044802)
			(xy 96.556524 -103.087059) (xy 96.571562 -103.110284) (xy 96.577912 -103.120444) (xy 96.59747 -103.13289)
			(xy 96.70161 -103.143304) (xy 96.723454 -103.135176) (xy 96.731836 -103.126286) (xy 96.749915 -103.107703)
			(xy 96.790247 -103.075125) (xy 96.834622 -103.048312) (xy 96.882221 -103.02776) (xy 96.932166 -103.013847)
			(xy 96.983535 -103.00683) (xy 97.009458 -103.006398) (xy 97.03671 -103.006894) (xy 97.09066 -103.014646)
			(xy 97.142958 -103.029997) (xy 97.192538 -103.052635) (xy 97.238392 -103.082099) (xy 97.279585 -103.117789)
			(xy 97.315279 -103.158979) (xy 97.344748 -103.20483) (xy 97.367391 -103.254408) (xy 97.382747 -103.306705)
			(xy 97.390503 -103.360654) (xy 97.390966 -103.387906) (xy 97.390512 -103.415277) (xy 97.382692 -103.469457)
			(xy 97.367201 -103.52196) (xy 97.344356 -103.571707) (xy 97.314629 -103.617673) (xy 97.296986 -103.638604)
			(xy 97.29089 -103.645716) (xy 97.28454 -103.662734) (xy 97.28454 -103.68565) (xy 108.492794 -103.68565)
			(xy 108.492794 -103.63115) (xy 108.50055 -103.577205) (xy 108.515905 -103.524912) (xy 108.538545 -103.475338)
			(xy 108.56801 -103.429489) (xy 108.603699 -103.388301) (xy 108.644888 -103.352611) (xy 108.690736 -103.323146)
			(xy 108.740311 -103.300505) (xy 108.792603 -103.285151) (xy 108.846548 -103.277394) (xy 108.873798 -103.276908)
			(xy 108.900116 -103.277313) (xy 108.952252 -103.284543) (xy 109.002901 -103.298865) (xy 109.051103 -103.320008)
			(xy 109.095944 -103.347572) (xy 109.136573 -103.381034) (xy 109.154722 -103.400098) (xy 109.162234 -103.407511)
			(xy 109.181521 -103.416029) (xy 109.19206 -103.416608) (xy 109.266736 -103.416608) (xy 109.277283 -103.416056)
			(xy 109.296579 -103.407537) (xy 109.304074 -103.400098) (xy 109.322221 -103.381031) (xy 109.362839 -103.347552)
			(xy 109.407677 -103.31998) (xy 109.455882 -103.298839) (xy 109.506537 -103.284532) (xy 109.558679 -103.27733)
			(xy 109.584998 -103.276908) (xy 109.611316 -103.277313) (xy 109.663452 -103.284543) (xy 109.714101 -103.298865)
			(xy 109.762303 -103.320008) (xy 109.807144 -103.347572) (xy 109.847773 -103.381034) (xy 109.865922 -103.400098)
			(xy 109.873434 -103.407511) (xy 109.892721 -103.416029) (xy 109.90326 -103.416608) (xy 109.977936 -103.416608)
			(xy 109.988483 -103.416056) (xy 110.007779 -103.407537) (xy 110.015274 -103.400098) (xy 110.033421 -103.381031)
			(xy 110.074039 -103.347552) (xy 110.118877 -103.31998) (xy 110.167082 -103.298839) (xy 110.217737 -103.284532)
			(xy 110.269879 -103.27733) (xy 110.296198 -103.276908) (xy 110.323452 -103.277339) (xy 110.377406 -103.285096)
			(xy 110.429706 -103.300452) (xy 110.479288 -103.323096) (xy 110.525144 -103.352565) (xy 110.566338 -103.38826)
			(xy 110.602034 -103.429455) (xy 110.631503 -103.47531) (xy 110.654147 -103.524892) (xy 110.669504 -103.577192)
			(xy 110.677261 -103.631146) (xy 110.677261 -103.685654) (xy 110.669504 -103.739608) (xy 110.654147 -103.791908)
			(xy 110.631503 -103.84149) (xy 110.602034 -103.887345) (xy 110.566338 -103.92854) (xy 110.525144 -103.964235)
			(xy 110.479288 -103.993704) (xy 110.429706 -104.016348) (xy 110.377406 -104.031704) (xy 110.323452 -104.039461)
			(xy 110.296198 -104.039924) (xy 110.269881 -104.039511) (xy 110.217745 -104.032282) (xy 110.167097 -104.01796)
			(xy 110.118895 -103.996818) (xy 110.074054 -103.969256) (xy 110.033423 -103.935797) (xy 110.015274 -103.916734)
			(xy 110.00776 -103.909324) (xy 109.988474 -103.900803) (xy 109.977936 -103.900224) (xy 109.90326 -103.900224)
			(xy 109.892712 -103.900765) (xy 109.873416 -103.909291) (xy 109.865922 -103.916734) (xy 109.847764 -103.93579)
			(xy 109.80715 -103.969273) (xy 109.762315 -103.996848) (xy 109.714112 -104.017991) (xy 109.663458 -104.0323)
			(xy 109.611316 -104.039502) (xy 109.584998 -104.039924) (xy 109.558681 -104.039511) (xy 109.506545 -104.032282)
			(xy 109.455897 -104.01796) (xy 109.407695 -103.996818) (xy 109.362854 -103.969256) (xy 109.322223 -103.935797)
			(xy 109.304074 -103.916734) (xy 109.29656 -103.909324) (xy 109.277274 -103.900803) (xy 109.266736 -103.900224)
			(xy 109.19206 -103.900224) (xy 109.181512 -103.900765) (xy 109.162216 -103.909291) (xy 109.154722 -103.916734)
			(xy 109.136564 -103.93579) (xy 109.09595 -103.969273) (xy 109.051115 -103.996848) (xy 109.002912 -104.017991)
			(xy 108.952258 -104.0323) (xy 108.900116 -104.039502) (xy 108.873798 -104.039924) (xy 108.846548 -104.039406)
			(xy 108.792603 -104.031649) (xy 108.740311 -104.016295) (xy 108.690736 -103.993654) (xy 108.644888 -103.964189)
			(xy 108.603699 -103.928499) (xy 108.56801 -103.887311) (xy 108.538545 -103.841462) (xy 108.515905 -103.791888)
			(xy 108.50055 -103.739595) (xy 108.492794 -103.68565) (xy 97.28454 -103.68565) (xy 97.28454 -103.748078)
			(xy 97.29089 -103.765096) (xy 97.296986 -103.772208) (xy 97.31464 -103.793128) (xy 97.34435 -103.839104)
			(xy 97.367183 -103.888854) (xy 97.382671 -103.941358) (xy 97.390495 -103.995536) (xy 97.390966 -104.022906)
			(xy 97.39055 -104.050161) (xy 97.382791 -104.104116) (xy 97.367432 -104.156417) (xy 97.344786 -104.206)
			(xy 97.315314 -104.251855) (xy 97.279615 -104.293049) (xy 97.238417 -104.328742) (xy 97.192558 -104.358209)
			(xy 97.142972 -104.380849) (xy 97.090669 -104.396201) (xy 97.036713 -104.403954) (xy 97.009458 -104.404414)
			(xy 96.980541 -104.403886) (xy 96.923369 -104.395164) (xy 96.868169 -104.37791) (xy 96.816206 -104.35252)
			(xy 96.768673 -104.319576) (xy 96.726657 -104.279834) (xy 96.708468 -104.257348) (xy 96.700925 -104.248567)
			(xy 96.680152 -104.238396) (xy 96.66859 -104.23779) (xy 96.588326 -104.23779) (xy 96.576761 -104.238379)
			(xy 96.55599 -104.248561) (xy 96.548448 -104.257348) (xy 96.530242 -104.279818) (xy 96.488224 -104.319552)
			(xy 96.440692 -104.352491) (xy 96.388734 -104.377882) (xy 96.333539 -104.395141) (xy 96.276373 -104.403876)
			(xy 96.247458 -104.404414) (xy 96.220206 -104.403961) (xy 96.166257 -104.396199) (xy 96.113962 -104.380839)
			(xy 96.064385 -104.358193) (xy 96.018536 -104.328723) (xy 95.977346 -104.293029) (xy 95.941655 -104.251836)
			(xy 95.912189 -104.205983) (xy 95.889548 -104.156404) (xy 95.874193 -104.104107) (xy 95.866436 -104.050158)
			(xy 95.86595 -104.022906) (xy 91.117329 -104.022906) (xy 91.11615 -104.024176) (xy 91.109038 -104.041702)
			(xy 91.109038 -104.13111) (xy 91.11615 -104.148636) (xy 91.122754 -104.155748) (xy 91.142032 -104.177069)
			(xy 91.174599 -104.224432) (xy 91.199691 -104.276144) (xy 91.216742 -104.331036) (xy 91.225365 -104.387865)
			(xy 91.225364 -104.445344) (xy 91.21674 -104.502172) (xy 91.199688 -104.557064) (xy 91.174594 -104.608776)
			(xy 91.142026 -104.656138) (xy 91.122754 -104.677464) (xy 91.11615 -104.684576) (xy 91.109038 -104.702102)
			(xy 91.109038 -104.79151) (xy 91.11615 -104.809036) (xy 91.122754 -104.816148) (xy 91.142032 -104.837469)
			(xy 91.174599 -104.884832) (xy 91.199691 -104.936544) (xy 91.216742 -104.991436) (xy 91.225365 -105.048265)
			(xy 91.225364 -105.084455) (xy 95.743949 -105.084455) (xy 95.743949 -105.029945) (xy 95.751707 -104.975991)
			(xy 95.767065 -104.92369) (xy 95.78971 -104.874107) (xy 95.819181 -104.828252) (xy 95.854879 -104.787058)
			(xy 95.896076 -104.751363) (xy 95.941933 -104.721896) (xy 95.991518 -104.699255) (xy 96.04382 -104.683901)
			(xy 96.097775 -104.676147) (xy 96.12503 -104.675686) (xy 96.152401 -104.676138) (xy 96.20658 -104.68396)
			(xy 96.259083 -104.699452) (xy 96.30883 -104.722297) (xy 96.354796 -104.752024) (xy 96.375728 -104.769666)
			(xy 96.38284 -104.775762) (xy 96.399858 -104.782112) (xy 96.485202 -104.782112) (xy 96.50222 -104.775762)
			(xy 96.509332 -104.769666) (xy 96.530265 -104.752025) (xy 96.576233 -104.722301) (xy 96.625979 -104.699455)
			(xy 96.678481 -104.683959) (xy 96.732659 -104.67613) (xy 96.787401 -104.67613) (xy 96.841579 -104.683959)
			(xy 96.894081 -104.699455) (xy 96.943827 -104.722301) (xy 96.989795 -104.752025) (xy 97.010728 -104.769666)
			(xy 97.01784 -104.775762) (xy 97.034858 -104.782112) (xy 97.120202 -104.782112) (xy 97.13722 -104.775762)
			(xy 97.144332 -104.769666) (xy 97.165265 -104.752025) (xy 97.211233 -104.722301) (xy 97.260979 -104.699455)
			(xy 97.313481 -104.683959) (xy 97.367659 -104.67613) (xy 97.422401 -104.67613) (xy 97.476579 -104.683959)
			(xy 97.529081 -104.699455) (xy 97.578827 -104.722301) (xy 97.624795 -104.752025) (xy 97.645728 -104.769666)
			(xy 97.65284 -104.775762) (xy 97.669858 -104.782112) (xy 97.755202 -104.782112) (xy 97.77222 -104.775762)
			(xy 97.779332 -104.769666) (xy 97.800275 -104.75204) (xy 97.846245 -104.722327) (xy 97.89599 -104.699489)
			(xy 97.948488 -104.683995) (xy 98.002662 -104.676163) (xy 98.03003 -104.675686) (xy 98.057279 -104.676186)
			(xy 98.111223 -104.683946) (xy 98.163513 -104.699303) (xy 98.213086 -104.721946) (xy 98.258932 -104.751412)
			(xy 98.300118 -104.787103) (xy 98.335806 -104.828292) (xy 98.365269 -104.87414) (xy 98.387907 -104.923715)
			(xy 98.403261 -104.976006) (xy 98.411016 -105.029951) (xy 98.411016 -105.084449) (xy 98.403261 -105.138394)
			(xy 98.387907 -105.190685) (xy 98.365269 -105.24026) (xy 98.335806 -105.286108) (xy 98.300118 -105.327297)
			(xy 98.258932 -105.362988) (xy 98.213086 -105.392454) (xy 98.163513 -105.415097) (xy 98.111223 -105.430454)
			(xy 98.057279 -105.438214) (xy 98.03003 -105.438702) (xy 98.00266 -105.438218) (xy 97.948482 -105.430404)
			(xy 97.895979 -105.414919) (xy 97.846232 -105.392082) (xy 97.800264 -105.362361) (xy 97.779332 -105.344722)
			(xy 97.77222 -105.338626) (xy 97.755202 -105.332276) (xy 97.669858 -105.332276) (xy 97.65284 -105.338626)
			(xy 97.645728 -105.344722) (xy 97.624795 -105.362363) (xy 97.578827 -105.392087) (xy 97.529081 -105.414933)
			(xy 97.476579 -105.430429) (xy 97.422401 -105.438258) (xy 97.367659 -105.438258) (xy 97.313481 -105.430429)
			(xy 97.260979 -105.414933) (xy 97.211233 -105.392087) (xy 97.165265 -105.362363) (xy 97.144332 -105.344722)
			(xy 97.13722 -105.338626) (xy 97.120202 -105.332276) (xy 97.034858 -105.332276) (xy 97.01784 -105.338626)
			(xy 97.010728 -105.344722) (xy 96.989795 -105.362363) (xy 96.943827 -105.392087) (xy 96.894081 -105.414933)
			(xy 96.841579 -105.430429) (xy 96.787401 -105.438258) (xy 96.732659 -105.438258) (xy 96.678481 -105.430429)
			(xy 96.625979 -105.414933) (xy 96.576233 -105.392087) (xy 96.530265 -105.362363) (xy 96.509332 -105.344722)
			(xy 96.50222 -105.338626) (xy 96.485202 -105.332276) (xy 96.399858 -105.332276) (xy 96.38284 -105.338626)
			(xy 96.375728 -105.344722) (xy 96.354799 -105.362365) (xy 96.308825 -105.392075) (xy 96.259077 -105.41491)
			(xy 96.206575 -105.4304) (xy 96.152399 -105.438228) (xy 96.12503 -105.438702) (xy 96.097775 -105.438253)
			(xy 96.04382 -105.430499) (xy 95.991518 -105.415145) (xy 95.941933 -105.392504) (xy 95.896076 -105.363037)
			(xy 95.854879 -105.327342) (xy 95.819181 -105.286148) (xy 95.78971 -105.240293) (xy 95.767065 -105.19071)
			(xy 95.751707 -105.138409) (xy 95.743949 -105.084455) (xy 91.225364 -105.084455) (xy 91.225364 -105.105744)
			(xy 91.21674 -105.162572) (xy 91.199688 -105.217464) (xy 91.174594 -105.269176) (xy 91.142026 -105.316538)
			(xy 91.122754 -105.337864) (xy 91.11615 -105.344976) (xy 91.109038 -105.362502) (xy 91.109038 -105.45191)
			(xy 91.11615 -105.469436) (xy 91.122754 -105.476548) (xy 91.142032 -105.497869) (xy 91.174599 -105.545232)
			(xy 91.199691 -105.596944) (xy 91.216742 -105.651836) (xy 91.225365 -105.708665) (xy 91.225364 -105.766144)
			(xy 91.21674 -105.822972) (xy 91.199688 -105.877864) (xy 91.174594 -105.929576) (xy 91.142026 -105.976938)
			(xy 91.122754 -105.998264) (xy 91.11615 -106.005376) (xy 91.109038 -106.022902) (xy 91.109038 -106.11231)
			(xy 91.11615 -106.129836) (xy 91.122754 -106.136948) (xy 91.142032 -106.158269) (xy 91.174599 -106.205632)
			(xy 91.199691 -106.257344) (xy 91.216742 -106.312236) (xy 91.225365 -106.369065) (xy 91.225364 -106.426544)
			(xy 91.21674 -106.483372) (xy 91.199688 -106.538264) (xy 91.174594 -106.589976) (xy 91.142026 -106.637338)
			(xy 91.122754 -106.658664) (xy 91.11615 -106.665776) (xy 91.109038 -106.683302) (xy 91.109038 -106.77271)
			(xy 91.11615 -106.790236) (xy 91.122754 -106.797348) (xy 91.127367 -106.80245) (xy 108.420905 -106.80245)
			(xy 108.420905 -106.74795) (xy 108.428662 -106.694005) (xy 108.444016 -106.641712) (xy 108.466657 -106.592138)
			(xy 108.496123 -106.54629) (xy 108.531814 -106.505102) (xy 108.573003 -106.469413) (xy 108.618852 -106.439949)
			(xy 108.668427 -106.417311) (xy 108.72072 -106.401958) (xy 108.774666 -106.394204) (xy 108.801916 -106.393742)
			(xy 108.828232 -106.394191) (xy 108.880367 -106.40141) (xy 108.931016 -106.415723) (xy 108.979218 -106.436858)
			(xy 109.02406 -106.464415) (xy 109.064691 -106.497871) (xy 109.08284 -106.516932) (xy 109.090354 -106.524343)
			(xy 109.109639 -106.532865) (xy 109.120178 -106.533442) (xy 109.194854 -106.533442) (xy 109.205401 -106.532889)
			(xy 109.224695 -106.524369) (xy 109.232192 -106.516932) (xy 109.250337 -106.497863) (xy 109.290954 -106.464382)
			(xy 109.335793 -106.43681) (xy 109.383998 -106.415669) (xy 109.434654 -106.401363) (xy 109.486797 -106.394163)
			(xy 109.513116 -106.393742) (xy 109.539432 -106.394191) (xy 109.591567 -106.40141) (xy 109.642216 -106.415723)
			(xy 109.690418 -106.436858) (xy 109.73526 -106.464415) (xy 109.775891 -106.497871) (xy 109.79404 -106.516932)
			(xy 109.801554 -106.524343) (xy 109.820839 -106.532865) (xy 109.831378 -106.533442) (xy 109.906054 -106.533442)
			(xy 109.916601 -106.532889) (xy 109.935895 -106.524369) (xy 109.943392 -106.516932) (xy 109.961537 -106.497863)
			(xy 110.002154 -106.464382) (xy 110.046993 -106.43681) (xy 110.095198 -106.415669) (xy 110.145854 -106.401363)
			(xy 110.197997 -106.394163) (xy 110.224316 -106.393742) (xy 110.25157 -106.394129) (xy 110.305523 -106.401888)
			(xy 110.357823 -106.417247) (xy 110.407405 -106.439892) (xy 110.453259 -106.469362) (xy 110.494453 -106.505059)
			(xy 110.530147 -106.546254) (xy 110.559616 -106.59211) (xy 110.582259 -106.641692) (xy 110.597615 -106.693993)
			(xy 110.605372 -106.747946) (xy 110.605372 -106.802454) (xy 110.597615 -106.856407) (xy 110.582259 -106.908708)
			(xy 110.559616 -106.95829) (xy 110.530147 -107.004146) (xy 110.494453 -107.045341) (xy 110.453259 -107.081038)
			(xy 110.407405 -107.110508) (xy 110.357823 -107.133153) (xy 110.305523 -107.148512) (xy 110.25157 -107.156271)
			(xy 110.224316 -107.156758) (xy 110.197998 -107.156354) (xy 110.145861 -107.149126) (xy 110.095212 -107.134804)
			(xy 110.04701 -107.11366) (xy 110.002169 -107.086096) (xy 109.96154 -107.052633) (xy 109.943392 -107.033568)
			(xy 109.935866 -107.026171) (xy 109.91659 -107.017642) (xy 109.906054 -107.017058) (xy 109.831378 -107.017058)
			(xy 109.820833 -107.017628) (xy 109.801538 -107.026136) (xy 109.79404 -107.033568) (xy 109.775879 -107.052622)
			(xy 109.735265 -107.086103) (xy 109.69043 -107.113678) (xy 109.642228 -107.134821) (xy 109.591575 -107.149131)
			(xy 109.539434 -107.156335) (xy 109.513116 -107.156758) (xy 109.486798 -107.156354) (xy 109.434661 -107.149126)
			(xy 109.384012 -107.134804) (xy 109.33581 -107.11366) (xy 109.290969 -107.086096) (xy 109.25034 -107.052633)
			(xy 109.232192 -107.033568) (xy 109.224666 -107.026171) (xy 109.20539 -107.017642) (xy 109.194854 -107.017058)
			(xy 109.120178 -107.017058) (xy 109.109633 -107.017628) (xy 109.090338 -107.026136) (xy 109.08284 -107.033568)
			(xy 109.064679 -107.052622) (xy 109.024065 -107.086103) (xy 108.97923 -107.113678) (xy 108.931028 -107.134821)
			(xy 108.880375 -107.149131) (xy 108.828234 -107.156335) (xy 108.801916 -107.156758) (xy 108.774666 -107.156196)
			(xy 108.72072 -107.148442) (xy 108.668427 -107.133089) (xy 108.618852 -107.110451) (xy 108.573003 -107.080987)
			(xy 108.531813 -107.045298) (xy 108.496123 -107.00411) (xy 108.466657 -106.958262) (xy 108.444016 -106.908688)
			(xy 108.428662 -106.856395) (xy 108.420905 -106.80245) (xy 91.127367 -106.80245) (xy 91.142032 -106.818669)
			(xy 91.174599 -106.866032) (xy 91.199691 -106.917744) (xy 91.216742 -106.972636) (xy 91.225365 -107.029465)
			(xy 91.225364 -107.086944) (xy 91.21674 -107.143772) (xy 91.199688 -107.198664) (xy 91.174594 -107.250376)
			(xy 91.142026 -107.297738) (xy 91.122754 -107.319064) (xy 91.11615 -107.326176) (xy 91.109038 -107.343702)
			(xy 91.109038 -107.43311) (xy 91.11615 -107.450636) (xy 91.122754 -107.457748) (xy 91.142032 -107.479069)
			(xy 91.174599 -107.526432) (xy 91.199691 -107.578144) (xy 91.216742 -107.633036) (xy 91.225365 -107.689865)
			(xy 91.225364 -107.740253) (xy 95.684273 -107.740253) (xy 95.684273 -107.685747) (xy 95.692031 -107.631795)
			(xy 95.707388 -107.579496) (xy 95.730033 -107.529916) (xy 95.759503 -107.484063) (xy 95.795199 -107.442871)
			(xy 95.836395 -107.407179) (xy 95.882251 -107.377714) (xy 95.931834 -107.355074) (xy 95.984134 -107.339723)
			(xy 96.038087 -107.331971) (xy 96.06534 -107.33151) (xy 96.092709 -107.332009) (xy 96.146887 -107.339818)
			(xy 96.19939 -107.3553) (xy 96.249137 -107.378134) (xy 96.295105 -107.407852) (xy 96.316038 -107.42549)
			(xy 96.32315 -107.431586) (xy 96.340168 -107.437936) (xy 96.425512 -107.437936) (xy 96.44253 -107.431586)
			(xy 96.449642 -107.42549) (xy 96.470575 -107.407849) (xy 96.516543 -107.378125) (xy 96.566289 -107.355279)
			(xy 96.618791 -107.339783) (xy 96.672969 -107.331954) (xy 96.727711 -107.331954) (xy 96.781889 -107.339783)
			(xy 96.834391 -107.355279) (xy 96.884137 -107.378125) (xy 96.930105 -107.407849) (xy 96.951038 -107.42549)
			(xy 96.95815 -107.431586) (xy 96.975168 -107.437936) (xy 97.060512 -107.437936) (xy 97.07753 -107.431586)
			(xy 97.084642 -107.42549) (xy 97.105575 -107.407849) (xy 97.151543 -107.378125) (xy 97.201289 -107.355279)
			(xy 97.253791 -107.339783) (xy 97.307969 -107.331954) (xy 97.362711 -107.331954) (xy 97.416889 -107.339783)
			(xy 97.469391 -107.355279) (xy 97.519137 -107.378125) (xy 97.565105 -107.407849) (xy 97.586038 -107.42549)
			(xy 97.59315 -107.431586) (xy 97.610168 -107.437936) (xy 97.695512 -107.437936) (xy 97.71253 -107.431586)
			(xy 97.719642 -107.42549) (xy 97.740584 -107.407863) (xy 97.786554 -107.37815) (xy 97.836299 -107.355312)
			(xy 97.888798 -107.339818) (xy 97.942972 -107.331986) (xy 97.97034 -107.33151) (xy 97.997591 -107.331963)
			(xy 98.051537 -107.339724) (xy 98.103829 -107.355083) (xy 98.153404 -107.377728) (xy 98.199251 -107.407197)
			(xy 98.240438 -107.44289) (xy 98.276127 -107.484081) (xy 98.305591 -107.529932) (xy 98.328231 -107.579508)
			(xy 98.343584 -107.631803) (xy 98.35134 -107.685749) (xy 98.35134 -107.740251) (xy 98.343584 -107.794197)
			(xy 98.328231 -107.846492) (xy 98.305591 -107.896068) (xy 98.276127 -107.941919) (xy 98.240438 -107.98311)
			(xy 98.199251 -108.018803) (xy 98.153404 -108.048272) (xy 98.103829 -108.070917) (xy 98.051537 -108.086276)
			(xy 97.997591 -108.094037) (xy 97.97034 -108.094526) (xy 97.94297 -108.094055) (xy 97.88879 -108.086241)
			(xy 97.836286 -108.070754) (xy 97.786539 -108.047913) (xy 97.740573 -108.018188) (xy 97.719642 -108.000546)
			(xy 97.71253 -107.99445) (xy 97.695512 -107.9881) (xy 97.610168 -107.9881) (xy 97.59315 -107.99445)
			(xy 97.586038 -108.000546) (xy 97.565105 -108.018187) (xy 97.519137 -108.047911) (xy 97.469391 -108.070757)
			(xy 97.416889 -108.086253) (xy 97.362711 -108.094082) (xy 97.307969 -108.094082) (xy 97.253791 -108.086253)
			(xy 97.201289 -108.070757) (xy 97.151543 -108.047911) (xy 97.105575 -108.018187) (xy 97.084642 -108.000546)
			(xy 97.07753 -107.99445) (xy 97.060512 -107.9881) (xy 96.975168 -107.9881) (xy 96.95815 -107.99445)
			(xy 96.951038 -108.000546) (xy 96.930105 -108.018187) (xy 96.884137 -108.047911) (xy 96.834391 -108.070757)
			(xy 96.781889 -108.086253) (xy 96.727711 -108.094082) (xy 96.672969 -108.094082) (xy 96.618791 -108.086253)
			(xy 96.566289 -108.070757) (xy 96.516543 -108.047911) (xy 96.470575 -108.018187) (xy 96.449642 -108.000546)
			(xy 96.44253 -107.99445) (xy 96.425512 -107.9881) (xy 96.340168 -107.9881) (xy 96.32315 -107.99445)
			(xy 96.316038 -108.000546) (xy 96.295095 -108.018172) (xy 96.249126 -108.047888) (xy 96.199382 -108.070727)
			(xy 96.146883 -108.086221) (xy 96.092709 -108.094051) (xy 96.06534 -108.094526) (xy 96.038087 -108.094029)
			(xy 95.984134 -108.086277) (xy 95.931834 -108.070926) (xy 95.882251 -108.048286) (xy 95.836395 -108.018821)
			(xy 95.795199 -107.983129) (xy 95.759503 -107.941937) (xy 95.730033 -107.896084) (xy 95.707388 -107.846504)
			(xy 95.692031 -107.794205) (xy 95.684273 -107.740253) (xy 91.225364 -107.740253) (xy 91.225364 -107.747344)
			(xy 91.21674 -107.804172) (xy 91.199688 -107.859064) (xy 91.174594 -107.910776) (xy 91.142026 -107.958138)
			(xy 91.122754 -107.979464) (xy 91.11615 -107.986576) (xy 91.109038 -108.004102) (xy 91.109038 -108.09351)
			(xy 91.11615 -108.111036) (xy 91.122754 -108.118148) (xy 91.142026 -108.139474) (xy 91.174593 -108.186836)
			(xy 91.199685 -108.238548) (xy 91.216735 -108.293439) (xy 91.225357 -108.350267) (xy 91.225878 -108.379006)
			(xy 91.225392 -108.406257) (xy 91.217636 -108.460205) (xy 91.202281 -108.5125) (xy 91.179639 -108.562077)
			(xy 91.174865 -108.569506) (xy 106.861102 -108.569506) (xy 106.861571 -108.542136) (xy 106.869388 -108.487957)
			(xy 106.884876 -108.435454) (xy 106.907718 -108.385707) (xy 106.937441 -108.33974) (xy 106.955082 -108.318808)
			(xy 106.961178 -108.311696) (xy 106.967528 -108.294678) (xy 106.967528 -108.209334) (xy 106.961178 -108.192316)
			(xy 106.955082 -108.185204) (xy 106.937429 -108.164284) (xy 106.907719 -108.118307) (xy 106.884887 -108.068557)
			(xy 106.869399 -108.016054) (xy 106.861574 -107.961876) (xy 106.861102 -107.934506) (xy 106.861588 -107.907255)
			(xy 106.869344 -107.853307) (xy 106.884699 -107.801012) (xy 106.907341 -107.751435) (xy 106.936807 -107.705585)
			(xy 106.972498 -107.664394) (xy 107.013689 -107.628703) (xy 107.059539 -107.599237) (xy 107.109116 -107.576595)
			(xy 107.161411 -107.56124) (xy 107.215359 -107.553484) (xy 107.269861 -107.553484) (xy 107.323809 -107.56124)
			(xy 107.376104 -107.576595) (xy 107.425681 -107.599237) (xy 107.471531 -107.628703) (xy 107.512722 -107.664394)
			(xy 107.548413 -107.705585) (xy 107.577879 -107.751435) (xy 107.600521 -107.801012) (xy 107.615876 -107.853307)
			(xy 107.623632 -107.907255) (xy 107.624118 -107.934506) (xy 107.623675 -107.961877) (xy 107.615855 -108.016058)
			(xy 107.600362 -108.068562) (xy 107.577514 -108.118309) (xy 107.547783 -108.164274) (xy 107.530138 -108.185204)
			(xy 107.524042 -108.192316) (xy 107.517692 -108.209334) (xy 107.517692 -108.294678) (xy 107.524042 -108.311696)
			(xy 107.530138 -108.318808) (xy 107.547801 -108.339721) (xy 107.577508 -108.3857) (xy 107.600339 -108.435452)
			(xy 107.615824 -108.487957) (xy 107.623647 -108.542136) (xy 107.624118 -108.569506) (xy 107.623632 -108.596757)
			(xy 107.615876 -108.650705) (xy 107.600521 -108.703) (xy 107.577879 -108.752577) (xy 107.548413 -108.798427)
			(xy 107.512722 -108.839618) (xy 107.471531 -108.875309) (xy 107.425681 -108.904775) (xy 107.376104 -108.927417)
			(xy 107.323809 -108.942772) (xy 107.269861 -108.950528) (xy 107.215359 -108.950528) (xy 107.161411 -108.942772)
			(xy 107.109116 -108.927417) (xy 107.059539 -108.904775) (xy 107.013689 -108.875309) (xy 106.972498 -108.839618)
			(xy 106.936807 -108.798427) (xy 106.907341 -108.752577) (xy 106.884699 -108.703) (xy 106.869344 -108.650705)
			(xy 106.861588 -108.596757) (xy 106.861102 -108.569506) (xy 91.174865 -108.569506) (xy 91.150173 -108.607927)
			(xy 91.114482 -108.649118) (xy 91.073291 -108.684809) (xy 91.027441 -108.714275) (xy 90.977864 -108.736917)
			(xy 90.925569 -108.752272) (xy 90.871621 -108.760028) (xy 90.817119 -108.760028) (xy 90.763171 -108.752272)
			(xy 90.710876 -108.736917) (xy 90.661299 -108.714275) (xy 90.615449 -108.684809) (xy 90.574258 -108.649118)
			(xy 90.538567 -108.607927) (xy 90.509101 -108.562077) (xy 90.486459 -108.5125) (xy 90.471104 -108.460205)
			(xy 90.463348 -108.406257) (xy 90.462862 -108.379006) (xy 83.15198 -108.379006) (xy 83.15198 -108.467398)
			(xy 83.151494 -108.493486) (xy 83.143328 -108.545018) (xy 83.127197 -108.594636) (xy 83.103498 -108.641119)
			(xy 83.072817 -108.683319) (xy 83.054698 -108.702094) (xy 82.871564 -108.885228) (xy 82.864715 -108.892625)
			(xy 82.856981 -108.911224) (xy 82.856578 -108.921296) (xy 82.856578 -109.130084) (xy 82.856139 -109.140147)
			(xy 82.848401 -109.158727) (xy 82.841592 -109.166152) (xy 82.505296 -109.502448) (xy 109.414562 -109.502448)
			(xy 109.418633 -109.446826) (xy 109.430759 -109.392389) (xy 109.450682 -109.340298) (xy 109.477978 -109.291663)
			(xy 109.512064 -109.24752) (xy 109.552213 -109.208811) (xy 109.597571 -109.17636) (xy 109.647171 -109.150859)
			(xy 109.699955 -109.132852) (xy 109.754798 -109.122722) (xy 109.810532 -109.120685) (xy 109.865969 -109.126785)
			(xy 109.919926 -109.140891) (xy 109.971255 -109.162703) (xy 110.018861 -109.191757) (xy 110.061729 -109.227432)
			(xy 110.098946 -109.268969) (xy 110.129719 -109.315482) (xy 110.153391 -109.365979) (xy 110.169459 -109.419386)
			(xy 110.177579 -109.474562) (xy 110.178088 -109.502448) (xy 110.177579 -109.530334) (xy 110.169459 -109.58551)
			(xy 110.153391 -109.638917) (xy 110.129719 -109.689414) (xy 110.098946 -109.735927) (xy 110.061729 -109.777464)
			(xy 110.018861 -109.813139) (xy 109.971255 -109.842193) (xy 109.919926 -109.864005) (xy 109.865969 -109.878111)
			(xy 109.810532 -109.884211) (xy 109.754798 -109.882174) (xy 109.699955 -109.872044) (xy 109.647171 -109.854037)
			(xy 109.597571 -109.828536) (xy 109.552213 -109.796085) (xy 109.512064 -109.757376) (xy 109.477978 -109.713233)
			(xy 109.450682 -109.664598) (xy 109.430759 -109.612507) (xy 109.418633 -109.55807) (xy 109.414562 -109.502448)
			(xy 82.505296 -109.502448) (xy 82.504026 -109.503718) (xy 82.497215 -109.511063) (xy 82.489485 -109.529526)
			(xy 82.48904 -109.539532) (xy 82.48904 -110.621572) (xy 90.56116 -110.621572) (xy 90.561627 -110.595257)
			(xy 90.568846 -110.543124) (xy 90.583157 -110.492476) (xy 90.604289 -110.444275) (xy 90.631841 -110.399432)
			(xy 90.665292 -110.358799) (xy 90.68435 -110.340648) (xy 90.691769 -110.333141) (xy 90.700285 -110.31385)
			(xy 90.70086 -110.30331) (xy 90.70086 -110.228634) (xy 90.700338 -110.218083) (xy 90.691799 -110.198787)
			(xy 90.68435 -110.191296) (xy 90.665278 -110.173153) (xy 90.631798 -110.132536) (xy 90.604225 -110.087697)
			(xy 90.583085 -110.039491) (xy 90.568779 -109.988835) (xy 90.561581 -109.936691) (xy 90.56116 -109.910372)
			(xy 90.561646 -109.883121) (xy 90.569402 -109.829173) (xy 90.584757 -109.776878) (xy 90.607399 -109.727301)
			(xy 90.636865 -109.681451) (xy 90.672556 -109.64026) (xy 90.713747 -109.604569) (xy 90.759597 -109.575103)
			(xy 90.809174 -109.552461) (xy 90.861469 -109.537106) (xy 90.915417 -109.52935) (xy 90.969919 -109.52935)
			(xy 91.023867 -109.537106) (xy 91.076162 -109.552461) (xy 91.125739 -109.575103) (xy 91.171589 -109.604569)
			(xy 91.21278 -109.64026) (xy 91.248471 -109.681451) (xy 91.277937 -109.727301) (xy 91.300579 -109.776878)
			(xy 91.315934 -109.829173) (xy 91.32369 -109.883121) (xy 91.324176 -109.910372) (xy 91.323758 -109.936689)
			(xy 91.316532 -109.988825) (xy 91.302213 -110.039474) (xy 91.281072 -110.087676) (xy 91.25351 -110.132517)
			(xy 91.220049 -110.173147) (xy 91.200986 -110.191296) (xy 91.193582 -110.198815) (xy 91.185059 -110.218097)
			(xy 91.184476 -110.228634) (xy 91.184476 -110.30331) (xy 91.184993 -110.313861) (xy 91.193538 -110.333156)
			(xy 91.200986 -110.340648) (xy 91.220086 -110.358762) (xy 91.253563 -110.399387) (xy 91.281131 -110.444231)
			(xy 91.302266 -110.492443) (xy 91.316566 -110.543104) (xy 91.323758 -110.595251) (xy 91.324176 -110.621572)
			(xy 91.32369 -110.648823) (xy 91.315934 -110.702771) (xy 91.300579 -110.755066) (xy 91.277937 -110.804643)
			(xy 91.248471 -110.850493) (xy 91.21278 -110.891684) (xy 91.171589 -110.927375) (xy 91.125739 -110.956841)
			(xy 91.076162 -110.979483) (xy 91.023867 -110.994838) (xy 90.969919 -111.002594) (xy 90.915417 -111.002594)
			(xy 90.861469 -110.994838) (xy 90.809174 -110.979483) (xy 90.759597 -110.956841) (xy 90.713747 -110.927375)
			(xy 90.672556 -110.891684) (xy 90.636865 -110.850493) (xy 90.607399 -110.804643) (xy 90.584757 -110.755066)
			(xy 90.569402 -110.702771) (xy 90.561646 -110.648823) (xy 90.56116 -110.621572) (xy 82.48904 -110.621572)
			(xy 82.48904 -112.297972) (xy 93.069918 -112.297972) (xy 93.070367 -112.271656) (xy 93.077587 -112.219521)
			(xy 93.0919 -112.168873) (xy 93.113036 -112.120671) (xy 93.140592 -112.075829) (xy 93.174047 -112.035198)
			(xy 93.193108 -112.017048) (xy 93.200536 -112.009549) (xy 93.209045 -111.990252) (xy 93.209618 -111.97971)
			(xy 93.209618 -111.905034) (xy 93.209079 -111.894486) (xy 93.20055 -111.875191) (xy 93.193108 -111.867696)
			(xy 93.174028 -111.849562) (xy 93.14055 -111.808941) (xy 93.112979 -111.764101) (xy 93.091841 -111.715893)
			(xy 93.077536 -111.665236) (xy 93.070338 -111.613092) (xy 93.069918 -111.586772) (xy 93.070404 -111.559521)
			(xy 93.07816 -111.505573) (xy 93.093515 -111.453278) (xy 93.116157 -111.403701) (xy 93.145623 -111.357851)
			(xy 93.181314 -111.31666) (xy 93.222505 -111.280969) (xy 93.268355 -111.251503) (xy 93.317932 -111.228861)
			(xy 93.370227 -111.213506) (xy 93.424175 -111.20575) (xy 93.478677 -111.20575) (xy 93.532625 -111.213506)
			(xy 93.58492 -111.228861) (xy 93.634497 -111.251503) (xy 93.680347 -111.280969) (xy 93.721538 -111.31666)
			(xy 93.757229 -111.357851) (xy 93.786695 -111.403701) (xy 93.809337 -111.453278) (xy 93.824692 -111.505573)
			(xy 93.832448 -111.559521) (xy 93.832934 -111.586772) (xy 93.832498 -111.613088) (xy 93.825273 -111.665223)
			(xy 93.810956 -111.715871) (xy 93.789818 -111.764072) (xy 93.76226 -111.808914) (xy 93.728805 -111.849546)
			(xy 93.709744 -111.867696) (xy 93.702349 -111.875223) (xy 93.693819 -111.894499) (xy 93.693234 -111.905034)
			(xy 93.693234 -111.97971) (xy 93.693734 -111.990263) (xy 93.702289 -112.009559) (xy 93.709744 -112.017048)
			(xy 93.728836 -112.03517) (xy 93.762315 -112.075792) (xy 93.789885 -112.120635) (xy 93.811022 -112.168845)
			(xy 93.825323 -112.219505) (xy 93.832516 -112.271652) (xy 93.832934 -112.297972) (xy 95.101918 -112.297972)
			(xy 95.102367 -112.271656) (xy 95.109587 -112.219521) (xy 95.1239 -112.168873) (xy 95.145036 -112.120671)
			(xy 95.172592 -112.075829) (xy 95.206047 -112.035198) (xy 95.225108 -112.017048) (xy 95.232536 -112.009549)
			(xy 95.241045 -111.990252) (xy 95.241618 -111.97971) (xy 95.241618 -111.905034) (xy 95.241079 -111.894486)
			(xy 95.23255 -111.875191) (xy 95.225108 -111.867696) (xy 95.206028 -111.849562) (xy 95.17255 -111.808941)
			(xy 95.144979 -111.764101) (xy 95.123841 -111.715893) (xy 95.109536 -111.665236) (xy 95.102338 -111.613092)
			(xy 95.101918 -111.586772) (xy 95.102404 -111.559521) (xy 95.11016 -111.505573) (xy 95.125515 -111.453278)
			(xy 95.148157 -111.403701) (xy 95.177623 -111.357851) (xy 95.213314 -111.31666) (xy 95.254505 -111.280969)
			(xy 95.300355 -111.251503) (xy 95.349932 -111.228861) (xy 95.402227 -111.213506) (xy 95.456175 -111.20575)
			(xy 95.510677 -111.20575) (xy 95.564625 -111.213506) (xy 95.61692 -111.228861) (xy 95.666497 -111.251503)
			(xy 95.712347 -111.280969) (xy 95.753538 -111.31666) (xy 95.789229 -111.357851) (xy 95.818695 -111.403701)
			(xy 95.841337 -111.453278) (xy 95.856692 -111.505573) (xy 95.864448 -111.559521) (xy 95.864934 -111.586772)
			(xy 95.864498 -111.613088) (xy 95.857273 -111.665223) (xy 95.842956 -111.715871) (xy 95.821818 -111.764072)
			(xy 95.79426 -111.808914) (xy 95.760805 -111.849546) (xy 95.741744 -111.867696) (xy 95.734349 -111.875223)
			(xy 95.725819 -111.894499) (xy 95.725234 -111.905034) (xy 95.725234 -111.97971) (xy 95.725734 -111.990263)
			(xy 95.734289 -112.009559) (xy 95.741744 -112.017048) (xy 95.760836 -112.03517) (xy 95.794315 -112.075792)
			(xy 95.821885 -112.120635) (xy 95.843022 -112.168845) (xy 95.857323 -112.219505) (xy 95.864516 -112.271652)
			(xy 95.864934 -112.297972) (xy 95.864448 -112.325223) (xy 95.856692 -112.379171) (xy 95.841337 -112.431466)
			(xy 95.818695 -112.481043) (xy 95.789229 -112.526893) (xy 95.753538 -112.568084) (xy 95.712347 -112.603775)
			(xy 95.666497 -112.633241) (xy 95.61692 -112.655883) (xy 95.564625 -112.671238) (xy 95.510677 -112.678994)
			(xy 95.456175 -112.678994) (xy 95.402227 -112.671238) (xy 95.349932 -112.655883) (xy 95.300355 -112.633241)
			(xy 95.254505 -112.603775) (xy 95.213314 -112.568084) (xy 95.177623 -112.526893) (xy 95.148157 -112.481043)
			(xy 95.125515 -112.431466) (xy 95.11016 -112.379171) (xy 95.102404 -112.325223) (xy 95.101918 -112.297972)
			(xy 93.832934 -112.297972) (xy 93.832448 -112.325223) (xy 93.824692 -112.379171) (xy 93.809337 -112.431466)
			(xy 93.786695 -112.481043) (xy 93.757229 -112.526893) (xy 93.721538 -112.568084) (xy 93.680347 -112.603775)
			(xy 93.634497 -112.633241) (xy 93.58492 -112.655883) (xy 93.532625 -112.671238) (xy 93.478677 -112.678994)
			(xy 93.424175 -112.678994) (xy 93.370227 -112.671238) (xy 93.317932 -112.655883) (xy 93.268355 -112.633241)
			(xy 93.222505 -112.603775) (xy 93.181314 -112.568084) (xy 93.145623 -112.526893) (xy 93.116157 -112.481043)
			(xy 93.093515 -112.431466) (xy 93.07816 -112.379171) (xy 93.070404 -112.325223) (xy 93.069918 -112.297972)
			(xy 82.48904 -112.297972) (xy 82.48904 -112.748822) (xy 97.556828 -112.748822) (xy 97.55724 -112.722505)
			(xy 97.564468 -112.670368) (xy 97.578788 -112.619719) (xy 97.59993 -112.571517) (xy 97.627493 -112.526676)
			(xy 97.660954 -112.486047) (xy 97.680018 -112.467898) (xy 97.687425 -112.460382) (xy 97.695946 -112.441097)
			(xy 97.696528 -112.43056) (xy 97.696528 -112.355884) (xy 97.696013 -112.345333) (xy 97.687467 -112.326038)
			(xy 97.680018 -112.318546) (xy 97.660916 -112.300434) (xy 97.627439 -112.259809) (xy 97.599871 -112.214964)
			(xy 97.578737 -112.166752) (xy 97.564437 -112.11609) (xy 97.557245 -112.063943) (xy 97.556828 -112.037622)
			(xy 97.55724 -112.011305) (xy 97.564468 -111.959168) (xy 97.578788 -111.908519) (xy 97.59993 -111.860317)
			(xy 97.627493 -111.815476) (xy 97.660954 -111.774847) (xy 97.680018 -111.756698) (xy 97.687425 -111.749182)
			(xy 97.695946 -111.729897) (xy 97.696528 -111.71936) (xy 97.696528 -111.644684) (xy 97.696013 -111.634133)
			(xy 97.687467 -111.614838) (xy 97.680018 -111.607346) (xy 97.660916 -111.589234) (xy 97.627439 -111.548609)
			(xy 97.599871 -111.503764) (xy 97.578737 -111.455552) (xy 97.564437 -111.40489) (xy 97.557245 -111.352743)
			(xy 97.556828 -111.326422) (xy 97.557314 -111.299171) (xy 97.56507 -111.245223) (xy 97.580425 -111.192928)
			(xy 97.603067 -111.143351) (xy 97.632533 -111.097501) (xy 97.668224 -111.05631) (xy 97.709415 -111.020619)
			(xy 97.755265 -110.991153) (xy 97.804842 -110.968511) (xy 97.857137 -110.953156) (xy 97.911085 -110.9454)
			(xy 97.965587 -110.9454) (xy 98.019535 -110.953156) (xy 98.07183 -110.968511) (xy 98.121407 -110.991153)
			(xy 98.167257 -111.020619) (xy 98.208448 -111.05631) (xy 98.244139 -111.097501) (xy 98.273605 -111.143351)
			(xy 98.296247 -111.192928) (xy 98.311602 -111.245223) (xy 98.319358 -111.299171) (xy 98.319844 -111.326422)
			(xy 98.319371 -111.352737) (xy 98.312153 -111.40487) (xy 98.297843 -111.455517) (xy 98.276712 -111.503719)
			(xy 98.249161 -111.548561) (xy 98.215712 -111.589195) (xy 98.196654 -111.607346) (xy 98.189238 -111.614856)
			(xy 98.18072 -111.634144) (xy 98.180144 -111.644684) (xy 98.180144 -111.71936) (xy 98.180668 -111.729911)
			(xy 98.189206 -111.749207) (xy 98.196654 -111.756698) (xy 98.215724 -111.774843) (xy 98.249204 -111.81546)
			(xy 98.276777 -111.860298) (xy 98.297918 -111.908504) (xy 98.312224 -111.95916) (xy 98.319423 -112.011303)
			(xy 98.319844 -112.037622) (xy 98.319371 -112.063937) (xy 98.312153 -112.11607) (xy 98.297843 -112.166717)
			(xy 98.276712 -112.214919) (xy 98.249161 -112.259761) (xy 98.215712 -112.300395) (xy 98.196654 -112.318546)
			(xy 98.189238 -112.326056) (xy 98.18072 -112.345344) (xy 98.180144 -112.355884) (xy 98.180144 -112.43056)
			(xy 98.180668 -112.441111) (xy 98.189206 -112.460407) (xy 98.196654 -112.467898) (xy 98.215724 -112.486043)
			(xy 98.249204 -112.52666) (xy 98.276777 -112.571498) (xy 98.297918 -112.619704) (xy 98.312224 -112.67036)
			(xy 98.319423 -112.722503) (xy 98.319844 -112.748822) (xy 100.09505 -112.748822) (xy 100.095455 -112.722504)
			(xy 100.102683 -112.670367) (xy 100.117004 -112.619718) (xy 100.138148 -112.571516) (xy 100.165712 -112.526675)
			(xy 100.199175 -112.486046) (xy 100.21824 -112.467898) (xy 100.225636 -112.460371) (xy 100.234165 -112.441095)
			(xy 100.23475 -112.43056) (xy 100.23475 -112.355884) (xy 100.234228 -112.345334) (xy 100.225686 -112.326039)
			(xy 100.21824 -112.318546) (xy 100.199142 -112.30043) (xy 100.165664 -112.259806) (xy 100.138095 -112.214962)
			(xy 100.11696 -112.166751) (xy 100.102659 -112.11609) (xy 100.095467 -112.063943) (xy 100.09505 -112.037622)
			(xy 100.095455 -112.011304) (xy 100.102683 -111.959167) (xy 100.117004 -111.908518) (xy 100.138148 -111.860316)
			(xy 100.165712 -111.815475) (xy 100.199175 -111.774846) (xy 100.21824 -111.756698) (xy 100.225636 -111.749171)
			(xy 100.234165 -111.729895) (xy 100.23475 -111.71936) (xy 100.23475 -111.644684) (xy 100.234228 -111.634134)
			(xy 100.225686 -111.614839) (xy 100.21824 -111.607346) (xy 100.199142 -111.58923) (xy 100.165664 -111.548606)
			(xy 100.138095 -111.503762) (xy 100.11696 -111.455551) (xy 100.102659 -111.40489) (xy 100.095467 -111.352743)
			(xy 100.09505 -111.326422) (xy 100.095536 -111.299171) (xy 100.103292 -111.245223) (xy 100.118647 -111.192928)
			(xy 100.141289 -111.143351) (xy 100.170755 -111.097501) (xy 100.206446 -111.05631) (xy 100.247637 -111.020619)
			(xy 100.293487 -110.991153) (xy 100.343064 -110.968511) (xy 100.395359 -110.953156) (xy 100.449307 -110.9454)
			(xy 100.503809 -110.9454) (xy 100.557757 -110.953156) (xy 100.610052 -110.968511) (xy 100.659629 -110.991153)
			(xy 100.705479 -111.020619) (xy 100.74667 -111.05631) (xy 100.782361 -111.097501) (xy 100.811827 -111.143351)
			(xy 100.834469 -111.192928) (xy 100.849824 -111.245223) (xy 100.85758 -111.299171) (xy 100.858066 -111.326422)
			(xy 100.857618 -111.352738) (xy 100.850399 -111.404873) (xy 100.836085 -111.455522) (xy 100.81495 -111.503724)
			(xy 100.787393 -111.548566) (xy 100.753937 -111.589197) (xy 100.734876 -111.607346) (xy 100.727463 -111.614859)
			(xy 100.718942 -111.634145) (xy 100.718366 -111.644684) (xy 100.718366 -111.71936) (xy 100.718913 -111.729907)
			(xy 100.727437 -111.749202) (xy 100.734876 -111.756698) (xy 100.75395 -111.774838) (xy 100.787429 -111.815457)
			(xy 100.815001 -111.860296) (xy 100.836141 -111.908503) (xy 100.850446 -111.959159) (xy 100.857645 -112.011303)
			(xy 100.858066 -112.037622) (xy 100.857618 -112.063938) (xy 100.850399 -112.116073) (xy 100.836085 -112.166722)
			(xy 100.81495 -112.214924) (xy 100.787393 -112.259766) (xy 100.753937 -112.300397) (xy 100.734876 -112.318546)
			(xy 100.727463 -112.326059) (xy 100.718942 -112.345345) (xy 100.718366 -112.355884) (xy 100.718366 -112.43056)
			(xy 100.718913 -112.441107) (xy 100.727437 -112.460402) (xy 100.734876 -112.467898) (xy 100.75395 -112.486038)
			(xy 100.787429 -112.526657) (xy 100.815001 -112.571496) (xy 100.836141 -112.619703) (xy 100.850446 -112.670359)
			(xy 100.855247 -112.705134) (xy 104.297988 -112.705134) (xy 104.298421 -112.678817) (xy 104.305646 -112.626683)
			(xy 104.319963 -112.576034) (xy 104.341101 -112.527832) (xy 104.36866 -112.482991) (xy 104.402116 -112.44236)
			(xy 104.421178 -112.42421) (xy 104.428574 -112.416684) (xy 104.437102 -112.397407) (xy 104.437688 -112.386872)
			(xy 104.437688 -112.312196) (xy 104.437178 -112.301644) (xy 104.42863 -112.282349) (xy 104.421178 -112.274858)
			(xy 104.402093 -112.256728) (xy 104.368613 -112.216109) (xy 104.341041 -112.171268) (xy 104.319903 -112.123059)
			(xy 104.3056 -112.0724) (xy 104.298406 -112.020254) (xy 104.297988 -111.993934) (xy 104.298421 -111.967617)
			(xy 104.305646 -111.915483) (xy 104.319963 -111.864834) (xy 104.341101 -111.816632) (xy 104.36866 -111.771791)
			(xy 104.402116 -111.73116) (xy 104.421178 -111.71301) (xy 104.428574 -111.705484) (xy 104.437102 -111.686207)
			(xy 104.437688 -111.675672) (xy 104.437688 -111.600996) (xy 104.437178 -111.590444) (xy 104.42863 -111.571149)
			(xy 104.421178 -111.563658) (xy 104.402093 -111.545528) (xy 104.368613 -111.504909) (xy 104.341041 -111.460068)
			(xy 104.319903 -111.411859) (xy 104.3056 -111.3612) (xy 104.298406 -111.309054) (xy 104.297988 -111.282734)
			(xy 104.298421 -111.256417) (xy 104.305646 -111.204283) (xy 104.319963 -111.153634) (xy 104.341101 -111.105432)
			(xy 104.36866 -111.060591) (xy 104.402116 -111.01996) (xy 104.421178 -111.00181) (xy 104.428574 -110.994284)
			(xy 104.437102 -110.975007) (xy 104.437688 -110.964472) (xy 104.437688 -110.889796) (xy 104.437178 -110.879244)
			(xy 104.42863 -110.859949) (xy 104.421178 -110.852458) (xy 104.402093 -110.834328) (xy 104.368613 -110.793709)
			(xy 104.341041 -110.748868) (xy 104.319903 -110.700659) (xy 104.3056 -110.65) (xy 104.298406 -110.597854)
			(xy 104.297988 -110.571534) (xy 104.298487 -110.544282) (xy 104.306239 -110.490333) (xy 104.321591 -110.438036)
			(xy 104.344229 -110.388456) (xy 104.373693 -110.342603) (xy 104.409383 -110.30141) (xy 104.450572 -110.265716)
			(xy 104.496423 -110.236247) (xy 104.546 -110.213604) (xy 104.598296 -110.198247) (xy 104.652244 -110.19049)
			(xy 104.679496 -110.190026) (xy 104.705814 -110.190427) (xy 104.757951 -110.197657) (xy 104.8086 -110.211979)
			(xy 104.856802 -110.233123) (xy 104.901643 -110.260688) (xy 104.942272 -110.294151) (xy 104.96042 -110.313216)
			(xy 104.96793 -110.320631) (xy 104.987219 -110.329147) (xy 104.997758 -110.329726) (xy 105.072434 -110.329726)
			(xy 105.08298 -110.329167) (xy 105.102275 -110.320652) (xy 105.109772 -110.313216) (xy 105.127924 -110.294153)
			(xy 105.16854 -110.260673) (xy 105.213377 -110.2331) (xy 105.261581 -110.211958) (xy 105.312236 -110.197651)
			(xy 105.364377 -110.190449) (xy 105.390696 -110.190026) (xy 105.41795 -110.190459) (xy 105.471904 -110.198216)
			(xy 105.524205 -110.213574) (xy 105.573787 -110.236218) (xy 105.613417 -110.261688) (xy 106.914421 -110.261688)
			(xy 106.914421 -110.209712) (xy 106.922553 -110.158377) (xy 106.938615 -110.108946) (xy 106.962213 -110.062636)
			(xy 106.992766 -110.020588) (xy 107.02952 -109.983839) (xy 107.071572 -109.953291) (xy 107.117884 -109.929699)
			(xy 107.167318 -109.913643) (xy 107.218654 -109.905518) (xy 107.244642 -109.905038) (xy 107.271287 -109.905526)
			(xy 107.323889 -109.914057) (xy 107.374439 -109.930922) (xy 107.421625 -109.955684) (xy 107.464224 -109.987701)
			(xy 107.50113 -110.026141) (xy 107.516676 -110.047786) (xy 107.52504 -110.059072) (xy 107.546713 -110.076927)
			(xy 107.572427 -110.08821) (xy 107.600242 -110.092068) (xy 107.628057 -110.08821) (xy 107.653771 -110.076927)
			(xy 107.675444 -110.059072) (xy 107.683808 -110.047786) (xy 107.699397 -110.026178) (xy 107.73631 -109.987761)
			(xy 107.778906 -109.95576) (xy 107.826082 -109.931002) (xy 107.876617 -109.914129) (xy 107.929203 -109.905578)
			(xy 107.955842 -109.905038) (xy 107.981831 -109.905459) (xy 108.033167 -109.913596) (xy 108.082599 -109.929663)
			(xy 108.128909 -109.953264) (xy 108.170957 -109.983819) (xy 108.207709 -110.020575) (xy 108.238258 -110.062627)
			(xy 108.261853 -110.10894) (xy 108.277914 -110.158374) (xy 108.286044 -110.209711) (xy 108.286044 -110.261689)
			(xy 108.277914 -110.313026) (xy 108.261853 -110.36246) (xy 108.238258 -110.408773) (xy 108.207709 -110.450825)
			(xy 108.170957 -110.487581) (xy 108.132325 -110.515654) (xy 110.828072 -110.515654) (xy 110.832143 -110.460032)
			(xy 110.844269 -110.405595) (xy 110.864192 -110.353504) (xy 110.891488 -110.304869) (xy 110.925574 -110.260726)
			(xy 110.965723 -110.222017) (xy 111.011081 -110.189566) (xy 111.060681 -110.164065) (xy 111.113465 -110.146058)
			(xy 111.168308 -110.135928) (xy 111.224042 -110.133891) (xy 111.279479 -110.139991) (xy 111.333436 -110.154097)
			(xy 111.384765 -110.175909) (xy 111.432371 -110.204963) (xy 111.475239 -110.240638) (xy 111.512456 -110.282175)
			(xy 111.543229 -110.328688) (xy 111.566901 -110.379185) (xy 111.582969 -110.432592) (xy 111.591089 -110.487768)
			(xy 111.591598 -110.515654) (xy 111.591089 -110.54354) (xy 111.582969 -110.598716) (xy 111.566901 -110.652123)
			(xy 111.543229 -110.70262) (xy 111.512456 -110.749133) (xy 111.475239 -110.79067) (xy 111.432371 -110.826345)
			(xy 111.384765 -110.855399) (xy 111.333436 -110.877211) (xy 111.279479 -110.891317) (xy 111.224042 -110.897417)
			(xy 111.168308 -110.89538) (xy 111.113465 -110.88525) (xy 111.060681 -110.867243) (xy 111.011081 -110.841742)
			(xy 110.965723 -110.809291) (xy 110.925574 -110.770582) (xy 110.891488 -110.726439) (xy 110.864192 -110.677804)
			(xy 110.844269 -110.625713) (xy 110.832143 -110.571276) (xy 110.828072 -110.515654) (xy 108.132325 -110.515654)
			(xy 108.128909 -110.518136) (xy 108.082599 -110.541737) (xy 108.033167 -110.557804) (xy 107.981831 -110.565941)
			(xy 107.955842 -110.566454) (xy 107.929197 -110.565981) (xy 107.876594 -110.557448) (xy 107.826043 -110.54058)
			(xy 107.778857 -110.515815) (xy 107.736259 -110.483795) (xy 107.699354 -110.445352) (xy 107.683808 -110.423706)
			(xy 107.675444 -110.41242) (xy 107.653771 -110.394565) (xy 107.628057 -110.383282) (xy 107.600242 -110.379424)
			(xy 107.572427 -110.383282) (xy 107.546713 -110.394565) (xy 107.52504 -110.41242) (xy 107.516676 -110.423706)
			(xy 107.501095 -110.44532) (xy 107.46418 -110.483737) (xy 107.421583 -110.515738) (xy 107.374405 -110.540494)
			(xy 107.323869 -110.557366) (xy 107.271281 -110.565916) (xy 107.244642 -110.566454) (xy 107.218654 -110.565882)
			(xy 107.167318 -110.557757) (xy 107.117884 -110.541701) (xy 107.071572 -110.518109) (xy 107.02952 -110.487561)
			(xy 106.992766 -110.450812) (xy 106.962213 -110.408764) (xy 106.938615 -110.362454) (xy 106.922553 -110.313023)
			(xy 106.914421 -110.261688) (xy 105.613417 -110.261688) (xy 105.619642 -110.265689) (xy 105.660835 -110.301386)
			(xy 105.696529 -110.342582) (xy 105.725996 -110.388439) (xy 105.748637 -110.438024) (xy 105.76399 -110.490325)
			(xy 105.771743 -110.54428) (xy 105.772204 -110.571534) (xy 105.771752 -110.59785) (xy 105.764532 -110.649984)
			(xy 105.750218 -110.700632) (xy 105.729084 -110.748834) (xy 105.701528 -110.793676) (xy 105.668074 -110.834308)
			(xy 105.649014 -110.852458) (xy 105.641631 -110.859995) (xy 105.633095 -110.879263) (xy 105.632504 -110.889796)
			(xy 105.632504 -110.964472) (xy 105.633034 -110.975022) (xy 105.641568 -110.994317) (xy 105.649014 -111.00181)
			(xy 105.668101 -111.019937) (xy 105.701578 -111.060559) (xy 105.729147 -111.105402) (xy 105.750284 -111.153611)
			(xy 105.752622 -111.16189) (xy 106.914397 -111.16189) (xy 106.914397 -111.10991) (xy 106.922529 -111.058571)
			(xy 106.938593 -111.009136) (xy 106.962193 -110.962823) (xy 106.992748 -110.920773) (xy 107.029505 -110.88402)
			(xy 107.071559 -110.853471) (xy 107.117875 -110.829877) (xy 107.167312 -110.813819) (xy 107.218652 -110.805694)
			(xy 107.244642 -110.805214) (xy 107.271286 -110.805713) (xy 107.323887 -110.814242) (xy 107.374436 -110.831106)
			(xy 107.421622 -110.855866) (xy 107.464222 -110.887881) (xy 107.501129 -110.926319) (xy 107.516676 -110.947962)
			(xy 107.52504 -110.959248) (xy 107.546713 -110.977103) (xy 107.572427 -110.988386) (xy 107.600242 -110.992244)
			(xy 107.628057 -110.988386) (xy 107.653771 -110.977103) (xy 107.675444 -110.959248) (xy 107.683808 -110.947962)
			(xy 107.69939 -110.926349) (xy 107.736306 -110.887933) (xy 107.778903 -110.855933) (xy 107.82608 -110.831177)
			(xy 107.876616 -110.814305) (xy 107.929203 -110.805754) (xy 107.955842 -110.805214) (xy 107.981829 -110.805683)
			(xy 108.033162 -110.813819) (xy 108.08259 -110.829885) (xy 108.128897 -110.853484) (xy 108.170942 -110.884037)
			(xy 108.20769 -110.92079) (xy 108.238238 -110.962839) (xy 108.261831 -111.009149) (xy 108.277891 -111.058579)
			(xy 108.286021 -111.109913) (xy 108.286021 -111.161887) (xy 108.277891 -111.213221) (xy 108.261831 -111.262651)
			(xy 108.238238 -111.308961) (xy 108.20769 -111.35101) (xy 108.170942 -111.387763) (xy 108.128897 -111.418316)
			(xy 108.08259 -111.441915) (xy 108.033162 -111.457981) (xy 107.981829 -111.466117) (xy 107.955842 -111.46663)
			(xy 107.929196 -111.466167) (xy 107.876592 -111.457633) (xy 107.826041 -111.440764) (xy 107.778855 -111.415997)
			(xy 107.736257 -111.383975) (xy 107.699353 -111.345529) (xy 107.683808 -111.323882) (xy 107.675444 -111.312596)
			(xy 107.653771 -111.294741) (xy 107.628057 -111.283458) (xy 107.600242 -111.2796) (xy 107.572427 -111.283458)
			(xy 107.546713 -111.294741) (xy 107.52504 -111.312596) (xy 107.516676 -111.323882) (xy 107.501117 -111.345512)
			(xy 107.464195 -111.383925) (xy 107.421592 -111.415922) (xy 107.374411 -111.440675) (xy 107.323872 -111.457543)
			(xy 107.271282 -111.466092) (xy 107.244642 -111.46663) (xy 107.218652 -111.466106) (xy 107.167312 -111.457981)
			(xy 107.117875 -111.441923) (xy 107.071559 -111.418329) (xy 107.029505 -111.38778) (xy 106.992748 -111.351027)
			(xy 106.962193 -111.308977) (xy 106.938593 -111.262664) (xy 106.922529 -111.213229) (xy 106.914397 -111.16189)
			(xy 105.752622 -111.16189) (xy 105.764587 -111.204269) (xy 105.771784 -111.256414) (xy 105.772204 -111.282734)
			(xy 105.771752 -111.30905) (xy 105.764532 -111.361184) (xy 105.750218 -111.411832) (xy 105.729084 -111.460034)
			(xy 105.701528 -111.504876) (xy 105.668074 -111.545508) (xy 105.649014 -111.563658) (xy 105.641631 -111.571195)
			(xy 105.633095 -111.590463) (xy 105.632504 -111.600996) (xy 105.632504 -111.675672) (xy 105.633034 -111.686222)
			(xy 105.641568 -111.705517) (xy 105.649014 -111.71301) (xy 105.668101 -111.731137) (xy 105.701578 -111.771759)
			(xy 105.729147 -111.816602) (xy 105.750284 -111.864811) (xy 105.764587 -111.915469) (xy 105.771784 -111.967614)
			(xy 105.772204 -111.993934) (xy 105.771752 -112.02025) (xy 105.765999 -112.061788) (xy 106.914419 -112.061788)
			(xy 106.914419 -112.009812) (xy 106.922551 -111.958476) (xy 106.938613 -111.909045) (xy 106.962212 -111.862735)
			(xy 106.992764 -111.820687) (xy 107.029519 -111.783937) (xy 107.071571 -111.75339) (xy 107.117884 -111.729797)
			(xy 107.167317 -111.713741) (xy 107.218654 -111.705616) (xy 107.244642 -111.705136) (xy 107.271287 -111.705625)
			(xy 107.323888 -111.714156) (xy 107.374438 -111.73102) (xy 107.421625 -111.755782) (xy 107.464224 -111.787799)
			(xy 107.501129 -111.826239) (xy 107.516676 -111.847884) (xy 107.52504 -111.85917) (xy 107.546713 -111.877025)
			(xy 107.572427 -111.888308) (xy 107.600242 -111.892166) (xy 107.628057 -111.888308) (xy 107.653771 -111.877025)
			(xy 107.675444 -111.85917) (xy 107.683808 -111.847884) (xy 107.699396 -111.826275) (xy 107.73631 -111.787859)
			(xy 107.778906 -111.755857) (xy 107.826082 -111.7311) (xy 107.876617 -111.714227) (xy 107.929203 -111.705676)
			(xy 107.955842 -111.705136) (xy 107.98183 -111.705561) (xy 108.033167 -111.713698) (xy 108.082598 -111.729765)
			(xy 108.128908 -111.753366) (xy 108.170956 -111.78392) (xy 108.17269 -111.785654) (xy 109.457742 -111.785654)
			(xy 109.461813 -111.730032) (xy 109.473939 -111.675595) (xy 109.493862 -111.623504) (xy 109.521158 -111.574869)
			(xy 109.555244 -111.530726) (xy 109.595393 -111.492017) (xy 109.640751 -111.459566) (xy 109.690351 -111.434065)
			(xy 109.743135 -111.416058) (xy 109.797978 -111.405928) (xy 109.853712 -111.403891) (xy 109.909149 -111.409991)
			(xy 109.963106 -111.424097) (xy 110.014435 -111.445909) (xy 110.062041 -111.474963) (xy 110.104909 -111.510638)
			(xy 110.142126 -111.552175) (xy 110.172899 -111.598688) (xy 110.196571 -111.649185) (xy 110.212639 -111.702592)
			(xy 110.220759 -111.757768) (xy 110.221268 -111.785654) (xy 110.220759 -111.81354) (xy 110.212639 -111.868716)
			(xy 110.196571 -111.922123) (xy 110.172899 -111.97262) (xy 110.142126 -112.019133) (xy 110.104909 -112.06067)
			(xy 110.062041 -112.096345) (xy 110.014435 -112.125399) (xy 109.963106 -112.147211) (xy 109.909149 -112.161317)
			(xy 109.853712 -112.167417) (xy 109.797978 -112.16538) (xy 109.743135 -112.15525) (xy 109.690351 -112.137243)
			(xy 109.640751 -112.111742) (xy 109.595393 -112.079291) (xy 109.555244 -112.040582) (xy 109.521158 -111.996439)
			(xy 109.493862 -111.947804) (xy 109.473939 -111.895713) (xy 109.461813 -111.841276) (xy 109.457742 -111.785654)
			(xy 108.17269 -111.785654) (xy 108.207707 -111.820676) (xy 108.238256 -111.862728) (xy 108.261852 -111.909041)
			(xy 108.277912 -111.958474) (xy 108.286042 -112.009811) (xy 108.286042 -112.061789) (xy 108.277912 -112.113126)
			(xy 108.261852 -112.162559) (xy 108.238256 -112.208872) (xy 108.207707 -112.250924) (xy 108.170956 -112.28768)
			(xy 108.15819 -112.296956) (xy 110.894874 -112.296956) (xy 110.898945 -112.241334) (xy 110.911071 -112.186897)
			(xy 110.930994 -112.134806) (xy 110.95829 -112.086171) (xy 110.992376 -112.042028) (xy 111.032525 -112.003319)
			(xy 111.077883 -111.970868) (xy 111.127483 -111.945367) (xy 111.180267 -111.92736) (xy 111.23511 -111.91723)
			(xy 111.290844 -111.915193) (xy 111.346281 -111.921293) (xy 111.400238 -111.935399) (xy 111.451567 -111.957211)
			(xy 111.499173 -111.986265) (xy 111.542041 -112.02194) (xy 111.579258 -112.063477) (xy 111.610031 -112.10999)
			(xy 111.633703 -112.160487) (xy 111.649771 -112.213894) (xy 111.657891 -112.26907) (xy 111.6584 -112.296956)
			(xy 111.657891 -112.324842) (xy 111.649771 -112.380018) (xy 111.633703 -112.433425) (xy 111.610031 -112.483922)
			(xy 111.579258 -112.530435) (xy 111.542041 -112.571972) (xy 111.499173 -112.607647) (xy 111.451567 -112.636701)
			(xy 111.400238 -112.658513) (xy 111.346281 -112.672619) (xy 111.290844 -112.678719) (xy 111.23511 -112.676682)
			(xy 111.180267 -112.666552) (xy 111.127483 -112.648545) (xy 111.077883 -112.623044) (xy 111.032525 -112.590593)
			(xy 110.992376 -112.551884) (xy 110.95829 -112.507741) (xy 110.930994 -112.459106) (xy 110.911071 -112.407015)
			(xy 110.898945 -112.352578) (xy 110.894874 -112.296956) (xy 108.15819 -112.296956) (xy 108.128908 -112.318234)
			(xy 108.082598 -112.341835) (xy 108.033167 -112.357902) (xy 107.98183 -112.366039) (xy 107.955842 -112.366552)
			(xy 107.929197 -112.36608) (xy 107.876594 -112.357547) (xy 107.826043 -112.340679) (xy 107.778857 -112.315913)
			(xy 107.736259 -112.283894) (xy 107.699354 -112.24545) (xy 107.683808 -112.223804) (xy 107.675444 -112.212518)
			(xy 107.653771 -112.194663) (xy 107.628057 -112.18338) (xy 107.600242 -112.179522) (xy 107.572427 -112.18338)
			(xy 107.546713 -112.194663) (xy 107.52504 -112.212518) (xy 107.516676 -112.223804) (xy 107.501094 -112.245417)
			(xy 107.46418 -112.283835) (xy 107.421582 -112.315836) (xy 107.374405 -112.340592) (xy 107.323869 -112.357464)
			(xy 107.271281 -112.366014) (xy 107.244642 -112.366552) (xy 107.218654 -112.365984) (xy 107.167317 -112.357859)
			(xy 107.117884 -112.341803) (xy 107.071571 -112.31821) (xy 107.029519 -112.287663) (xy 106.992764 -112.250913)
			(xy 106.962212 -112.208865) (xy 106.938613 -112.162555) (xy 106.922551 -112.113124) (xy 106.914419 -112.061788)
			(xy 105.765999 -112.061788) (xy 105.764532 -112.072384) (xy 105.750218 -112.123032) (xy 105.729084 -112.171234)
			(xy 105.701528 -112.216076) (xy 105.668074 -112.256708) (xy 105.649014 -112.274858) (xy 105.641631 -112.282395)
			(xy 105.633095 -112.301663) (xy 105.632504 -112.312196) (xy 105.632504 -112.386872) (xy 105.633034 -112.397422)
			(xy 105.641568 -112.416717) (xy 105.649014 -112.42421) (xy 105.668101 -112.442337) (xy 105.701578 -112.482959)
			(xy 105.729147 -112.527802) (xy 105.750284 -112.576011) (xy 105.764587 -112.626669) (xy 105.771784 -112.678814)
			(xy 105.772204 -112.705134) (xy 105.771754 -112.732386) (xy 105.763993 -112.786335) (xy 105.748633 -112.838631)
			(xy 105.725988 -112.888209) (xy 105.696517 -112.934059) (xy 105.672482 -112.961794) (xy 106.914341 -112.961794)
			(xy 106.914341 -112.909806) (xy 106.922475 -112.858458) (xy 106.938541 -112.809015) (xy 106.962145 -112.762694)
			(xy 106.992705 -112.720636) (xy 107.029468 -112.683878) (xy 107.07153 -112.653323) (xy 107.117854 -112.629725)
			(xy 107.167299 -112.613665) (xy 107.218648 -112.605538) (xy 107.244642 -112.605058) (xy 107.271287 -112.605538)
			(xy 107.32389 -112.614069) (xy 107.37444 -112.630935) (xy 107.421627 -112.655699) (xy 107.464225 -112.687717)
			(xy 107.50113 -112.72616) (xy 107.516676 -112.747806) (xy 107.52504 -112.759092) (xy 107.546713 -112.776947)
			(xy 107.572427 -112.78823) (xy 107.600242 -112.792088) (xy 107.628057 -112.78823) (xy 107.653771 -112.776947)
			(xy 107.675444 -112.759092) (xy 107.683808 -112.747806) (xy 107.699373 -112.72618) (xy 107.736294 -112.687768)
			(xy 107.778896 -112.655771) (xy 107.826076 -112.631018) (xy 107.876614 -112.614148) (xy 107.929202 -112.605598)
			(xy 107.955842 -112.605058) (xy 107.981824 -112.605639) (xy 108.033148 -112.613774) (xy 108.082568 -112.629837)
			(xy 108.128867 -112.653432) (xy 108.170905 -112.68398) (xy 108.207648 -112.720727) (xy 108.23819 -112.762769)
			(xy 108.26178 -112.809071) (xy 108.277836 -112.858492) (xy 108.285965 -112.909818) (xy 108.285965 -112.961782)
			(xy 108.277836 -113.013108) (xy 108.26178 -113.062529) (xy 108.23819 -113.108831) (xy 108.207648 -113.150873)
			(xy 108.170905 -113.18762) (xy 108.128867 -113.218168) (xy 108.082568 -113.241763) (xy 108.033148 -113.257826)
			(xy 107.981824 -113.265961) (xy 107.955842 -113.266474) (xy 107.929197 -113.265992) (xy 107.876595 -113.25746)
			(xy 107.826045 -113.240593) (xy 107.778859 -113.21583) (xy 107.73626 -113.183812) (xy 107.699355 -113.145371)
			(xy 107.683808 -113.123726) (xy 107.675444 -113.11244) (xy 107.653771 -113.094585) (xy 107.628057 -113.083302)
			(xy 107.600242 -113.079444) (xy 107.572427 -113.083302) (xy 107.546713 -113.094585) (xy 107.52504 -113.11244)
			(xy 107.516676 -113.123726) (xy 107.501101 -113.145344) (xy 107.464184 -113.18376) (xy 107.421585 -113.21576)
			(xy 107.374407 -113.240516) (xy 107.32387 -113.257386) (xy 107.271281 -113.265936) (xy 107.244642 -113.266474)
			(xy 107.218648 -113.266062) (xy 107.167299 -113.257935) (xy 107.117854 -113.241875) (xy 107.07153 -113.218277)
			(xy 107.029468 -113.187722) (xy 106.992705 -113.150964) (xy 106.962145 -113.108906) (xy 106.938541 -113.062585)
			(xy 106.922475 -113.013142) (xy 106.914341 -112.961794) (xy 105.672482 -112.961794) (xy 105.660822 -112.975249)
			(xy 105.619629 -113.01094) (xy 105.573775 -113.040406) (xy 105.524195 -113.063046) (xy 105.471898 -113.078401)
			(xy 105.417948 -113.086157) (xy 105.390696 -113.086642) (xy 105.364381 -113.086158) (xy 105.312249 -113.078942)
			(xy 105.261602 -113.064634) (xy 105.2134 -113.043506) (xy 105.168557 -113.015956) (xy 105.127924 -112.982509)
			(xy 105.109772 -112.963452) (xy 105.102256 -112.956044) (xy 105.082972 -112.947521) (xy 105.072434 -112.946942)
			(xy 104.997758 -112.946942) (xy 104.987209 -112.947477) (xy 104.967912 -112.956007) (xy 104.96042 -112.963452)
			(xy 104.942266 -112.982513) (xy 104.901651 -113.015994) (xy 104.856815 -113.043568) (xy 104.808611 -113.06471)
			(xy 104.757956 -113.079018) (xy 104.705815 -113.08622) (xy 104.679496 -113.086642) (xy 104.652246 -113.086126)
			(xy 104.598301 -113.07837) (xy 104.546009 -113.063016) (xy 104.496434 -113.040377) (xy 104.450585 -113.010913)
			(xy 104.409396 -112.975225) (xy 104.373705 -112.934039) (xy 104.344238 -112.888192) (xy 104.321595 -112.838619)
			(xy 104.306237 -112.786328) (xy 104.298476 -112.732384) (xy 104.297988 -112.705134) (xy 100.855247 -112.705134)
			(xy 100.857645 -112.722503) (xy 100.858066 -112.748822) (xy 100.85758 -112.776073) (xy 100.849824 -112.830021)
			(xy 100.834469 -112.882316) (xy 100.811827 -112.931893) (xy 100.782361 -112.977743) (xy 100.74667 -113.018934)
			(xy 100.705479 -113.054625) (xy 100.659629 -113.084091) (xy 100.610052 -113.106733) (xy 100.557757 -113.122088)
			(xy 100.503809 -113.129844) (xy 100.449307 -113.129844) (xy 100.395359 -113.122088) (xy 100.343064 -113.106733)
			(xy 100.293487 -113.084091) (xy 100.247637 -113.054625) (xy 100.206446 -113.018934) (xy 100.170755 -112.977743)
			(xy 100.141289 -112.931893) (xy 100.118647 -112.882316) (xy 100.103292 -112.830021) (xy 100.095536 -112.776073)
			(xy 100.09505 -112.748822) (xy 98.319844 -112.748822) (xy 98.319358 -112.776073) (xy 98.311602 -112.830021)
			(xy 98.296247 -112.882316) (xy 98.273605 -112.931893) (xy 98.244139 -112.977743) (xy 98.208448 -113.018934)
			(xy 98.167257 -113.054625) (xy 98.121407 -113.084091) (xy 98.07183 -113.106733) (xy 98.019535 -113.122088)
			(xy 97.965587 -113.129844) (xy 97.911085 -113.129844) (xy 97.857137 -113.122088) (xy 97.804842 -113.106733)
			(xy 97.755265 -113.084091) (xy 97.709415 -113.054625) (xy 97.668224 -113.018934) (xy 97.632533 -112.977743)
			(xy 97.603067 -112.931893) (xy 97.580425 -112.882316) (xy 97.56507 -112.830021) (xy 97.557314 -112.776073)
			(xy 97.556828 -112.748822) (xy 82.48904 -112.748822) (xy 82.48904 -113.846864) (xy 82.489454 -113.856887)
			(xy 82.497119 -113.875409) (xy 82.511294 -113.889583) (xy 82.529817 -113.897247) (xy 82.53984 -113.897664)
			(xy 84.772754 -113.897664) (xy 84.798839 -113.898154) (xy 84.850366 -113.906329) (xy 84.899978 -113.922468)
			(xy 84.946452 -113.946174) (xy 84.988643 -113.976862) (xy 85.00745 -113.994946) (xy 85.097141 -114.084637)
			(xy 89.449407 -114.084637) (xy 89.449409 -114.03014) (xy 89.457166 -113.976198) (xy 89.472521 -113.923908)
			(xy 89.495161 -113.874336) (xy 89.524626 -113.828491) (xy 89.560315 -113.787305) (xy 89.601502 -113.751618)
			(xy 89.647348 -113.722155) (xy 89.696921 -113.699517) (xy 89.749211 -113.684163) (xy 89.803153 -113.676408)
			(xy 89.830402 -113.675922) (xy 89.854245 -113.676275) (xy 89.901562 -113.682198) (xy 89.947774 -113.693965)
			(xy 89.970102 -113.702338) (xy 89.982802 -113.707418) (xy 90.009218 -113.703354) (xy 90.099642 -113.631726)
			(xy 90.109548 -113.606834) (xy 90.10777 -113.593118) (xy 90.105892 -113.579479) (xy 90.103858 -113.552021)
			(xy 90.103706 -113.538254) (xy 90.104135 -113.511001) (xy 90.111898 -113.45705) (xy 90.12726 -113.404754)
			(xy 90.149907 -113.355176) (xy 90.17938 -113.309325) (xy 90.215077 -113.268135) (xy 90.256273 -113.232444)
			(xy 90.302128 -113.202979) (xy 90.35171 -113.180339) (xy 90.404009 -113.164985) (xy 90.457961 -113.157231)
			(xy 90.485214 -113.156746) (xy 90.514129 -113.157309) (xy 90.571299 -113.166026) (xy 90.626498 -113.183274)
			(xy 90.67846 -113.208657) (xy 90.725995 -113.241594) (xy 90.768013 -113.281329) (xy 90.786204 -113.303812)
			(xy 90.793767 -113.312573) (xy 90.814525 -113.322756) (xy 90.826082 -113.32337) (xy 90.906346 -113.32337)
			(xy 90.917911 -113.322779) (xy 90.938683 -113.3126) (xy 90.946224 -113.303812) (xy 90.964405 -113.28132)
			(xy 91.006426 -113.241584) (xy 91.053963 -113.208646) (xy 91.105926 -113.183259) (xy 91.161126 -113.166005)
			(xy 91.218297 -113.157279) (xy 91.247214 -113.156746) (xy 91.274464 -113.157265) (xy 91.328408 -113.165022)
			(xy 91.380699 -113.180376) (xy 91.430273 -113.203016) (xy 91.476121 -113.232479) (xy 91.51731 -113.268167)
			(xy 91.553001 -113.309353) (xy 91.582469 -113.355199) (xy 91.605112 -113.404771) (xy 91.620471 -113.457061)
			(xy 91.628233 -113.511005) (xy 91.628722 -113.538254) (xy 91.628284 -113.565013) (xy 91.627758 -113.568734)
			(xy 110.889794 -113.568734) (xy 110.893865 -113.513112) (xy 110.905991 -113.458675) (xy 110.925914 -113.406584)
			(xy 110.95321 -113.357949) (xy 110.987296 -113.313806) (xy 111.027445 -113.275097) (xy 111.072803 -113.242646)
			(xy 111.122403 -113.217145) (xy 111.175187 -113.199138) (xy 111.23003 -113.189008) (xy 111.285764 -113.186971)
			(xy 111.341201 -113.193071) (xy 111.395158 -113.207177) (xy 111.446487 -113.228989) (xy 111.494093 -113.258043)
			(xy 111.536961 -113.293718) (xy 111.574178 -113.335255) (xy 111.604951 -113.381768) (xy 111.628623 -113.432265)
			(xy 111.644691 -113.485672) (xy 111.652811 -113.540848) (xy 111.65332 -113.568734) (xy 111.652811 -113.59662)
			(xy 111.644691 -113.651796) (xy 111.628623 -113.705203) (xy 111.604951 -113.7557) (xy 111.574178 -113.802213)
			(xy 111.536961 -113.84375) (xy 111.494093 -113.879425) (xy 111.446487 -113.908479) (xy 111.395158 -113.930291)
			(xy 111.341201 -113.944397) (xy 111.285764 -113.950497) (xy 111.23003 -113.94846) (xy 111.175187 -113.93833)
			(xy 111.122403 -113.920323) (xy 111.072803 -113.894822) (xy 111.027445 -113.862371) (xy 110.987296 -113.823662)
			(xy 110.95321 -113.779519) (xy 110.925914 -113.730884) (xy 110.905991 -113.678793) (xy 110.893865 -113.624356)
			(xy 110.889794 -113.568734) (xy 91.627758 -113.568734) (xy 91.620797 -113.618004) (xy 91.605979 -113.669429)
			(xy 91.58412 -113.718279) (xy 91.555649 -113.763594) (xy 91.521125 -113.804487) (xy 91.481225 -113.840153)
			(xy 91.436732 -113.869894) (xy 91.412822 -113.881916) (xy 91.401392 -113.887504) (xy 91.38666 -113.907316)
			(xy 91.369642 -114.014758) (xy 91.377516 -114.03838) (xy 91.38666 -114.047016) (xy 91.396783 -114.05681)
			(xy 91.415729 -114.077656) (xy 91.424506 -114.088672) (xy 91.432057 -114.097444) (xy 91.452825 -114.107619)
			(xy 91.464384 -114.10823) (xy 91.544648 -114.10823) (xy 91.556216 -114.107654) (xy 91.576988 -114.097466)
			(xy 91.584526 -114.088672) (xy 91.602695 -114.06617) (xy 91.64472 -114.026437) (xy 91.69226 -113.993501)
			(xy 91.744225 -113.968116) (xy 91.799426 -113.950864) (xy 91.856599 -113.942139) (xy 91.885516 -113.941606)
			(xy 91.912768 -113.942065) (xy 91.966715 -113.949824) (xy 92.01901 -113.965181) (xy 92.068587 -113.987824)
			(xy 92.114437 -114.017291) (xy 92.127342 -114.028474) (xy 105.005122 -114.028474) (xy 105.009193 -113.972852)
			(xy 105.021319 -113.918415) (xy 105.041242 -113.866324) (xy 105.068538 -113.817689) (xy 105.102624 -113.773546)
			(xy 105.142773 -113.734837) (xy 105.188131 -113.702386) (xy 105.237731 -113.676885) (xy 105.290515 -113.658878)
			(xy 105.345358 -113.648748) (xy 105.401092 -113.646711) (xy 105.456529 -113.652811) (xy 105.510486 -113.666917)
			(xy 105.561815 -113.688729) (xy 105.609421 -113.717783) (xy 105.652289 -113.753458) (xy 105.689506 -113.794995)
			(xy 105.720279 -113.841508) (xy 105.743951 -113.892005) (xy 105.760019 -113.945412) (xy 105.768139 -114.000588)
			(xy 105.768648 -114.028474) (xy 105.768139 -114.05636) (xy 105.760019 -114.111536) (xy 105.743951 -114.164943)
			(xy 105.720279 -114.21544) (xy 105.689506 -114.261953) (xy 105.652289 -114.30349) (xy 105.609421 -114.339165)
			(xy 105.561815 -114.368219) (xy 105.510486 -114.390031) (xy 105.456529 -114.404137) (xy 105.401092 -114.410237)
			(xy 105.345358 -114.4082) (xy 105.290515 -114.39807) (xy 105.237731 -114.380063) (xy 105.188131 -114.354562)
			(xy 105.142773 -114.322111) (xy 105.102624 -114.283402) (xy 105.068538 -114.239259) (xy 105.041242 -114.190624)
			(xy 105.021319 -114.138533) (xy 105.009193 -114.084096) (xy 105.005122 -114.028474) (xy 92.127342 -114.028474)
			(xy 92.155627 -114.052984) (xy 92.191318 -114.094175) (xy 92.220784 -114.140027) (xy 92.243425 -114.189605)
			(xy 92.25878 -114.2419) (xy 92.266536 -114.295848) (xy 92.266536 -114.350352) (xy 92.25878 -114.4043)
			(xy 92.243425 -114.456595) (xy 92.220784 -114.506173) (xy 92.191318 -114.552025) (xy 92.155627 -114.593216)
			(xy 92.114437 -114.628909) (xy 92.068587 -114.658376) (xy 92.01901 -114.681019) (xy 91.966715 -114.696376)
			(xy 91.912767 -114.704135) (xy 91.885516 -114.704622) (xy 91.856598 -114.704122) (xy 91.799425 -114.695393)
			(xy 91.744224 -114.678134) (xy 91.692262 -114.652739) (xy 91.644729 -114.619791) (xy 91.602714 -114.580044)
			(xy 91.584526 -114.557556) (xy 91.576956 -114.548803) (xy 91.556203 -114.538617) (xy 91.544648 -114.537998)
			(xy 91.464384 -114.537998) (xy 91.452815 -114.53856) (xy 91.432044 -114.548761) (xy 91.424506 -114.557556)
			(xy 91.4063 -114.580027) (xy 91.364285 -114.619765) (xy 91.316754 -114.652707) (xy 91.264795 -114.678098)
			(xy 91.209599 -114.695356) (xy 91.152431 -114.704087) (xy 91.123516 -114.704622) (xy 91.096264 -114.70413)
			(xy 91.042315 -114.696375) (xy 90.990019 -114.681022) (xy 90.940439 -114.658383) (xy 90.894587 -114.628917)
			(xy 90.853394 -114.593227) (xy 90.817701 -114.552037) (xy 90.788232 -114.506187) (xy 90.765588 -114.45661)
			(xy 90.750231 -114.404314) (xy 90.742472 -114.350366) (xy 90.742008 -114.323114) (xy 90.742459 -114.296356)
			(xy 90.749948 -114.243367) (xy 90.764767 -114.191945) (xy 90.786626 -114.143097) (xy 90.815095 -114.097782)
			(xy 90.849616 -114.056889) (xy 90.889512 -114.021221) (xy 90.934 -113.991476) (xy 90.957908 -113.979452)
			(xy 90.969338 -113.973864) (xy 90.98407 -113.954052) (xy 91.001088 -113.84661) (xy 90.993214 -113.822988)
			(xy 90.98407 -113.814352) (xy 90.973942 -113.804563) (xy 90.954999 -113.783714) (xy 90.946224 -113.772696)
			(xy 90.938648 -113.763949) (xy 90.9179 -113.753757) (xy 90.906346 -113.753138) (xy 90.826082 -113.753138)
			(xy 90.814511 -113.753685) (xy 90.793739 -113.763895) (xy 90.786204 -113.772696) (xy 90.76801 -113.795177)
			(xy 90.725991 -113.834912) (xy 90.678457 -113.867852) (xy 90.626496 -113.893241) (xy 90.571299 -113.910497)
			(xy 90.51413 -113.919227) (xy 90.485214 -113.919762) (xy 90.461371 -113.919405) (xy 90.414054 -113.913484)
			(xy 90.367842 -113.901718) (xy 90.345514 -113.893346) (xy 90.332814 -113.888266) (xy 90.306398 -113.89233)
			(xy 90.215974 -113.963958) (xy 90.206068 -113.98885) (xy 90.207846 -114.002566) (xy 90.209722 -114.016205)
			(xy 90.211757 -114.043663) (xy 90.21191 -114.05743) (xy 90.21139 -114.084679) (xy 90.20363 -114.138621)
			(xy 90.188272 -114.190909) (xy 90.16563 -114.24048) (xy 90.136163 -114.286324) (xy 90.100472 -114.327508)
			(xy 90.059283 -114.363193) (xy 90.013436 -114.392654) (xy 89.963862 -114.41529) (xy 89.911571 -114.430641)
			(xy 89.857628 -114.438393) (xy 89.803131 -114.43839) (xy 89.749189 -114.430632) (xy 89.6969 -114.415276)
			(xy 89.647328 -114.392634) (xy 89.601483 -114.363169) (xy 89.560299 -114.327479) (xy 89.524612 -114.286291)
			(xy 89.49515 -114.240444) (xy 89.472513 -114.19087) (xy 89.457161 -114.13858) (xy 89.449407 -114.084637)
			(xy 85.097141 -114.084637) (xy 86.565994 -115.55349) (xy 86.573338 -115.560303) (xy 86.591801 -115.568039)
			(xy 86.601808 -115.568476) (xy 87.164164 -115.568476) (xy 87.175094 -115.567958) (xy 87.194976 -115.558877)
			(xy 87.202518 -115.55095) (xy 87.260176 -115.48491) (xy 87.266272 -115.464082) (xy 87.264748 -115.452906)
			(xy 87.263073 -115.439954) (xy 87.261291 -115.413896) (xy 87.261192 -115.400836) (xy 87.261653 -115.373581)
			(xy 87.269406 -115.319627) (xy 87.284759 -115.267324) (xy 87.307399 -115.21774) (xy 87.336866 -115.171882)
			(xy 87.37256 -115.130685) (xy 87.413753 -115.094988) (xy 87.459608 -115.065516) (xy 87.509191 -115.042871)
			(xy 87.561491 -115.027513) (xy 87.615446 -115.019755) (xy 87.6427 -115.019328) (xy 87.673502 -115.01994)
			(xy 87.7343 -115.029877) (xy 87.792715 -115.049444) (xy 87.820246 -115.06327) (xy 87.825834 -115.066064)
			(xy 87.837772 -115.069112) (xy 88.654636 -115.069112) (xy 88.680714 -115.069576) (xy 88.732233 -115.077695)
			(xy 88.781847 -115.093774) (xy 88.828334 -115.117418) (xy 88.87055 -115.148043) (xy 88.889332 -115.16614)
			(xy 89.093548 -115.370356) (xy 89.361262 -115.370356) (xy 89.365333 -115.314734) (xy 89.377459 -115.260297)
			(xy 89.397382 -115.208206) (xy 89.424678 -115.159571) (xy 89.458764 -115.115428) (xy 89.498913 -115.076719)
			(xy 89.544271 -115.044268) (xy 89.593871 -115.018767) (xy 89.646655 -115.00076) (xy 89.701498 -114.99063)
			(xy 89.757232 -114.988593) (xy 89.812669 -114.994693) (xy 89.866626 -115.008799) (xy 89.871678 -115.010946)
			(xy 106.6198 -115.010946) (xy 106.623871 -114.955324) (xy 106.635997 -114.900887) (xy 106.65592 -114.848796)
			(xy 106.683216 -114.800161) (xy 106.717302 -114.756018) (xy 106.757451 -114.717309) (xy 106.802809 -114.684858)
			(xy 106.852409 -114.659357) (xy 106.905193 -114.64135) (xy 106.960036 -114.63122) (xy 107.01577 -114.629183)
			(xy 107.071207 -114.635283) (xy 107.125164 -114.649389) (xy 107.176493 -114.671201) (xy 107.224099 -114.700255)
			(xy 107.266967 -114.73593) (xy 107.304184 -114.777467) (xy 107.334957 -114.82398) (xy 107.358629 -114.874477)
			(xy 107.374697 -114.927884) (xy 107.382817 -114.98306) (xy 107.383326 -115.010946) (xy 107.382817 -115.038832)
			(xy 107.379893 -115.058698) (xy 107.98632 -115.058698) (xy 107.990391 -115.003076) (xy 108.002517 -114.948639)
			(xy 108.02244 -114.896548) (xy 108.049736 -114.847913) (xy 108.083822 -114.80377) (xy 108.123971 -114.765061)
			(xy 108.169329 -114.73261) (xy 108.218929 -114.707109) (xy 108.271713 -114.689102) (xy 108.326556 -114.678972)
			(xy 108.38229 -114.676935) (xy 108.437727 -114.683035) (xy 108.491684 -114.697141) (xy 108.543013 -114.718953)
			(xy 108.590619 -114.748007) (xy 108.633487 -114.783682) (xy 108.670704 -114.825219) (xy 108.701477 -114.871732)
			(xy 108.725149 -114.922229) (xy 108.741217 -114.975636) (xy 108.743386 -114.990372) (xy 109.365032 -114.990372)
			(xy 109.369103 -114.93475) (xy 109.381229 -114.880313) (xy 109.401152 -114.828222) (xy 109.428448 -114.779587)
			(xy 109.462534 -114.735444) (xy 109.502683 -114.696735) (xy 109.548041 -114.664284) (xy 109.597641 -114.638783)
			(xy 109.650425 -114.620776) (xy 109.705268 -114.610646) (xy 109.761002 -114.608609) (xy 109.816439 -114.614709)
			(xy 109.870396 -114.628815) (xy 109.921725 -114.650627) (xy 109.969331 -114.679681) (xy 110.012199 -114.715356)
			(xy 110.049416 -114.756893) (xy 110.080189 -114.803406) (xy 110.103861 -114.853903) (xy 110.119929 -114.90731)
			(xy 110.127779 -114.960654) (xy 110.891826 -114.960654) (xy 110.895897 -114.905032) (xy 110.908023 -114.850595)
			(xy 110.927946 -114.798504) (xy 110.955242 -114.749869) (xy 110.989328 -114.705726) (xy 111.029477 -114.667017)
			(xy 111.074835 -114.634566) (xy 111.124435 -114.609065) (xy 111.177219 -114.591058) (xy 111.232062 -114.580928)
			(xy 111.287796 -114.578891) (xy 111.343233 -114.584991) (xy 111.39719 -114.599097) (xy 111.448519 -114.620909)
			(xy 111.496125 -114.649963) (xy 111.538993 -114.685638) (xy 111.57621 -114.727175) (xy 111.606983 -114.773688)
			(xy 111.630655 -114.824185) (xy 111.646723 -114.877592) (xy 111.654843 -114.932768) (xy 111.655352 -114.960654)
			(xy 111.654843 -114.98854) (xy 111.646723 -115.043716) (xy 111.630655 -115.097123) (xy 111.606983 -115.14762)
			(xy 111.57621 -115.194133) (xy 111.538993 -115.23567) (xy 111.496125 -115.271345) (xy 111.448519 -115.300399)
			(xy 111.39719 -115.322211) (xy 111.343233 -115.336317) (xy 111.287796 -115.342417) (xy 111.232062 -115.34038)
			(xy 111.177219 -115.33025) (xy 111.124435 -115.312243) (xy 111.074835 -115.286742) (xy 111.029477 -115.254291)
			(xy 110.989328 -115.215582) (xy 110.955242 -115.171439) (xy 110.927946 -115.122804) (xy 110.908023 -115.070713)
			(xy 110.895897 -115.016276) (xy 110.891826 -114.960654) (xy 110.127779 -114.960654) (xy 110.128049 -114.962486)
			(xy 110.128558 -114.990372) (xy 110.128049 -115.018258) (xy 110.119929 -115.073434) (xy 110.103861 -115.126841)
			(xy 110.080189 -115.177338) (xy 110.049416 -115.223851) (xy 110.012199 -115.265388) (xy 109.969331 -115.301063)
			(xy 109.921725 -115.330117) (xy 109.870396 -115.351929) (xy 109.816439 -115.366035) (xy 109.761002 -115.372135)
			(xy 109.705268 -115.370098) (xy 109.650425 -115.359968) (xy 109.597641 -115.341961) (xy 109.548041 -115.31646)
			(xy 109.502683 -115.284009) (xy 109.462534 -115.2453) (xy 109.428448 -115.201157) (xy 109.401152 -115.152522)
			(xy 109.381229 -115.100431) (xy 109.369103 -115.045994) (xy 109.365032 -114.990372) (xy 108.743386 -114.990372)
			(xy 108.749337 -115.030812) (xy 108.749846 -115.058698) (xy 108.749337 -115.086584) (xy 108.741217 -115.14176)
			(xy 108.725149 -115.195167) (xy 108.701477 -115.245664) (xy 108.670704 -115.292177) (xy 108.633487 -115.333714)
			(xy 108.590619 -115.369389) (xy 108.543013 -115.398443) (xy 108.491684 -115.420255) (xy 108.437727 -115.434361)
			(xy 108.38229 -115.440461) (xy 108.326556 -115.438424) (xy 108.271713 -115.428294) (xy 108.218929 -115.410287)
			(xy 108.169329 -115.384786) (xy 108.123971 -115.352335) (xy 108.083822 -115.313626) (xy 108.049736 -115.269483)
			(xy 108.02244 -115.220848) (xy 108.002517 -115.168757) (xy 107.990391 -115.11432) (xy 107.98632 -115.058698)
			(xy 107.379893 -115.058698) (xy 107.374697 -115.094008) (xy 107.358629 -115.147415) (xy 107.334957 -115.197912)
			(xy 107.304184 -115.244425) (xy 107.266967 -115.285962) (xy 107.224099 -115.321637) (xy 107.176493 -115.350691)
			(xy 107.125164 -115.372503) (xy 107.071207 -115.386609) (xy 107.01577 -115.392709) (xy 106.960036 -115.390672)
			(xy 106.905193 -115.380542) (xy 106.852409 -115.362535) (xy 106.802809 -115.337034) (xy 106.757451 -115.304583)
			(xy 106.717302 -115.265874) (xy 106.683216 -115.221731) (xy 106.65592 -115.173096) (xy 106.635997 -115.121005)
			(xy 106.623871 -115.066568) (xy 106.6198 -115.010946) (xy 89.871678 -115.010946) (xy 89.917955 -115.030611)
			(xy 89.965561 -115.059665) (xy 90.008429 -115.09534) (xy 90.045646 -115.136877) (xy 90.076419 -115.18339)
			(xy 90.100091 -115.233887) (xy 90.116159 -115.287294) (xy 90.124279 -115.34247) (xy 90.124788 -115.370356)
			(xy 90.124279 -115.398242) (xy 90.116159 -115.453418) (xy 90.100091 -115.506825) (xy 90.076419 -115.557322)
			(xy 90.045646 -115.603835) (xy 90.008429 -115.645372) (xy 89.965561 -115.681047) (xy 89.917955 -115.710101)
			(xy 89.866626 -115.731913) (xy 89.812669 -115.746019) (xy 89.757232 -115.752119) (xy 89.701498 -115.750082)
			(xy 89.646655 -115.739952) (xy 89.593871 -115.721945) (xy 89.544271 -115.696444) (xy 89.498913 -115.663993)
			(xy 89.458764 -115.625284) (xy 89.424678 -115.581141) (xy 89.397382 -115.532506) (xy 89.377459 -115.480415)
			(xy 89.365333 -115.425978) (xy 89.361262 -115.370356) (xy 89.093548 -115.370356) (xy 89.174828 -115.451636)
			(xy 89.192918 -115.470426) (xy 89.223558 -115.512635) (xy 89.247214 -115.559119) (xy 89.263304 -115.608733)
			(xy 89.271431 -115.660253) (xy 89.271856 -115.686332) (xy 89.271856 -115.832636) (xy 92.979238 -115.832636)
			(xy 92.983309 -115.777014) (xy 92.995435 -115.722577) (xy 93.015358 -115.670486) (xy 93.042654 -115.621851)
			(xy 93.07674 -115.577708) (xy 93.116889 -115.538999) (xy 93.162247 -115.506548) (xy 93.211847 -115.481047)
			(xy 93.264631 -115.46304) (xy 93.319474 -115.45291) (xy 93.375208 -115.450873) (xy 93.430645 -115.456973)
			(xy 93.484602 -115.471079) (xy 93.535931 -115.492891) (xy 93.583537 -115.521945) (xy 93.626405 -115.55762)
			(xy 93.663622 -115.599157) (xy 93.694395 -115.64567) (xy 93.718067 -115.696167) (xy 93.734135 -115.749574)
			(xy 93.742255 -115.80475) (xy 93.742764 -115.832636) (xy 93.742255 -115.860522) (xy 93.734135 -115.915698)
			(xy 93.718067 -115.969105) (xy 93.694395 -116.019602) (xy 93.663622 -116.066115) (xy 93.626405 -116.107652)
			(xy 93.583537 -116.143327) (xy 93.535931 -116.172381) (xy 93.484602 -116.194193) (xy 93.430645 -116.208299)
			(xy 93.375208 -116.214399) (xy 93.319474 -116.212362) (xy 93.264631 -116.202232) (xy 93.211847 -116.184225)
			(xy 93.162247 -116.158724) (xy 93.116889 -116.126273) (xy 93.07674 -116.087564) (xy 93.042654 -116.043421)
			(xy 93.015358 -115.994786) (xy 92.995435 -115.942695) (xy 92.983309 -115.888258) (xy 92.979238 -115.832636)
			(xy 89.271856 -115.832636) (xy 89.271856 -116.539772) (xy 89.27239 -116.549761) (xy 89.280102 -116.568195)
			(xy 89.286842 -116.575586) (xy 89.302336 -116.591334) (xy 89.309714 -116.598147) (xy 89.328244 -116.605849)
			(xy 89.34831 -116.605849) (xy 89.36684 -116.598147) (xy 89.374218 -116.591334) (xy 89.379044 -116.586508)
			(xy 89.385394 -116.575332) (xy 89.387426 -116.568728) (xy 89.395219 -116.542228) (xy 89.417387 -116.491637)
			(xy 89.446617 -116.44477) (xy 89.482298 -116.402607) (xy 89.523684 -116.366028) (xy 89.569912 -116.335797)
			(xy 89.620015 -116.312547) (xy 89.672947 -116.296762) (xy 89.727601 -116.288773) (xy 89.755218 -116.288312)
			(xy 89.782469 -116.288777) (xy 89.836417 -116.296536) (xy 89.888712 -116.311894) (xy 89.938289 -116.334537)
			(xy 89.984138 -116.364006) (xy 90.025327 -116.3997) (xy 90.061017 -116.440893) (xy 90.090481 -116.486745)
			(xy 90.11312 -116.536324) (xy 90.128472 -116.58862) (xy 90.134302 -116.62918) (xy 105.137964 -116.62918)
			(xy 105.142035 -116.573558) (xy 105.154161 -116.519121) (xy 105.174084 -116.46703) (xy 105.20138 -116.418395)
			(xy 105.235466 -116.374252) (xy 105.275615 -116.335543) (xy 105.320973 -116.303092) (xy 105.370573 -116.277591)
			(xy 105.423357 -116.259584) (xy 105.4782 -116.249454) (xy 105.533934 -116.247417) (xy 105.589371 -116.253517)
			(xy 105.643328 -116.267623) (xy 105.694657 -116.289435) (xy 105.742263 -116.318489) (xy 105.785131 -116.354164)
			(xy 105.822348 -116.395701) (xy 105.853121 -116.442214) (xy 105.876793 -116.492711) (xy 105.892861 -116.546118)
			(xy 105.900981 -116.601294) (xy 105.90149 -116.62918) (xy 105.900981 -116.657066) (xy 105.892861 -116.712242)
			(xy 105.876793 -116.765649) (xy 105.853121 -116.816146) (xy 105.822348 -116.862659) (xy 105.785131 -116.904196)
			(xy 105.742263 -116.939871) (xy 105.694657 -116.968925) (xy 105.643328 -116.990737) (xy 105.589371 -117.004843)
			(xy 105.533934 -117.010943) (xy 105.4782 -117.008906) (xy 105.423357 -116.998776) (xy 105.370573 -116.980769)
			(xy 105.320973 -116.955268) (xy 105.275615 -116.922817) (xy 105.235466 -116.884108) (xy 105.20138 -116.839965)
			(xy 105.174084 -116.79133) (xy 105.154161 -116.739239) (xy 105.142035 -116.684802) (xy 105.137964 -116.62918)
			(xy 90.134302 -116.62918) (xy 90.136226 -116.642568) (xy 90.136726 -116.66982) (xy 90.13626 -116.696769)
			(xy 90.128669 -116.75013) (xy 90.113643 -116.801891) (xy 90.091479 -116.851021) (xy 90.06262 -116.896542)
			(xy 90.027641 -116.937546) (xy 89.987237 -116.973219) (xy 89.942213 -117.002848) (xy 89.918032 -117.014752)
			(xy 89.906602 -117.020086) (xy 89.89187 -117.039644) (xy 89.875614 -117.133878) (xy 89.874166 -117.14605)
			(xy 89.881451 -117.169414) (xy 89.889584 -117.178582) (xy 90.10147 -117.390451) (xy 90.742495 -117.390451)
			(xy 90.742495 -117.335949) (xy 90.750252 -117.282003) (xy 90.765607 -117.229709) (xy 90.788248 -117.180133)
			(xy 90.817715 -117.134284) (xy 90.853406 -117.093095) (xy 90.894597 -117.057405) (xy 90.940447 -117.027941)
			(xy 90.990024 -117.005301) (xy 91.042318 -116.989948) (xy 91.096265 -116.982194) (xy 91.123516 -116.981732)
			(xy 91.152431 -116.982299) (xy 91.209601 -116.991016) (xy 91.264799 -117.008264) (xy 91.316761 -117.033646)
			(xy 91.364296 -117.066582) (xy 91.406315 -117.106316) (xy 91.424506 -117.128798) (xy 91.43207 -117.137558)
			(xy 91.452827 -117.147743) (xy 91.464384 -117.148356) (xy 91.544648 -117.148356) (xy 91.556214 -117.147771)
			(xy 91.576987 -117.137588) (xy 91.584526 -117.128798) (xy 91.602702 -117.106302) (xy 91.644725 -117.066567)
			(xy 91.692263 -117.03363) (xy 91.744227 -117.008244) (xy 91.799427 -116.99099) (xy 91.856599 -116.982265)
			(xy 91.885516 -116.981732) (xy 91.912769 -116.982139) (xy 91.966721 -116.989898) (xy 92.019019 -117.005256)
			(xy 92.0686 -117.027901) (xy 92.114453 -117.057371) (xy 92.155646 -117.093066) (xy 92.163938 -117.102636)
			(xy 92.979238 -117.102636) (xy 92.983309 -117.047014) (xy 92.995435 -116.992577) (xy 93.015358 -116.940486)
			(xy 93.042654 -116.891851) (xy 93.07674 -116.847708) (xy 93.116889 -116.808999) (xy 93.162247 -116.776548)
			(xy 93.211847 -116.751047) (xy 93.264631 -116.73304) (xy 93.319474 -116.72291) (xy 93.375208 -116.720873)
			(xy 93.430645 -116.726973) (xy 93.484602 -116.741079) (xy 93.535931 -116.762891) (xy 93.583537 -116.791945)
			(xy 93.626405 -116.82762) (xy 93.663622 -116.869157) (xy 93.694395 -116.91567) (xy 93.718067 -116.966167)
			(xy 93.734135 -117.019574) (xy 93.742255 -117.07475) (xy 93.742764 -117.102636) (xy 93.742255 -117.130522)
			(xy 93.734135 -117.185698) (xy 93.718067 -117.239105) (xy 93.713814 -117.248178) (xy 107.738924 -117.248178)
			(xy 107.742995 -117.192556) (xy 107.755121 -117.138119) (xy 107.775044 -117.086028) (xy 107.80234 -117.037393)
			(xy 107.836426 -116.99325) (xy 107.876575 -116.954541) (xy 107.921933 -116.92209) (xy 107.971533 -116.896589)
			(xy 108.024317 -116.878582) (xy 108.07916 -116.868452) (xy 108.134894 -116.866415) (xy 108.190331 -116.872515)
			(xy 108.244288 -116.886621) (xy 108.295617 -116.908433) (xy 108.343223 -116.937487) (xy 108.386091 -116.973162)
			(xy 108.423308 -117.014699) (xy 108.454081 -117.061212) (xy 108.477753 -117.111709) (xy 108.493821 -117.165116)
			(xy 108.501941 -117.220292) (xy 108.50245 -117.248178) (xy 108.754924 -117.248178) (xy 108.758995 -117.192556)
			(xy 108.771121 -117.138119) (xy 108.791044 -117.086028) (xy 108.81834 -117.037393) (xy 108.852426 -116.99325)
			(xy 108.892575 -116.954541) (xy 108.937933 -116.92209) (xy 108.987533 -116.896589) (xy 109.040317 -116.878582)
			(xy 109.09516 -116.868452) (xy 109.150894 -116.866415) (xy 109.206331 -116.872515) (xy 109.260288 -116.886621)
			(xy 109.311617 -116.908433) (xy 109.359223 -116.937487) (xy 109.402091 -116.973162) (xy 109.439308 -117.014699)
			(xy 109.470081 -117.061212) (xy 109.493753 -117.111709) (xy 109.509821 -117.165116) (xy 109.517941 -117.220292)
			(xy 109.51845 -117.248178) (xy 109.770924 -117.248178) (xy 109.774995 -117.192556) (xy 109.787121 -117.138119)
			(xy 109.807044 -117.086028) (xy 109.83434 -117.037393) (xy 109.868426 -116.99325) (xy 109.908575 -116.954541)
			(xy 109.953933 -116.92209) (xy 110.003533 -116.896589) (xy 110.056317 -116.878582) (xy 110.11116 -116.868452)
			(xy 110.166894 -116.866415) (xy 110.222331 -116.872515) (xy 110.276288 -116.886621) (xy 110.327617 -116.908433)
			(xy 110.375223 -116.937487) (xy 110.418091 -116.973162) (xy 110.422205 -116.977754) (xy 116.998945 -116.977754)
			(xy 116.998945 -116.923246) (xy 117.006702 -116.869293) (xy 117.022059 -116.816994) (xy 117.044702 -116.767412)
			(xy 117.074171 -116.721558) (xy 117.109866 -116.680364) (xy 117.151061 -116.644669) (xy 117.196916 -116.6152)
			(xy 117.246498 -116.592557) (xy 117.298797 -116.577201) (xy 117.35275 -116.569445) (xy 117.380004 -116.568982)
			(xy 117.408923 -116.569466) (xy 117.466097 -116.578198) (xy 117.521298 -116.595461) (xy 117.57326 -116.620859)
			(xy 117.620793 -116.65381) (xy 117.662806 -116.693559) (xy 117.680994 -116.716048) (xy 117.688554 -116.724811)
			(xy 117.709315 -116.734992) (xy 117.720872 -116.735606) (xy 117.801136 -116.735606) (xy 117.812699 -116.734997)
			(xy 117.83347 -116.724829) (xy 117.841014 -116.716048) (xy 117.859184 -116.693547) (xy 117.90121 -116.653815)
			(xy 117.948749 -116.62088) (xy 118.000715 -116.595495) (xy 118.055915 -116.578242) (xy 118.113087 -116.569516)
			(xy 118.142004 -116.568982) (xy 118.169254 -116.569489) (xy 118.2232 -116.577245) (xy 118.275493 -116.5926)
			(xy 118.325068 -116.615241) (xy 118.370917 -116.644707) (xy 118.412106 -116.680397) (xy 118.447796 -116.721586)
			(xy 118.477261 -116.767435) (xy 118.499901 -116.817011) (xy 118.515256 -116.869304) (xy 118.523012 -116.92325)
			(xy 118.523012 -116.97775) (xy 118.515256 -117.031696) (xy 118.499901 -117.083989) (xy 118.477261 -117.133565)
			(xy 118.447796 -117.179414) (xy 118.412106 -117.220603) (xy 118.370917 -117.256293) (xy 118.325068 -117.285759)
			(xy 118.275493 -117.3084) (xy 118.2232 -117.323755) (xy 118.169254 -117.331511) (xy 118.142004 -117.331998)
			(xy 118.113087 -117.331477) (xy 118.055916 -117.322749) (xy 118.000717 -117.305491) (xy 117.948756 -117.2801)
			(xy 117.901222 -117.247157) (xy 117.859204 -117.207417) (xy 117.841014 -117.184932) (xy 117.833453 -117.17617)
			(xy 117.812693 -117.165989) (xy 117.801136 -117.165374) (xy 117.720872 -117.165374) (xy 117.709305 -117.16596)
			(xy 117.688532 -117.176141) (xy 117.680994 -117.184932) (xy 117.662814 -117.207425) (xy 117.620791 -117.247158)
			(xy 117.573254 -117.280095) (xy 117.52129 -117.305482) (xy 117.466091 -117.322736) (xy 117.408921 -117.331464)
			(xy 117.380004 -117.331998) (xy 117.35275 -117.331555) (xy 117.298797 -117.323799) (xy 117.246498 -117.308443)
			(xy 117.196916 -117.2858) (xy 117.151061 -117.256331) (xy 117.109866 -117.220636) (xy 117.074171 -117.179442)
			(xy 117.044702 -117.133588) (xy 117.022059 -117.084006) (xy 117.006702 -117.031707) (xy 116.998945 -116.977754)
			(xy 110.422205 -116.977754) (xy 110.455308 -117.014699) (xy 110.486081 -117.061212) (xy 110.509753 -117.111709)
			(xy 110.525821 -117.165116) (xy 110.533941 -117.220292) (xy 110.53445 -117.248178) (xy 110.533941 -117.276064)
			(xy 110.525821 -117.33124) (xy 110.509753 -117.384647) (xy 110.486081 -117.435144) (xy 110.455308 -117.481657)
			(xy 110.418091 -117.523194) (xy 110.375223 -117.558869) (xy 110.327617 -117.587923) (xy 110.276288 -117.609735)
			(xy 110.222331 -117.623841) (xy 110.166894 -117.629941) (xy 110.11116 -117.627904) (xy 110.056317 -117.617774)
			(xy 110.003533 -117.599767) (xy 109.953933 -117.574266) (xy 109.908575 -117.541815) (xy 109.868426 -117.503106)
			(xy 109.83434 -117.458963) (xy 109.807044 -117.410328) (xy 109.787121 -117.358237) (xy 109.774995 -117.3038)
			(xy 109.770924 -117.248178) (xy 109.51845 -117.248178) (xy 109.517941 -117.276064) (xy 109.509821 -117.33124)
			(xy 109.493753 -117.384647) (xy 109.470081 -117.435144) (xy 109.439308 -117.481657) (xy 109.402091 -117.523194)
			(xy 109.359223 -117.558869) (xy 109.311617 -117.587923) (xy 109.260288 -117.609735) (xy 109.206331 -117.623841)
			(xy 109.150894 -117.629941) (xy 109.09516 -117.627904) (xy 109.040317 -117.617774) (xy 108.987533 -117.599767)
			(xy 108.937933 -117.574266) (xy 108.892575 -117.541815) (xy 108.852426 -117.503106) (xy 108.81834 -117.458963)
			(xy 108.791044 -117.410328) (xy 108.771121 -117.358237) (xy 108.758995 -117.3038) (xy 108.754924 -117.248178)
			(xy 108.50245 -117.248178) (xy 108.501941 -117.276064) (xy 108.493821 -117.33124) (xy 108.477753 -117.384647)
			(xy 108.454081 -117.435144) (xy 108.423308 -117.481657) (xy 108.386091 -117.523194) (xy 108.343223 -117.558869)
			(xy 108.295617 -117.587923) (xy 108.244288 -117.609735) (xy 108.190331 -117.623841) (xy 108.134894 -117.629941)
			(xy 108.07916 -117.627904) (xy 108.024317 -117.617774) (xy 107.971533 -117.599767) (xy 107.921933 -117.574266)
			(xy 107.876575 -117.541815) (xy 107.836426 -117.503106) (xy 107.80234 -117.458963) (xy 107.775044 -117.410328)
			(xy 107.755121 -117.358237) (xy 107.742995 -117.3038) (xy 107.738924 -117.248178) (xy 93.713814 -117.248178)
			(xy 93.694395 -117.289602) (xy 93.663622 -117.336115) (xy 93.626405 -117.377652) (xy 93.583537 -117.413327)
			(xy 93.535931 -117.442381) (xy 93.484602 -117.464193) (xy 93.430645 -117.478299) (xy 93.375208 -117.484399)
			(xy 93.319474 -117.482362) (xy 93.264631 -117.472232) (xy 93.211847 -117.454225) (xy 93.162247 -117.428724)
			(xy 93.116889 -117.396273) (xy 93.07674 -117.357564) (xy 93.042654 -117.313421) (xy 93.015358 -117.264786)
			(xy 92.995435 -117.212695) (xy 92.983309 -117.158258) (xy 92.979238 -117.102636) (xy 92.163938 -117.102636)
			(xy 92.191339 -117.13426) (xy 92.220807 -117.180114) (xy 92.243449 -117.229696) (xy 92.258805 -117.281995)
			(xy 92.266562 -117.335947) (xy 92.266562 -117.390453) (xy 92.258805 -117.444405) (xy 92.243449 -117.496704)
			(xy 92.220807 -117.546286) (xy 92.191339 -117.59214) (xy 92.155646 -117.633334) (xy 92.114453 -117.66903)
			(xy 92.0686 -117.698499) (xy 92.019019 -117.721144) (xy 91.974969 -117.73408) (xy 116.39626 -117.73408)
			(xy 116.400331 -117.678458) (xy 116.412457 -117.624021) (xy 116.43238 -117.57193) (xy 116.459676 -117.523295)
			(xy 116.493762 -117.479152) (xy 116.533911 -117.440443) (xy 116.579269 -117.407992) (xy 116.628869 -117.382491)
			(xy 116.681653 -117.364484) (xy 116.736496 -117.354354) (xy 116.79223 -117.352317) (xy 116.847667 -117.358417)
			(xy 116.901624 -117.372523) (xy 116.952953 -117.394335) (xy 117.000559 -117.423389) (xy 117.043427 -117.459064)
			(xy 117.080644 -117.500601) (xy 117.111417 -117.547114) (xy 117.135089 -117.597611) (xy 117.151157 -117.651018)
			(xy 117.159277 -117.706194) (xy 117.159786 -117.73408) (xy 117.159277 -117.761966) (xy 117.151157 -117.817142)
			(xy 117.135089 -117.870549) (xy 117.111417 -117.921046) (xy 117.080644 -117.967559) (xy 117.043427 -118.009096)
			(xy 117.000559 -118.044771) (xy 116.952953 -118.073825) (xy 116.901624 -118.095637) (xy 116.847667 -118.109743)
			(xy 116.79223 -118.115843) (xy 116.736496 -118.113806) (xy 116.681653 -118.103676) (xy 116.628869 -118.085669)
			(xy 116.579269 -118.060168) (xy 116.533911 -118.027717) (xy 116.493762 -117.989008) (xy 116.459676 -117.944865)
			(xy 116.43238 -117.89623) (xy 116.412457 -117.844139) (xy 116.400331 -117.789702) (xy 116.39626 -117.73408)
			(xy 91.974969 -117.73408) (xy 91.966721 -117.736502) (xy 91.912769 -117.744261) (xy 91.885516 -117.744748)
			(xy 91.856599 -117.744238) (xy 91.799426 -117.73551) (xy 91.744226 -117.718252) (xy 91.692264 -117.692859)
			(xy 91.644731 -117.659913) (xy 91.602715 -117.620169) (xy 91.584526 -117.597682) (xy 91.576952 -117.588933)
			(xy 91.556202 -117.578743) (xy 91.544648 -117.578124) (xy 91.464384 -117.578124) (xy 91.452814 -117.578677)
			(xy 91.432042 -117.588883) (xy 91.424506 -117.597682) (xy 91.406307 -117.620159) (xy 91.364289 -117.659895)
			(xy 91.316756 -117.692836) (xy 91.264797 -117.718225) (xy 91.2096 -117.735483) (xy 91.152432 -117.744213)
			(xy 91.123516 -117.744748) (xy 91.096265 -117.744206) (xy 91.042318 -117.736452) (xy 90.990024 -117.721099)
			(xy 90.940447 -117.698459) (xy 90.894597 -117.668995) (xy 90.853406 -117.633305) (xy 90.817715 -117.592116)
			(xy 90.788248 -117.546267) (xy 90.765607 -117.496691) (xy 90.750252 -117.444397) (xy 90.742495 -117.390451)
			(xy 90.10147 -117.390451) (xy 91.178992 -118.467886) (xy 97.482404 -118.467886) (xy 97.486475 -118.412264)
			(xy 97.498601 -118.357827) (xy 97.518524 -118.305736) (xy 97.54582 -118.257101) (xy 97.579906 -118.212958)
			(xy 97.620055 -118.174249) (xy 97.665413 -118.141798) (xy 97.715013 -118.116297) (xy 97.767797 -118.09829)
			(xy 97.82264 -118.08816) (xy 97.878374 -118.086123) (xy 97.933811 -118.092223) (xy 97.987768 -118.106329)
			(xy 98.039097 -118.128141) (xy 98.086703 -118.157195) (xy 98.129571 -118.19287) (xy 98.166788 -118.234407)
			(xy 98.197561 -118.28092) (xy 98.221233 -118.331417) (xy 98.237301 -118.384824) (xy 98.245421 -118.44)
			(xy 98.24593 -118.467886) (xy 98.245421 -118.495772) (xy 98.237301 -118.550948) (xy 98.221233 -118.604355)
			(xy 98.197561 -118.654852) (xy 98.166788 -118.701365) (xy 98.129571 -118.742902) (xy 98.108737 -118.76024)
			(xy 102.564436 -118.76024) (xy 102.568507 -118.704618) (xy 102.580633 -118.650181) (xy 102.600556 -118.59809)
			(xy 102.627852 -118.549455) (xy 102.661938 -118.505312) (xy 102.702087 -118.466603) (xy 102.747445 -118.434152)
			(xy 102.797045 -118.408651) (xy 102.849829 -118.390644) (xy 102.904672 -118.380514) (xy 102.960406 -118.378477)
			(xy 103.015843 -118.384577) (xy 103.0698 -118.398683) (xy 103.121129 -118.420495) (xy 103.168735 -118.449549)
			(xy 103.211603 -118.485224) (xy 103.24882 -118.526761) (xy 103.279593 -118.573274) (xy 103.303265 -118.623771)
			(xy 103.319333 -118.677178) (xy 103.327453 -118.732354) (xy 103.327962 -118.76024) (xy 103.327453 -118.788126)
			(xy 103.319333 -118.843302) (xy 103.303265 -118.896709) (xy 103.279593 -118.947206) (xy 103.24882 -118.993719)
			(xy 103.211603 -119.035256) (xy 103.168735 -119.070931) (xy 103.157994 -119.077486) (xy 114.208558 -119.077486)
			(xy 114.212629 -119.021864) (xy 114.224755 -118.967427) (xy 114.244678 -118.915336) (xy 114.271974 -118.866701)
			(xy 114.30606 -118.822558) (xy 114.346209 -118.783849) (xy 114.391567 -118.751398) (xy 114.441167 -118.725897)
			(xy 114.493951 -118.70789) (xy 114.548794 -118.69776) (xy 114.604528 -118.695723) (xy 114.659965 -118.701823)
			(xy 114.713922 -118.715929) (xy 114.765251 -118.737741) (xy 114.812857 -118.766795) (xy 114.855725 -118.80247)
			(xy 114.892942 -118.844007) (xy 114.923715 -118.89052) (xy 114.947387 -118.941017) (xy 114.963455 -118.994424)
			(xy 114.971193 -119.047006) (xy 116.309138 -119.047006) (xy 116.313209 -118.991384) (xy 116.325335 -118.936947)
			(xy 116.345258 -118.884856) (xy 116.372554 -118.836221) (xy 116.40664 -118.792078) (xy 116.446789 -118.753369)
			(xy 116.492147 -118.720918) (xy 116.541747 -118.695417) (xy 116.594531 -118.67741) (xy 116.649374 -118.66728)
			(xy 116.705108 -118.665243) (xy 116.760545 -118.671343) (xy 116.814502 -118.685449) (xy 116.865831 -118.707261)
			(xy 116.913437 -118.736315) (xy 116.956305 -118.77199) (xy 116.993522 -118.813527) (xy 117.024295 -118.86004)
			(xy 117.047967 -118.910537) (xy 117.064035 -118.963944) (xy 117.072155 -119.01912) (xy 117.072664 -119.047006)
			(xy 117.072155 -119.074892) (xy 117.064035 -119.130068) (xy 117.047967 -119.183475) (xy 117.024295 -119.233972)
			(xy 116.993522 -119.280485) (xy 116.956305 -119.322022) (xy 116.913437 -119.357697) (xy 116.865831 -119.386751)
			(xy 116.814502 -119.408563) (xy 116.760545 -119.422669) (xy 116.705108 -119.428769) (xy 116.649374 -119.426732)
			(xy 116.594531 -119.416602) (xy 116.541747 -119.398595) (xy 116.492147 -119.373094) (xy 116.446789 -119.340643)
			(xy 116.40664 -119.301934) (xy 116.372554 -119.257791) (xy 116.345258 -119.209156) (xy 116.325335 -119.157065)
			(xy 116.313209 -119.102628) (xy 116.309138 -119.047006) (xy 114.971193 -119.047006) (xy 114.971575 -119.0496)
			(xy 114.972084 -119.077486) (xy 114.971575 -119.105372) (xy 114.963455 -119.160548) (xy 114.947387 -119.213955)
			(xy 114.923715 -119.264452) (xy 114.892942 -119.310965) (xy 114.855725 -119.352502) (xy 114.812857 -119.388177)
			(xy 114.765251 -119.417231) (xy 114.713922 -119.439043) (xy 114.659965 -119.453149) (xy 114.604528 -119.459249)
			(xy 114.548794 -119.457212) (xy 114.493951 -119.447082) (xy 114.441167 -119.429075) (xy 114.391567 -119.403574)
			(xy 114.346209 -119.371123) (xy 114.30606 -119.332414) (xy 114.271974 -119.288271) (xy 114.244678 -119.239636)
			(xy 114.224755 -119.187545) (xy 114.212629 -119.133108) (xy 114.208558 -119.077486) (xy 103.157994 -119.077486)
			(xy 103.121129 -119.099985) (xy 103.0698 -119.121797) (xy 103.015843 -119.135903) (xy 102.960406 -119.142003)
			(xy 102.904672 -119.139966) (xy 102.849829 -119.129836) (xy 102.797045 -119.111829) (xy 102.747445 -119.086328)
			(xy 102.702087 -119.053877) (xy 102.661938 -119.015168) (xy 102.627852 -118.971025) (xy 102.600556 -118.92239)
			(xy 102.580633 -118.870299) (xy 102.568507 -118.815862) (xy 102.564436 -118.76024) (xy 98.108737 -118.76024)
			(xy 98.086703 -118.778577) (xy 98.039097 -118.807631) (xy 97.987768 -118.829443) (xy 97.933811 -118.843549)
			(xy 97.878374 -118.849649) (xy 97.82264 -118.847612) (xy 97.767797 -118.837482) (xy 97.715013 -118.819475)
			(xy 97.665413 -118.793974) (xy 97.620055 -118.761523) (xy 97.579906 -118.722814) (xy 97.54582 -118.678671)
			(xy 97.518524 -118.630036) (xy 97.498601 -118.577945) (xy 97.486475 -118.523508) (xy 97.482404 -118.467886)
			(xy 91.178992 -118.467886) (xy 92.118736 -119.407554) (xy 94.499632 -119.407554) (xy 94.499632 -119.353046)
			(xy 94.507389 -119.299093) (xy 94.522745 -119.246794) (xy 94.545388 -119.197211) (xy 94.574856 -119.151356)
			(xy 94.61055 -119.110162) (xy 94.651743 -119.074466) (xy 94.697597 -119.044995) (xy 94.747179 -119.022351)
			(xy 94.799478 -119.006992) (xy 94.85343 -118.999233) (xy 94.880684 -118.998746) (xy 94.908054 -118.99921)
			(xy 94.962234 -119.007027) (xy 95.014738 -119.022516) (xy 95.064484 -119.045358) (xy 95.110451 -119.075084)
			(xy 95.131382 -119.092726) (xy 95.138494 -119.098822) (xy 95.155512 -119.105172) (xy 95.240856 -119.105172)
			(xy 95.257874 -119.098822) (xy 95.264986 -119.092726) (xy 95.285916 -119.075084) (xy 95.331889 -119.045372)
			(xy 95.381637 -119.022536) (xy 95.434138 -119.007046) (xy 95.488315 -118.999219) (xy 95.515684 -118.998746)
			(xy 95.542934 -118.9993) (xy 95.59688 -119.007054) (xy 95.649174 -119.022407) (xy 95.69875 -119.045046)
			(xy 95.7446 -119.07451) (xy 95.785789 -119.110199) (xy 95.82148 -119.151387) (xy 95.850946 -119.197236)
			(xy 95.873587 -119.246811) (xy 95.888942 -119.299104) (xy 95.896699 -119.35305) (xy 95.896699 -119.40755)
			(xy 95.888942 -119.461496) (xy 95.884381 -119.477028) (xy 99.60813 -119.477028) (xy 99.612201 -119.421406)
			(xy 99.624327 -119.366969) (xy 99.64425 -119.314878) (xy 99.671546 -119.266243) (xy 99.705632 -119.2221)
			(xy 99.745781 -119.183391) (xy 99.791139 -119.15094) (xy 99.840739 -119.125439) (xy 99.893523 -119.107432)
			(xy 99.948366 -119.097302) (xy 100.0041 -119.095265) (xy 100.059537 -119.101365) (xy 100.113494 -119.115471)
			(xy 100.164823 -119.137283) (xy 100.212429 -119.166337) (xy 100.255297 -119.202012) (xy 100.292514 -119.243549)
			(xy 100.323287 -119.290062) (xy 100.346959 -119.340559) (xy 100.363027 -119.393966) (xy 100.371147 -119.449142)
			(xy 100.371656 -119.477028) (xy 100.371147 -119.504914) (xy 100.363027 -119.56009) (xy 100.346959 -119.613497)
			(xy 100.323287 -119.663994) (xy 100.292514 -119.710507) (xy 100.255297 -119.752044) (xy 100.226222 -119.77624)
			(xy 100.535992 -119.77624) (xy 100.540063 -119.720618) (xy 100.552189 -119.666181) (xy 100.572112 -119.61409)
			(xy 100.599408 -119.565455) (xy 100.633494 -119.521312) (xy 100.673643 -119.482603) (xy 100.719001 -119.450152)
			(xy 100.768601 -119.424651) (xy 100.821385 -119.406644) (xy 100.876228 -119.396514) (xy 100.931962 -119.394477)
			(xy 100.987399 -119.400577) (xy 101.041356 -119.414683) (xy 101.092685 -119.436495) (xy 101.140291 -119.465549)
			(xy 101.183159 -119.501224) (xy 101.220376 -119.542761) (xy 101.251149 -119.589274) (xy 101.274821 -119.639771)
			(xy 101.290889 -119.693178) (xy 101.294665 -119.718836) (xy 107.536486 -119.718836) (xy 107.540557 -119.663214)
			(xy 107.552683 -119.608777) (xy 107.572606 -119.556686) (xy 107.599902 -119.508051) (xy 107.633988 -119.463908)
			(xy 107.674137 -119.425199) (xy 107.719495 -119.392748) (xy 107.769095 -119.367247) (xy 107.821879 -119.34924)
			(xy 107.876722 -119.33911) (xy 107.932456 -119.337073) (xy 107.987893 -119.343173) (xy 108.04185 -119.357279)
			(xy 108.093179 -119.379091) (xy 108.140785 -119.408145) (xy 108.183653 -119.44382) (xy 108.22087 -119.485357)
			(xy 108.251643 -119.53187) (xy 108.275315 -119.582367) (xy 108.291383 -119.635774) (xy 108.299503 -119.69095)
			(xy 108.300012 -119.718836) (xy 108.299503 -119.746722) (xy 108.291383 -119.801898) (xy 108.275315 -119.855305)
			(xy 108.251643 -119.905802) (xy 108.22087 -119.952315) (xy 108.183653 -119.993852) (xy 108.140785 -120.029527)
			(xy 108.093179 -120.058581) (xy 108.04185 -120.080393) (xy 107.987893 -120.094499) (xy 107.932456 -120.100599)
			(xy 107.876722 -120.098562) (xy 107.821879 -120.088432) (xy 107.769095 -120.070425) (xy 107.719495 -120.044924)
			(xy 107.674137 -120.012473) (xy 107.633988 -119.973764) (xy 107.599902 -119.929621) (xy 107.572606 -119.880986)
			(xy 107.552683 -119.828895) (xy 107.540557 -119.774458) (xy 107.536486 -119.718836) (xy 101.294665 -119.718836)
			(xy 101.299009 -119.748354) (xy 101.299518 -119.77624) (xy 101.299009 -119.804126) (xy 101.290889 -119.859302)
			(xy 101.274821 -119.912709) (xy 101.251149 -119.963206) (xy 101.220376 -120.009719) (xy 101.183159 -120.051256)
			(xy 101.140291 -120.086931) (xy 101.092685 -120.115985) (xy 101.041356 -120.137797) (xy 100.987399 -120.151903)
			(xy 100.931962 -120.158003) (xy 100.876228 -120.155966) (xy 100.821385 -120.145836) (xy 100.768601 -120.127829)
			(xy 100.719001 -120.102328) (xy 100.673643 -120.069877) (xy 100.633494 -120.031168) (xy 100.599408 -119.987025)
			(xy 100.572112 -119.93839) (xy 100.552189 -119.886299) (xy 100.540063 -119.831862) (xy 100.535992 -119.77624)
			(xy 100.226222 -119.77624) (xy 100.212429 -119.787719) (xy 100.164823 -119.816773) (xy 100.113494 -119.838585)
			(xy 100.059537 -119.852691) (xy 100.0041 -119.858791) (xy 99.948366 -119.856754) (xy 99.893523 -119.846624)
			(xy 99.840739 -119.828617) (xy 99.791139 -119.803116) (xy 99.745781 -119.770665) (xy 99.705632 -119.731956)
			(xy 99.671546 -119.687813) (xy 99.64425 -119.639178) (xy 99.624327 -119.587087) (xy 99.612201 -119.53265)
			(xy 99.60813 -119.477028) (xy 95.884381 -119.477028) (xy 95.873587 -119.513789) (xy 95.850946 -119.563364)
			(xy 95.82148 -119.609213) (xy 95.785789 -119.650401) (xy 95.7446 -119.68609) (xy 95.69875 -119.715554)
			(xy 95.649174 -119.738193) (xy 95.59688 -119.753546) (xy 95.542934 -119.7613) (xy 95.515684 -119.761762)
			(xy 95.488313 -119.761315) (xy 95.434133 -119.753494) (xy 95.381629 -119.738001) (xy 95.331882 -119.715155)
			(xy 95.285917 -119.685426) (xy 95.264986 -119.667782) (xy 95.257874 -119.661686) (xy 95.240856 -119.655336)
			(xy 95.155512 -119.655336) (xy 95.138494 -119.661686) (xy 95.131382 -119.667782) (xy 95.110428 -119.685393)
			(xy 95.064461 -119.71511) (xy 95.014719 -119.737952) (xy 94.962224 -119.753449) (xy 94.908052 -119.761284)
			(xy 94.880684 -119.761762) (xy 94.85343 -119.761367) (xy 94.799478 -119.753608) (xy 94.747179 -119.738249)
			(xy 94.697597 -119.715605) (xy 94.651743 -119.686134) (xy 94.61055 -119.650438) (xy 94.574856 -119.609244)
			(xy 94.545388 -119.563389) (xy 94.522745 -119.513806) (xy 94.507389 -119.461507) (xy 94.499632 -119.407554)
			(xy 92.118736 -119.407554) (xy 92.604301 -119.89308) (xy 97.569018 -119.89308) (xy 97.573089 -119.837458)
			(xy 97.585215 -119.783021) (xy 97.605138 -119.73093) (xy 97.632434 -119.682295) (xy 97.66652 -119.638152)
			(xy 97.706669 -119.599443) (xy 97.752027 -119.566992) (xy 97.801627 -119.541491) (xy 97.854411 -119.523484)
			(xy 97.909254 -119.513354) (xy 97.964988 -119.511317) (xy 98.020425 -119.517417) (xy 98.074382 -119.531523)
			(xy 98.125711 -119.553335) (xy 98.173317 -119.582389) (xy 98.216185 -119.618064) (xy 98.253402 -119.659601)
			(xy 98.284175 -119.706114) (xy 98.307847 -119.756611) (xy 98.323915 -119.810018) (xy 98.332035 -119.865194)
			(xy 98.332544 -119.89308) (xy 98.332035 -119.920966) (xy 98.323915 -119.976142) (xy 98.307847 -120.029549)
			(xy 98.284175 -120.080046) (xy 98.253402 -120.126559) (xy 98.216185 -120.168096) (xy 98.173317 -120.203771)
			(xy 98.125711 -120.232825) (xy 98.074382 -120.254637) (xy 98.020425 -120.268743) (xy 97.964988 -120.274843)
			(xy 97.909254 -120.272806) (xy 97.854411 -120.262676) (xy 97.801627 -120.244669) (xy 97.752027 -120.219168)
			(xy 97.706669 -120.186717) (xy 97.66652 -120.148008) (xy 97.632434 -120.103865) (xy 97.605138 -120.05523)
			(xy 97.585215 -120.003139) (xy 97.573089 -119.948702) (xy 97.569018 -119.89308) (xy 92.604301 -119.89308)
			(xy 93.038676 -120.32742) (xy 93.046085 -120.334106) (xy 93.064521 -120.341693) (xy 93.07449 -120.342152)
			(xy 94.702376 -120.342152) (xy 94.728464 -120.342636) (xy 94.779997 -120.3508) (xy 94.829617 -120.36693)
			(xy 94.876101 -120.390628) (xy 94.918301 -120.42131) (xy 94.937072 -120.439434) (xy 95.73641 -121.238772)
			(xy 97.584258 -121.238772) (xy 97.588329 -121.18315) (xy 97.600455 -121.128713) (xy 97.620378 -121.076622)
			(xy 97.647674 -121.027987) (xy 97.68176 -120.983844) (xy 97.721909 -120.945135) (xy 97.767267 -120.912684)
			(xy 97.816867 -120.887183) (xy 97.869651 -120.869176) (xy 97.924494 -120.859046) (xy 97.980228 -120.857009)
			(xy 98.035665 -120.863109) (xy 98.089622 -120.877215) (xy 98.140951 -120.899027) (xy 98.188557 -120.928081)
			(xy 98.231425 -120.963756) (xy 98.268642 -121.005293) (xy 98.299415 -121.051806) (xy 98.323087 -121.102303)
			(xy 98.339155 -121.15571) (xy 98.347275 -121.210886) (xy 98.347784 -121.238772) (xy 98.347275 -121.266658)
			(xy 98.339155 -121.321834) (xy 98.323087 -121.375241) (xy 98.299415 -121.425738) (xy 98.268642 -121.472251)
			(xy 98.231425 -121.513788) (xy 98.188557 -121.549463) (xy 98.140951 -121.578517) (xy 98.089622 -121.600329)
			(xy 98.035665 -121.614435) (xy 97.980228 -121.620535) (xy 97.924494 -121.618498) (xy 97.869651 -121.608368)
			(xy 97.816867 -121.590361) (xy 97.767267 -121.56486) (xy 97.721909 -121.532409) (xy 97.68176 -121.4937)
			(xy 97.647674 -121.449557) (xy 97.620378 -121.400922) (xy 97.600455 -121.348831) (xy 97.588329 -121.294394)
			(xy 97.584258 -121.238772) (xy 95.73641 -121.238772) (xy 97.920048 -123.42241) (xy 97.930716 -123.42876)
			(xy 97.936558 -123.430792) (xy 97.949004 -123.434856) (xy 97.959052 -123.437835) (xy 97.979932 -123.436298)
			(xy 97.998466 -123.426559) (xy 98.011575 -123.410235) (xy 98.017084 -123.390036) (xy 98.014077 -123.369317)
			(xy 98.008948 -123.36018) (xy 97.995502 -123.337518) (xy 97.974299 -123.289277) (xy 97.959952 -123.238574)
			(xy 97.952735 -123.186376) (xy 97.952306 -123.160028) (xy 97.952767 -123.132774) (xy 97.960521 -123.078821)
			(xy 97.975875 -123.026521) (xy 97.998516 -122.976938) (xy 98.027984 -122.931082) (xy 98.063677 -122.889887)
			(xy 98.104871 -122.854192) (xy 98.150726 -122.824723) (xy 98.200307 -122.80208) (xy 98.252607 -122.786724)
			(xy 98.30656 -122.778968) (xy 98.333814 -122.77852) (xy 98.343802 -122.778572) (xy 98.363751 -122.779588)
			(xy 98.373692 -122.780552) (xy 98.384614 -122.781822) (xy 98.404934 -122.775218) (xy 98.468942 -122.717306)
			(xy 98.47656 -122.709739) (xy 98.485357 -122.69018) (xy 98.48596 -122.67946) (xy 98.48596 -121.661428)
			(xy 98.486427 -121.635352) (xy 98.494552 -121.583837) (xy 98.510637 -121.534227) (xy 98.534286 -121.487746)
			(xy 98.564917 -121.445537) (xy 98.582988 -121.426732) (xy 99.613466 -120.396254) (xy 99.619816 -120.385586)
			(xy 99.621848 -120.379744) (xy 99.630283 -120.354185) (xy 99.653334 -120.305551) (xy 99.682991 -120.260638)
			(xy 99.718665 -120.220338) (xy 99.759648 -120.18545) (xy 99.805126 -120.156668) (xy 99.854198 -120.134562)
			(xy 99.905889 -120.11957) (xy 99.959174 -120.111991) (xy 99.986084 -120.11152) (xy 100.013337 -120.111982)
			(xy 100.067288 -120.119738) (xy 100.119586 -120.135092) (xy 100.169167 -120.157734) (xy 100.21502 -120.187202)
			(xy 100.256212 -120.222897) (xy 100.291905 -120.26409) (xy 100.321371 -120.309944) (xy 100.344012 -120.359525)
			(xy 100.359365 -120.411824) (xy 100.367119 -120.465775) (xy 100.367592 -120.493028) (xy 100.367134 -120.519943)
			(xy 100.359576 -120.573239) (xy 100.344598 -120.624942) (xy 100.322499 -120.674026) (xy 100.293718 -120.719516)
			(xy 100.258827 -120.760506) (xy 100.222974 -120.79224) (xy 100.535992 -120.79224) (xy 100.540063 -120.736618)
			(xy 100.552189 -120.682181) (xy 100.572112 -120.63009) (xy 100.599408 -120.581455) (xy 100.633494 -120.537312)
			(xy 100.673643 -120.498603) (xy 100.719001 -120.466152) (xy 100.768601 -120.440651) (xy 100.821385 -120.422644)
			(xy 100.876228 -120.412514) (xy 100.931962 -120.410477) (xy 100.987399 -120.416577) (xy 101.041356 -120.430683)
			(xy 101.092685 -120.452495) (xy 101.140291 -120.481549) (xy 101.183159 -120.517224) (xy 101.220376 -120.558761)
			(xy 101.251149 -120.605274) (xy 101.274821 -120.655771) (xy 101.290889 -120.709178) (xy 101.299009 -120.764354)
			(xy 101.299518 -120.79224) (xy 102.691436 -120.79224) (xy 102.695507 -120.736618) (xy 102.707633 -120.682181)
			(xy 102.727556 -120.63009) (xy 102.754852 -120.581455) (xy 102.788938 -120.537312) (xy 102.829087 -120.498603)
			(xy 102.874445 -120.466152) (xy 102.924045 -120.440651) (xy 102.976829 -120.422644) (xy 103.031672 -120.412514)
			(xy 103.087406 -120.410477) (xy 103.142843 -120.416577) (xy 103.1968 -120.430683) (xy 103.248129 -120.452495)
			(xy 103.295735 -120.481549) (xy 103.338603 -120.517224) (xy 103.346737 -120.526302) (xy 105.993436 -120.526302)
			(xy 105.997507 -120.47068) (xy 106.009633 -120.416243) (xy 106.029556 -120.364152) (xy 106.056852 -120.315517)
			(xy 106.090938 -120.271374) (xy 106.131087 -120.232665) (xy 106.176445 -120.200214) (xy 106.226045 -120.174713)
			(xy 106.278829 -120.156706) (xy 106.333672 -120.146576) (xy 106.389406 -120.144539) (xy 106.444843 -120.150639)
			(xy 106.4988 -120.164745) (xy 106.550129 -120.186557) (xy 106.597735 -120.215611) (xy 106.640603 -120.251286)
			(xy 106.67782 -120.292823) (xy 106.708593 -120.339336) (xy 106.711937 -120.34647) (xy 116.321076 -120.34647)
			(xy 116.325147 -120.290848) (xy 116.337273 -120.236411) (xy 116.357196 -120.18432) (xy 116.384492 -120.135685)
			(xy 116.418578 -120.091542) (xy 116.458727 -120.052833) (xy 116.504085 -120.020382) (xy 116.553685 -119.994881)
			(xy 116.606469 -119.976874) (xy 116.661312 -119.966744) (xy 116.717046 -119.964707) (xy 116.772483 -119.970807)
			(xy 116.82644 -119.984913) (xy 116.877769 -120.006725) (xy 116.925375 -120.035779) (xy 116.968243 -120.071454)
			(xy 117.00546 -120.112991) (xy 117.036233 -120.159504) (xy 117.059905 -120.210001) (xy 117.075973 -120.263408)
			(xy 117.084093 -120.318584) (xy 117.084602 -120.34647) (xy 117.084093 -120.374356) (xy 117.075973 -120.429532)
			(xy 117.059905 -120.482939) (xy 117.036233 -120.533436) (xy 117.00546 -120.579949) (xy 116.968243 -120.621486)
			(xy 116.925375 -120.657161) (xy 116.877769 -120.686215) (xy 116.82644 -120.708027) (xy 116.772483 -120.722133)
			(xy 116.717046 -120.728233) (xy 116.661312 -120.726196) (xy 116.606469 -120.716066) (xy 116.553685 -120.698059)
			(xy 116.504085 -120.672558) (xy 116.458727 -120.640107) (xy 116.418578 -120.601398) (xy 116.384492 -120.557255)
			(xy 116.357196 -120.50862) (xy 116.337273 -120.456529) (xy 116.325147 -120.402092) (xy 116.321076 -120.34647)
			(xy 106.711937 -120.34647) (xy 106.732265 -120.389833) (xy 106.748333 -120.44324) (xy 106.756453 -120.498416)
			(xy 106.756962 -120.526302) (xy 106.756453 -120.554188) (xy 106.748333 -120.609364) (xy 106.732265 -120.662771)
			(xy 106.708593 -120.713268) (xy 106.67782 -120.759781) (xy 106.640603 -120.801318) (xy 106.597735 -120.836993)
			(xy 106.550129 -120.866047) (xy 106.4988 -120.887859) (xy 106.444843 -120.901965) (xy 106.389406 -120.908065)
			(xy 106.333672 -120.906028) (xy 106.278829 -120.895898) (xy 106.226045 -120.877891) (xy 106.176445 -120.85239)
			(xy 106.131087 -120.819939) (xy 106.090938 -120.78123) (xy 106.056852 -120.737087) (xy 106.029556 -120.688452)
			(xy 106.009633 -120.636361) (xy 105.997507 -120.581924) (xy 105.993436 -120.526302) (xy 103.346737 -120.526302)
			(xy 103.37582 -120.558761) (xy 103.406593 -120.605274) (xy 103.430265 -120.655771) (xy 103.446333 -120.709178)
			(xy 103.454453 -120.764354) (xy 103.454962 -120.79224) (xy 103.454453 -120.820126) (xy 103.446333 -120.875302)
			(xy 103.430265 -120.928709) (xy 103.406593 -120.979206) (xy 103.37582 -121.025719) (xy 103.338603 -121.067256)
			(xy 103.295735 -121.102931) (xy 103.248129 -121.131985) (xy 103.1968 -121.153797) (xy 103.142843 -121.167903)
			(xy 103.087406 -121.174003) (xy 103.031672 -121.171966) (xy 102.976829 -121.161836) (xy 102.924045 -121.143829)
			(xy 102.874445 -121.118328) (xy 102.829087 -121.085877) (xy 102.788938 -121.047168) (xy 102.754852 -121.003025)
			(xy 102.727556 -120.95439) (xy 102.707633 -120.902299) (xy 102.695507 -120.847862) (xy 102.691436 -120.79224)
			(xy 101.299518 -120.79224) (xy 101.299009 -120.820126) (xy 101.290889 -120.875302) (xy 101.274821 -120.928709)
			(xy 101.251149 -120.979206) (xy 101.220376 -121.025719) (xy 101.183159 -121.067256) (xy 101.140291 -121.102931)
			(xy 101.092685 -121.131985) (xy 101.041356 -121.153797) (xy 100.987399 -121.167903) (xy 100.931962 -121.174003)
			(xy 100.876228 -121.171966) (xy 100.821385 -121.161836) (xy 100.768601 -121.143829) (xy 100.719001 -121.118328)
			(xy 100.673643 -121.085877) (xy 100.633494 -121.047168) (xy 100.599408 -121.003025) (xy 100.572112 -120.95439)
			(xy 100.552189 -120.902299) (xy 100.540063 -120.847862) (xy 100.535992 -120.79224) (xy 100.222974 -120.79224)
			(xy 100.218519 -120.796183) (xy 100.173595 -120.825838) (xy 100.124947 -120.848882) (xy 100.099368 -120.857264)
			(xy 100.093526 -120.859296) (xy 100.082858 -120.865646) (xy 99.164394 -121.78411) (xy 99.157585 -121.791456)
			(xy 99.149858 -121.809918) (xy 99.149408 -121.819924) (xy 99.149408 -123.485148) (xy 99.148943 -123.511225)
			(xy 99.140823 -123.562744) (xy 99.124743 -123.612357) (xy 99.101099 -123.658844) (xy 99.070475 -123.70106)
			(xy 99.05238 -123.719844) (xy 95.780098 -126.992126) (xy 104.844342 -126.992126) (xy 104.844813 -126.964756)
			(xy 104.852628 -126.910577) (xy 104.868115 -126.858073) (xy 104.890956 -126.808326) (xy 104.920681 -126.762359)
			(xy 104.938322 -126.741428) (xy 104.944418 -126.734316) (xy 104.950768 -126.717298) (xy 104.950768 -126.631954)
			(xy 104.944418 -126.614936) (xy 104.938322 -126.607824) (xy 104.920707 -126.586871) (xy 104.890982 -126.540906)
			(xy 104.868135 -126.491163) (xy 104.852637 -126.438664) (xy 104.844806 -126.384489) (xy 104.844803 -126.32975)
			(xy 104.852629 -126.275574) (xy 104.868121 -126.223073) (xy 104.890963 -126.173328) (xy 104.920683 -126.127361)
			(xy 104.938322 -126.106428) (xy 104.944418 -126.099316) (xy 104.950768 -126.082298) (xy 104.950768 -125.996954)
			(xy 104.944418 -125.979936) (xy 104.938322 -125.972824) (xy 104.920707 -125.951871) (xy 104.890982 -125.905906)
			(xy 104.868135 -125.856163) (xy 104.852637 -125.803664) (xy 104.844806 -125.749489) (xy 104.844803 -125.69475)
			(xy 104.852629 -125.640574) (xy 104.868121 -125.588073) (xy 104.890963 -125.538328) (xy 104.920683 -125.492361)
			(xy 104.938322 -125.471428) (xy 104.944418 -125.464316) (xy 104.950768 -125.447298) (xy 104.950768 -125.361954)
			(xy 104.944418 -125.344936) (xy 104.938322 -125.337824) (xy 104.920684 -125.316891) (xy 104.890971 -125.270919)
			(xy 104.868135 -125.221172) (xy 104.852644 -125.168671) (xy 104.844816 -125.114495) (xy 104.844342 -125.087126)
			(xy 104.844828 -125.059875) (xy 104.852584 -125.005927) (xy 104.867939 -124.953632) (xy 104.890581 -124.904055)
			(xy 104.920047 -124.858205) (xy 104.955738 -124.817014) (xy 104.996929 -124.781323) (xy 105.042779 -124.751857)
			(xy 105.092356 -124.729215) (xy 105.144651 -124.71386) (xy 105.198599 -124.706104) (xy 105.253101 -124.706104)
			(xy 105.307049 -124.71386) (xy 105.359344 -124.729215) (xy 105.408921 -124.751857) (xy 105.454771 -124.781323)
			(xy 105.495962 -124.817014) (xy 105.531653 -124.858205) (xy 105.561119 -124.904055) (xy 105.583761 -124.953632)
			(xy 105.599116 -125.005927) (xy 105.606872 -125.059875) (xy 105.607358 -125.087126) (xy 105.606917 -125.114497)
			(xy 105.599095 -125.168678) (xy 105.583601 -125.221182) (xy 105.560753 -125.270928) (xy 105.531022 -125.316893)
			(xy 105.513378 -125.337824) (xy 105.507282 -125.344936) (xy 105.500932 -125.361954) (xy 105.500932 -125.447298)
			(xy 105.507282 -125.464316) (xy 105.513378 -125.471428) (xy 105.531044 -125.49234) (xy 105.560767 -125.538312)
			(xy 105.583611 -125.588061) (xy 105.599105 -125.640567) (xy 105.606931 -125.694748) (xy 105.606928 -125.749491)
			(xy 105.599097 -125.803672) (xy 105.583597 -125.856175) (xy 105.560748 -125.905923) (xy 105.53102 -125.951891)
			(xy 105.513378 -125.972824) (xy 105.507282 -125.979936) (xy 105.500932 -125.996954) (xy 105.500932 -126.082298)
			(xy 105.507282 -126.099316) (xy 105.513378 -126.106428) (xy 105.531044 -126.12734) (xy 105.560767 -126.173312)
			(xy 105.583611 -126.223061) (xy 105.599105 -126.275567) (xy 105.606931 -126.329748) (xy 105.606928 -126.384491)
			(xy 105.599097 -126.438672) (xy 105.583597 -126.491175) (xy 105.560748 -126.540923) (xy 105.53102 -126.586891)
			(xy 105.513378 -126.607824) (xy 105.507282 -126.614936) (xy 105.500932 -126.631954) (xy 105.500932 -126.717298)
			(xy 105.507282 -126.734316) (xy 105.513378 -126.741428) (xy 105.530993 -126.762379) (xy 105.56071 -126.808346)
			(xy 105.58355 -126.858089) (xy 105.599047 -126.910586) (xy 105.606881 -126.964758) (xy 105.607358 -126.992126)
			(xy 105.606872 -127.019377) (xy 105.602208 -127.051816) (xy 107.500166 -127.051816) (xy 107.500625 -127.024445)
			(xy 107.508442 -126.970265) (xy 107.523932 -126.917762) (xy 107.546776 -126.868015) (xy 107.576503 -126.822049)
			(xy 107.594146 -126.801118) (xy 107.600242 -126.794006) (xy 107.606592 -126.776988) (xy 107.606592 -126.691644)
			(xy 107.600242 -126.674626) (xy 107.594146 -126.667514) (xy 107.57652 -126.646569) (xy 107.546793 -126.600604)
			(xy 107.523946 -126.55086) (xy 107.508448 -126.498359) (xy 107.500617 -126.444182) (xy 107.500615 -126.389442)
			(xy 107.508442 -126.335264) (xy 107.523937 -126.282763) (xy 107.546782 -126.233017) (xy 107.576506 -126.18705)
			(xy 107.594146 -126.166118) (xy 107.600242 -126.159006) (xy 107.606592 -126.141988) (xy 107.606592 -126.056644)
			(xy 107.600242 -126.039626) (xy 107.594146 -126.032514) (xy 107.57652 -126.011569) (xy 107.546793 -125.965604)
			(xy 107.523946 -125.91586) (xy 107.508448 -125.863359) (xy 107.500617 -125.809182) (xy 107.500615 -125.754442)
			(xy 107.508442 -125.700264) (xy 107.523937 -125.647763) (xy 107.546782 -125.598017) (xy 107.576506 -125.55205)
			(xy 107.594146 -125.531118) (xy 107.600242 -125.524006) (xy 107.606592 -125.506988) (xy 107.606592 -125.421644)
			(xy 107.600242 -125.404626) (xy 107.594146 -125.397514) (xy 107.576507 -125.376582) (xy 107.546794 -125.33061)
			(xy 107.523957 -125.280862) (xy 107.508466 -125.228361) (xy 107.500639 -125.174185) (xy 107.500166 -125.146816)
			(xy 107.500652 -125.119565) (xy 107.508408 -125.065617) (xy 107.523763 -125.013322) (xy 107.546405 -124.963745)
			(xy 107.575871 -124.917895) (xy 107.611562 -124.876704) (xy 107.652753 -124.841013) (xy 107.698603 -124.811547)
			(xy 107.74818 -124.788905) (xy 107.800475 -124.77355) (xy 107.854423 -124.765794) (xy 107.908925 -124.765794)
			(xy 107.962873 -124.77355) (xy 108.015168 -124.788905) (xy 108.064745 -124.811547) (xy 108.110595 -124.841013)
			(xy 108.151786 -124.876704) (xy 108.158044 -124.883926) (xy 116.439948 -124.883926) (xy 116.444019 -124.828304)
			(xy 116.456145 -124.773867) (xy 116.476068 -124.721776) (xy 116.503364 -124.673141) (xy 116.53745 -124.628998)
			(xy 116.577599 -124.590289) (xy 116.622957 -124.557838) (xy 116.672557 -124.532337) (xy 116.725341 -124.51433)
			(xy 116.780184 -124.5042) (xy 116.835918 -124.502163) (xy 116.891355 -124.508263) (xy 116.945312 -124.522369)
			(xy 116.996641 -124.544181) (xy 117.044247 -124.573235) (xy 117.087115 -124.60891) (xy 117.124332 -124.650447)
			(xy 117.155105 -124.69696) (xy 117.178777 -124.747457) (xy 117.194845 -124.800864) (xy 117.202965 -124.85604)
			(xy 117.203474 -124.883926) (xy 117.202965 -124.911812) (xy 117.194845 -124.966988) (xy 117.178777 -125.020395)
			(xy 117.155105 -125.070892) (xy 117.124332 -125.117405) (xy 117.087115 -125.158942) (xy 117.044247 -125.194617)
			(xy 116.996641 -125.223671) (xy 116.945312 -125.245483) (xy 116.891355 -125.259589) (xy 116.835918 -125.265689)
			(xy 116.780184 -125.263652) (xy 116.725341 -125.253522) (xy 116.672557 -125.235515) (xy 116.622957 -125.210014)
			(xy 116.577599 -125.177563) (xy 116.53745 -125.138854) (xy 116.503364 -125.094711) (xy 116.476068 -125.046076)
			(xy 116.456145 -124.993985) (xy 116.444019 -124.939548) (xy 116.439948 -124.883926) (xy 108.158044 -124.883926)
			(xy 108.187477 -124.917895) (xy 108.216943 -124.963745) (xy 108.239585 -125.013322) (xy 108.25494 -125.065617)
			(xy 108.262696 -125.119565) (xy 108.263182 -125.146816) (xy 108.26273 -125.174187) (xy 108.254909 -125.228367)
			(xy 108.239417 -125.28087) (xy 108.216572 -125.330617) (xy 108.186845 -125.376583) (xy 108.169202 -125.397514)
			(xy 108.163106 -125.404626) (xy 108.156756 -125.421644) (xy 108.156756 -125.506988) (xy 108.163106 -125.524006)
			(xy 108.169202 -125.531118) (xy 108.186857 -125.552039) (xy 108.216579 -125.598009) (xy 108.239422 -125.647758)
			(xy 108.254916 -125.700261) (xy 108.262742 -125.754441) (xy 108.26274 -125.809183) (xy 108.25491 -125.863362)
			(xy 108.239413 -125.915865) (xy 108.216567 -125.965612) (xy 108.186843 -126.011581) (xy 108.169202 -126.032514)
			(xy 108.163106 -126.039626) (xy 108.156756 -126.056644) (xy 108.156756 -126.141988) (xy 108.163106 -126.159006)
			(xy 108.169202 -126.166118) (xy 108.186022 -126.186075) (xy 108.193742 -126.197868) (xy 116.44579 -126.197868)
			(xy 116.449861 -126.142246) (xy 116.461987 -126.087809) (xy 116.48191 -126.035718) (xy 116.509206 -125.987083)
			(xy 116.543292 -125.94294) (xy 116.583441 -125.904231) (xy 116.628799 -125.87178) (xy 116.678399 -125.846279)
			(xy 116.731183 -125.828272) (xy 116.786026 -125.818142) (xy 116.84176 -125.816105) (xy 116.897197 -125.822205)
			(xy 116.951154 -125.836311) (xy 117.002483 -125.858123) (xy 117.050089 -125.887177) (xy 117.092957 -125.922852)
			(xy 117.130174 -125.964389) (xy 117.160947 -126.010902) (xy 117.184619 -126.061399) (xy 117.200687 -126.114806)
			(xy 117.208807 -126.169982) (xy 117.209316 -126.197868) (xy 117.208807 -126.225754) (xy 117.200687 -126.28093)
			(xy 117.184619 -126.334337) (xy 117.160947 -126.384834) (xy 117.130174 -126.431347) (xy 117.092957 -126.472884)
			(xy 117.050089 -126.508559) (xy 117.002483 -126.537613) (xy 116.951154 -126.559425) (xy 116.897197 -126.573531)
			(xy 116.84176 -126.579631) (xy 116.786026 -126.577594) (xy 116.731183 -126.567464) (xy 116.678399 -126.549457)
			(xy 116.628799 -126.523956) (xy 116.583441 -126.491505) (xy 116.543292 -126.452796) (xy 116.509206 -126.408653)
			(xy 116.48191 -126.360018) (xy 116.461987 -126.307927) (xy 116.449861 -126.25349) (xy 116.44579 -126.197868)
			(xy 108.193742 -126.197868) (xy 108.214608 -126.229744) (xy 108.236986 -126.276896) (xy 108.252738 -126.326655)
			(xy 108.257594 -126.3523) (xy 108.25988 -126.365254) (xy 108.275882 -126.385574) (xy 108.379514 -126.428754)
			(xy 108.405168 -126.42596) (xy 108.415836 -126.418594) (xy 108.439986 -126.402441) (xy 108.492126 -126.376812)
			(xy 108.547549 -126.359386) (xy 108.604973 -126.350564) (xy 108.634022 -126.350014) (xy 108.661275 -126.350457)
			(xy 108.715225 -126.358217) (xy 108.767522 -126.373577) (xy 108.817101 -126.396222) (xy 108.862952 -126.425692)
			(xy 108.904143 -126.461388) (xy 108.939834 -126.502583) (xy 108.969299 -126.548438) (xy 108.991939 -126.598019)
			(xy 109.007292 -126.650318) (xy 109.015046 -126.704269) (xy 109.01553 -126.731522) (xy 109.015096 -126.758152)
			(xy 109.00769 -126.810896) (xy 108.993024 -126.862097) (xy 108.971382 -126.910763) (xy 108.943187 -126.955948)
			(xy 108.908984 -126.996776) (xy 108.869437 -127.032452) (xy 108.847636 -127.047752) (xy 108.837476 -127.05461)
			(xy 108.825792 -127.075438) (xy 108.821474 -127.18161) (xy 108.83138 -127.203454) (xy 108.841032 -127.211074)
			(xy 108.862881 -127.229325) (xy 108.901486 -127.27116) (xy 108.933453 -127.318263) (xy 108.95807 -127.369591)
			(xy 108.963528 -127.38735) (xy 110.308898 -127.38735) (xy 110.309418 -127.357979) (xy 110.318417 -127.29993)
			(xy 110.336209 -127.243946) (xy 110.362374 -127.191353) (xy 110.396293 -127.143393) (xy 110.41634 -127.12192)
			(xy 110.423198 -127.114808) (xy 110.430564 -127.097282) (xy 110.432088 -127.007874) (xy 110.42523 -126.990348)
			(xy 110.418626 -126.982982) (xy 110.400068 -126.961814) (xy 110.368766 -126.915023) (xy 110.344678 -126.864142)
			(xy 110.328326 -126.810275) (xy 110.320065 -126.754589) (xy 110.319566 -126.726442) (xy 110.320094 -126.699191)
			(xy 110.327845 -126.645244) (xy 110.343194 -126.592949) (xy 110.36583 -126.543371) (xy 110.395291 -126.497519)
			(xy 110.430978 -126.456326) (xy 110.472164 -126.420632) (xy 110.518011 -126.391163) (xy 110.567585 -126.368518)
			(xy 110.619878 -126.353159) (xy 110.673823 -126.345399) (xy 110.701074 -126.344934) (xy 110.729754 -126.345504)
			(xy 110.786466 -126.35411) (xy 110.841253 -126.371103) (xy 110.892881 -126.3961) (xy 110.940189 -126.428538)
			(xy 110.982113 -126.467688) (xy 111.017708 -126.512669) (xy 111.046175 -126.562468) (xy 111.066872 -126.615966)
			(xy 111.079333 -126.671957) (xy 111.08182 -126.700534) (xy 111.082582 -126.713488) (xy 111.096552 -126.735332)
			(xy 111.194596 -126.788926) (xy 111.220504 -126.788926) (xy 111.231934 -126.782576) (xy 111.260259 -126.767784)
			(xy 111.320618 -126.74682) (xy 111.383627 -126.736213) (xy 111.415576 -126.735586) (xy 111.44283 -126.73606)
			(xy 111.496782 -126.743814) (xy 111.549082 -126.759167) (xy 111.598664 -126.781808) (xy 111.64452 -126.811275)
			(xy 111.685715 -126.846968) (xy 111.72141 -126.888161) (xy 111.75088 -126.934014) (xy 111.773524 -126.983595)
			(xy 111.788881 -127.035894) (xy 111.796639 -127.089846) (xy 111.796639 -127.144354) (xy 111.788881 -127.198306)
			(xy 111.773524 -127.250605) (xy 111.75088 -127.300186) (xy 111.72141 -127.346039) (xy 111.685715 -127.387232)
			(xy 111.64452 -127.422925) (xy 111.598664 -127.452392) (xy 111.549082 -127.475033) (xy 111.518979 -127.48387)
			(xy 116.59438 -127.48387) (xy 116.598451 -127.428248) (xy 116.610577 -127.373811) (xy 116.6305 -127.32172)
			(xy 116.657796 -127.273085) (xy 116.691882 -127.228942) (xy 116.732031 -127.190233) (xy 116.777389 -127.157782)
			(xy 116.826989 -127.132281) (xy 116.879773 -127.114274) (xy 116.934616 -127.104144) (xy 116.99035 -127.102107)
			(xy 117.045787 -127.108207) (xy 117.099744 -127.122313) (xy 117.151073 -127.144125) (xy 117.198679 -127.173179)
			(xy 117.241547 -127.208854) (xy 117.278764 -127.250391) (xy 117.309537 -127.296904) (xy 117.333209 -127.347401)
			(xy 117.349277 -127.400808) (xy 117.357397 -127.455984) (xy 117.357906 -127.48387) (xy 117.357397 -127.511756)
			(xy 117.349277 -127.566932) (xy 117.333209 -127.620339) (xy 117.309537 -127.670836) (xy 117.278764 -127.717349)
			(xy 117.241547 -127.758886) (xy 117.198679 -127.794561) (xy 117.151073 -127.823615) (xy 117.099744 -127.845427)
			(xy 117.045787 -127.859533) (xy 116.99035 -127.865633) (xy 116.934616 -127.863596) (xy 116.879773 -127.853466)
			(xy 116.826989 -127.835459) (xy 116.777389 -127.809958) (xy 116.732031 -127.777507) (xy 116.691882 -127.738798)
			(xy 116.657796 -127.694655) (xy 116.6305 -127.64602) (xy 116.610577 -127.593929) (xy 116.598451 -127.539492)
			(xy 116.59438 -127.48387) (xy 111.518979 -127.48387) (xy 111.496782 -127.490386) (xy 111.44283 -127.49814)
			(xy 111.415576 -127.498602) (xy 111.388288 -127.498128) (xy 111.334267 -127.49036) (xy 111.281905 -127.47497)
			(xy 111.232272 -127.452274) (xy 111.209074 -127.437896) (xy 111.19866 -127.431292) (xy 111.175292 -127.428752)
			(xy 111.075978 -127.465582) (xy 111.059976 -127.482854) (xy 111.05642 -127.494792) (xy 111.048249 -127.520795)
			(xy 111.025627 -127.570382) (xy 110.996177 -127.616243) (xy 110.960498 -127.657445) (xy 110.919317 -127.693147)
			(xy 110.873472 -127.722623) (xy 110.823899 -127.745273) (xy 110.771605 -127.760634) (xy 110.717657 -127.768394)
			(xy 110.690406 -127.768858) (xy 110.663151 -127.768439) (xy 110.609196 -127.760681) (xy 110.556894 -127.745324)
			(xy 110.507311 -127.722678) (xy 110.461455 -127.693206) (xy 110.420261 -127.657508) (xy 110.384567 -127.61631)
			(xy 110.355101 -127.570451) (xy 110.332461 -127.520865) (xy 110.317109 -127.468561) (xy 110.309358 -127.414605)
			(xy 110.308898 -127.38735) (xy 108.963528 -127.38735) (xy 108.974793 -127.424005) (xy 108.983252 -127.480299)
			(xy 108.98378 -127.508762) (xy 108.983294 -127.536013) (xy 108.975538 -127.589961) (xy 108.960183 -127.642256)
			(xy 108.937541 -127.691833) (xy 108.908075 -127.737683) (xy 108.872384 -127.778874) (xy 108.831193 -127.814565)
			(xy 108.785343 -127.844031) (xy 108.735766 -127.866673) (xy 108.683471 -127.882028) (xy 108.629523 -127.889784)
			(xy 108.575021 -127.889784) (xy 108.521073 -127.882028) (xy 108.468778 -127.866673) (xy 108.419201 -127.844031)
			(xy 108.373351 -127.814565) (xy 108.33216 -127.778874) (xy 108.296469 -127.737683) (xy 108.267003 -127.691833)
			(xy 108.244361 -127.642256) (xy 108.229006 -127.589961) (xy 108.22125 -127.536013) (xy 108.220764 -127.508762)
			(xy 108.22178 -127.479552) (xy 108.22305 -127.465328) (xy 108.210604 -127.440436) (xy 108.110528 -127.376936)
			(xy 108.082842 -127.376428) (xy 108.070396 -127.383286) (xy 108.048743 -127.395152) (xy 108.003045 -127.413849)
			(xy 107.955319 -127.426507) (xy 107.906361 -127.432913) (xy 107.881674 -127.433324) (xy 107.854423 -127.432846)
			(xy 107.800476 -127.425087) (xy 107.748182 -127.409729) (xy 107.698605 -127.387086) (xy 107.652756 -127.357619)
			(xy 107.611566 -127.321926) (xy 107.575875 -127.280736) (xy 107.546409 -127.234886) (xy 107.523767 -127.185309)
			(xy 107.508411 -127.133015) (xy 107.500653 -127.079067) (xy 107.500166 -127.051816) (xy 105.602208 -127.051816)
			(xy 105.599116 -127.073325) (xy 105.583761 -127.12562) (xy 105.561119 -127.175197) (xy 105.531653 -127.221047)
			(xy 105.495962 -127.262238) (xy 105.454771 -127.297929) (xy 105.408921 -127.327395) (xy 105.359344 -127.350037)
			(xy 105.307049 -127.365392) (xy 105.253101 -127.373148) (xy 105.198599 -127.373148) (xy 105.144651 -127.365392)
			(xy 105.092356 -127.350037) (xy 105.042779 -127.327395) (xy 104.996929 -127.297929) (xy 104.955738 -127.262238)
			(xy 104.920047 -127.221047) (xy 104.890581 -127.175197) (xy 104.867939 -127.12562) (xy 104.852584 -127.073325)
			(xy 104.844828 -127.019377) (xy 104.844342 -126.992126) (xy 95.780098 -126.992126) (xy 94.106978 -128.665246)
			(xy 112.888324 -128.665246) (xy 112.888324 -128.610754) (xy 112.896079 -128.556815) (xy 112.91143 -128.504529)
			(xy 112.934066 -128.45496) (xy 112.963526 -128.409117) (xy 112.99921 -128.367933) (xy 113.040391 -128.332245)
			(xy 113.086232 -128.302782) (xy 113.135799 -128.280142) (xy 113.188084 -128.264786) (xy 113.242022 -128.257026)
			(xy 113.269268 -128.256538) (xy 113.296638 -128.257014) (xy 113.350817 -128.264828) (xy 113.40332 -128.280314)
			(xy 113.453067 -128.303154) (xy 113.499034 -128.332877) (xy 113.519966 -128.350518) (xy 113.527078 -128.356614)
			(xy 113.544096 -128.362964) (xy 113.62944 -128.362964) (xy 113.646458 -128.356614) (xy 113.65357 -128.350518)
			(xy 113.674503 -128.332877) (xy 113.720471 -128.303153) (xy 113.770217 -128.280307) (xy 113.822719 -128.264811)
			(xy 113.876897 -128.256982) (xy 113.931639 -128.256982) (xy 113.985817 -128.264811) (xy 114.038319 -128.280307)
			(xy 114.088065 -128.303153) (xy 114.134033 -128.332877) (xy 114.154966 -128.350518) (xy 114.162078 -128.356614)
			(xy 114.179096 -128.362964) (xy 114.26444 -128.362964) (xy 114.281458 -128.356614) (xy 114.28857 -128.350518)
			(xy 114.309505 -128.332882) (xy 114.355477 -128.303169) (xy 114.405223 -128.280332) (xy 114.457724 -128.264841)
			(xy 114.511899 -128.257012) (xy 114.539268 -128.256538) (xy 114.566526 -128.256907) (xy 114.620487 -128.264661)
			(xy 114.672795 -128.280016) (xy 114.722385 -128.30266) (xy 114.768248 -128.33213) (xy 114.809449 -128.367828)
			(xy 114.845151 -128.409027) (xy 114.874625 -128.454887) (xy 114.897273 -128.504475) (xy 114.912632 -128.556782)
			(xy 114.920391 -128.610742) (xy 114.920391 -128.665258) (xy 114.912632 -128.719218) (xy 114.897273 -128.771525)
			(xy 114.874625 -128.821113) (xy 114.845151 -128.866973) (xy 114.809449 -128.908172) (xy 114.768248 -128.94387)
			(xy 114.722385 -128.97334) (xy 114.672795 -128.995984) (xy 114.620487 -129.011339) (xy 114.566526 -129.019093)
			(xy 114.539268 -129.019554) (xy 114.511897 -129.019118) (xy 114.457716 -129.011295) (xy 114.405212 -128.995799)
			(xy 114.355465 -128.97295) (xy 114.3095 -128.943219) (xy 114.28857 -128.925574) (xy 114.281458 -128.919478)
			(xy 114.26444 -128.913128) (xy 114.179096 -128.913128) (xy 114.162078 -128.919478) (xy 114.154966 -128.925574)
			(xy 114.134033 -128.943215) (xy 114.088065 -128.972939) (xy 114.038319 -128.995785) (xy 113.985817 -129.011281)
			(xy 113.931639 -129.01911) (xy 113.876897 -129.01911) (xy 113.822719 -129.011281) (xy 113.770217 -128.995785)
			(xy 113.720471 -128.972939) (xy 113.674503 -128.943215) (xy 113.65357 -128.925574) (xy 113.646458 -128.919478)
			(xy 113.62944 -128.913128) (xy 113.544096 -128.913128) (xy 113.527078 -128.919478) (xy 113.519966 -128.925574)
			(xy 113.499017 -128.943192) (xy 113.453049 -128.972908) (xy 113.403306 -128.995748) (xy 113.350809 -129.011244)
			(xy 113.296636 -129.019077) (xy 113.269268 -129.019554) (xy 113.242022 -129.018974) (xy 113.188084 -129.011214)
			(xy 113.135799 -128.995858) (xy 113.086232 -128.973218) (xy 113.040391 -128.943755) (xy 112.99921 -128.908067)
			(xy 112.963526 -128.866883) (xy 112.934067 -128.82104) (xy 112.91143 -128.771471) (xy 112.896079 -128.719185)
			(xy 112.888324 -128.665246) (xy 94.106978 -128.665246) (xy 93.646244 -129.12598) (xy 93.639405 -129.133381)
			(xy 93.631693 -129.151979) (xy 93.631258 -129.162048) (xy 93.631258 -129.409444) (xy 116.367812 -129.409444)
			(xy 116.371883 -129.353822) (xy 116.384009 -129.299385) (xy 116.403932 -129.247294) (xy 116.431228 -129.198659)
			(xy 116.465314 -129.154516) (xy 116.505463 -129.115807) (xy 116.550821 -129.083356) (xy 116.600421 -129.057855)
			(xy 116.653205 -129.039848) (xy 116.708048 -129.029718) (xy 116.763782 -129.027681) (xy 116.819219 -129.033781)
			(xy 116.873176 -129.047887) (xy 116.924505 -129.069699) (xy 116.972111 -129.098753) (xy 117.014979 -129.134428)
			(xy 117.052196 -129.175965) (xy 117.082969 -129.222478) (xy 117.106641 -129.272975) (xy 117.122709 -129.326382)
			(xy 117.130829 -129.381558) (xy 117.131338 -129.409444) (xy 117.130829 -129.43733) (xy 117.122709 -129.492506)
			(xy 117.106641 -129.545913) (xy 117.087504 -129.586736) (xy 117.524528 -129.586736) (xy 117.528599 -129.531114)
			(xy 117.540725 -129.476677) (xy 117.560648 -129.424586) (xy 117.587944 -129.375951) (xy 117.62203 -129.331808)
			(xy 117.662179 -129.293099) (xy 117.707537 -129.260648) (xy 117.757137 -129.235147) (xy 117.809921 -129.21714)
			(xy 117.864764 -129.20701) (xy 117.920498 -129.204973) (xy 117.975935 -129.211073) (xy 118.029892 -129.225179)
			(xy 118.081221 -129.246991) (xy 118.128827 -129.276045) (xy 118.171695 -129.31172) (xy 118.208912 -129.353257)
			(xy 118.239685 -129.39977) (xy 118.263357 -129.450267) (xy 118.279425 -129.503674) (xy 118.287545 -129.55885)
			(xy 118.288054 -129.586736) (xy 118.287545 -129.614622) (xy 118.279425 -129.669798) (xy 118.263357 -129.723205)
			(xy 118.239685 -129.773702) (xy 118.208912 -129.820215) (xy 118.171695 -129.861752) (xy 118.128827 -129.897427)
			(xy 118.081221 -129.926481) (xy 118.029892 -129.948293) (xy 117.975935 -129.962399) (xy 117.920498 -129.968499)
			(xy 117.864764 -129.966462) (xy 117.809921 -129.956332) (xy 117.757137 -129.938325) (xy 117.707537 -129.912824)
			(xy 117.662179 -129.880373) (xy 117.62203 -129.841664) (xy 117.587944 -129.797521) (xy 117.560648 -129.748886)
			(xy 117.540725 -129.696795) (xy 117.528599 -129.642358) (xy 117.524528 -129.586736) (xy 117.087504 -129.586736)
			(xy 117.082969 -129.59641) (xy 117.052196 -129.642923) (xy 117.014979 -129.68446) (xy 116.972111 -129.720135)
			(xy 116.924505 -129.749189) (xy 116.873176 -129.771001) (xy 116.819219 -129.785107) (xy 116.763782 -129.791207)
			(xy 116.708048 -129.78917) (xy 116.653205 -129.77904) (xy 116.600421 -129.761033) (xy 116.550821 -129.735532)
			(xy 116.505463 -129.703081) (xy 116.465314 -129.664372) (xy 116.431228 -129.620229) (xy 116.403932 -129.571594)
			(xy 116.384009 -129.519503) (xy 116.371883 -129.465066) (xy 116.367812 -129.409444) (xy 93.631258 -129.409444)
			(xy 93.631258 -129.951246) (xy 112.909426 -129.951246) (xy 112.909426 -129.896754) (xy 112.91718 -129.842818)
			(xy 112.932531 -129.790534) (xy 112.955166 -129.740966) (xy 112.984623 -129.695124) (xy 113.020305 -129.65394)
			(xy 113.061484 -129.618253) (xy 113.107322 -129.58879) (xy 113.156887 -129.566148) (xy 113.209169 -129.550791)
			(xy 113.263105 -129.54303) (xy 113.29035 -129.54254) (xy 113.31772 -129.543026) (xy 113.371898 -129.550837)
			(xy 113.424402 -129.566321) (xy 113.474149 -129.589159) (xy 113.520116 -129.61888) (xy 113.541048 -129.63652)
			(xy 113.54816 -129.642616) (xy 113.565178 -129.648966) (xy 113.650522 -129.648966) (xy 113.66754 -129.642616)
			(xy 113.674652 -129.63652) (xy 113.695594 -129.618893) (xy 113.741564 -129.589179) (xy 113.791309 -129.56634)
			(xy 113.843807 -129.550846) (xy 113.897981 -129.543015) (xy 113.92535 -129.54254) (xy 113.952609 -129.542904)
			(xy 114.006572 -129.550656) (xy 114.058882 -129.566009) (xy 114.108475 -129.588652) (xy 114.15434 -129.618122)
			(xy 114.195544 -129.65382) (xy 114.231248 -129.69502) (xy 114.260724 -129.740881) (xy 114.283373 -129.790471)
			(xy 114.298734 -129.842779) (xy 114.306493 -129.896741) (xy 114.306493 -129.951259) (xy 114.298734 -130.005221)
			(xy 114.283373 -130.057529) (xy 114.260724 -130.107119) (xy 114.231248 -130.15298) (xy 114.195544 -130.19418)
			(xy 114.15434 -130.229878) (xy 114.108475 -130.259348) (xy 114.058882 -130.281991) (xy 114.006572 -130.297344)
			(xy 113.952609 -130.305096) (xy 113.92535 -130.305556) (xy 113.89798 -130.305071) (xy 113.843802 -130.29726)
			(xy 113.791298 -130.281776) (xy 113.741551 -130.258938) (xy 113.695584 -130.229216) (xy 113.674652 -130.211576)
			(xy 113.66754 -130.20548) (xy 113.650522 -130.19913) (xy 113.565178 -130.19913) (xy 113.54816 -130.20548)
			(xy 113.541048 -130.211576) (xy 113.520106 -130.229202) (xy 113.474136 -130.258917) (xy 113.424391 -130.281756)
			(xy 113.371893 -130.29725) (xy 113.317719 -130.305081) (xy 113.29035 -130.305556) (xy 113.263105 -130.30497)
			(xy 113.209169 -130.297209) (xy 113.156887 -130.281852) (xy 113.107322 -130.259211) (xy 113.061484 -130.229747)
			(xy 113.020305 -130.19406) (xy 112.984623 -130.152876) (xy 112.955166 -130.107034) (xy 112.932531 -130.057466)
			(xy 112.91718 -130.005182) (xy 112.909426 -129.951246) (xy 93.631258 -129.951246) (xy 93.631258 -131.715256)
			(xy 95.345756 -131.715256) (xy 95.349827 -131.659634) (xy 95.361953 -131.605197) (xy 95.381876 -131.553106)
			(xy 95.409172 -131.504471) (xy 95.443258 -131.460328) (xy 95.483407 -131.421619) (xy 95.528765 -131.389168)
			(xy 95.578365 -131.363667) (xy 95.631149 -131.34566) (xy 95.685992 -131.33553) (xy 95.741726 -131.333493)
			(xy 95.797163 -131.339593) (xy 95.85112 -131.353699) (xy 95.902449 -131.375511) (xy 95.950055 -131.404565)
			(xy 95.992923 -131.44024) (xy 96.03014 -131.481777) (xy 96.060913 -131.52829) (xy 96.084585 -131.578787)
			(xy 96.100653 -131.632194) (xy 96.108773 -131.68737) (xy 96.109282 -131.715256) (xy 96.108773 -131.743142)
			(xy 96.100653 -131.798318) (xy 96.084585 -131.851725) (xy 96.060913 -131.902222) (xy 96.03014 -131.948735)
			(xy 95.992923 -131.990272) (xy 95.950055 -132.025947) (xy 95.942192 -132.030746) (xy 112.909424 -132.030746)
			(xy 112.909424 -131.976254) (xy 112.917178 -131.922318) (xy 112.932529 -131.870033) (xy 112.955164 -131.820465)
			(xy 112.984622 -131.774623) (xy 113.020304 -131.733439) (xy 113.061483 -131.697752) (xy 113.107321 -131.668288)
			(xy 113.156886 -131.645647) (xy 113.209169 -131.630289) (xy 113.263104 -131.622528) (xy 113.29035 -131.622038)
			(xy 113.31772 -131.622524) (xy 113.371898 -131.630336) (xy 113.424401 -131.64582) (xy 113.474149 -131.668657)
			(xy 113.520116 -131.698378) (xy 113.541048 -131.716018) (xy 113.54816 -131.722114) (xy 113.565178 -131.728464)
			(xy 113.650522 -131.728464) (xy 113.66754 -131.722114) (xy 113.674652 -131.716018) (xy 113.695594 -131.698391)
			(xy 113.741564 -131.668677) (xy 113.791309 -131.645838) (xy 113.843807 -131.630344) (xy 113.897981 -131.622513)
			(xy 113.92535 -131.622038) (xy 113.952608 -131.622406) (xy 114.006571 -131.630158) (xy 114.058882 -131.645511)
			(xy 114.108474 -131.668154) (xy 114.154339 -131.697624) (xy 114.195543 -131.733322) (xy 114.231246 -131.774521)
			(xy 114.260722 -131.820382) (xy 114.283371 -131.869971) (xy 114.298732 -131.92228) (xy 114.306491 -131.976242)
			(xy 114.306491 -132.030758) (xy 114.298732 -132.08472) (xy 114.283371 -132.137029) (xy 114.260722 -132.186618)
			(xy 114.231246 -132.232479) (xy 114.195543 -132.273678) (xy 114.154339 -132.309376) (xy 114.108474 -132.338846)
			(xy 114.058882 -132.361489) (xy 114.006571 -132.376842) (xy 113.952609 -132.384594) (xy 113.92535 -132.385054)
			(xy 113.89798 -132.38457) (xy 113.843802 -132.376758) (xy 113.791298 -132.361274) (xy 113.741551 -132.338436)
			(xy 113.695584 -132.308714) (xy 113.674652 -132.291074) (xy 113.66754 -132.284978) (xy 113.650522 -132.278628)
			(xy 113.565178 -132.278628) (xy 113.54816 -132.284978) (xy 113.541048 -132.291074) (xy 113.520105 -132.3087)
			(xy 113.474136 -132.338415) (xy 113.424391 -132.361254) (xy 113.371893 -132.376748) (xy 113.317719 -132.384579)
			(xy 113.29035 -132.385054) (xy 113.263104 -132.384472) (xy 113.209169 -132.376711) (xy 113.156886 -132.361353)
			(xy 113.107321 -132.338712) (xy 113.061483 -132.309248) (xy 113.020304 -132.273561) (xy 112.984622 -132.232377)
			(xy 112.955164 -132.186535) (xy 112.932529 -132.136967) (xy 112.917178 -132.084682) (xy 112.909424 -132.030746)
			(xy 95.942192 -132.030746) (xy 95.902449 -132.055001) (xy 95.85112 -132.076813) (xy 95.797163 -132.090919)
			(xy 95.741726 -132.097019) (xy 95.685992 -132.094982) (xy 95.631149 -132.084852) (xy 95.578365 -132.066845)
			(xy 95.528765 -132.041344) (xy 95.483407 -132.008893) (xy 95.443258 -131.970184) (xy 95.409172 -131.926041)
			(xy 95.381876 -131.877406) (xy 95.361953 -131.825315) (xy 95.349827 -131.770878) (xy 95.345756 -131.715256)
			(xy 93.631258 -131.715256) (xy 93.631258 -133.282436) (xy 93.631689 -133.292502) (xy 93.639419 -133.311091)
			(xy 93.646244 -133.318504) (xy 94.827344 -134.499604) (xy 94.834745 -134.506443) (xy 94.853343 -134.514161)
			(xy 94.863412 -134.51459)
		)
		(stroke
			(width 0)
			(type solid)
		)
		(fill yes)
		(layer "In5.Cu")
		(net "GND")
	)
	(gr_poly
		(pts
			(xy 210.69173 -308.061106) (xy 210.701798 -308.060678) (xy 210.720395 -308.052956) (xy 210.727798 -308.04612)
			(xy 210.777328 -307.99659) (xy 210.784181 -307.989194) (xy 210.791923 -307.970596) (xy 210.792314 -307.960522)
			(xy 210.792314 -288.142426) (xy 210.791878 -288.132361) (xy 210.784146 -288.113775) (xy 210.777328 -288.106358)
			(xy 210.171792 -287.500822) (xy 210.164394 -287.493975) (xy 210.145796 -287.48624) (xy 210.135724 -287.485836)
			(xy 207.958436 -287.485836) (xy 207.949954 -287.486153) (xy 207.933932 -287.491721) (xy 207.920631 -287.502248)
			(xy 207.915764 -287.509204) (xy 207.862678 -287.592262) (xy 207.8609 -287.617916) (xy 207.866234 -287.629854)
			(xy 207.876474 -287.653161) (xy 207.891381 -287.701838) (xy 207.895952 -287.726882) (xy 207.89773 -287.738058)
			(xy 207.909922 -287.756092) (xy 207.981296 -287.79978) (xy 207.987354 -287.803232) (xy 208.000746 -287.807087)
			(xy 208.007712 -287.8074) (xy 208.026254 -287.8074) (xy 208.033112 -287.805368) (xy 208.059209 -287.798265)
			(xy 208.11275 -287.790619) (xy 208.139792 -287.790128) (xy 208.140046 -287.790128) (xy 208.167292 -287.790617)
			(xy 208.22123 -287.798378) (xy 208.273514 -287.813736) (xy 208.323081 -287.836378) (xy 208.368921 -287.865842)
			(xy 208.410102 -287.90153) (xy 208.445785 -287.942716) (xy 208.475244 -287.988559) (xy 208.49788 -288.038129)
			(xy 208.513231 -288.090415) (xy 208.520986 -288.144353) (xy 208.520986 -288.198847) (xy 208.513231 -288.252785)
			(xy 208.49788 -288.305071) (xy 208.475244 -288.354641) (xy 208.445785 -288.400484) (xy 208.410102 -288.44167)
			(xy 208.368921 -288.477358) (xy 208.323081 -288.506822) (xy 208.273514 -288.529464) (xy 208.22123 -288.544822)
			(xy 208.167292 -288.552583) (xy 208.140046 -288.553144) (xy 208.113182 -288.552688) (xy 208.059986 -288.545156)
			(xy 208.008373 -288.530233) (xy 207.959365 -288.508215) (xy 207.913931 -288.479538) (xy 207.872971 -288.444769)
			(xy 207.837295 -288.404597) (xy 207.807609 -288.359816) (xy 207.784501 -288.311312) (xy 207.768427 -288.260045)
			(xy 207.763618 -288.233612) (xy 207.76184 -288.222436) (xy 207.749648 -288.204402) (xy 207.678274 -288.160714)
			(xy 207.672218 -288.157254) (xy 207.658826 -288.153382) (xy 207.651858 -288.153094) (xy 207.633316 -288.153094)
			(xy 207.626458 -288.155126) (xy 207.600361 -288.162227) (xy 207.54682 -288.169869) (xy 207.519778 -288.170366)
			(xy 207.519524 -288.170366) (xy 207.50563 -288.170229) (xy 207.477917 -288.168193) (xy 207.464152 -288.166302)
			(xy 207.453738 -288.164778) (xy 207.433672 -288.170112) (xy 207.358742 -288.228532) (xy 207.348836 -288.246566)
			(xy 207.34782 -288.257234) (xy 207.34465 -288.285225) (xy 207.331128 -288.339909) (xy 207.309712 -288.392011)
			(xy 207.280868 -288.440397) (xy 207.245222 -288.484017) (xy 207.203551 -288.521921) (xy 207.156759 -288.553286)
			(xy 207.105864 -288.57743) (xy 207.051973 -288.593828) (xy 206.996256 -288.602124) (xy 206.96809 -288.602674)
			(xy 206.940842 -288.602187) (xy 206.8869 -288.59443) (xy 206.834611 -288.579076) (xy 206.78504 -288.556436)
			(xy 206.739195 -288.526972) (xy 206.698009 -288.491284) (xy 206.662322 -288.450097) (xy 206.632859 -288.404252)
			(xy 206.610221 -288.35468) (xy 206.594868 -288.30239) (xy 206.587112 -288.248448) (xy 206.587112 -288.193952)
			(xy 206.594868 -288.14001) (xy 206.610221 -288.08772) (xy 206.632859 -288.038148) (xy 206.662322 -287.992303)
			(xy 206.698009 -287.951116) (xy 206.739195 -287.915428) (xy 206.78504 -287.885964) (xy 206.834611 -287.863324)
			(xy 206.8869 -287.84797) (xy 206.940842 -287.840213) (xy 206.96809 -287.839658) (xy 206.981984 -287.839795)
			(xy 207.009697 -287.841832) (xy 207.023462 -287.843722) (xy 207.033876 -287.845246) (xy 207.053942 -287.839912)
			(xy 207.128872 -287.781492) (xy 207.138778 -287.763458) (xy 207.139794 -287.75279) (xy 207.143467 -287.721001)
			(xy 207.160062 -287.659203) (xy 207.172814 -287.629854) (xy 207.178148 -287.617916) (xy 207.17637 -287.592262)
			(xy 207.123284 -287.509204) (xy 207.118425 -287.502251) (xy 207.105098 -287.491772) (xy 207.089087 -287.486195)
			(xy 207.080612 -287.485836) (xy 206.062072 -287.485836) (xy 206.055985 -287.486044) (xy 206.044173 -287.488998)
			(xy 206.038704 -287.491678) (xy 206.03845 -287.491678) (xy 206.031886 -287.495477) (xy 206.021169 -287.506197)
			(xy 206.017368 -287.51276) (xy 205.97495 -287.5915) (xy 205.970985 -287.599757) (xy 205.968601 -287.617905)
			(xy 205.972745 -287.635734) (xy 205.97749 -287.64357) (xy 205.97749 -287.643824) (xy 205.992477 -287.667389)
			(xy 206.016145 -287.717972) (xy 206.032192 -287.771463) (xy 206.040277 -287.826721) (xy 206.040736 -287.854644)
			(xy 206.040736 -287.860994) (xy 206.039792 -287.887927) (xy 206.031259 -287.941137) (xy 206.015322 -287.992617)
			(xy 205.9923 -288.041343) (xy 205.96265 -288.086343) (xy 205.926961 -288.126723) (xy 205.885946 -288.161679)
			(xy 205.840419 -288.190514) (xy 205.791288 -288.212656) (xy 205.739529 -288.227663) (xy 205.686173 -288.235237)
			(xy 205.659228 -288.235644) (xy 205.634138 -288.235247) (xy 205.58439 -288.228669) (xy 205.535936 -288.215623)
			(xy 205.48961 -288.196335) (xy 205.467712 -288.184082) (xy 205.456282 -288.177478) (xy 205.430882 -288.176716)
			(xy 205.331314 -288.227262) (xy 205.316836 -288.24809) (xy 205.315566 -288.261298) (xy 205.312138 -288.289064)
			(xy 205.298195 -288.343243) (xy 205.276488 -288.394805) (xy 205.247484 -288.442644) (xy 205.211803 -288.485733)
			(xy 205.170212 -288.523149) (xy 205.123601 -288.55409) (xy 205.072972 -288.577891) (xy 205.01941 -288.594042)
			(xy 204.964062 -288.602197) (xy 204.93609 -288.602674) (xy 204.909961 -288.602243) (xy 204.858193 -288.595103)
			(xy 204.807886 -288.580958) (xy 204.759983 -288.560073) (xy 204.715382 -288.53284) (xy 204.67492 -288.499769)
			(xy 204.639355 -288.461481) (xy 204.609353 -288.418693) (xy 204.597 -288.395664) (xy 204.590142 -288.382964)
			(xy 204.566266 -288.368232) (xy 204.446886 -288.368232) (xy 204.42301 -288.382964) (xy 204.416152 -288.395664)
			(xy 204.403828 -288.418709) (xy 204.373819 -288.461496) (xy 204.338248 -288.499783) (xy 204.297781 -288.532853)
			(xy 204.253177 -288.560087) (xy 204.205272 -288.580974) (xy 204.154962 -288.595123) (xy 204.103192 -288.602269)
			(xy 204.077062 -288.602674) (xy 204.048599 -288.602146) (xy 203.992305 -288.593687) (xy 203.937891 -288.576964)
			(xy 203.886564 -288.552346) (xy 203.83946 -288.52038) (xy 203.797626 -288.481773) (xy 203.779374 -288.459926)
			(xy 203.767436 -288.444686) (xy 203.729082 -288.438336) (xy 203.141072 -288.80943) (xy 203.106448 -288.830766)
			(xy 209.253072 -288.830766) (xy 209.257143 -288.775144) (xy 209.269269 -288.720707) (xy 209.289192 -288.668616)
			(xy 209.316488 -288.619981) (xy 209.350574 -288.575838) (xy 209.390723 -288.537129) (xy 209.436081 -288.504678)
			(xy 209.485681 -288.479177) (xy 209.538465 -288.46117) (xy 209.593308 -288.45104) (xy 209.649042 -288.449003)
			(xy 209.704479 -288.455103) (xy 209.758436 -288.469209) (xy 209.809765 -288.491021) (xy 209.857371 -288.520075)
			(xy 209.900239 -288.55575) (xy 209.937456 -288.597287) (xy 209.968229 -288.6438) (xy 209.991901 -288.694297)
			(xy 210.007969 -288.747704) (xy 210.016089 -288.80288) (xy 210.016598 -288.830766) (xy 210.016089 -288.858652)
			(xy 210.007969 -288.913828) (xy 209.991901 -288.967235) (xy 209.968229 -289.017732) (xy 209.937456 -289.064245)
			(xy 209.900239 -289.105782) (xy 209.857371 -289.141457) (xy 209.809765 -289.170511) (xy 209.758436 -289.192323)
			(xy 209.704479 -289.206429) (xy 209.649042 -289.212529) (xy 209.593308 -289.210492) (xy 209.538465 -289.200362)
			(xy 209.485681 -289.182355) (xy 209.436081 -289.156854) (xy 209.390723 -289.124403) (xy 209.350574 -289.085694)
			(xy 209.316488 -289.041551) (xy 209.289192 -288.992916) (xy 209.269269 -288.940825) (xy 209.257143 -288.886388)
			(xy 209.253072 -288.830766) (xy 203.106448 -288.830766) (xy 203.104361 -288.832052) (xy 203.027723 -288.871594)
			(xy 202.947954 -288.904365) (xy 202.865651 -288.930118) (xy 202.78143 -288.948661) (xy 202.738736 -288.954718)
			(xy 202.729084 -288.955988) (xy 202.712574 -288.965132) (xy 202.655932 -289.033966) (xy 202.65009 -289.051746)
			(xy 202.650598 -289.061652) (xy 202.65136 -289.08502) (xy 202.650874 -289.112271) (xy 202.643118 -289.166219)
			(xy 202.627763 -289.218514) (xy 202.605121 -289.268091) (xy 202.575655 -289.313941) (xy 202.539964 -289.355132)
			(xy 202.498773 -289.390823) (xy 202.452923 -289.420289) (xy 202.403346 -289.442931) (xy 202.351051 -289.458286)
			(xy 202.297103 -289.466042) (xy 202.242601 -289.466042) (xy 202.188653 -289.458286) (xy 202.136358 -289.442931)
			(xy 202.086781 -289.420289) (xy 202.040931 -289.390823) (xy 201.99974 -289.355132) (xy 201.964049 -289.313941)
			(xy 201.934583 -289.268091) (xy 201.911941 -289.218514) (xy 201.896586 -289.166219) (xy 201.88883 -289.112271)
			(xy 201.888344 -289.08502) (xy 201.888598 -289.069018) (xy 201.889106 -289.058604) (xy 201.88174 -289.0393)
			(xy 201.823828 -288.978848) (xy 201.816401 -288.971735) (xy 201.797524 -288.963629) (xy 201.787252 -288.9631)
			(xy 200.024746 -288.9631) (xy 199.962008 -288.961322) (xy 199.949687 -288.961101) (xy 199.92719 -288.971091)
			(xy 199.919082 -288.980372) (xy 199.903309 -288.999544) (xy 199.866993 -289.033392) (xy 199.826028 -289.061434)
			(xy 199.781331 -289.08304) (xy 199.733909 -289.097725) (xy 199.684824 -289.105158) (xy 199.660002 -289.105594)
			(xy 199.633708 -289.105087) (xy 199.581782 -289.096764) (xy 199.531828 -289.080329) (xy 199.485105 -289.056194)
			(xy 199.442791 -289.024969) (xy 199.424036 -289.006534) (xy 199.423782 -289.00628) (xy 199.416416 -288.998914)
			(xy 199.38873 -288.986976) (xy 199.38393 -288.985085) (xy 199.373821 -288.983034) (xy 199.368664 -288.982912)
			(xy 199.31634 -288.982912) (xy 199.311179 -288.983006) (xy 199.301065 -288.985055) (xy 199.296274 -288.986976)
			(xy 199.268588 -288.998914) (xy 199.261222 -289.00628) (xy 199.260968 -289.006534) (xy 199.242197 -289.024954)
			(xy 199.199896 -289.0562) (xy 199.153178 -289.080348) (xy 199.103224 -289.096788) (xy 199.051297 -289.105106)
			(xy 199.025002 -289.105594) (xy 198.998649 -289.105082) (xy 198.946611 -289.09672) (xy 198.896558 -289.080207)
			(xy 198.84976 -289.055961) (xy 198.807401 -289.024598) (xy 198.770555 -288.986911) (xy 198.740156 -288.943856)
			(xy 198.728076 -288.920428) (xy 198.721726 -288.907474) (xy 198.697088 -288.89198) (xy 198.402956 -288.89198)
			(xy 198.378318 -288.907474) (xy 198.371968 -288.920428) (xy 198.35991 -288.943865) (xy 198.3295 -288.986911)
			(xy 198.292647 -289.024589) (xy 198.250284 -289.055944) (xy 198.203484 -289.080183) (xy 198.153431 -289.096691)
			(xy 198.101394 -289.105051) (xy 198.04869 -289.105051) (xy 197.996653 -289.096691) (xy 197.9466 -289.080183)
			(xy 197.8998 -289.055944) (xy 197.857437 -289.024589) (xy 197.820584 -288.986911) (xy 197.790174 -288.943865)
			(xy 197.778116 -288.920428) (xy 197.771766 -288.907474) (xy 197.747128 -288.89198) (xy 197.452996 -288.89198)
			(xy 197.428358 -288.907474) (xy 197.422008 -288.920428) (xy 197.409368 -288.944944) (xy 197.377208 -288.989751)
			(xy 197.338071 -289.028614) (xy 197.293039 -289.060458) (xy 197.243355 -289.084405) (xy 197.21703 -289.09264)
			(xy 197.21312 -289.093818) (xy 197.205714 -289.097261) (xy 197.202298 -289.099498) (xy 197.167511 -289.123004)
			(xy 197.094581 -289.164613) (xy 197.018335 -289.199778) (xy 196.939341 -289.228238) (xy 196.858187 -289.24978)
			(xy 196.775478 -289.264244) (xy 196.69183 -289.271523) (xy 196.649848 -289.271964) (xy 196.384418 -289.271964)
			(xy 196.334262 -289.271286) (xy 196.234492 -289.260856) (xy 196.185282 -289.251136) (xy 196.180117 -289.250189)
			(xy 196.169619 -289.250189) (xy 196.164454 -289.251136) (xy 196.13487 -289.257146) (xy 196.075137 -289.265917)
			(xy 196.045074 -289.268662) (xy 196.034162 -289.270087) (xy 196.014996 -289.280854) (xy 196.002072 -289.298637)
			(xy 195.999354 -289.309302) (xy 195.995321 -289.328007) (xy 195.983221 -289.364308) (xy 195.975224 -289.381692)
			(xy 195.971117 -289.391368) (xy 195.970305 -289.412349) (xy 195.977965 -289.431899) (xy 195.992815 -289.446743)
			(xy 196.012367 -289.454398) (xy 196.033348 -289.453579) (xy 196.043042 -289.44951) (xy 196.063726 -289.440077)
			(xy 196.107185 -289.426743) (xy 196.152139 -289.419985) (xy 196.174868 -289.419538) (xy 196.199685 -289.420021)
			(xy 196.248666 -289.428046) (xy 196.295703 -289.443889) (xy 196.339558 -289.467133) (xy 196.379074 -289.497166)
			(xy 196.413211 -289.533196) (xy 196.44107 -289.574274) (xy 196.461916 -289.619318) (xy 196.4752 -289.667141)
			(xy 196.480572 -289.716483) (xy 196.48012 -289.724846) (xy 196.819278 -289.724846) (xy 196.823238 -289.675792)
			(xy 196.835015 -289.628008) (xy 196.854306 -289.582732) (xy 196.880609 -289.541136) (xy 196.913244 -289.504299)
			(xy 196.951365 -289.473174) (xy 196.993986 -289.448567) (xy 197.040002 -289.431115) (xy 197.088221 -289.421271)
			(xy 197.137396 -289.41929) (xy 197.186251 -289.425222) (xy 197.233522 -289.438914) (xy 197.277984 -289.460012)
			(xy 197.318487 -289.487968) (xy 197.35398 -289.52206) (xy 197.383545 -289.561404) (xy 197.406416 -289.604981)
			(xy 197.422 -289.651662) (xy 197.429895 -289.700239) (xy 197.43039 -289.724846) (xy 197.769238 -289.724846)
			(xy 197.773198 -289.675792) (xy 197.784975 -289.628008) (xy 197.804266 -289.582732) (xy 197.830569 -289.541136)
			(xy 197.863204 -289.504299) (xy 197.901325 -289.473174) (xy 197.943946 -289.448567) (xy 197.989962 -289.431115)
			(xy 198.038181 -289.421271) (xy 198.087356 -289.41929) (xy 198.136211 -289.425222) (xy 198.183482 -289.438914)
			(xy 198.227944 -289.460012) (xy 198.268447 -289.487968) (xy 198.30394 -289.52206) (xy 198.333505 -289.561404)
			(xy 198.356376 -289.604981) (xy 198.37196 -289.651662) (xy 198.379855 -289.700239) (xy 198.38035 -289.724846)
			(xy 198.719198 -289.724846) (xy 198.723158 -289.675792) (xy 198.734935 -289.628008) (xy 198.754226 -289.582732)
			(xy 198.780529 -289.541136) (xy 198.813164 -289.504299) (xy 198.851285 -289.473174) (xy 198.893906 -289.448567)
			(xy 198.939922 -289.431115) (xy 198.988141 -289.421271) (xy 199.037316 -289.41929) (xy 199.086171 -289.425222)
			(xy 199.133442 -289.438914) (xy 199.177904 -289.460012) (xy 199.218407 -289.487968) (xy 199.2539 -289.52206)
			(xy 199.283465 -289.561404) (xy 199.306336 -289.604981) (xy 199.32192 -289.651662) (xy 199.329815 -289.700239)
			(xy 199.33031 -289.724846) (xy 199.329815 -289.749453) (xy 199.32192 -289.79803) (xy 199.306336 -289.844711)
			(xy 199.283465 -289.888288) (xy 199.2539 -289.927632) (xy 199.218407 -289.961724) (xy 199.177904 -289.98968)
			(xy 199.133442 -290.010778) (xy 199.086171 -290.02447) (xy 199.037316 -290.030402) (xy 198.988141 -290.028421)
			(xy 198.939922 -290.018577) (xy 198.893906 -290.001125) (xy 198.851285 -289.976518) (xy 198.813164 -289.945393)
			(xy 198.780529 -289.908556) (xy 198.754226 -289.86696) (xy 198.734935 -289.821684) (xy 198.723158 -289.7739)
			(xy 198.719198 -289.724846) (xy 198.38035 -289.724846) (xy 198.379855 -289.749453) (xy 198.37196 -289.79803)
			(xy 198.356376 -289.844711) (xy 198.333505 -289.888288) (xy 198.30394 -289.927632) (xy 198.268447 -289.961724)
			(xy 198.227944 -289.98968) (xy 198.183482 -290.010778) (xy 198.136211 -290.02447) (xy 198.087356 -290.030402)
			(xy 198.038181 -290.028421) (xy 197.989962 -290.018577) (xy 197.943946 -290.001125) (xy 197.901325 -289.976518)
			(xy 197.863204 -289.945393) (xy 197.830569 -289.908556) (xy 197.804266 -289.86696) (xy 197.784975 -289.821684)
			(xy 197.773198 -289.7739) (xy 197.769238 -289.724846) (xy 197.43039 -289.724846) (xy 197.429895 -289.749453)
			(xy 197.422 -289.79803) (xy 197.406416 -289.844711) (xy 197.383545 -289.888288) (xy 197.35398 -289.927632)
			(xy 197.318487 -289.961724) (xy 197.277984 -289.98968) (xy 197.233522 -290.010778) (xy 197.186251 -290.02447)
			(xy 197.137396 -290.030402) (xy 197.088221 -290.028421) (xy 197.040002 -290.018577) (xy 196.993986 -290.001125)
			(xy 196.951365 -289.976518) (xy 196.913244 -289.945393) (xy 196.880609 -289.908556) (xy 196.854306 -289.86696)
			(xy 196.835015 -289.821684) (xy 196.823238 -289.7739) (xy 196.819278 -289.724846) (xy 196.48012 -289.724846)
			(xy 196.477891 -289.766044) (xy 196.467227 -289.814519) (xy 196.448861 -289.86063) (xy 196.423278 -289.903162)
			(xy 196.39115 -289.940995) (xy 196.353325 -289.973132) (xy 196.3108 -289.998727) (xy 196.264694 -290.017104)
			(xy 196.216222 -290.02778) (xy 196.166661 -290.030474) (xy 196.117317 -290.025114) (xy 196.069491 -290.011843)
			(xy 196.024442 -289.991008) (xy 195.983356 -289.96316) (xy 195.947318 -289.929032) (xy 195.917275 -289.889523)
			(xy 195.89402 -289.845675) (xy 195.878165 -289.798642) (xy 195.870127 -289.749663) (xy 195.86956 -289.724846)
			(xy 195.869744 -289.710663) (xy 195.872413 -289.682423) (xy 195.874894 -289.668458) (xy 195.87718 -289.656012)
			(xy 195.869814 -289.63239) (xy 195.792344 -289.55492) (xy 195.768722 -289.547554) (xy 195.756276 -289.54984)
			(xy 195.742311 -289.552325) (xy 195.714071 -289.554996) (xy 195.699888 -289.555174) (xy 195.685706 -289.554987)
			(xy 195.657467 -289.552312) (xy 195.6435 -289.54984) (xy 195.631054 -289.547554) (xy 195.607432 -289.55492)
			(xy 195.529962 -289.63239) (xy 195.522596 -289.656012) (xy 195.524882 -289.668458) (xy 195.527365 -289.682423)
			(xy 195.530033 -289.710663) (xy 195.530216 -289.724846) (xy 195.529726 -289.749667) (xy 195.521688 -289.798653)
			(xy 195.505831 -289.845694) (xy 195.482572 -289.88955) (xy 195.452525 -289.929065) (xy 195.416481 -289.963199)
			(xy 195.37539 -289.991053) (xy 195.330333 -290.011891) (xy 195.2825 -290.025166) (xy 195.233148 -290.030528)
			(xy 195.18358 -290.027835) (xy 195.1351 -290.017158) (xy 195.088986 -289.998779) (xy 195.046452 -289.973182)
			(xy 195.00862 -289.941042) (xy 194.976486 -289.903204) (xy 194.950896 -289.860666) (xy 194.932526 -289.814549)
			(xy 194.921858 -289.766067) (xy 194.919174 -289.716498) (xy 194.924544 -289.667147) (xy 194.937828 -289.619316)
			(xy 194.958674 -289.574263) (xy 194.986535 -289.533177) (xy 195.020675 -289.497139) (xy 195.060196 -289.467099)
			(xy 195.104055 -289.443848) (xy 195.151099 -289.427999) (xy 195.200087 -289.419969) (xy 195.224908 -289.419538)
			(xy 195.23909 -289.419725) (xy 195.26733 -289.422399) (xy 195.281296 -289.424872) (xy 195.293742 -289.427158)
			(xy 195.317364 -289.419792) (xy 195.394834 -289.342322) (xy 195.4022 -289.3187) (xy 195.399914 -289.306254)
			(xy 195.397726 -289.29417) (xy 195.395053 -289.269757) (xy 195.39458 -289.257486) (xy 195.393946 -289.247351)
			(xy 195.385721 -289.228802) (xy 195.370932 -289.21491) (xy 195.36156 -289.211004) (xy 195.323837 -289.19658)
			(xy 195.250697 -289.162317) (xy 195.180653 -289.1221) (xy 195.147184 -289.099498) (xy 195.143773 -289.097205)
			(xy 195.136368 -289.093636) (xy 195.132452 -289.092386) (xy 195.106008 -289.084102) (xy 195.056132 -289.059959)
			(xy 195.010981 -289.027836) (xy 194.971822 -288.988631) (xy 194.939749 -288.943445) (xy 194.915663 -288.893541)
			(xy 194.907408 -288.867088) (xy 194.90616 -288.863171) (xy 194.902588 -288.855768) (xy 194.900296 -288.852356)
			(xy 194.877707 -288.818941) (xy 194.837524 -288.748999) (xy 194.820032 -288.712656) (xy 194.816104 -288.705072)
			(xy 194.804156 -288.692883) (xy 194.796664 -288.68878) (xy 194.756532 -288.667698) (xy 194.744594 -288.661094)
			(xy 194.716908 -288.661602) (xy 194.629532 -288.71545) (xy 194.622073 -288.72047) (xy 194.610964 -288.734594)
			(xy 194.605381 -288.751673) (xy 194.605402 -288.760662) (xy 194.605402 -288.760916) (xy 194.605656 -288.774632)
			(xy 194.605656 -288.77514) (xy 194.605602 -288.786796) (xy 194.604074 -288.810058) (xy 194.602608 -288.821622)
			(xy 194.602608 -288.821876) (xy 194.600502 -288.835676) (xy 194.594269 -288.86289) (xy 194.590162 -288.876232)
			(xy 194.586606 -288.886138) (xy 194.577629 -288.909896) (xy 194.55344 -288.954553) (xy 194.522713 -288.994991)
			(xy 194.48617 -289.030261) (xy 194.444669 -289.059535) (xy 194.399183 -289.082126) (xy 194.350779 -289.097504)
			(xy 194.300595 -289.105308) (xy 194.275202 -289.105848) (xy 193.324988 -289.105848) (xy 193.29898 -289.105364)
			(xy 193.247604 -289.097225) (xy 193.198134 -289.081149) (xy 193.151788 -289.057532) (xy 193.109707 -289.026956)
			(xy 193.072927 -288.990173) (xy 193.042354 -288.94809) (xy 193.018741 -288.901742) (xy 193.002669 -288.852271)
			(xy 192.994534 -288.800894) (xy 192.994026 -288.774886) (xy 192.994186 -288.761232) (xy 192.996471 -288.734018)
			(xy 192.998598 -288.72053) (xy 193.00063 -288.708592) (xy 192.993518 -288.685986) (xy 192.92062 -288.609532)
			(xy 192.898268 -288.601658) (xy 192.88633 -288.603182) (xy 192.877283 -288.604171) (xy 192.859109 -288.605186)
			(xy 192.850008 -288.605214) (xy 192.825186 -288.604729) (xy 192.776197 -288.596699) (xy 192.729152 -288.580849)
			(xy 192.685291 -288.557596) (xy 192.64577 -288.527554) (xy 192.61163 -288.491514) (xy 192.58377 -288.450425)
			(xy 192.562925 -288.405371) (xy 192.549643 -288.357537) (xy 192.544275 -288.308185) (xy 192.546962 -288.258615)
			(xy 192.557634 -288.210132) (xy 192.576008 -288.164015) (xy 192.601602 -288.121478) (xy 192.63374 -288.083641)
			(xy 192.671576 -288.051503) (xy 192.714113 -288.025909) (xy 192.76023 -288.007534) (xy 192.808713 -287.996863)
			(xy 192.858283 -287.994175) (xy 192.907635 -287.999543) (xy 192.955469 -288.012824) (xy 193.000524 -288.033669)
			(xy 193.041613 -288.061529) (xy 193.077653 -288.095669) (xy 193.107695 -288.13519) (xy 193.130948 -288.17905)
			(xy 193.146798 -288.226095) (xy 193.154829 -288.275084) (xy 193.155316 -288.299906) (xy 193.155277 -288.309007)
			(xy 193.15426 -288.32718) (xy 193.153284 -288.336228) (xy 193.15176 -288.348166) (xy 193.159634 -288.370518)
			(xy 193.236088 -288.443416) (xy 193.258694 -288.450528) (xy 193.270632 -288.448496) (xy 193.28412 -288.446365)
			(xy 193.311333 -288.444074) (xy 193.324988 -288.443924) (xy 193.395346 -288.443924) (xy 193.406011 -288.443476)
			(xy 193.425497 -288.43481) (xy 193.432938 -288.42716) (xy 193.49085 -288.362898) (xy 193.497454 -288.342578)
			(xy 193.496438 -288.331656) (xy 193.49466 -288.299906) (xy 193.49513 -288.275914) (xy 193.502635 -288.228519)
			(xy 193.517462 -288.182882) (xy 193.539245 -288.140127) (xy 193.567447 -288.101304) (xy 193.601376 -288.067372)
			(xy 193.640194 -288.039164) (xy 193.682947 -288.017376) (xy 193.728582 -288.002544) (xy 193.775976 -287.995033)
			(xy 193.799968 -287.994598) (xy 193.809072 -287.994697) (xy 193.827245 -287.995842) (xy 193.83629 -287.996884)
			(xy 193.848482 -287.998154) (xy 193.870834 -287.99028) (xy 193.943732 -287.913826) (xy 193.950844 -287.89122)
			(xy 193.948812 -287.879282) (xy 193.94668 -287.865794) (xy 193.944391 -287.838581) (xy 193.94424 -287.824926)
			(xy 193.944402 -287.811272) (xy 193.946692 -287.78406) (xy 193.948812 -287.77057) (xy 193.950844 -287.758632)
			(xy 193.943732 -287.736026) (xy 193.870834 -287.659572) (xy 193.848482 -287.651698) (xy 193.83629 -287.652968)
			(xy 193.827246 -287.654015) (xy 193.809072 -287.655157) (xy 193.799968 -287.655254) (xy 193.775977 -287.654781)
			(xy 193.728587 -287.647271) (xy 193.682954 -287.632442) (xy 193.640202 -287.610657) (xy 193.601384 -287.582454)
			(xy 193.567455 -287.548526) (xy 193.53925 -287.50971) (xy 193.517464 -287.466959) (xy 193.502632 -287.421327)
			(xy 193.49512 -287.373937) (xy 193.49466 -287.349946) (xy 193.496438 -287.317688) (xy 193.497454 -287.306766)
			(xy 193.49085 -287.286446) (xy 193.433192 -287.222184) (xy 193.425677 -287.21452) (xy 193.406071 -287.205832)
			(xy 193.395346 -287.20542) (xy 193.333878 -287.20542) (xy 193.333624 -287.205674) (xy 193.324988 -287.205674)
			(xy 193.311334 -287.205514) (xy 193.28412 -287.203229) (xy 193.270632 -287.201102) (xy 193.258694 -287.19907)
			(xy 193.236088 -287.206182) (xy 193.159634 -287.27908) (xy 193.15176 -287.301432) (xy 193.15303 -287.313624)
			(xy 193.154077 -287.322668) (xy 193.155218 -287.340842) (xy 193.155316 -287.349946) (xy 193.154826 -287.374767)
			(xy 193.146788 -287.423753) (xy 193.130931 -287.470794) (xy 193.107672 -287.51465) (xy 193.077625 -287.554165)
			(xy 193.041581 -287.588299) (xy 193.00049 -287.616153) (xy 192.955433 -287.636991) (xy 192.9076 -287.650266)
			(xy 192.858248 -287.655628) (xy 192.80868 -287.652935) (xy 192.7602 -287.642258) (xy 192.714086 -287.623879)
			(xy 192.671552 -287.598282) (xy 192.63372 -287.566142) (xy 192.601586 -287.528304) (xy 192.575996 -287.485766)
			(xy 192.557626 -287.439649) (xy 192.546958 -287.391167) (xy 192.544274 -287.341598) (xy 192.549644 -287.292247)
			(xy 192.562928 -287.244416) (xy 192.583774 -287.199363) (xy 192.611635 -287.158277) (xy 192.645775 -287.122239)
			(xy 192.685296 -287.092199) (xy 192.729155 -287.068948) (xy 192.776199 -287.053099) (xy 192.825187 -287.045069)
			(xy 192.850008 -287.044638) (xy 192.876254 -287.045161) (xy 192.927979 -287.054102) (xy 192.952878 -287.062418)
			(xy 192.962164 -287.065267) (xy 192.981556 -287.064511) (xy 192.999277 -287.0566) (xy 193.012786 -287.042668)
			(xy 193.020147 -287.024711) (xy 193.020305 -287.005305) (xy 193.01714 -286.996124) (xy 193.008758 -286.972248)
			(xy 193.008758 -286.97174) (xy 193.004948 -286.95904) (xy 193.004948 -286.958786) (xy 193.003424 -286.95269)
			(xy 192.998852 -286.9311) (xy 192.998344 -286.927036) (xy 192.996411 -286.914042) (xy 192.994378 -286.887849)
			(xy 192.99428 -286.874712) (xy 192.994448 -286.861121) (xy 192.996734 -286.834036) (xy 192.998852 -286.82061)
			(xy 193.00063 -286.808672) (xy 192.993772 -286.786066) (xy 192.920874 -286.709612) (xy 192.898522 -286.701738)
			(xy 192.88633 -286.703008) (xy 192.877286 -286.704057) (xy 192.859112 -286.705201) (xy 192.850008 -286.705294)
			(xy 192.825188 -286.704809) (xy 192.776203 -286.696779) (xy 192.729162 -286.680931) (xy 192.685304 -286.657681)
			(xy 192.645786 -286.627641) (xy 192.611648 -286.591605) (xy 192.58379 -286.55052) (xy 192.562945 -286.505469)
			(xy 192.549664 -286.457639) (xy 192.544295 -286.408291) (xy 192.546981 -286.358725) (xy 192.557651 -286.310246)
			(xy 192.576022 -286.264131) (xy 192.601613 -286.221597) (xy 192.633747 -286.183763) (xy 192.671579 -286.151625)
			(xy 192.714112 -286.126032) (xy 192.760225 -286.107657) (xy 192.808703 -286.096984) (xy 192.858269 -286.094295)
			(xy 192.907618 -286.09966) (xy 192.955448 -286.112938) (xy 193.0005 -286.133779) (xy 193.041587 -286.161634)
			(xy 193.077627 -286.195769) (xy 193.107669 -286.235286) (xy 193.130922 -286.279141) (xy 193.146774 -286.326181)
			(xy 193.154807 -286.375166) (xy 193.155316 -286.399986) (xy 193.155277 -286.409087) (xy 193.154261 -286.42726)
			(xy 193.153284 -286.436308) (xy 193.15176 -286.448246) (xy 193.159634 -286.470598) (xy 193.236088 -286.543496)
			(xy 193.258694 -286.550608) (xy 193.270632 -286.548576) (xy 193.28412 -286.546445) (xy 193.311333 -286.544156)
			(xy 193.324988 -286.544004) (xy 193.395346 -286.544004) (xy 193.40601 -286.543555) (xy 193.425494 -286.534887)
			(xy 193.432938 -286.52724) (xy 193.49085 -286.462978) (xy 193.497454 -286.442658) (xy 193.496438 -286.431736)
			(xy 193.49466 -286.399986) (xy 193.495132 -286.375995) (xy 193.502639 -286.328603) (xy 193.517468 -286.282969)
			(xy 193.539251 -286.240215) (xy 193.567454 -286.201396) (xy 193.601382 -286.167466) (xy 193.6402 -286.139261)
			(xy 193.682952 -286.117474) (xy 193.728585 -286.102643) (xy 193.775977 -286.095133) (xy 193.799968 -286.094678)
			(xy 193.809072 -286.094777) (xy 193.827245 -286.095922) (xy 193.83629 -286.096964) (xy 193.848482 -286.098234)
			(xy 193.87058 -286.09036) (xy 193.943478 -286.013906) (xy 193.95059 -285.9913) (xy 193.948558 -285.979108)
			(xy 193.944625 -285.95207) (xy 193.944633 -285.897436) (xy 193.948558 -285.870396) (xy 193.95059 -285.858458)
			(xy 193.943478 -285.835852) (xy 193.87058 -285.759398) (xy 193.848228 -285.751524) (xy 193.83629 -285.753048)
			(xy 193.827243 -285.754038) (xy 193.809069 -285.755057) (xy 193.799968 -285.75508) (xy 193.775979 -285.754607)
			(xy 193.728593 -285.747097) (xy 193.682965 -285.732266) (xy 193.640219 -285.71048) (xy 193.601407 -285.682276)
			(xy 193.567485 -285.648347) (xy 193.539288 -285.60953) (xy 193.517511 -285.566779) (xy 193.502689 -285.521149)
			(xy 193.495188 -285.473761) (xy 193.49466 -285.449772) (xy 193.496438 -285.417768) (xy 193.497454 -285.406846)
			(xy 193.49085 -285.386526) (xy 193.433192 -285.322264) (xy 193.425676 -285.314602) (xy 193.406071 -285.305917)
			(xy 193.395346 -285.3055) (xy 193.324988 -285.3055) (xy 193.311334 -285.30534) (xy 193.28412 -285.303055)
			(xy 193.270632 -285.300928) (xy 193.258694 -285.298896) (xy 193.236088 -285.306008) (xy 193.159634 -285.378906)
			(xy 193.15176 -285.401258) (xy 193.15303 -285.41345) (xy 193.154079 -285.422494) (xy 193.155225 -285.440668)
			(xy 193.155316 -285.449772) (xy 193.154832 -285.474594) (xy 193.146805 -285.523585) (xy 193.130958 -285.570632)
			(xy 193.107707 -285.614495) (xy 193.077667 -285.654019) (xy 193.041628 -285.688162) (xy 193.00054 -285.716024)
			(xy 192.955485 -285.736872) (xy 192.907651 -285.750156) (xy 192.858298 -285.755526) (xy 192.808727 -285.752841)
			(xy 192.760242 -285.742171) (xy 192.714123 -285.723798) (xy 192.671584 -285.698206) (xy 192.633746 -285.666068)
			(xy 192.601606 -285.628232) (xy 192.576011 -285.585695) (xy 192.557634 -285.539577) (xy 192.546961 -285.491093)
			(xy 192.544273 -285.441522) (xy 192.54964 -285.392169) (xy 192.562921 -285.344334) (xy 192.583766 -285.299278)
			(xy 192.611626 -285.258188) (xy 192.645766 -285.222147) (xy 192.685288 -285.192104) (xy 192.72915 -285.16885)
			(xy 192.776195 -285.153) (xy 192.825186 -285.144969) (xy 192.850008 -285.144464) (xy 192.859112 -285.144561)
			(xy 192.877286 -285.145703) (xy 192.88633 -285.14675) (xy 192.898522 -285.14802) (xy 192.920874 -285.140146)
			(xy 192.993772 -285.063692) (xy 193.000884 -285.041086) (xy 192.998852 -285.029148) (xy 192.996722 -285.01566)
			(xy 192.994434 -284.988447) (xy 192.99428 -284.974792) (xy 192.994444 -284.961138) (xy 192.996737 -284.933926)
			(xy 192.998852 -284.920436) (xy 193.000884 -284.908498) (xy 192.993772 -284.885892) (xy 192.920874 -284.809438)
			(xy 192.898522 -284.801564) (xy 192.88633 -284.802834) (xy 192.877286 -284.803883) (xy 192.859112 -284.805027)
			(xy 192.850008 -284.80512) (xy 192.825186 -284.804635) (xy 192.776195 -284.796604) (xy 192.729149 -284.780754)
			(xy 192.685287 -284.757501) (xy 192.645765 -284.727458) (xy 192.611625 -284.691417) (xy 192.583764 -284.650327)
			(xy 192.562919 -284.605271) (xy 192.549637 -284.557437) (xy 192.544269 -284.508083) (xy 192.546957 -284.458512)
			(xy 192.557629 -284.410028) (xy 192.576004 -284.36391) (xy 192.601598 -284.321372) (xy 192.633738 -284.283535)
			(xy 192.671575 -284.251396) (xy 192.714113 -284.225802) (xy 192.760232 -284.207428) (xy 192.808716 -284.196756)
			(xy 192.858287 -284.194069) (xy 192.907641 -284.199438) (xy 192.955475 -284.21272) (xy 193.000531 -284.233566)
			(xy 193.04162 -284.261427) (xy 193.077661 -284.295568) (xy 193.107703 -284.335091) (xy 193.130955 -284.378953)
			(xy 193.146805 -284.425999) (xy 193.154835 -284.47499) (xy 193.155316 -284.499812) (xy 193.155219 -284.508916)
			(xy 193.154077 -284.52709) (xy 193.15303 -284.536134) (xy 193.15176 -284.548326) (xy 193.159634 -284.570678)
			(xy 193.236088 -284.643576) (xy 193.258694 -284.650688) (xy 193.270632 -284.648656) (xy 193.28412 -284.646525)
			(xy 193.311333 -284.644236) (xy 193.324988 -284.644084) (xy 193.395346 -284.644084) (xy 193.406035 -284.643516)
			(xy 193.425582 -284.634849) (xy 193.433192 -284.62732) (xy 193.49085 -284.563058) (xy 193.497454 -284.542738)
			(xy 193.496438 -284.531816) (xy 193.49466 -284.499812) (xy 193.49513 -284.475819) (xy 193.502634 -284.428424)
			(xy 193.51746 -284.382787) (xy 193.539242 -284.34003) (xy 193.567445 -284.301207) (xy 193.601373 -284.267274)
			(xy 193.640192 -284.239065) (xy 193.682946 -284.217277) (xy 193.728581 -284.202444) (xy 193.775975 -284.194933)
			(xy 193.799968 -284.194504) (xy 193.809072 -284.194603) (xy 193.827245 -284.195748) (xy 193.83629 -284.19679)
			(xy 193.848228 -284.19806) (xy 193.87058 -284.190186) (xy 193.943478 -284.113732) (xy 193.95059 -284.091126)
			(xy 193.948558 -284.079188) (xy 193.944619 -284.05215) (xy 193.944614 -283.997513) (xy 193.948558 -283.970476)
			(xy 193.95059 -283.958538) (xy 193.943478 -283.935932) (xy 193.87058 -283.859478) (xy 193.848228 -283.851604)
			(xy 193.83629 -283.853128) (xy 193.827243 -283.854118) (xy 193.809069 -283.855137) (xy 193.799968 -283.85516)
			(xy 193.775978 -283.854711) (xy 193.728589 -283.8472) (xy 193.682959 -283.832368) (xy 193.640211 -283.810581)
			(xy 193.601397 -283.782374) (xy 193.567474 -283.748442) (xy 193.539278 -283.709621) (xy 193.517501 -283.666867)
			(xy 193.502681 -283.621233) (xy 193.495182 -283.573842) (xy 193.49466 -283.549852) (xy 193.496438 -283.517848)
			(xy 193.497454 -283.506926) (xy 193.49085 -283.486606) (xy 193.433192 -283.422344) (xy 193.425675 -283.414685)
			(xy 193.40607 -283.406004) (xy 193.395346 -283.40558) (xy 193.324988 -283.40558) (xy 193.311334 -283.40542)
			(xy 193.28412 -283.403135) (xy 193.270632 -283.401008) (xy 193.258694 -283.398976) (xy 193.236088 -283.406088)
			(xy 193.159634 -283.478986) (xy 193.15176 -283.501338) (xy 193.15303 -283.51353) (xy 193.15408 -283.522574)
			(xy 193.155226 -283.540748) (xy 193.155316 -283.549852) (xy 193.154834 -283.574675) (xy 193.14681 -283.623667)
			(xy 193.130965 -283.670715) (xy 193.107717 -283.71458) (xy 193.077678 -283.754106) (xy 193.04164 -283.788252)
			(xy 193.000553 -283.816117) (xy 192.955499 -283.836967) (xy 192.907665 -283.850254) (xy 192.858312 -283.855626)
			(xy 192.808739 -283.852943) (xy 192.760254 -283.842275) (xy 192.714134 -283.823903) (xy 192.671593 -283.798312)
			(xy 192.633753 -283.766175) (xy 192.601612 -283.72834) (xy 192.576015 -283.685802) (xy 192.557637 -283.639684)
			(xy 192.546962 -283.5912) (xy 192.544273 -283.541628) (xy 192.549639 -283.492274) (xy 192.562919 -283.444439)
			(xy 192.583764 -283.399382) (xy 192.611623 -283.358291) (xy 192.645764 -283.322249) (xy 192.685286 -283.292205)
			(xy 192.729148 -283.268951) (xy 192.776194 -283.2531) (xy 192.825186 -283.245069) (xy 192.850008 -283.244544)
			(xy 192.859112 -283.244641) (xy 192.877286 -283.245783) (xy 192.88633 -283.24683) (xy 192.898522 -283.2481)
			(xy 192.920874 -283.240226) (xy 192.993772 -283.163772) (xy 193.000884 -283.141166) (xy 192.998852 -283.129228)
			(xy 192.996722 -283.11574) (xy 192.994437 -283.088526) (xy 192.99428 -283.074872) (xy 192.99444 -283.061218)
			(xy 192.996727 -283.034005) (xy 192.998852 -283.020516) (xy 193.000884 -283.008578) (xy 192.993772 -282.985972)
			(xy 192.920874 -282.909518) (xy 192.898522 -282.901644) (xy 192.88633 -282.902914) (xy 192.877286 -282.903963)
			(xy 192.859112 -282.905107) (xy 192.850008 -282.9052) (xy 192.825188 -282.904715) (xy 192.776201 -282.896685)
			(xy 192.729159 -282.880836) (xy 192.6853 -282.857585) (xy 192.645781 -282.827545) (xy 192.611642 -282.791507)
			(xy 192.583784 -282.750421) (xy 192.562939 -282.705369) (xy 192.549658 -282.657539) (xy 192.544289 -282.60819)
			(xy 192.546976 -282.558622) (xy 192.557645 -282.510142) (xy 192.576018 -282.464026) (xy 192.601609 -282.421491)
			(xy 192.633745 -282.383656) (xy 192.671578 -282.351519) (xy 192.714112 -282.325925) (xy 192.760226 -282.30755)
			(xy 192.808706 -282.296878) (xy 192.858273 -282.294189) (xy 192.907623 -282.299555) (xy 192.955454 -282.312834)
			(xy 193.000507 -282.333676) (xy 193.041595 -282.361532) (xy 193.077635 -282.395669) (xy 193.107677 -282.435187)
			(xy 193.13093 -282.479044) (xy 193.146781 -282.526086) (xy 193.154813 -282.575072) (xy 193.155316 -282.599892)
			(xy 193.155217 -282.608996) (xy 193.15407 -282.627169) (xy 193.15303 -282.636214) (xy 193.15176 -282.648406)
			(xy 193.159634 -282.670758) (xy 193.236088 -282.743656) (xy 193.258694 -282.750768) (xy 193.270632 -282.748736)
			(xy 193.28412 -282.746605) (xy 193.311333 -282.744316) (xy 193.324988 -282.744164) (xy 193.395346 -282.744164)
			(xy 193.406035 -282.743595) (xy 193.42558 -282.734927) (xy 193.433192 -282.7274) (xy 193.49085 -282.663138)
			(xy 193.497454 -282.642818) (xy 193.496438 -282.631896) (xy 193.49466 -282.599892) (xy 193.495131 -282.5759)
			(xy 193.502638 -282.528508) (xy 193.517466 -282.482873) (xy 193.539249 -282.440119) (xy 193.567452 -282.401299)
			(xy 193.60138 -282.367368) (xy 193.640198 -282.339162) (xy 193.68295 -282.317375) (xy 193.728584 -282.302544)
			(xy 193.775976 -282.295033) (xy 193.799968 -282.294584) (xy 193.809072 -282.294683) (xy 193.827245 -282.295828)
			(xy 193.83629 -282.29687) (xy 193.848228 -282.29814) (xy 193.87058 -282.290266) (xy 193.943478 -282.213812)
			(xy 193.95059 -282.191206) (xy 193.948558 -282.179268) (xy 193.94462 -282.152166) (xy 193.944622 -282.097404)
			(xy 193.948558 -282.070302) (xy 193.95059 -282.058364) (xy 193.943478 -282.035758) (xy 193.87058 -281.959304)
			(xy 193.848228 -281.95143) (xy 193.83629 -281.9527) (xy 193.827182 -281.953754) (xy 193.808882 -281.954897)
			(xy 193.799714 -281.954986) (xy 193.775721 -281.954541) (xy 193.728325 -281.947036) (xy 193.682687 -281.932208)
			(xy 193.63993 -281.910423) (xy 193.601108 -281.882217) (xy 193.567177 -281.848285) (xy 193.538973 -281.809463)
			(xy 193.517189 -281.766706) (xy 193.502362 -281.721067) (xy 193.494859 -281.673671) (xy 193.494406 -281.649678)
			(xy 193.494451 -281.640641) (xy 193.495465 -281.622595) (xy 193.496438 -281.61361) (xy 193.497962 -281.601672)
			(xy 193.490088 -281.57932) (xy 193.413634 -281.506422) (xy 193.391028 -281.499564) (xy 193.37909 -281.501342)
			(xy 193.365602 -281.503473) (xy 193.338389 -281.505766) (xy 193.324734 -281.505914) (xy 193.311143 -281.505746)
			(xy 193.284058 -281.503461) (xy 193.270632 -281.501342) (xy 193.258694 -281.499564) (xy 193.236088 -281.506422)
			(xy 193.159634 -281.57932) (xy 193.15176 -281.601672) (xy 193.153284 -281.61361) (xy 193.154274 -281.622657)
			(xy 193.155294 -281.640831) (xy 193.155316 -281.649932) (xy 193.154794 -281.675187) (xy 193.146481 -281.725009)
			(xy 193.13008 -281.772783) (xy 193.106039 -281.817206) (xy 193.075015 -281.857066) (xy 193.037853 -281.891276)
			(xy 192.995567 -281.918902) (xy 192.949311 -281.939192) (xy 192.900346 -281.951592) (xy 192.850008 -281.955763)
			(xy 192.79967 -281.951592) (xy 192.750705 -281.939192) (xy 192.704449 -281.918902) (xy 192.662163 -281.891276)
			(xy 192.625001 -281.857066) (xy 192.593977 -281.817206) (xy 192.569936 -281.772783) (xy 192.553535 -281.725009)
			(xy 192.545222 -281.675187) (xy 192.5447 -281.649932) (xy 192.544799 -281.640828) (xy 192.545944 -281.622655)
			(xy 192.546986 -281.61361) (xy 192.548256 -281.601418) (xy 192.540382 -281.579066) (xy 192.463928 -281.506168)
			(xy 192.441322 -281.499056) (xy 192.429384 -281.501088) (xy 192.415896 -281.50322) (xy 192.388683 -281.50551)
			(xy 192.375028 -281.50566) (xy 192.361374 -281.505498) (xy 192.334161 -281.503208) (xy 192.320672 -281.501088)
			(xy 192.308734 -281.499056) (xy 192.286128 -281.506168) (xy 192.209674 -281.579066) (xy 192.2018 -281.601418)
			(xy 192.20307 -281.61361) (xy 192.204117 -281.622654) (xy 192.205259 -281.640828) (xy 192.205356 -281.649932)
			(xy 192.204834 -281.675187) (xy 192.196521 -281.725009) (xy 192.18012 -281.772783) (xy 192.156079 -281.817206)
			(xy 192.125055 -281.857066) (xy 192.087893 -281.891276) (xy 192.045607 -281.918902) (xy 191.999351 -281.939192)
			(xy 191.950386 -281.951592) (xy 191.900048 -281.955763) (xy 191.84971 -281.951592) (xy 191.800745 -281.939192)
			(xy 191.754489 -281.918902) (xy 191.712203 -281.891276) (xy 191.675041 -281.857066) (xy 191.644017 -281.817206)
			(xy 191.619976 -281.772783) (xy 191.603575 -281.725009) (xy 191.595262 -281.675187) (xy 191.59474 -281.649932)
			(xy 191.594839 -281.640828) (xy 191.595984 -281.622655) (xy 191.597026 -281.61361) (xy 191.598296 -281.601672)
			(xy 191.590422 -281.57932) (xy 191.513968 -281.506422) (xy 191.491362 -281.49931) (xy 191.479424 -281.501342)
			(xy 191.465873 -281.503479) (xy 191.438532 -281.505767) (xy 191.424814 -281.505914) (xy 191.411223 -281.505746)
			(xy 191.384138 -281.503458) (xy 191.370712 -281.501342) (xy 191.358774 -281.499564) (xy 191.336168 -281.506422)
			(xy 191.259714 -281.57932) (xy 191.25184 -281.601672) (xy 191.253364 -281.61361) (xy 191.254354 -281.622657)
			(xy 191.255373 -281.640831) (xy 191.255396 -281.649932) (xy 191.254874 -281.675187) (xy 191.246561 -281.725009)
			(xy 191.23016 -281.772783) (xy 191.206119 -281.817206) (xy 191.175095 -281.857066) (xy 191.137933 -281.891276)
			(xy 191.095647 -281.918902) (xy 191.049391 -281.939192) (xy 191.000426 -281.951592) (xy 190.950088 -281.955763)
			(xy 190.89975 -281.951592) (xy 190.850785 -281.939192) (xy 190.804529 -281.918902) (xy 190.762243 -281.891276)
			(xy 190.725081 -281.857066) (xy 190.694057 -281.817206) (xy 190.670016 -281.772783) (xy 190.653615 -281.725009)
			(xy 190.645302 -281.675187) (xy 190.64478 -281.649932) (xy 190.644872 -281.640764) (xy 190.646013 -281.622464)
			(xy 190.647066 -281.613356) (xy 190.648336 -281.601418) (xy 190.640462 -281.579066) (xy 190.564008 -281.506168)
			(xy 190.541402 -281.499056) (xy 190.529464 -281.501088) (xy 190.515913 -281.503226) (xy 190.488572 -281.505514)
			(xy 190.474854 -281.50566) (xy 190.4612 -281.505499) (xy 190.433987 -281.503211) (xy 190.420498 -281.501088)
			(xy 190.40856 -281.499056) (xy 190.385954 -281.506168) (xy 190.3095 -281.579066) (xy 190.301626 -281.601418)
			(xy 190.302896 -281.61361) (xy 190.303944 -281.622654) (xy 190.305085 -281.640828) (xy 190.305182 -281.649932)
			(xy 190.30466 -281.675187) (xy 190.296347 -281.725009) (xy 190.279946 -281.772783) (xy 190.255905 -281.817206)
			(xy 190.224881 -281.857066) (xy 190.187719 -281.891276) (xy 190.145433 -281.918902) (xy 190.099177 -281.939192)
			(xy 190.050212 -281.951592) (xy 189.999874 -281.955763) (xy 189.949536 -281.951592) (xy 189.900571 -281.939192)
			(xy 189.854315 -281.918902) (xy 189.812029 -281.891276) (xy 189.774867 -281.857066) (xy 189.743843 -281.817206)
			(xy 189.719802 -281.772783) (xy 189.703401 -281.725009) (xy 189.695088 -281.675187) (xy 189.694566 -281.649932)
			(xy 189.694604 -281.640831) (xy 189.695619 -281.622658) (xy 189.696598 -281.61361) (xy 189.698122 -281.601672)
			(xy 189.690248 -281.57932) (xy 189.613794 -281.506422) (xy 189.591188 -281.49931) (xy 189.57925 -281.501342)
			(xy 189.565762 -281.503472) (xy 189.538549 -281.505761) (xy 189.524894 -281.505914) (xy 189.51124 -281.50575)
			(xy 189.484028 -281.503458) (xy 189.470538 -281.501342) (xy 189.4586 -281.49931) (xy 189.435994 -281.506422)
			(xy 189.35954 -281.57932) (xy 189.351666 -281.601672) (xy 189.35319 -281.61361) (xy 189.35418 -281.622657)
			(xy 189.3552 -281.640831) (xy 189.355222 -281.649932) (xy 189.3547 -281.675187) (xy 189.346387 -281.725009)
			(xy 189.329986 -281.772783) (xy 189.305945 -281.817206) (xy 189.274921 -281.857066) (xy 189.237759 -281.891276)
			(xy 189.195473 -281.918902) (xy 189.149217 -281.939192) (xy 189.100252 -281.951592) (xy 189.049914 -281.955763)
			(xy 188.999576 -281.951592) (xy 188.950611 -281.939192) (xy 188.904355 -281.918902) (xy 188.862069 -281.891276)
			(xy 188.824907 -281.857066) (xy 188.793883 -281.817206) (xy 188.769842 -281.772783) (xy 188.753441 -281.725009)
			(xy 188.745128 -281.675187) (xy 188.744606 -281.649932) (xy 188.744705 -281.640828) (xy 188.74585 -281.622655)
			(xy 188.746892 -281.61361) (xy 188.748162 -281.601418) (xy 188.740288 -281.579066) (xy 188.663834 -281.506168)
			(xy 188.641228 -281.499056) (xy 188.62929 -281.501088) (xy 188.615802 -281.50322) (xy 188.588589 -281.50551)
			(xy 188.574934 -281.50566) (xy 188.56128 -281.505498) (xy 188.534067 -281.503209) (xy 188.520578 -281.501088)
			(xy 188.50864 -281.499056) (xy 188.486034 -281.506168) (xy 188.40958 -281.579066) (xy 188.401706 -281.601418)
			(xy 188.402976 -281.61361) (xy 188.404023 -281.622654) (xy 188.405165 -281.640828) (xy 188.405262 -281.649932)
			(xy 188.40474 -281.675187) (xy 188.396427 -281.725009) (xy 188.380026 -281.772783) (xy 188.355985 -281.817206)
			(xy 188.324961 -281.857066) (xy 188.287799 -281.891276) (xy 188.245513 -281.918902) (xy 188.199257 -281.939192)
			(xy 188.150292 -281.951592) (xy 188.099954 -281.955763) (xy 188.049616 -281.951592) (xy 188.000651 -281.939192)
			(xy 187.954395 -281.918902) (xy 187.912109 -281.891276) (xy 187.874947 -281.857066) (xy 187.843923 -281.817206)
			(xy 187.819882 -281.772783) (xy 187.803481 -281.725009) (xy 187.795168 -281.675187) (xy 187.794646 -281.649932)
			(xy 187.794738 -281.640764) (xy 187.795879 -281.622464) (xy 187.796932 -281.613356) (xy 187.798202 -281.601418)
			(xy 187.790328 -281.579066) (xy 187.713874 -281.506168) (xy 187.691268 -281.499056) (xy 187.67933 -281.501088)
			(xy 187.665779 -281.503229) (xy 187.638438 -281.505522) (xy 187.62472 -281.50566) (xy 187.61113 -281.505488)
			(xy 187.584045 -281.503195) (xy 187.570618 -281.501088) (xy 187.55868 -281.49931) (xy 187.536074 -281.506168)
			(xy 187.45962 -281.579066) (xy 187.451746 -281.601418) (xy 187.453016 -281.61361) (xy 187.454063 -281.622654)
			(xy 187.455205 -281.640828) (xy 187.455302 -281.649932) (xy 187.45478 -281.675187) (xy 187.446467 -281.725009)
			(xy 187.430066 -281.772783) (xy 187.406025 -281.817206) (xy 187.375001 -281.857066) (xy 187.337839 -281.891276)
			(xy 187.295553 -281.918902) (xy 187.249297 -281.939192) (xy 187.200332 -281.951592) (xy 187.149994 -281.955763)
			(xy 187.099656 -281.951592) (xy 187.050691 -281.939192) (xy 187.004435 -281.918902) (xy 186.962149 -281.891276)
			(xy 186.924987 -281.857066) (xy 186.893963 -281.817206) (xy 186.869922 -281.772783) (xy 186.853521 -281.725009)
			(xy 186.845208 -281.675187) (xy 186.844686 -281.649932) (xy 186.844778 -281.640764) (xy 186.845919 -281.622464)
			(xy 186.846972 -281.613356) (xy 186.848242 -281.601164) (xy 186.840368 -281.579066) (xy 186.763914 -281.505914)
			(xy 186.741308 -281.498802) (xy 186.72937 -281.500834) (xy 186.715882 -281.502965) (xy 186.688669 -281.505255)
			(xy 186.675014 -281.505406) (xy 186.66136 -281.505243) (xy 186.634148 -281.502953) (xy 186.620658 -281.500834)
			(xy 186.60872 -281.498802) (xy 186.586114 -281.505914) (xy 186.50966 -281.579066) (xy 186.501786 -281.601164)
			(xy 186.503056 -281.613356) (xy 186.504111 -281.622463) (xy 186.505258 -281.640764) (xy 186.505342 -281.649932)
			(xy 186.504869 -281.673923) (xy 186.497359 -281.721312) (xy 186.482529 -281.766944) (xy 186.460745 -281.809695)
			(xy 186.432541 -281.848512) (xy 186.398614 -281.88244) (xy 186.359797 -281.910644) (xy 186.317046 -281.932429)
			(xy 186.271414 -281.947259) (xy 186.224025 -281.954769) (xy 186.200034 -281.95524) (xy 186.190866 -281.955148)
			(xy 186.172566 -281.954007) (xy 186.163458 -281.952954) (xy 186.151266 -281.951684) (xy 186.129168 -281.959558)
			(xy 186.056016 -282.036012) (xy 186.049158 -282.058618) (xy 186.050936 -282.070556) (xy 186.054818 -282.097255)
			(xy 186.054878 -282.151203) (xy 186.046183 -282.204446) (xy 186.028964 -282.255573) (xy 186.003676 -282.303228)
			(xy 185.97099 -282.346147) (xy 185.931773 -282.383194) (xy 185.909712 -282.398724) (xy 185.899698 -282.406256)
			(xy 185.887986 -282.428372) (xy 185.88736 -282.440888) (xy 185.88736 -282.599892) (xy 189.69407 -282.599892)
			(xy 189.69803 -282.550838) (xy 189.709807 -282.503054) (xy 189.729098 -282.457778) (xy 189.755401 -282.416182)
			(xy 189.788036 -282.379345) (xy 189.826157 -282.34822) (xy 189.868778 -282.323613) (xy 189.914794 -282.306161)
			(xy 189.963013 -282.296317) (xy 190.012188 -282.294336) (xy 190.061043 -282.300268) (xy 190.108314 -282.31396)
			(xy 190.152776 -282.335058) (xy 190.193279 -282.363014) (xy 190.228772 -282.397106) (xy 190.258337 -282.43645)
			(xy 190.281208 -282.480027) (xy 190.296792 -282.526708) (xy 190.304687 -282.575285) (xy 190.305182 -282.599892)
			(xy 190.64403 -282.599892) (xy 190.64799 -282.550838) (xy 190.659767 -282.503054) (xy 190.679058 -282.457778)
			(xy 190.705361 -282.416182) (xy 190.737996 -282.379345) (xy 190.776117 -282.34822) (xy 190.818738 -282.323613)
			(xy 190.864754 -282.306161) (xy 190.912973 -282.296317) (xy 190.962148 -282.294336) (xy 191.011003 -282.300268)
			(xy 191.058274 -282.31396) (xy 191.102736 -282.335058) (xy 191.143239 -282.363014) (xy 191.178732 -282.397106)
			(xy 191.208297 -282.43645) (xy 191.231168 -282.480027) (xy 191.246752 -282.526708) (xy 191.254647 -282.575285)
			(xy 191.255142 -282.599892) (xy 191.254647 -282.624499) (xy 191.246752 -282.673076) (xy 191.231168 -282.719757)
			(xy 191.208297 -282.763334) (xy 191.178732 -282.802678) (xy 191.143239 -282.83677) (xy 191.102736 -282.864726)
			(xy 191.058274 -282.885824) (xy 191.011003 -282.899516) (xy 190.962148 -282.905448) (xy 190.912973 -282.903467)
			(xy 190.864754 -282.893623) (xy 190.818738 -282.876171) (xy 190.776117 -282.851564) (xy 190.737996 -282.820439)
			(xy 190.705361 -282.783602) (xy 190.679058 -282.742006) (xy 190.659767 -282.69673) (xy 190.64799 -282.648946)
			(xy 190.64403 -282.599892) (xy 190.305182 -282.599892) (xy 190.304687 -282.624499) (xy 190.296792 -282.673076)
			(xy 190.281208 -282.719757) (xy 190.258337 -282.763334) (xy 190.228772 -282.802678) (xy 190.193279 -282.83677)
			(xy 190.152776 -282.864726) (xy 190.108314 -282.885824) (xy 190.061043 -282.899516) (xy 190.012188 -282.905448)
			(xy 189.963013 -282.903467) (xy 189.914794 -282.893623) (xy 189.868778 -282.876171) (xy 189.826157 -282.851564)
			(xy 189.788036 -282.820439) (xy 189.755401 -282.783602) (xy 189.729098 -282.742006) (xy 189.709807 -282.69673)
			(xy 189.69803 -282.648946) (xy 189.69407 -282.599892) (xy 185.88736 -282.599892) (xy 185.88736 -282.758388)
			(xy 185.888009 -282.770892) (xy 185.899736 -282.792983) (xy 185.909712 -282.800552) (xy 185.93012 -282.814828)
			(xy 185.966802 -282.848514) (xy 185.998018 -282.88732) (xy 186.023061 -282.930368) (xy 186.041366 -282.976685)
			(xy 186.052518 -283.025223) (xy 186.056264 -283.074872) (xy 186.36921 -283.074872) (xy 186.37317 -283.025818)
			(xy 186.384947 -282.978034) (xy 186.404238 -282.932758) (xy 186.430541 -282.891162) (xy 186.463176 -282.854325)
			(xy 186.501297 -282.8232) (xy 186.543918 -282.798593) (xy 186.589934 -282.781141) (xy 186.638153 -282.771297)
			(xy 186.687328 -282.769316) (xy 186.736183 -282.775248) (xy 186.783454 -282.78894) (xy 186.827916 -282.810038)
			(xy 186.868419 -282.837994) (xy 186.903912 -282.872086) (xy 186.933477 -282.91143) (xy 186.956348 -282.955007)
			(xy 186.971932 -283.001688) (xy 186.979827 -283.050265) (xy 186.980322 -283.074872) (xy 187.31917 -283.074872)
			(xy 187.32313 -283.025818) (xy 187.334907 -282.978034) (xy 187.354198 -282.932758) (xy 187.380501 -282.891162)
			(xy 187.413136 -282.854325) (xy 187.451257 -282.8232) (xy 187.493878 -282.798593) (xy 187.539894 -282.781141)
			(xy 187.588113 -282.771297) (xy 187.637288 -282.769316) (xy 187.686143 -282.775248) (xy 187.733414 -282.78894)
			(xy 187.777876 -282.810038) (xy 187.818379 -282.837994) (xy 187.853872 -282.872086) (xy 187.883437 -282.91143)
			(xy 187.906308 -282.955007) (xy 187.921892 -283.001688) (xy 187.929787 -283.050265) (xy 187.930282 -283.074872)
			(xy 188.26913 -283.074872) (xy 188.27309 -283.025818) (xy 188.284867 -282.978034) (xy 188.304158 -282.932758)
			(xy 188.330461 -282.891162) (xy 188.363096 -282.854325) (xy 188.401217 -282.8232) (xy 188.443838 -282.798593)
			(xy 188.489854 -282.781141) (xy 188.538073 -282.771297) (xy 188.587248 -282.769316) (xy 188.636103 -282.775248)
			(xy 188.683374 -282.78894) (xy 188.727836 -282.810038) (xy 188.768339 -282.837994) (xy 188.803832 -282.872086)
			(xy 188.833397 -282.91143) (xy 188.856268 -282.955007) (xy 188.871852 -283.001688) (xy 188.879747 -283.050265)
			(xy 188.880242 -283.074872) (xy 188.879747 -283.099479) (xy 188.871852 -283.148056) (xy 188.856268 -283.194737)
			(xy 188.833397 -283.238314) (xy 188.803832 -283.277658) (xy 188.768339 -283.31175) (xy 188.727836 -283.339706)
			(xy 188.683374 -283.360804) (xy 188.636103 -283.374496) (xy 188.587248 -283.380428) (xy 188.538073 -283.378447)
			(xy 188.489854 -283.368603) (xy 188.443838 -283.351151) (xy 188.401217 -283.326544) (xy 188.363096 -283.295419)
			(xy 188.330461 -283.258582) (xy 188.304158 -283.216986) (xy 188.284867 -283.17171) (xy 188.27309 -283.123926)
			(xy 188.26913 -283.074872) (xy 187.930282 -283.074872) (xy 187.929787 -283.099479) (xy 187.921892 -283.148056)
			(xy 187.906308 -283.194737) (xy 187.883437 -283.238314) (xy 187.853872 -283.277658) (xy 187.818379 -283.31175)
			(xy 187.777876 -283.339706) (xy 187.733414 -283.360804) (xy 187.686143 -283.374496) (xy 187.637288 -283.380428)
			(xy 187.588113 -283.378447) (xy 187.539894 -283.368603) (xy 187.493878 -283.351151) (xy 187.451257 -283.326544)
			(xy 187.413136 -283.295419) (xy 187.380501 -283.258582) (xy 187.354198 -283.216986) (xy 187.334907 -283.17171)
			(xy 187.32313 -283.123926) (xy 187.31917 -283.074872) (xy 186.980322 -283.074872) (xy 186.979827 -283.099479)
			(xy 186.971932 -283.148056) (xy 186.956348 -283.194737) (xy 186.933477 -283.238314) (xy 186.903912 -283.277658)
			(xy 186.868419 -283.31175) (xy 186.827916 -283.339706) (xy 186.783454 -283.360804) (xy 186.736183 -283.374496)
			(xy 186.687328 -283.380428) (xy 186.638153 -283.378447) (xy 186.589934 -283.368603) (xy 186.543918 -283.351151)
			(xy 186.501297 -283.326544) (xy 186.463176 -283.295419) (xy 186.430541 -283.258582) (xy 186.404238 -283.216986)
			(xy 186.384947 -283.17171) (xy 186.37317 -283.123926) (xy 186.36921 -283.074872) (xy 186.056264 -283.074872)
			(xy 186.056265 -283.074884) (xy 186.052523 -283.124546) (xy 186.041375 -283.173085) (xy 186.023075 -283.219404)
			(xy 185.998035 -283.262454) (xy 185.966823 -283.301263) (xy 185.930144 -283.334952) (xy 185.909712 -283.349192)
			(xy 185.899693 -283.356722) (xy 185.887966 -283.378838) (xy 185.88736 -283.391356) (xy 185.88736 -283.549852)
			(xy 189.69407 -283.549852) (xy 189.69803 -283.500798) (xy 189.709807 -283.453014) (xy 189.729098 -283.407738)
			(xy 189.755401 -283.366142) (xy 189.788036 -283.329305) (xy 189.826157 -283.29818) (xy 189.868778 -283.273573)
			(xy 189.914794 -283.256121) (xy 189.963013 -283.246277) (xy 190.012188 -283.244296) (xy 190.061043 -283.250228)
			(xy 190.108314 -283.26392) (xy 190.152776 -283.285018) (xy 190.193279 -283.312974) (xy 190.228772 -283.347066)
			(xy 190.258337 -283.38641) (xy 190.281208 -283.429987) (xy 190.296792 -283.476668) (xy 190.304687 -283.525245)
			(xy 190.305182 -283.549852) (xy 190.64403 -283.549852) (xy 190.64799 -283.500798) (xy 190.659767 -283.453014)
			(xy 190.679058 -283.407738) (xy 190.705361 -283.366142) (xy 190.737996 -283.329305) (xy 190.776117 -283.29818)
			(xy 190.818738 -283.273573) (xy 190.864754 -283.256121) (xy 190.912973 -283.246277) (xy 190.962148 -283.244296)
			(xy 191.011003 -283.250228) (xy 191.058274 -283.26392) (xy 191.102736 -283.285018) (xy 191.143239 -283.312974)
			(xy 191.178732 -283.347066) (xy 191.208297 -283.38641) (xy 191.231168 -283.429987) (xy 191.246752 -283.476668)
			(xy 191.254647 -283.525245) (xy 191.255142 -283.549852) (xy 191.594244 -283.549852) (xy 191.598204 -283.500798)
			(xy 191.609981 -283.453014) (xy 191.629272 -283.407738) (xy 191.655575 -283.366142) (xy 191.68821 -283.329305)
			(xy 191.726331 -283.29818) (xy 191.768952 -283.273573) (xy 191.814968 -283.256121) (xy 191.863187 -283.246277)
			(xy 191.912362 -283.244296) (xy 191.961217 -283.250228) (xy 192.008488 -283.26392) (xy 192.05295 -283.285018)
			(xy 192.093453 -283.312974) (xy 192.128946 -283.347066) (xy 192.158511 -283.38641) (xy 192.181382 -283.429987)
			(xy 192.196966 -283.476668) (xy 192.204861 -283.525245) (xy 192.205356 -283.549852) (xy 192.204861 -283.574459)
			(xy 192.196966 -283.623036) (xy 192.181382 -283.669717) (xy 192.158511 -283.713294) (xy 192.128946 -283.752638)
			(xy 192.093453 -283.78673) (xy 192.05295 -283.814686) (xy 192.008488 -283.835784) (xy 191.961217 -283.849476)
			(xy 191.912362 -283.855408) (xy 191.863187 -283.853427) (xy 191.814968 -283.843583) (xy 191.768952 -283.826131)
			(xy 191.726331 -283.801524) (xy 191.68821 -283.770399) (xy 191.655575 -283.733562) (xy 191.629272 -283.691966)
			(xy 191.609981 -283.64669) (xy 191.598204 -283.598906) (xy 191.594244 -283.549852) (xy 191.255142 -283.549852)
			(xy 191.254647 -283.574459) (xy 191.246752 -283.623036) (xy 191.231168 -283.669717) (xy 191.208297 -283.713294)
			(xy 191.178732 -283.752638) (xy 191.143239 -283.78673) (xy 191.102736 -283.814686) (xy 191.058274 -283.835784)
			(xy 191.011003 -283.849476) (xy 190.962148 -283.855408) (xy 190.912973 -283.853427) (xy 190.864754 -283.843583)
			(xy 190.818738 -283.826131) (xy 190.776117 -283.801524) (xy 190.737996 -283.770399) (xy 190.705361 -283.733562)
			(xy 190.679058 -283.691966) (xy 190.659767 -283.64669) (xy 190.64799 -283.598906) (xy 190.64403 -283.549852)
			(xy 190.305182 -283.549852) (xy 190.304687 -283.574459) (xy 190.296792 -283.623036) (xy 190.281208 -283.669717)
			(xy 190.258337 -283.713294) (xy 190.228772 -283.752638) (xy 190.193279 -283.78673) (xy 190.152776 -283.814686)
			(xy 190.108314 -283.835784) (xy 190.061043 -283.849476) (xy 190.012188 -283.855408) (xy 189.963013 -283.853427)
			(xy 189.914794 -283.843583) (xy 189.868778 -283.826131) (xy 189.826157 -283.801524) (xy 189.788036 -283.770399)
			(xy 189.755401 -283.733562) (xy 189.729098 -283.691966) (xy 189.709807 -283.64669) (xy 189.69803 -283.598906)
			(xy 189.69407 -283.549852) (xy 185.88736 -283.549852) (xy 185.88736 -283.708348) (xy 185.888001 -283.720857)
			(xy 185.899718 -283.742962) (xy 185.909712 -283.750512) (xy 185.930115 -283.764788) (xy 185.966788 -283.798473)
			(xy 185.997996 -283.837276) (xy 186.023031 -283.88032) (xy 186.041328 -283.926631) (xy 186.052474 -283.975163)
			(xy 186.056215 -284.024818) (xy 186.056214 -284.024832) (xy 186.36921 -284.024832) (xy 186.37317 -283.975778)
			(xy 186.384947 -283.927994) (xy 186.404238 -283.882718) (xy 186.430541 -283.841122) (xy 186.463176 -283.804285)
			(xy 186.501297 -283.77316) (xy 186.543918 -283.748553) (xy 186.589934 -283.731101) (xy 186.638153 -283.721257)
			(xy 186.687328 -283.719276) (xy 186.736183 -283.725208) (xy 186.783454 -283.7389) (xy 186.827916 -283.759998)
			(xy 186.868419 -283.787954) (xy 186.903912 -283.822046) (xy 186.933477 -283.86139) (xy 186.956348 -283.904967)
			(xy 186.971932 -283.951648) (xy 186.979827 -284.000225) (xy 186.980322 -284.024832) (xy 186.979827 -284.049439)
			(xy 186.971932 -284.098016) (xy 186.956348 -284.144697) (xy 186.933477 -284.188274) (xy 186.903912 -284.227618)
			(xy 186.868419 -284.26171) (xy 186.827916 -284.289666) (xy 186.783454 -284.310764) (xy 186.736183 -284.324456)
			(xy 186.687328 -284.330388) (xy 186.638153 -284.328407) (xy 186.589934 -284.318563) (xy 186.543918 -284.301111)
			(xy 186.501297 -284.276504) (xy 186.463176 -284.245379) (xy 186.430541 -284.208542) (xy 186.404238 -284.166946)
			(xy 186.384947 -284.12167) (xy 186.37317 -284.073886) (xy 186.36921 -284.024832) (xy 186.056214 -284.024832)
			(xy 186.052468 -284.074472) (xy 186.041318 -284.123003) (xy 186.023015 -284.169312) (xy 185.997975 -284.212354)
			(xy 185.966764 -284.251154) (xy 185.930087 -284.284834) (xy 185.909712 -284.299152) (xy 185.899703 -284.306686)
			(xy 185.888003 -284.328803) (xy 185.88736 -284.341316) (xy 185.88736 -284.499812) (xy 189.69407 -284.499812)
			(xy 189.69803 -284.450758) (xy 189.709807 -284.402974) (xy 189.729098 -284.357698) (xy 189.755401 -284.316102)
			(xy 189.788036 -284.279265) (xy 189.826157 -284.24814) (xy 189.868778 -284.223533) (xy 189.914794 -284.206081)
			(xy 189.963013 -284.196237) (xy 190.012188 -284.194256) (xy 190.061043 -284.200188) (xy 190.108314 -284.21388)
			(xy 190.152776 -284.234978) (xy 190.193279 -284.262934) (xy 190.228772 -284.297026) (xy 190.258337 -284.33637)
			(xy 190.281208 -284.379947) (xy 190.296792 -284.426628) (xy 190.304687 -284.475205) (xy 190.305182 -284.499812)
			(xy 190.64403 -284.499812) (xy 190.64799 -284.450758) (xy 190.659767 -284.402974) (xy 190.679058 -284.357698)
			(xy 190.705361 -284.316102) (xy 190.737996 -284.279265) (xy 190.776117 -284.24814) (xy 190.818738 -284.223533)
			(xy 190.864754 -284.206081) (xy 190.912973 -284.196237) (xy 190.962148 -284.194256) (xy 191.011003 -284.200188)
			(xy 191.058274 -284.21388) (xy 191.102736 -284.234978) (xy 191.143239 -284.262934) (xy 191.178732 -284.297026)
			(xy 191.208297 -284.33637) (xy 191.231168 -284.379947) (xy 191.246752 -284.426628) (xy 191.254647 -284.475205)
			(xy 191.255142 -284.499812) (xy 191.594244 -284.499812) (xy 191.598204 -284.450758) (xy 191.609981 -284.402974)
			(xy 191.629272 -284.357698) (xy 191.655575 -284.316102) (xy 191.68821 -284.279265) (xy 191.726331 -284.24814)
			(xy 191.768952 -284.223533) (xy 191.814968 -284.206081) (xy 191.863187 -284.196237) (xy 191.912362 -284.194256)
			(xy 191.961217 -284.200188) (xy 192.008488 -284.21388) (xy 192.05295 -284.234978) (xy 192.093453 -284.262934)
			(xy 192.128946 -284.297026) (xy 192.158511 -284.33637) (xy 192.181382 -284.379947) (xy 192.196966 -284.426628)
			(xy 192.204861 -284.475205) (xy 192.205356 -284.499812) (xy 192.204861 -284.524419) (xy 192.196966 -284.572996)
			(xy 192.181382 -284.619677) (xy 192.158511 -284.663254) (xy 192.128946 -284.702598) (xy 192.093453 -284.73669)
			(xy 192.05295 -284.764646) (xy 192.008488 -284.785744) (xy 191.961217 -284.799436) (xy 191.912362 -284.805368)
			(xy 191.863187 -284.803387) (xy 191.814968 -284.793543) (xy 191.768952 -284.776091) (xy 191.726331 -284.751484)
			(xy 191.68821 -284.720359) (xy 191.655575 -284.683522) (xy 191.629272 -284.641926) (xy 191.609981 -284.59665)
			(xy 191.598204 -284.548866) (xy 191.594244 -284.499812) (xy 191.255142 -284.499812) (xy 191.254647 -284.524419)
			(xy 191.246752 -284.572996) (xy 191.231168 -284.619677) (xy 191.208297 -284.663254) (xy 191.178732 -284.702598)
			(xy 191.143239 -284.73669) (xy 191.102736 -284.764646) (xy 191.058274 -284.785744) (xy 191.011003 -284.799436)
			(xy 190.962148 -284.805368) (xy 190.912973 -284.803387) (xy 190.864754 -284.793543) (xy 190.818738 -284.776091)
			(xy 190.776117 -284.751484) (xy 190.737996 -284.720359) (xy 190.705361 -284.683522) (xy 190.679058 -284.641926)
			(xy 190.659767 -284.59665) (xy 190.64799 -284.548866) (xy 190.64403 -284.499812) (xy 190.305182 -284.499812)
			(xy 190.304687 -284.524419) (xy 190.296792 -284.572996) (xy 190.281208 -284.619677) (xy 190.258337 -284.663254)
			(xy 190.228772 -284.702598) (xy 190.193279 -284.73669) (xy 190.152776 -284.764646) (xy 190.108314 -284.785744)
			(xy 190.061043 -284.799436) (xy 190.012188 -284.805368) (xy 189.963013 -284.803387) (xy 189.914794 -284.793543)
			(xy 189.868778 -284.776091) (xy 189.826157 -284.751484) (xy 189.788036 -284.720359) (xy 189.755401 -284.683522)
			(xy 189.729098 -284.641926) (xy 189.709807 -284.59665) (xy 189.69803 -284.548866) (xy 189.69407 -284.499812)
			(xy 185.88736 -284.499812) (xy 185.88736 -284.658308) (xy 185.888014 -284.67081) (xy 185.899745 -284.692893)
			(xy 185.909712 -284.700472) (xy 185.930118 -284.714748) (xy 185.966797 -284.748433) (xy 185.99801 -284.787238)
			(xy 186.023051 -284.830285) (xy 186.041353 -284.8766) (xy 186.052503 -284.925136) (xy 186.056249 -284.974792)
			(xy 186.36921 -284.974792) (xy 186.37317 -284.925738) (xy 186.384947 -284.877954) (xy 186.404238 -284.832678)
			(xy 186.430541 -284.791082) (xy 186.463176 -284.754245) (xy 186.501297 -284.72312) (xy 186.543918 -284.698513)
			(xy 186.589934 -284.681061) (xy 186.638153 -284.671217) (xy 186.687328 -284.669236) (xy 186.736183 -284.675168)
			(xy 186.783454 -284.68886) (xy 186.827916 -284.709958) (xy 186.868419 -284.737914) (xy 186.903912 -284.772006)
			(xy 186.933477 -284.81135) (xy 186.956348 -284.854927) (xy 186.971932 -284.901608) (xy 186.979827 -284.950185)
			(xy 186.980322 -284.974792) (xy 186.979827 -284.999399) (xy 186.971932 -285.047976) (xy 186.956348 -285.094657)
			(xy 186.933477 -285.138234) (xy 186.903912 -285.177578) (xy 186.868419 -285.21167) (xy 186.827916 -285.239626)
			(xy 186.783454 -285.260724) (xy 186.736183 -285.274416) (xy 186.687328 -285.280348) (xy 186.638153 -285.278367)
			(xy 186.589934 -285.268523) (xy 186.543918 -285.251071) (xy 186.501297 -285.226464) (xy 186.463176 -285.195339)
			(xy 186.430541 -285.158502) (xy 186.404238 -285.116906) (xy 186.384947 -285.07163) (xy 186.37317 -285.023846)
			(xy 186.36921 -284.974792) (xy 186.056249 -284.974792) (xy 186.056249 -284.974796) (xy 186.052505 -285.024455)
			(xy 186.041356 -285.072991) (xy 186.023055 -285.119307) (xy 185.998015 -285.162354) (xy 185.966803 -285.20116)
			(xy 185.930125 -285.234846) (xy 185.909712 -285.249112) (xy 185.899697 -285.256643) (xy 185.887979 -285.278759)
			(xy 185.88736 -285.291276) (xy 185.88736 -285.449772) (xy 189.69407 -285.449772) (xy 189.69803 -285.400718)
			(xy 189.709807 -285.352934) (xy 189.729098 -285.307658) (xy 189.755401 -285.266062) (xy 189.788036 -285.229225)
			(xy 189.826157 -285.1981) (xy 189.868778 -285.173493) (xy 189.914794 -285.156041) (xy 189.963013 -285.146197)
			(xy 190.012188 -285.144216) (xy 190.061043 -285.150148) (xy 190.108314 -285.16384) (xy 190.152776 -285.184938)
			(xy 190.193279 -285.212894) (xy 190.228772 -285.246986) (xy 190.258337 -285.28633) (xy 190.281208 -285.329907)
			(xy 190.296792 -285.376588) (xy 190.304687 -285.425165) (xy 190.305182 -285.449772) (xy 190.64403 -285.449772)
			(xy 190.64799 -285.400718) (xy 190.659767 -285.352934) (xy 190.679058 -285.307658) (xy 190.705361 -285.266062)
			(xy 190.737996 -285.229225) (xy 190.776117 -285.1981) (xy 190.818738 -285.173493) (xy 190.864754 -285.156041)
			(xy 190.912973 -285.146197) (xy 190.962148 -285.144216) (xy 191.011003 -285.150148) (xy 191.058274 -285.16384)
			(xy 191.102736 -285.184938) (xy 191.143239 -285.212894) (xy 191.178732 -285.246986) (xy 191.208297 -285.28633)
			(xy 191.231168 -285.329907) (xy 191.246752 -285.376588) (xy 191.254647 -285.425165) (xy 191.255142 -285.449772)
			(xy 191.594244 -285.449772) (xy 191.598204 -285.400718) (xy 191.609981 -285.352934) (xy 191.629272 -285.307658)
			(xy 191.655575 -285.266062) (xy 191.68821 -285.229225) (xy 191.726331 -285.1981) (xy 191.768952 -285.173493)
			(xy 191.814968 -285.156041) (xy 191.863187 -285.146197) (xy 191.912362 -285.144216) (xy 191.961217 -285.150148)
			(xy 192.008488 -285.16384) (xy 192.05295 -285.184938) (xy 192.093453 -285.212894) (xy 192.128946 -285.246986)
			(xy 192.158511 -285.28633) (xy 192.181382 -285.329907) (xy 192.196966 -285.376588) (xy 192.204861 -285.425165)
			(xy 192.205356 -285.449772) (xy 192.204861 -285.474379) (xy 192.196966 -285.522956) (xy 192.181382 -285.569637)
			(xy 192.158511 -285.613214) (xy 192.128946 -285.652558) (xy 192.093453 -285.68665) (xy 192.05295 -285.714606)
			(xy 192.008488 -285.735704) (xy 191.961217 -285.749396) (xy 191.912362 -285.755328) (xy 191.863187 -285.753347)
			(xy 191.814968 -285.743503) (xy 191.768952 -285.726051) (xy 191.726331 -285.701444) (xy 191.68821 -285.670319)
			(xy 191.655575 -285.633482) (xy 191.629272 -285.591886) (xy 191.609981 -285.54661) (xy 191.598204 -285.498826)
			(xy 191.594244 -285.449772) (xy 191.255142 -285.449772) (xy 191.254647 -285.474379) (xy 191.246752 -285.522956)
			(xy 191.231168 -285.569637) (xy 191.208297 -285.613214) (xy 191.178732 -285.652558) (xy 191.143239 -285.68665)
			(xy 191.102736 -285.714606) (xy 191.058274 -285.735704) (xy 191.011003 -285.749396) (xy 190.962148 -285.755328)
			(xy 190.912973 -285.753347) (xy 190.864754 -285.743503) (xy 190.818738 -285.726051) (xy 190.776117 -285.701444)
			(xy 190.737996 -285.670319) (xy 190.705361 -285.633482) (xy 190.679058 -285.591886) (xy 190.659767 -285.54661)
			(xy 190.64799 -285.498826) (xy 190.64403 -285.449772) (xy 190.305182 -285.449772) (xy 190.304687 -285.474379)
			(xy 190.296792 -285.522956) (xy 190.281208 -285.569637) (xy 190.258337 -285.613214) (xy 190.228772 -285.652558)
			(xy 190.193279 -285.68665) (xy 190.152776 -285.714606) (xy 190.108314 -285.735704) (xy 190.061043 -285.749396)
			(xy 190.012188 -285.755328) (xy 189.963013 -285.753347) (xy 189.914794 -285.743503) (xy 189.868778 -285.726051)
			(xy 189.826157 -285.701444) (xy 189.788036 -285.670319) (xy 189.755401 -285.633482) (xy 189.729098 -285.591886)
			(xy 189.709807 -285.54661) (xy 189.69803 -285.498826) (xy 189.69407 -285.449772) (xy 185.88736 -285.449772)
			(xy 185.88736 -285.608268) (xy 185.888005 -285.620774) (xy 185.899727 -285.642872) (xy 185.909712 -285.650432)
			(xy 185.930121 -285.664708) (xy 185.966806 -285.698394) (xy 185.998025 -285.737201) (xy 186.023071 -285.780251)
			(xy 186.041378 -285.826569) (xy 186.052533 -285.875109) (xy 186.05628 -285.924752) (xy 186.36921 -285.924752)
			(xy 186.37317 -285.875698) (xy 186.384947 -285.827914) (xy 186.404238 -285.782638) (xy 186.430541 -285.741042)
			(xy 186.463176 -285.704205) (xy 186.501297 -285.67308) (xy 186.543918 -285.648473) (xy 186.589934 -285.631021)
			(xy 186.638153 -285.621177) (xy 186.687328 -285.619196) (xy 186.736183 -285.625128) (xy 186.783454 -285.63882)
			(xy 186.827916 -285.659918) (xy 186.868419 -285.687874) (xy 186.903912 -285.721966) (xy 186.933477 -285.76131)
			(xy 186.956348 -285.804887) (xy 186.971932 -285.851568) (xy 186.979827 -285.900145) (xy 186.980322 -285.924752)
			(xy 186.979827 -285.949359) (xy 186.971932 -285.997936) (xy 186.956348 -286.044617) (xy 186.933477 -286.088194)
			(xy 186.903912 -286.127538) (xy 186.868419 -286.16163) (xy 186.827916 -286.189586) (xy 186.783454 -286.210684)
			(xy 186.736183 -286.224376) (xy 186.687328 -286.230308) (xy 186.638153 -286.228327) (xy 186.589934 -286.218483)
			(xy 186.543918 -286.201031) (xy 186.501297 -286.176424) (xy 186.463176 -286.145299) (xy 186.430541 -286.108462)
			(xy 186.404238 -286.066866) (xy 186.384947 -286.02159) (xy 186.37317 -285.973806) (xy 186.36921 -285.924752)
			(xy 186.05628 -285.924752) (xy 186.056282 -285.924773) (xy 186.052541 -285.974438) (xy 186.041394 -286.02298)
			(xy 186.023095 -286.069301) (xy 185.998055 -286.112355) (xy 185.966843 -286.151166) (xy 185.930163 -286.184859)
			(xy 185.909712 -286.199072) (xy 185.89969 -286.206601) (xy 185.887955 -286.228716) (xy 185.88736 -286.241236)
			(xy 185.88736 -286.399732) (xy 189.69407 -286.399732) (xy 189.69803 -286.350678) (xy 189.709807 -286.302894)
			(xy 189.729098 -286.257618) (xy 189.755401 -286.216022) (xy 189.788036 -286.179185) (xy 189.826157 -286.14806)
			(xy 189.868778 -286.123453) (xy 189.914794 -286.106001) (xy 189.963013 -286.096157) (xy 190.012188 -286.094176)
			(xy 190.061043 -286.100108) (xy 190.108314 -286.1138) (xy 190.152776 -286.134898) (xy 190.193279 -286.162854)
			(xy 190.228772 -286.196946) (xy 190.258337 -286.23629) (xy 190.281208 -286.279867) (xy 190.296792 -286.326548)
			(xy 190.304687 -286.375125) (xy 190.305182 -286.399732) (xy 190.644284 -286.399732) (xy 190.648244 -286.350678)
			(xy 190.660021 -286.302894) (xy 190.679312 -286.257618) (xy 190.705615 -286.216022) (xy 190.73825 -286.179185)
			(xy 190.776371 -286.14806) (xy 190.818992 -286.123453) (xy 190.865008 -286.106001) (xy 190.913227 -286.096157)
			(xy 190.962402 -286.094176) (xy 191.011257 -286.100108) (xy 191.058528 -286.1138) (xy 191.10299 -286.134898)
			(xy 191.143493 -286.162854) (xy 191.178986 -286.196946) (xy 191.208551 -286.23629) (xy 191.231422 -286.279867)
			(xy 191.247006 -286.326548) (xy 191.254901 -286.375125) (xy 191.255396 -286.399732) (xy 191.594244 -286.399732)
			(xy 191.598204 -286.350678) (xy 191.609981 -286.302894) (xy 191.629272 -286.257618) (xy 191.655575 -286.216022)
			(xy 191.68821 -286.179185) (xy 191.726331 -286.14806) (xy 191.768952 -286.123453) (xy 191.814968 -286.106001)
			(xy 191.863187 -286.096157) (xy 191.912362 -286.094176) (xy 191.961217 -286.100108) (xy 192.008488 -286.1138)
			(xy 192.05295 -286.134898) (xy 192.093453 -286.162854) (xy 192.128946 -286.196946) (xy 192.158511 -286.23629)
			(xy 192.181382 -286.279867) (xy 192.196966 -286.326548) (xy 192.204861 -286.375125) (xy 192.205356 -286.399732)
			(xy 192.204861 -286.424339) (xy 192.196966 -286.472916) (xy 192.181382 -286.519597) (xy 192.158511 -286.563174)
			(xy 192.128946 -286.602518) (xy 192.093453 -286.63661) (xy 192.05295 -286.664566) (xy 192.008488 -286.685664)
			(xy 191.961217 -286.699356) (xy 191.912362 -286.705288) (xy 191.863187 -286.703307) (xy 191.814968 -286.693463)
			(xy 191.768952 -286.676011) (xy 191.726331 -286.651404) (xy 191.68821 -286.620279) (xy 191.655575 -286.583442)
			(xy 191.629272 -286.541846) (xy 191.609981 -286.49657) (xy 191.598204 -286.448786) (xy 191.594244 -286.399732)
			(xy 191.255396 -286.399732) (xy 191.254901 -286.424339) (xy 191.247006 -286.472916) (xy 191.231422 -286.519597)
			(xy 191.208551 -286.563174) (xy 191.178986 -286.602518) (xy 191.143493 -286.63661) (xy 191.10299 -286.664566)
			(xy 191.058528 -286.685664) (xy 191.011257 -286.699356) (xy 190.962402 -286.705288) (xy 190.913227 -286.703307)
			(xy 190.865008 -286.693463) (xy 190.818992 -286.676011) (xy 190.776371 -286.651404) (xy 190.73825 -286.620279)
			(xy 190.705615 -286.583442) (xy 190.679312 -286.541846) (xy 190.660021 -286.49657) (xy 190.648244 -286.448786)
			(xy 190.644284 -286.399732) (xy 190.305182 -286.399732) (xy 190.304687 -286.424339) (xy 190.296792 -286.472916)
			(xy 190.281208 -286.519597) (xy 190.258337 -286.563174) (xy 190.228772 -286.602518) (xy 190.193279 -286.63661)
			(xy 190.152776 -286.664566) (xy 190.108314 -286.685664) (xy 190.061043 -286.699356) (xy 190.012188 -286.705288)
			(xy 189.963013 -286.703307) (xy 189.914794 -286.693463) (xy 189.868778 -286.676011) (xy 189.826157 -286.651404)
			(xy 189.788036 -286.620279) (xy 189.755401 -286.583442) (xy 189.729098 -286.541846) (xy 189.709807 -286.49657)
			(xy 189.69803 -286.448786) (xy 189.69407 -286.399732) (xy 185.88736 -286.399732) (xy 185.88736 -286.558482)
			(xy 185.888008 -286.570987) (xy 185.899733 -286.59308) (xy 185.909712 -286.600646) (xy 185.93012 -286.614922)
			(xy 185.966803 -286.648608) (xy 185.99802 -286.687414) (xy 186.023064 -286.730463) (xy 186.04137 -286.77678)
			(xy 186.052522 -286.825319) (xy 186.056269 -286.874966) (xy 186.36921 -286.874966) (xy 186.37317 -286.825912)
			(xy 186.384947 -286.778128) (xy 186.404238 -286.732852) (xy 186.430541 -286.691256) (xy 186.463176 -286.654419)
			(xy 186.501297 -286.623294) (xy 186.543918 -286.598687) (xy 186.589934 -286.581235) (xy 186.638153 -286.571391)
			(xy 186.687328 -286.56941) (xy 186.736183 -286.575342) (xy 186.783454 -286.589034) (xy 186.827916 -286.610132)
			(xy 186.868419 -286.638088) (xy 186.903912 -286.67218) (xy 186.933477 -286.711524) (xy 186.956348 -286.755101)
			(xy 186.971932 -286.801782) (xy 186.979827 -286.850359) (xy 186.980322 -286.874966) (xy 186.979827 -286.899573)
			(xy 186.971932 -286.94815) (xy 186.956348 -286.994831) (xy 186.933477 -287.038408) (xy 186.903912 -287.077752)
			(xy 186.868419 -287.111844) (xy 186.827916 -287.1398) (xy 186.783454 -287.160898) (xy 186.736183 -287.17459)
			(xy 186.687328 -287.180522) (xy 186.638153 -287.178541) (xy 186.589934 -287.168697) (xy 186.543918 -287.151245)
			(xy 186.501297 -287.126638) (xy 186.463176 -287.095513) (xy 186.430541 -287.058676) (xy 186.404238 -287.01708)
			(xy 186.384947 -286.971804) (xy 186.37317 -286.92402) (xy 186.36921 -286.874966) (xy 186.056269 -286.874966)
			(xy 186.05627 -286.874981) (xy 186.052528 -286.924644) (xy 186.041381 -286.973184) (xy 186.023081 -287.019503)
			(xy 185.998041 -287.062555) (xy 185.966829 -287.101364) (xy 185.93015 -287.135054) (xy 185.909712 -287.149286)
			(xy 185.899692 -287.156815) (xy 185.887963 -287.178931) (xy 185.88736 -287.19145) (xy 185.88736 -287.349946)
			(xy 189.69407 -287.349946) (xy 189.69803 -287.300892) (xy 189.709807 -287.253108) (xy 189.729098 -287.207832)
			(xy 189.755401 -287.166236) (xy 189.788036 -287.129399) (xy 189.826157 -287.098274) (xy 189.868778 -287.073667)
			(xy 189.914794 -287.056215) (xy 189.963013 -287.046371) (xy 190.012188 -287.04439) (xy 190.061043 -287.050322)
			(xy 190.108314 -287.064014) (xy 190.152776 -287.085112) (xy 190.193279 -287.113068) (xy 190.228772 -287.14716)
			(xy 190.258337 -287.186504) (xy 190.281208 -287.230081) (xy 190.296792 -287.276762) (xy 190.304687 -287.325339)
			(xy 190.305182 -287.349946) (xy 190.64403 -287.349946) (xy 190.64799 -287.300892) (xy 190.659767 -287.253108)
			(xy 190.679058 -287.207832) (xy 190.705361 -287.166236) (xy 190.737996 -287.129399) (xy 190.776117 -287.098274)
			(xy 190.818738 -287.073667) (xy 190.864754 -287.056215) (xy 190.912973 -287.046371) (xy 190.962148 -287.04439)
			(xy 191.011003 -287.050322) (xy 191.058274 -287.064014) (xy 191.102736 -287.085112) (xy 191.143239 -287.113068)
			(xy 191.178732 -287.14716) (xy 191.208297 -287.186504) (xy 191.231168 -287.230081) (xy 191.246752 -287.276762)
			(xy 191.254647 -287.325339) (xy 191.255142 -287.349946) (xy 191.594244 -287.349946) (xy 191.598204 -287.300892)
			(xy 191.609981 -287.253108) (xy 191.629272 -287.207832) (xy 191.655575 -287.166236) (xy 191.68821 -287.129399)
			(xy 191.726331 -287.098274) (xy 191.768952 -287.073667) (xy 191.814968 -287.056215) (xy 191.863187 -287.046371)
			(xy 191.912362 -287.04439) (xy 191.961217 -287.050322) (xy 192.008488 -287.064014) (xy 192.05295 -287.085112)
			(xy 192.093453 -287.113068) (xy 192.128946 -287.14716) (xy 192.158511 -287.186504) (xy 192.181382 -287.230081)
			(xy 192.196966 -287.276762) (xy 192.204861 -287.325339) (xy 192.205356 -287.349946) (xy 192.204861 -287.374553)
			(xy 192.196966 -287.42313) (xy 192.181382 -287.469811) (xy 192.158511 -287.513388) (xy 192.128946 -287.552732)
			(xy 192.093453 -287.586824) (xy 192.05295 -287.61478) (xy 192.008488 -287.635878) (xy 191.961217 -287.64957)
			(xy 191.912362 -287.655502) (xy 191.863187 -287.653521) (xy 191.814968 -287.643677) (xy 191.768952 -287.626225)
			(xy 191.726331 -287.601618) (xy 191.68821 -287.570493) (xy 191.655575 -287.533656) (xy 191.629272 -287.49206)
			(xy 191.609981 -287.446784) (xy 191.598204 -287.399) (xy 191.594244 -287.349946) (xy 191.255142 -287.349946)
			(xy 191.254647 -287.374553) (xy 191.246752 -287.42313) (xy 191.231168 -287.469811) (xy 191.208297 -287.513388)
			(xy 191.178732 -287.552732) (xy 191.143239 -287.586824) (xy 191.102736 -287.61478) (xy 191.058274 -287.635878)
			(xy 191.011003 -287.64957) (xy 190.962148 -287.655502) (xy 190.912973 -287.653521) (xy 190.864754 -287.643677)
			(xy 190.818738 -287.626225) (xy 190.776117 -287.601618) (xy 190.737996 -287.570493) (xy 190.705361 -287.533656)
			(xy 190.679058 -287.49206) (xy 190.659767 -287.446784) (xy 190.64799 -287.399) (xy 190.64403 -287.349946)
			(xy 190.305182 -287.349946) (xy 190.304687 -287.374553) (xy 190.296792 -287.42313) (xy 190.281208 -287.469811)
			(xy 190.258337 -287.513388) (xy 190.228772 -287.552732) (xy 190.193279 -287.586824) (xy 190.152776 -287.61478)
			(xy 190.108314 -287.635878) (xy 190.061043 -287.64957) (xy 190.012188 -287.655502) (xy 189.963013 -287.653521)
			(xy 189.914794 -287.643677) (xy 189.868778 -287.626225) (xy 189.826157 -287.601618) (xy 189.788036 -287.570493)
			(xy 189.755401 -287.533656) (xy 189.729098 -287.49206) (xy 189.709807 -287.446784) (xy 189.69803 -287.399)
			(xy 189.69407 -287.349946) (xy 185.88736 -287.349946) (xy 185.88736 -287.824926) (xy 186.36921 -287.824926)
			(xy 186.37317 -287.775872) (xy 186.384947 -287.728088) (xy 186.404238 -287.682812) (xy 186.430541 -287.641216)
			(xy 186.463176 -287.604379) (xy 186.501297 -287.573254) (xy 186.543918 -287.548647) (xy 186.589934 -287.531195)
			(xy 186.638153 -287.521351) (xy 186.687328 -287.51937) (xy 186.736183 -287.525302) (xy 186.783454 -287.538994)
			(xy 186.827916 -287.560092) (xy 186.868419 -287.588048) (xy 186.903912 -287.62214) (xy 186.933477 -287.661484)
			(xy 186.956348 -287.705061) (xy 186.971932 -287.751742) (xy 186.979827 -287.800319) (xy 186.980322 -287.824926)
			(xy 186.979827 -287.849533) (xy 186.971932 -287.89811) (xy 186.956348 -287.944791) (xy 186.933477 -287.988368)
			(xy 186.903912 -288.027712) (xy 186.868419 -288.061804) (xy 186.827916 -288.08976) (xy 186.783454 -288.110858)
			(xy 186.736183 -288.12455) (xy 186.687328 -288.130482) (xy 186.638153 -288.128501) (xy 186.589934 -288.118657)
			(xy 186.543918 -288.101205) (xy 186.501297 -288.076598) (xy 186.463176 -288.045473) (xy 186.430541 -288.008636)
			(xy 186.404238 -287.96704) (xy 186.384947 -287.921764) (xy 186.37317 -287.87398) (xy 186.36921 -287.824926)
			(xy 185.88736 -287.824926) (xy 185.88736 -288.299906) (xy 189.69407 -288.299906) (xy 189.69803 -288.250852)
			(xy 189.709807 -288.203068) (xy 189.729098 -288.157792) (xy 189.755401 -288.116196) (xy 189.788036 -288.079359)
			(xy 189.826157 -288.048234) (xy 189.868778 -288.023627) (xy 189.914794 -288.006175) (xy 189.963013 -287.996331)
			(xy 190.012188 -287.99435) (xy 190.061043 -288.000282) (xy 190.108314 -288.013974) (xy 190.152776 -288.035072)
			(xy 190.193279 -288.063028) (xy 190.228772 -288.09712) (xy 190.258337 -288.136464) (xy 190.281208 -288.180041)
			(xy 190.296792 -288.226722) (xy 190.304687 -288.275299) (xy 190.305182 -288.299906) (xy 190.644284 -288.299906)
			(xy 190.648244 -288.250852) (xy 190.660021 -288.203068) (xy 190.679312 -288.157792) (xy 190.705615 -288.116196)
			(xy 190.73825 -288.079359) (xy 190.776371 -288.048234) (xy 190.818992 -288.023627) (xy 190.865008 -288.006175)
			(xy 190.913227 -287.996331) (xy 190.962402 -287.99435) (xy 191.011257 -288.000282) (xy 191.058528 -288.013974)
			(xy 191.10299 -288.035072) (xy 191.143493 -288.063028) (xy 191.178986 -288.09712) (xy 191.208551 -288.136464)
			(xy 191.231422 -288.180041) (xy 191.247006 -288.226722) (xy 191.254901 -288.275299) (xy 191.255396 -288.299906)
			(xy 191.594244 -288.299906) (xy 191.598204 -288.250852) (xy 191.609981 -288.203068) (xy 191.629272 -288.157792)
			(xy 191.655575 -288.116196) (xy 191.68821 -288.079359) (xy 191.726331 -288.048234) (xy 191.768952 -288.023627)
			(xy 191.814968 -288.006175) (xy 191.863187 -287.996331) (xy 191.912362 -287.99435) (xy 191.961217 -288.000282)
			(xy 192.008488 -288.013974) (xy 192.05295 -288.035072) (xy 192.093453 -288.063028) (xy 192.128946 -288.09712)
			(xy 192.158511 -288.136464) (xy 192.181382 -288.180041) (xy 192.196966 -288.226722) (xy 192.204861 -288.275299)
			(xy 192.205356 -288.299906) (xy 192.204861 -288.324513) (xy 192.196966 -288.37309) (xy 192.181382 -288.419771)
			(xy 192.158511 -288.463348) (xy 192.128946 -288.502692) (xy 192.093453 -288.536784) (xy 192.05295 -288.56474)
			(xy 192.008488 -288.585838) (xy 191.961217 -288.59953) (xy 191.912362 -288.605462) (xy 191.863187 -288.603481)
			(xy 191.814968 -288.593637) (xy 191.768952 -288.576185) (xy 191.726331 -288.551578) (xy 191.68821 -288.520453)
			(xy 191.655575 -288.483616) (xy 191.629272 -288.44202) (xy 191.609981 -288.396744) (xy 191.598204 -288.34896)
			(xy 191.594244 -288.299906) (xy 191.255396 -288.299906) (xy 191.254901 -288.324513) (xy 191.247006 -288.37309)
			(xy 191.231422 -288.419771) (xy 191.208551 -288.463348) (xy 191.178986 -288.502692) (xy 191.143493 -288.536784)
			(xy 191.10299 -288.56474) (xy 191.058528 -288.585838) (xy 191.011257 -288.59953) (xy 190.962402 -288.605462)
			(xy 190.913227 -288.603481) (xy 190.865008 -288.593637) (xy 190.818992 -288.576185) (xy 190.776371 -288.551578)
			(xy 190.73825 -288.520453) (xy 190.705615 -288.483616) (xy 190.679312 -288.44202) (xy 190.660021 -288.396744)
			(xy 190.648244 -288.34896) (xy 190.644284 -288.299906) (xy 190.305182 -288.299906) (xy 190.304687 -288.324513)
			(xy 190.296792 -288.37309) (xy 190.281208 -288.419771) (xy 190.258337 -288.463348) (xy 190.228772 -288.502692)
			(xy 190.193279 -288.536784) (xy 190.152776 -288.56474) (xy 190.108314 -288.585838) (xy 190.061043 -288.59953)
			(xy 190.012188 -288.605462) (xy 189.963013 -288.603481) (xy 189.914794 -288.593637) (xy 189.868778 -288.576185)
			(xy 189.826157 -288.551578) (xy 189.788036 -288.520453) (xy 189.755401 -288.483616) (xy 189.729098 -288.44202)
			(xy 189.709807 -288.396744) (xy 189.69803 -288.34896) (xy 189.69407 -288.299906) (xy 185.88736 -288.299906)
			(xy 185.88736 -288.458402) (xy 185.888012 -288.470904) (xy 185.899743 -288.49299) (xy 185.909712 -288.500566)
			(xy 185.930119 -288.514842) (xy 185.966799 -288.548528) (xy 185.998013 -288.587333) (xy 186.023054 -288.63038)
			(xy 186.041357 -288.676696) (xy 186.052508 -288.725232) (xy 186.056254 -288.774886) (xy 186.36921 -288.774886)
			(xy 186.37317 -288.725832) (xy 186.384947 -288.678048) (xy 186.404238 -288.632772) (xy 186.430541 -288.591176)
			(xy 186.463176 -288.554339) (xy 186.501297 -288.523214) (xy 186.543918 -288.498607) (xy 186.589934 -288.481155)
			(xy 186.638153 -288.471311) (xy 186.687328 -288.46933) (xy 186.736183 -288.475262) (xy 186.783454 -288.488954)
			(xy 186.827916 -288.510052) (xy 186.868419 -288.538008) (xy 186.903912 -288.5721) (xy 186.933477 -288.611444)
			(xy 186.956348 -288.655021) (xy 186.971932 -288.701702) (xy 186.979827 -288.750279) (xy 186.980322 -288.774886)
			(xy 187.31917 -288.774886) (xy 187.32313 -288.725832) (xy 187.334907 -288.678048) (xy 187.354198 -288.632772)
			(xy 187.380501 -288.591176) (xy 187.413136 -288.554339) (xy 187.451257 -288.523214) (xy 187.493878 -288.498607)
			(xy 187.539894 -288.481155) (xy 187.588113 -288.471311) (xy 187.637288 -288.46933) (xy 187.686143 -288.475262)
			(xy 187.733414 -288.488954) (xy 187.777876 -288.510052) (xy 187.818379 -288.538008) (xy 187.853872 -288.5721)
			(xy 187.883437 -288.611444) (xy 187.906308 -288.655021) (xy 187.921892 -288.701702) (xy 187.929787 -288.750279)
			(xy 187.930282 -288.774886) (xy 188.26913 -288.774886) (xy 188.27309 -288.725832) (xy 188.284867 -288.678048)
			(xy 188.304158 -288.632772) (xy 188.330461 -288.591176) (xy 188.363096 -288.554339) (xy 188.401217 -288.523214)
			(xy 188.443838 -288.498607) (xy 188.489854 -288.481155) (xy 188.538073 -288.471311) (xy 188.587248 -288.46933)
			(xy 188.636103 -288.475262) (xy 188.683374 -288.488954) (xy 188.727836 -288.510052) (xy 188.768339 -288.538008)
			(xy 188.803832 -288.5721) (xy 188.833397 -288.611444) (xy 188.856268 -288.655021) (xy 188.871852 -288.701702)
			(xy 188.879747 -288.750279) (xy 188.880242 -288.774886) (xy 188.879747 -288.799493) (xy 188.871852 -288.84807)
			(xy 188.856268 -288.894751) (xy 188.833397 -288.938328) (xy 188.803832 -288.977672) (xy 188.768339 -289.011764)
			(xy 188.727836 -289.03972) (xy 188.683374 -289.060818) (xy 188.636103 -289.07451) (xy 188.587248 -289.080442)
			(xy 188.538073 -289.078461) (xy 188.489854 -289.068617) (xy 188.443838 -289.051165) (xy 188.401217 -289.026558)
			(xy 188.363096 -288.995433) (xy 188.330461 -288.958596) (xy 188.304158 -288.917) (xy 188.284867 -288.871724)
			(xy 188.27309 -288.82394) (xy 188.26913 -288.774886) (xy 187.930282 -288.774886) (xy 187.929787 -288.799493)
			(xy 187.921892 -288.84807) (xy 187.906308 -288.894751) (xy 187.883437 -288.938328) (xy 187.853872 -288.977672)
			(xy 187.818379 -289.011764) (xy 187.777876 -289.03972) (xy 187.733414 -289.060818) (xy 187.686143 -289.07451)
			(xy 187.637288 -289.080442) (xy 187.588113 -289.078461) (xy 187.539894 -289.068617) (xy 187.493878 -289.051165)
			(xy 187.451257 -289.026558) (xy 187.413136 -288.995433) (xy 187.380501 -288.958596) (xy 187.354198 -288.917)
			(xy 187.334907 -288.871724) (xy 187.32313 -288.82394) (xy 187.31917 -288.774886) (xy 186.980322 -288.774886)
			(xy 186.979827 -288.799493) (xy 186.971932 -288.84807) (xy 186.956348 -288.894751) (xy 186.933477 -288.938328)
			(xy 186.903912 -288.977672) (xy 186.868419 -289.011764) (xy 186.827916 -289.03972) (xy 186.783454 -289.060818)
			(xy 186.736183 -289.07451) (xy 186.687328 -289.080442) (xy 186.638153 -289.078461) (xy 186.589934 -289.068617)
			(xy 186.543918 -289.051165) (xy 186.501297 -289.026558) (xy 186.463176 -288.995433) (xy 186.430541 -288.958596)
			(xy 186.404238 -288.917) (xy 186.384947 -288.871724) (xy 186.37317 -288.82394) (xy 186.36921 -288.774886)
			(xy 186.056254 -288.774886) (xy 186.056254 -288.774892) (xy 186.05251 -288.824552) (xy 186.041362 -288.873089)
			(xy 186.023061 -288.919406) (xy 185.998021 -288.962454) (xy 185.966809 -289.001261) (xy 185.930131 -289.034948)
			(xy 185.909712 -289.049206) (xy 185.899696 -289.056737) (xy 185.887975 -289.078853) (xy 185.88736 -289.09137)
			(xy 185.88736 -289.408362) (xy 185.888004 -289.420869) (xy 185.899724 -289.442969) (xy 185.909712 -289.450526)
			(xy 185.930114 -289.464802) (xy 185.966785 -289.498486) (xy 185.997991 -289.537289) (xy 186.023024 -289.580332)
			(xy 186.04132 -289.626642) (xy 186.052464 -289.675173) (xy 186.056204 -289.724826) (xy 186.056202 -289.724846)
			(xy 186.36921 -289.724846) (xy 186.37317 -289.675792) (xy 186.384947 -289.628008) (xy 186.404238 -289.582732)
			(xy 186.430541 -289.541136) (xy 186.463176 -289.504299) (xy 186.501297 -289.473174) (xy 186.543918 -289.448567)
			(xy 186.589934 -289.431115) (xy 186.638153 -289.421271) (xy 186.687328 -289.41929) (xy 186.736183 -289.425222)
			(xy 186.783454 -289.438914) (xy 186.827916 -289.460012) (xy 186.868419 -289.487968) (xy 186.903912 -289.52206)
			(xy 186.933477 -289.561404) (xy 186.956348 -289.604981) (xy 186.971932 -289.651662) (xy 186.979827 -289.700239)
			(xy 186.980322 -289.724846) (xy 187.31917 -289.724846) (xy 187.32313 -289.675792) (xy 187.334907 -289.628008)
			(xy 187.354198 -289.582732) (xy 187.380501 -289.541136) (xy 187.413136 -289.504299) (xy 187.451257 -289.473174)
			(xy 187.493878 -289.448567) (xy 187.539894 -289.431115) (xy 187.588113 -289.421271) (xy 187.637288 -289.41929)
			(xy 187.686143 -289.425222) (xy 187.733414 -289.438914) (xy 187.777876 -289.460012) (xy 187.818379 -289.487968)
			(xy 187.853872 -289.52206) (xy 187.883437 -289.561404) (xy 187.906308 -289.604981) (xy 187.921892 -289.651662)
			(xy 187.929787 -289.700239) (xy 187.930282 -289.724846) (xy 188.26913 -289.724846) (xy 188.27309 -289.675792)
			(xy 188.284867 -289.628008) (xy 188.304158 -289.582732) (xy 188.330461 -289.541136) (xy 188.363096 -289.504299)
			(xy 188.401217 -289.473174) (xy 188.443838 -289.448567) (xy 188.489854 -289.431115) (xy 188.538073 -289.421271)
			(xy 188.587248 -289.41929) (xy 188.636103 -289.425222) (xy 188.683374 -289.438914) (xy 188.727836 -289.460012)
			(xy 188.768339 -289.487968) (xy 188.803832 -289.52206) (xy 188.833397 -289.561404) (xy 188.856268 -289.604981)
			(xy 188.871852 -289.651662) (xy 188.879747 -289.700239) (xy 188.880074 -289.716508) (xy 189.219227 -289.716508)
			(xy 189.224595 -289.667167) (xy 189.237875 -289.619344) (xy 189.258716 -289.574299) (xy 189.28657 -289.53322)
			(xy 189.320702 -289.497187) (xy 189.360214 -289.467151) (xy 189.404065 -289.443903) (xy 189.451099 -289.428054)
			(xy 189.500078 -289.420024) (xy 189.524894 -289.419538) (xy 189.539077 -289.419715) (xy 189.567317 -289.422387)
			(xy 189.581282 -289.424872) (xy 189.593728 -289.427158) (xy 189.61735 -289.419792) (xy 189.69482 -289.342322)
			(xy 189.702186 -289.3187) (xy 189.6999 -289.306254) (xy 189.697421 -289.292289) (xy 189.694751 -289.264049)
			(xy 189.694566 -289.249866) (xy 189.695088 -289.224611) (xy 189.703401 -289.174789) (xy 189.719802 -289.127015)
			(xy 189.743843 -289.082592) (xy 189.774867 -289.042732) (xy 189.812029 -289.008522) (xy 189.854315 -288.980896)
			(xy 189.900571 -288.960606) (xy 189.949536 -288.948206) (xy 189.999874 -288.944035) (xy 190.050212 -288.948206)
			(xy 190.099177 -288.960606) (xy 190.145433 -288.980896) (xy 190.187719 -289.008522) (xy 190.224881 -289.042732)
			(xy 190.255905 -289.082592) (xy 190.279946 -289.127015) (xy 190.296347 -289.174789) (xy 190.30466 -289.224611)
			(xy 190.305182 -289.249866) (xy 190.305001 -289.264049) (xy 190.302332 -289.292289) (xy 190.299848 -289.306254)
			(xy 190.297562 -289.3187) (xy 190.304928 -289.342576) (xy 190.382144 -289.419792) (xy 190.406274 -289.427158)
			(xy 190.418466 -289.424872) (xy 190.432494 -289.422381) (xy 190.460862 -289.419713) (xy 190.475108 -289.419538)
			(xy 190.499927 -289.419986) (xy 190.548912 -289.428018) (xy 190.595952 -289.443868) (xy 190.639808 -289.46712)
			(xy 190.679325 -289.49716) (xy 190.713461 -289.533197) (xy 190.741318 -289.574282) (xy 190.762162 -289.619332)
			(xy 190.775442 -289.667161) (xy 190.780811 -289.716509) (xy 190.780359 -289.724846) (xy 192.069224 -289.724846)
			(xy 192.073184 -289.675792) (xy 192.084961 -289.628008) (xy 192.104252 -289.582732) (xy 192.130555 -289.541136)
			(xy 192.16319 -289.504299) (xy 192.201311 -289.473174) (xy 192.243932 -289.448567) (xy 192.289948 -289.431115)
			(xy 192.338167 -289.421271) (xy 192.387342 -289.41929) (xy 192.436197 -289.425222) (xy 192.483468 -289.438914)
			(xy 192.52793 -289.460012) (xy 192.568433 -289.487968) (xy 192.603926 -289.52206) (xy 192.633491 -289.561404)
			(xy 192.656362 -289.604981) (xy 192.671946 -289.651662) (xy 192.679841 -289.700239) (xy 192.680336 -289.724846)
			(xy 193.019184 -289.724846) (xy 193.023144 -289.675792) (xy 193.034921 -289.628008) (xy 193.054212 -289.582732)
			(xy 193.080515 -289.541136) (xy 193.11315 -289.504299) (xy 193.151271 -289.473174) (xy 193.193892 -289.448567)
			(xy 193.239908 -289.431115) (xy 193.288127 -289.421271) (xy 193.337302 -289.41929) (xy 193.386157 -289.425222)
			(xy 193.433428 -289.438914) (xy 193.47789 -289.460012) (xy 193.518393 -289.487968) (xy 193.553886 -289.52206)
			(xy 193.583451 -289.561404) (xy 193.606322 -289.604981) (xy 193.621906 -289.651662) (xy 193.629801 -289.700239)
			(xy 193.630296 -289.724846) (xy 193.969144 -289.724846) (xy 193.973104 -289.675792) (xy 193.984881 -289.628008)
			(xy 194.004172 -289.582732) (xy 194.030475 -289.541136) (xy 194.06311 -289.504299) (xy 194.101231 -289.473174)
			(xy 194.143852 -289.448567) (xy 194.189868 -289.431115) (xy 194.238087 -289.421271) (xy 194.287262 -289.41929)
			(xy 194.336117 -289.425222) (xy 194.383388 -289.438914) (xy 194.42785 -289.460012) (xy 194.468353 -289.487968)
			(xy 194.503846 -289.52206) (xy 194.533411 -289.561404) (xy 194.556282 -289.604981) (xy 194.571866 -289.651662)
			(xy 194.579761 -289.700239) (xy 194.580256 -289.724846) (xy 194.579761 -289.749453) (xy 194.571866 -289.79803)
			(xy 194.556282 -289.844711) (xy 194.533411 -289.888288) (xy 194.503846 -289.927632) (xy 194.468353 -289.961724)
			(xy 194.42785 -289.98968) (xy 194.383388 -290.010778) (xy 194.336117 -290.02447) (xy 194.287262 -290.030402)
			(xy 194.238087 -290.028421) (xy 194.189868 -290.018577) (xy 194.143852 -290.001125) (xy 194.101231 -289.976518)
			(xy 194.06311 -289.945393) (xy 194.030475 -289.908556) (xy 194.004172 -289.86696) (xy 193.984881 -289.821684)
			(xy 193.973104 -289.7739) (xy 193.969144 -289.724846) (xy 193.630296 -289.724846) (xy 193.629801 -289.749453)
			(xy 193.621906 -289.79803) (xy 193.606322 -289.844711) (xy 193.583451 -289.888288) (xy 193.553886 -289.927632)
			(xy 193.518393 -289.961724) (xy 193.47789 -289.98968) (xy 193.433428 -290.010778) (xy 193.386157 -290.02447)
			(xy 193.337302 -290.030402) (xy 193.288127 -290.028421) (xy 193.239908 -290.018577) (xy 193.193892 -290.001125)
			(xy 193.151271 -289.976518) (xy 193.11315 -289.945393) (xy 193.080515 -289.908556) (xy 193.054212 -289.86696)
			(xy 193.034921 -289.821684) (xy 193.023144 -289.7739) (xy 193.019184 -289.724846) (xy 192.680336 -289.724846)
			(xy 192.679841 -289.749453) (xy 192.671946 -289.79803) (xy 192.656362 -289.844711) (xy 192.633491 -289.888288)
			(xy 192.603926 -289.927632) (xy 192.568433 -289.961724) (xy 192.52793 -289.98968) (xy 192.483468 -290.010778)
			(xy 192.436197 -290.02447) (xy 192.387342 -290.030402) (xy 192.338167 -290.028421) (xy 192.289948 -290.018577)
			(xy 192.243932 -290.001125) (xy 192.201311 -289.976518) (xy 192.16319 -289.945393) (xy 192.130555 -289.908556)
			(xy 192.104252 -289.86696) (xy 192.084961 -289.821684) (xy 192.073184 -289.7739) (xy 192.069224 -289.724846)
			(xy 190.780359 -289.724846) (xy 190.778125 -289.766075) (xy 190.767456 -289.814553) (xy 190.749085 -289.860667)
			(xy 190.723496 -289.903202) (xy 190.691363 -289.941036) (xy 190.653532 -289.973174) (xy 190.611001 -289.998768)
			(xy 190.564889 -290.017145) (xy 190.516412 -290.02782) (xy 190.466847 -290.030512) (xy 190.417499 -290.025149)
			(xy 190.369668 -290.011875) (xy 190.324615 -289.991037) (xy 190.283527 -289.963185) (xy 190.247485 -289.929053)
			(xy 190.21744 -289.88954) (xy 190.194183 -289.845687) (xy 190.178327 -289.798649) (xy 190.17029 -289.749665)
			(xy 190.1698 -289.724846) (xy 190.169983 -289.710663) (xy 190.172651 -289.682423) (xy 190.175134 -289.668458)
			(xy 190.17742 -289.656012) (xy 190.170054 -289.632136) (xy 190.092838 -289.55492) (xy 190.068708 -289.547554)
			(xy 190.056516 -289.54984) (xy 190.042486 -289.55232) (xy 190.01412 -289.554995) (xy 189.999874 -289.555174)
			(xy 189.985691 -289.555002) (xy 189.957451 -289.552327) (xy 189.943486 -289.54984) (xy 189.93104 -289.547554)
			(xy 189.907418 -289.55492) (xy 189.829948 -289.63239) (xy 189.822582 -289.656012) (xy 189.824868 -289.668458)
			(xy 189.827348 -289.682423) (xy 189.830018 -289.710663) (xy 189.830202 -289.724846) (xy 189.829673 -289.749662)
			(xy 189.821636 -289.79864) (xy 189.805782 -289.845672) (xy 189.782528 -289.88952) (xy 189.752486 -289.929028)
			(xy 189.716449 -289.963156) (xy 189.675366 -289.991004) (xy 189.630318 -290.011839) (xy 189.582493 -290.025112)
			(xy 189.533151 -290.030474) (xy 189.483592 -290.027782) (xy 189.435121 -290.017108) (xy 189.389015 -289.998734)
			(xy 189.346489 -289.973142) (xy 189.308663 -289.941008) (xy 189.276534 -289.903179) (xy 189.250948 -289.860649)
			(xy 189.23258 -289.814541) (xy 189.221913 -289.766068) (xy 189.219227 -289.716508) (xy 188.880074 -289.716508)
			(xy 188.880242 -289.724846) (xy 188.879747 -289.749453) (xy 188.871852 -289.79803) (xy 188.856268 -289.844711)
			(xy 188.833397 -289.888288) (xy 188.803832 -289.927632) (xy 188.768339 -289.961724) (xy 188.727836 -289.98968)
			(xy 188.683374 -290.010778) (xy 188.636103 -290.02447) (xy 188.587248 -290.030402) (xy 188.538073 -290.028421)
			(xy 188.489854 -290.018577) (xy 188.443838 -290.001125) (xy 188.401217 -289.976518) (xy 188.363096 -289.945393)
			(xy 188.330461 -289.908556) (xy 188.304158 -289.86696) (xy 188.284867 -289.821684) (xy 188.27309 -289.7739)
			(xy 188.26913 -289.724846) (xy 187.930282 -289.724846) (xy 187.929787 -289.749453) (xy 187.921892 -289.79803)
			(xy 187.906308 -289.844711) (xy 187.883437 -289.888288) (xy 187.853872 -289.927632) (xy 187.818379 -289.961724)
			(xy 187.777876 -289.98968) (xy 187.733414 -290.010778) (xy 187.686143 -290.02447) (xy 187.637288 -290.030402)
			(xy 187.588113 -290.028421) (xy 187.539894 -290.018577) (xy 187.493878 -290.001125) (xy 187.451257 -289.976518)
			(xy 187.413136 -289.945393) (xy 187.380501 -289.908556) (xy 187.354198 -289.86696) (xy 187.334907 -289.821684)
			(xy 187.32313 -289.7739) (xy 187.31917 -289.724846) (xy 186.980322 -289.724846) (xy 186.979827 -289.749453)
			(xy 186.971932 -289.79803) (xy 186.956348 -289.844711) (xy 186.933477 -289.888288) (xy 186.903912 -289.927632)
			(xy 186.868419 -289.961724) (xy 186.827916 -289.98968) (xy 186.783454 -290.010778) (xy 186.736183 -290.02447)
			(xy 186.687328 -290.030402) (xy 186.638153 -290.028421) (xy 186.589934 -290.018577) (xy 186.543918 -290.001125)
			(xy 186.501297 -289.976518) (xy 186.463176 -289.945393) (xy 186.430541 -289.908556) (xy 186.404238 -289.86696)
			(xy 186.384947 -289.821684) (xy 186.37317 -289.7739) (xy 186.36921 -289.724846) (xy 186.056202 -289.724846)
			(xy 186.052456 -289.774478) (xy 186.041304 -289.823007) (xy 186.023002 -289.869314) (xy 185.997961 -289.912354)
			(xy 185.96675 -289.951151) (xy 185.930074 -289.98483) (xy 185.909712 -289.999166) (xy 185.899706 -290.006701)
			(xy 185.888011 -290.028818) (xy 185.88736 -290.04133) (xy 185.88736 -290.358322) (xy 185.887995 -290.370834)
			(xy 185.899706 -290.392949) (xy 185.909712 -290.400486) (xy 185.930117 -290.414762) (xy 185.966794 -290.448447)
			(xy 185.998005 -290.487251) (xy 186.023044 -290.530297) (xy 186.041345 -290.576611) (xy 186.052493 -290.625146)
			(xy 186.056237 -290.674803) (xy 186.056237 -290.674806) (xy 186.36921 -290.674806) (xy 186.37317 -290.625752)
			(xy 186.384947 -290.577968) (xy 186.404238 -290.532692) (xy 186.430541 -290.491096) (xy 186.463176 -290.454259)
			(xy 186.501297 -290.423134) (xy 186.543918 -290.398527) (xy 186.589934 -290.381075) (xy 186.638153 -290.371231)
			(xy 186.687328 -290.36925) (xy 186.736183 -290.375182) (xy 186.783454 -290.388874) (xy 186.827916 -290.409972)
			(xy 186.868419 -290.437928) (xy 186.903912 -290.47202) (xy 186.933477 -290.511364) (xy 186.956348 -290.554941)
			(xy 186.971932 -290.601622) (xy 186.979827 -290.650199) (xy 186.980322 -290.674806) (xy 187.31917 -290.674806)
			(xy 187.32313 -290.625752) (xy 187.334907 -290.577968) (xy 187.354198 -290.532692) (xy 187.380501 -290.491096)
			(xy 187.413136 -290.454259) (xy 187.451257 -290.423134) (xy 187.493878 -290.398527) (xy 187.539894 -290.381075)
			(xy 187.588113 -290.371231) (xy 187.637288 -290.36925) (xy 187.686143 -290.375182) (xy 187.733414 -290.388874)
			(xy 187.777876 -290.409972) (xy 187.818379 -290.437928) (xy 187.853872 -290.47202) (xy 187.883437 -290.511364)
			(xy 187.906308 -290.554941) (xy 187.921892 -290.601622) (xy 187.929787 -290.650199) (xy 187.930282 -290.674806)
			(xy 188.26913 -290.674806) (xy 188.27309 -290.625752) (xy 188.284867 -290.577968) (xy 188.304158 -290.532692)
			(xy 188.330461 -290.491096) (xy 188.363096 -290.454259) (xy 188.401217 -290.423134) (xy 188.443838 -290.398527)
			(xy 188.489854 -290.381075) (xy 188.538073 -290.371231) (xy 188.587248 -290.36925) (xy 188.636103 -290.375182)
			(xy 188.683374 -290.388874) (xy 188.727836 -290.409972) (xy 188.768339 -290.437928) (xy 188.803832 -290.47202)
			(xy 188.833397 -290.511364) (xy 188.856268 -290.554941) (xy 188.871852 -290.601622) (xy 188.879747 -290.650199)
			(xy 188.880242 -290.674806) (xy 189.21909 -290.674806) (xy 189.22305 -290.625752) (xy 189.234827 -290.577968)
			(xy 189.254118 -290.532692) (xy 189.280421 -290.491096) (xy 189.313056 -290.454259) (xy 189.351177 -290.423134)
			(xy 189.393798 -290.398527) (xy 189.439814 -290.381075) (xy 189.488033 -290.371231) (xy 189.537208 -290.36925)
			(xy 189.586063 -290.375182) (xy 189.633334 -290.388874) (xy 189.677796 -290.409972) (xy 189.718299 -290.437928)
			(xy 189.753792 -290.47202) (xy 189.783357 -290.511364) (xy 189.806228 -290.554941) (xy 189.821812 -290.601622)
			(xy 189.829707 -290.650199) (xy 189.830202 -290.674806) (xy 190.16905 -290.674806) (xy 190.17301 -290.625752)
			(xy 190.184787 -290.577968) (xy 190.204078 -290.532692) (xy 190.230381 -290.491096) (xy 190.263016 -290.454259)
			(xy 190.301137 -290.423134) (xy 190.343758 -290.398527) (xy 190.389774 -290.381075) (xy 190.437993 -290.371231)
			(xy 190.487168 -290.36925) (xy 190.536023 -290.375182) (xy 190.583294 -290.388874) (xy 190.627756 -290.409972)
			(xy 190.668259 -290.437928) (xy 190.703752 -290.47202) (xy 190.733317 -290.511364) (xy 190.756188 -290.554941)
			(xy 190.771772 -290.601622) (xy 190.779667 -290.650199) (xy 190.780162 -290.674806) (xy 191.119264 -290.674806)
			(xy 191.123224 -290.625752) (xy 191.135001 -290.577968) (xy 191.154292 -290.532692) (xy 191.180595 -290.491096)
			(xy 191.21323 -290.454259) (xy 191.251351 -290.423134) (xy 191.293972 -290.398527) (xy 191.339988 -290.381075)
			(xy 191.388207 -290.371231) (xy 191.437382 -290.36925) (xy 191.486237 -290.375182) (xy 191.533508 -290.388874)
			(xy 191.57797 -290.409972) (xy 191.618473 -290.437928) (xy 191.653966 -290.47202) (xy 191.683531 -290.511364)
			(xy 191.706402 -290.554941) (xy 191.721986 -290.601622) (xy 191.729881 -290.650199) (xy 191.730376 -290.674806)
			(xy 192.069224 -290.674806) (xy 192.073184 -290.625752) (xy 192.084961 -290.577968) (xy 192.104252 -290.532692)
			(xy 192.130555 -290.491096) (xy 192.16319 -290.454259) (xy 192.201311 -290.423134) (xy 192.243932 -290.398527)
			(xy 192.289948 -290.381075) (xy 192.338167 -290.371231) (xy 192.387342 -290.36925) (xy 192.436197 -290.375182)
			(xy 192.483468 -290.388874) (xy 192.52793 -290.409972) (xy 192.568433 -290.437928) (xy 192.603926 -290.47202)
			(xy 192.633491 -290.511364) (xy 192.656362 -290.554941) (xy 192.671946 -290.601622) (xy 192.679841 -290.650199)
			(xy 192.680336 -290.674806) (xy 193.019184 -290.674806) (xy 193.023144 -290.625752) (xy 193.034921 -290.577968)
			(xy 193.054212 -290.532692) (xy 193.080515 -290.491096) (xy 193.11315 -290.454259) (xy 193.151271 -290.423134)
			(xy 193.193892 -290.398527) (xy 193.239908 -290.381075) (xy 193.288127 -290.371231) (xy 193.337302 -290.36925)
			(xy 193.386157 -290.375182) (xy 193.433428 -290.388874) (xy 193.47789 -290.409972) (xy 193.518393 -290.437928)
			(xy 193.553886 -290.47202) (xy 193.583451 -290.511364) (xy 193.606322 -290.554941) (xy 193.621906 -290.601622)
			(xy 193.629801 -290.650199) (xy 193.630296 -290.674806) (xy 193.969144 -290.674806) (xy 193.973104 -290.625752)
			(xy 193.984881 -290.577968) (xy 194.004172 -290.532692) (xy 194.030475 -290.491096) (xy 194.06311 -290.454259)
			(xy 194.101231 -290.423134) (xy 194.143852 -290.398527) (xy 194.189868 -290.381075) (xy 194.238087 -290.371231)
			(xy 194.287262 -290.36925) (xy 194.336117 -290.375182) (xy 194.383388 -290.388874) (xy 194.42785 -290.409972)
			(xy 194.468353 -290.437928) (xy 194.503846 -290.47202) (xy 194.533411 -290.511364) (xy 194.556282 -290.554941)
			(xy 194.571866 -290.601622) (xy 194.579761 -290.650199) (xy 194.580256 -290.674806) (xy 194.919104 -290.674806)
			(xy 194.923064 -290.625752) (xy 194.934841 -290.577968) (xy 194.954132 -290.532692) (xy 194.980435 -290.491096)
			(xy 195.01307 -290.454259) (xy 195.051191 -290.423134) (xy 195.093812 -290.398527) (xy 195.139828 -290.381075)
			(xy 195.188047 -290.371231) (xy 195.237222 -290.36925) (xy 195.286077 -290.375182) (xy 195.333348 -290.388874)
			(xy 195.37781 -290.409972) (xy 195.418313 -290.437928) (xy 195.453806 -290.47202) (xy 195.483371 -290.511364)
			(xy 195.506242 -290.554941) (xy 195.521826 -290.601622) (xy 195.529721 -290.650199) (xy 195.530216 -290.674806)
			(xy 195.869064 -290.674806) (xy 195.873024 -290.625752) (xy 195.884801 -290.577968) (xy 195.904092 -290.532692)
			(xy 195.930395 -290.491096) (xy 195.96303 -290.454259) (xy 196.001151 -290.423134) (xy 196.043772 -290.398527)
			(xy 196.089788 -290.381075) (xy 196.138007 -290.371231) (xy 196.187182 -290.36925) (xy 196.236037 -290.375182)
			(xy 196.283308 -290.388874) (xy 196.32777 -290.409972) (xy 196.368273 -290.437928) (xy 196.403766 -290.47202)
			(xy 196.433331 -290.511364) (xy 196.456202 -290.554941) (xy 196.471786 -290.601622) (xy 196.479681 -290.650199)
			(xy 196.480176 -290.674806) (xy 196.819278 -290.674806) (xy 196.823238 -290.625752) (xy 196.835015 -290.577968)
			(xy 196.854306 -290.532692) (xy 196.880609 -290.491096) (xy 196.913244 -290.454259) (xy 196.951365 -290.423134)
			(xy 196.993986 -290.398527) (xy 197.040002 -290.381075) (xy 197.088221 -290.371231) (xy 197.137396 -290.36925)
			(xy 197.186251 -290.375182) (xy 197.233522 -290.388874) (xy 197.277984 -290.409972) (xy 197.318487 -290.437928)
			(xy 197.35398 -290.47202) (xy 197.383545 -290.511364) (xy 197.406416 -290.554941) (xy 197.422 -290.601622)
			(xy 197.429895 -290.650199) (xy 197.43039 -290.674806) (xy 197.769238 -290.674806) (xy 197.773198 -290.625752)
			(xy 197.784975 -290.577968) (xy 197.804266 -290.532692) (xy 197.830569 -290.491096) (xy 197.863204 -290.454259)
			(xy 197.901325 -290.423134) (xy 197.943946 -290.398527) (xy 197.989962 -290.381075) (xy 198.038181 -290.371231)
			(xy 198.087356 -290.36925) (xy 198.136211 -290.375182) (xy 198.183482 -290.388874) (xy 198.227944 -290.409972)
			(xy 198.268447 -290.437928) (xy 198.30394 -290.47202) (xy 198.333505 -290.511364) (xy 198.356376 -290.554941)
			(xy 198.37196 -290.601622) (xy 198.379855 -290.650199) (xy 198.38035 -290.674806) (xy 198.719198 -290.674806)
			(xy 198.723158 -290.625752) (xy 198.734935 -290.577968) (xy 198.754226 -290.532692) (xy 198.780529 -290.491096)
			(xy 198.813164 -290.454259) (xy 198.851285 -290.423134) (xy 198.893906 -290.398527) (xy 198.939922 -290.381075)
			(xy 198.988141 -290.371231) (xy 199.037316 -290.36925) (xy 199.086171 -290.375182) (xy 199.133442 -290.388874)
			(xy 199.177904 -290.409972) (xy 199.19176 -290.419536) (xy 201.25385 -290.419536) (xy 201.257921 -290.363914)
			(xy 201.270047 -290.309477) (xy 201.28997 -290.257386) (xy 201.317266 -290.208751) (xy 201.351352 -290.164608)
			(xy 201.391501 -290.125899) (xy 201.436859 -290.093448) (xy 201.486459 -290.067947) (xy 201.539243 -290.04994)
			(xy 201.594086 -290.03981) (xy 201.64982 -290.037773) (xy 201.705257 -290.043873) (xy 201.759214 -290.057979)
			(xy 201.810543 -290.079791) (xy 201.858149 -290.108845) (xy 201.901017 -290.14452) (xy 201.938234 -290.186057)
			(xy 201.969007 -290.23257) (xy 201.971161 -290.237164) (xy 205.26451 -290.237164) (xy 205.268581 -290.181542)
			(xy 205.280707 -290.127105) (xy 205.30063 -290.075014) (xy 205.327926 -290.026379) (xy 205.362012 -289.982236)
			(xy 205.402161 -289.943527) (xy 205.447519 -289.911076) (xy 205.497119 -289.885575) (xy 205.549903 -289.867568)
			(xy 205.604746 -289.857438) (xy 205.66048 -289.855401) (xy 205.715917 -289.861501) (xy 205.769874 -289.875607)
			(xy 205.821203 -289.897419) (xy 205.868809 -289.926473) (xy 205.911677 -289.962148) (xy 205.948894 -290.003685)
			(xy 205.979667 -290.050198) (xy 206.003339 -290.100695) (xy 206.019407 -290.154102) (xy 206.027527 -290.209278)
			(xy 206.028036 -290.237164) (xy 206.027527 -290.26505) (xy 206.019407 -290.320226) (xy 206.003339 -290.373633)
			(xy 205.979667 -290.42413) (xy 205.948894 -290.470643) (xy 205.911677 -290.51218) (xy 205.868809 -290.547855)
			(xy 205.821203 -290.576909) (xy 205.769874 -290.598721) (xy 205.715917 -290.612827) (xy 205.66048 -290.618927)
			(xy 205.604746 -290.61689) (xy 205.549903 -290.60676) (xy 205.497119 -290.588753) (xy 205.447519 -290.563252)
			(xy 205.402161 -290.530801) (xy 205.362012 -290.492092) (xy 205.327926 -290.447949) (xy 205.30063 -290.399314)
			(xy 205.280707 -290.347223) (xy 205.268581 -290.292786) (xy 205.26451 -290.237164) (xy 201.971161 -290.237164)
			(xy 201.992679 -290.283067) (xy 202.008747 -290.336474) (xy 202.016867 -290.39165) (xy 202.017376 -290.419536)
			(xy 202.016867 -290.447422) (xy 202.008747 -290.502598) (xy 201.992679 -290.556005) (xy 201.969007 -290.606502)
			(xy 201.938234 -290.653015) (xy 201.901017 -290.694552) (xy 201.858149 -290.730227) (xy 201.810543 -290.759281)
			(xy 201.759214 -290.781093) (xy 201.705257 -290.795199) (xy 201.64982 -290.801299) (xy 201.594086 -290.799262)
			(xy 201.539243 -290.789132) (xy 201.486459 -290.771125) (xy 201.436859 -290.745624) (xy 201.391501 -290.713173)
			(xy 201.351352 -290.674464) (xy 201.317266 -290.630321) (xy 201.28997 -290.581686) (xy 201.270047 -290.529595)
			(xy 201.257921 -290.475158) (xy 201.25385 -290.419536) (xy 199.19176 -290.419536) (xy 199.218407 -290.437928)
			(xy 199.2539 -290.47202) (xy 199.283465 -290.511364) (xy 199.306336 -290.554941) (xy 199.32192 -290.601622)
			(xy 199.329815 -290.650199) (xy 199.33031 -290.674806) (xy 199.329815 -290.699413) (xy 199.32192 -290.74799)
			(xy 199.306336 -290.794671) (xy 199.283465 -290.838248) (xy 199.2539 -290.877592) (xy 199.218407 -290.911684)
			(xy 199.177904 -290.93964) (xy 199.133442 -290.960738) (xy 199.086171 -290.97443) (xy 199.037316 -290.980362)
			(xy 198.988141 -290.978381) (xy 198.939922 -290.968537) (xy 198.893906 -290.951085) (xy 198.851285 -290.926478)
			(xy 198.813164 -290.895353) (xy 198.780529 -290.858516) (xy 198.754226 -290.81692) (xy 198.734935 -290.771644)
			(xy 198.723158 -290.72386) (xy 198.719198 -290.674806) (xy 198.38035 -290.674806) (xy 198.379855 -290.699413)
			(xy 198.37196 -290.74799) (xy 198.356376 -290.794671) (xy 198.333505 -290.838248) (xy 198.30394 -290.877592)
			(xy 198.268447 -290.911684) (xy 198.227944 -290.93964) (xy 198.183482 -290.960738) (xy 198.136211 -290.97443)
			(xy 198.087356 -290.980362) (xy 198.038181 -290.978381) (xy 197.989962 -290.968537) (xy 197.943946 -290.951085)
			(xy 197.901325 -290.926478) (xy 197.863204 -290.895353) (xy 197.830569 -290.858516) (xy 197.804266 -290.81692)
			(xy 197.784975 -290.771644) (xy 197.773198 -290.72386) (xy 197.769238 -290.674806) (xy 197.43039 -290.674806)
			(xy 197.429895 -290.699413) (xy 197.422 -290.74799) (xy 197.406416 -290.794671) (xy 197.383545 -290.838248)
			(xy 197.35398 -290.877592) (xy 197.318487 -290.911684) (xy 197.277984 -290.93964) (xy 197.233522 -290.960738)
			(xy 197.186251 -290.97443) (xy 197.137396 -290.980362) (xy 197.088221 -290.978381) (xy 197.040002 -290.968537)
			(xy 196.993986 -290.951085) (xy 196.951365 -290.926478) (xy 196.913244 -290.895353) (xy 196.880609 -290.858516)
			(xy 196.854306 -290.81692) (xy 196.835015 -290.771644) (xy 196.823238 -290.72386) (xy 196.819278 -290.674806)
			(xy 196.480176 -290.674806) (xy 196.479681 -290.699413) (xy 196.471786 -290.74799) (xy 196.456202 -290.794671)
			(xy 196.433331 -290.838248) (xy 196.403766 -290.877592) (xy 196.368273 -290.911684) (xy 196.32777 -290.93964)
			(xy 196.283308 -290.960738) (xy 196.236037 -290.97443) (xy 196.187182 -290.980362) (xy 196.138007 -290.978381)
			(xy 196.089788 -290.968537) (xy 196.043772 -290.951085) (xy 196.001151 -290.926478) (xy 195.96303 -290.895353)
			(xy 195.930395 -290.858516) (xy 195.904092 -290.81692) (xy 195.884801 -290.771644) (xy 195.873024 -290.72386)
			(xy 195.869064 -290.674806) (xy 195.530216 -290.674806) (xy 195.529721 -290.699413) (xy 195.521826 -290.74799)
			(xy 195.506242 -290.794671) (xy 195.483371 -290.838248) (xy 195.453806 -290.877592) (xy 195.418313 -290.911684)
			(xy 195.37781 -290.93964) (xy 195.333348 -290.960738) (xy 195.286077 -290.97443) (xy 195.237222 -290.980362)
			(xy 195.188047 -290.978381) (xy 195.139828 -290.968537) (xy 195.093812 -290.951085) (xy 195.051191 -290.926478)
			(xy 195.01307 -290.895353) (xy 194.980435 -290.858516) (xy 194.954132 -290.81692) (xy 194.934841 -290.771644)
			(xy 194.923064 -290.72386) (xy 194.919104 -290.674806) (xy 194.580256 -290.674806) (xy 194.579761 -290.699413)
			(xy 194.571866 -290.74799) (xy 194.556282 -290.794671) (xy 194.533411 -290.838248) (xy 194.503846 -290.877592)
			(xy 194.468353 -290.911684) (xy 194.42785 -290.93964) (xy 194.383388 -290.960738) (xy 194.336117 -290.97443)
			(xy 194.287262 -290.980362) (xy 194.238087 -290.978381) (xy 194.189868 -290.968537) (xy 194.143852 -290.951085)
			(xy 194.101231 -290.926478) (xy 194.06311 -290.895353) (xy 194.030475 -290.858516) (xy 194.004172 -290.81692)
			(xy 193.984881 -290.771644) (xy 193.973104 -290.72386) (xy 193.969144 -290.674806) (xy 193.630296 -290.674806)
			(xy 193.629801 -290.699413) (xy 193.621906 -290.74799) (xy 193.606322 -290.794671) (xy 193.583451 -290.838248)
			(xy 193.553886 -290.877592) (xy 193.518393 -290.911684) (xy 193.47789 -290.93964) (xy 193.433428 -290.960738)
			(xy 193.386157 -290.97443) (xy 193.337302 -290.980362) (xy 193.288127 -290.978381) (xy 193.239908 -290.968537)
			(xy 193.193892 -290.951085) (xy 193.151271 -290.926478) (xy 193.11315 -290.895353) (xy 193.080515 -290.858516)
			(xy 193.054212 -290.81692) (xy 193.034921 -290.771644) (xy 193.023144 -290.72386) (xy 193.019184 -290.674806)
			(xy 192.680336 -290.674806) (xy 192.679841 -290.699413) (xy 192.671946 -290.74799) (xy 192.656362 -290.794671)
			(xy 192.633491 -290.838248) (xy 192.603926 -290.877592) (xy 192.568433 -290.911684) (xy 192.52793 -290.93964)
			(xy 192.483468 -290.960738) (xy 192.436197 -290.97443) (xy 192.387342 -290.980362) (xy 192.338167 -290.978381)
			(xy 192.289948 -290.968537) (xy 192.243932 -290.951085) (xy 192.201311 -290.926478) (xy 192.16319 -290.895353)
			(xy 192.130555 -290.858516) (xy 192.104252 -290.81692) (xy 192.084961 -290.771644) (xy 192.073184 -290.72386)
			(xy 192.069224 -290.674806) (xy 191.730376 -290.674806) (xy 191.729881 -290.699413) (xy 191.721986 -290.74799)
			(xy 191.706402 -290.794671) (xy 191.683531 -290.838248) (xy 191.653966 -290.877592) (xy 191.618473 -290.911684)
			(xy 191.57797 -290.93964) (xy 191.533508 -290.960738) (xy 191.486237 -290.97443) (xy 191.437382 -290.980362)
			(xy 191.388207 -290.978381) (xy 191.339988 -290.968537) (xy 191.293972 -290.951085) (xy 191.251351 -290.926478)
			(xy 191.21323 -290.895353) (xy 191.180595 -290.858516) (xy 191.154292 -290.81692) (xy 191.135001 -290.771644)
			(xy 191.123224 -290.72386) (xy 191.119264 -290.674806) (xy 190.780162 -290.674806) (xy 190.779667 -290.699413)
			(xy 190.771772 -290.74799) (xy 190.756188 -290.794671) (xy 190.733317 -290.838248) (xy 190.703752 -290.877592)
			(xy 190.668259 -290.911684) (xy 190.627756 -290.93964) (xy 190.583294 -290.960738) (xy 190.536023 -290.97443)
			(xy 190.487168 -290.980362) (xy 190.437993 -290.978381) (xy 190.389774 -290.968537) (xy 190.343758 -290.951085)
			(xy 190.301137 -290.926478) (xy 190.263016 -290.895353) (xy 190.230381 -290.858516) (xy 190.204078 -290.81692)
			(xy 190.184787 -290.771644) (xy 190.17301 -290.72386) (xy 190.16905 -290.674806) (xy 189.830202 -290.674806)
			(xy 189.829707 -290.699413) (xy 189.821812 -290.74799) (xy 189.806228 -290.794671) (xy 189.783357 -290.838248)
			(xy 189.753792 -290.877592) (xy 189.718299 -290.911684) (xy 189.677796 -290.93964) (xy 189.633334 -290.960738)
			(xy 189.586063 -290.97443) (xy 189.537208 -290.980362) (xy 189.488033 -290.978381) (xy 189.439814 -290.968537)
			(xy 189.393798 -290.951085) (xy 189.351177 -290.926478) (xy 189.313056 -290.895353) (xy 189.280421 -290.858516)
			(xy 189.254118 -290.81692) (xy 189.234827 -290.771644) (xy 189.22305 -290.72386) (xy 189.21909 -290.674806)
			(xy 188.880242 -290.674806) (xy 188.879747 -290.699413) (xy 188.871852 -290.74799) (xy 188.856268 -290.794671)
			(xy 188.833397 -290.838248) (xy 188.803832 -290.877592) (xy 188.768339 -290.911684) (xy 188.727836 -290.93964)
			(xy 188.683374 -290.960738) (xy 188.636103 -290.97443) (xy 188.587248 -290.980362) (xy 188.538073 -290.978381)
			(xy 188.489854 -290.968537) (xy 188.443838 -290.951085) (xy 188.401217 -290.926478) (xy 188.363096 -290.895353)
			(xy 188.330461 -290.858516) (xy 188.304158 -290.81692) (xy 188.284867 -290.771644) (xy 188.27309 -290.72386)
			(xy 188.26913 -290.674806) (xy 187.930282 -290.674806) (xy 187.929787 -290.699413) (xy 187.921892 -290.74799)
			(xy 187.906308 -290.794671) (xy 187.883437 -290.838248) (xy 187.853872 -290.877592) (xy 187.818379 -290.911684)
			(xy 187.777876 -290.93964) (xy 187.733414 -290.960738) (xy 187.686143 -290.97443) (xy 187.637288 -290.980362)
			(xy 187.588113 -290.978381) (xy 187.539894 -290.968537) (xy 187.493878 -290.951085) (xy 187.451257 -290.926478)
			(xy 187.413136 -290.895353) (xy 187.380501 -290.858516) (xy 187.354198 -290.81692) (xy 187.334907 -290.771644)
			(xy 187.32313 -290.72386) (xy 187.31917 -290.674806) (xy 186.980322 -290.674806) (xy 186.979827 -290.699413)
			(xy 186.971932 -290.74799) (xy 186.956348 -290.794671) (xy 186.933477 -290.838248) (xy 186.903912 -290.877592)
			(xy 186.868419 -290.911684) (xy 186.827916 -290.93964) (xy 186.783454 -290.960738) (xy 186.736183 -290.97443)
			(xy 186.687328 -290.980362) (xy 186.638153 -290.978381) (xy 186.589934 -290.968537) (xy 186.543918 -290.951085)
			(xy 186.501297 -290.926478) (xy 186.463176 -290.895353) (xy 186.430541 -290.858516) (xy 186.404238 -290.81692)
			(xy 186.384947 -290.771644) (xy 186.37317 -290.72386) (xy 186.36921 -290.674806) (xy 186.056237 -290.674806)
			(xy 186.052492 -290.724461) (xy 186.041343 -290.772995) (xy 186.023041 -290.819309) (xy 185.998001 -290.862354)
			(xy 185.96679 -290.901158) (xy 185.930112 -290.934842) (xy 185.909712 -290.949126) (xy 185.899699 -290.956658)
			(xy 185.887987 -290.978775) (xy 185.88736 -290.99129) (xy 185.88736 -291.238686) (xy 202.096622 -291.238686)
			(xy 202.100693 -291.183064) (xy 202.112819 -291.128627) (xy 202.132742 -291.076536) (xy 202.160038 -291.027901)
			(xy 202.194124 -290.983758) (xy 202.234273 -290.945049) (xy 202.279631 -290.912598) (xy 202.329231 -290.887097)
			(xy 202.382015 -290.86909) (xy 202.436858 -290.85896) (xy 202.492592 -290.856923) (xy 202.548029 -290.863023)
			(xy 202.601986 -290.877129) (xy 202.653315 -290.898941) (xy 202.700921 -290.927995) (xy 202.743789 -290.96367)
			(xy 202.781006 -291.005207) (xy 202.811779 -291.05172) (xy 202.835451 -291.102217) (xy 202.851519 -291.155624)
			(xy 202.859639 -291.2108) (xy 202.860148 -291.238686) (xy 202.859639 -291.266572) (xy 202.851519 -291.321748)
			(xy 202.835451 -291.375155) (xy 202.811779 -291.425652) (xy 202.781006 -291.472165) (xy 202.743789 -291.513702)
			(xy 202.700921 -291.549377) (xy 202.653315 -291.578431) (xy 202.621384 -291.592) (xy 204.54188 -291.592)
			(xy 204.545951 -291.536378) (xy 204.558077 -291.481941) (xy 204.578 -291.42985) (xy 204.605296 -291.381215)
			(xy 204.639382 -291.337072) (xy 204.679531 -291.298363) (xy 204.724889 -291.265912) (xy 204.774489 -291.240411)
			(xy 204.827273 -291.222404) (xy 204.882116 -291.212274) (xy 204.93785 -291.210237) (xy 204.993287 -291.216337)
			(xy 205.047244 -291.230443) (xy 205.098573 -291.252255) (xy 205.146179 -291.281309) (xy 205.189047 -291.316984)
			(xy 205.226264 -291.358521) (xy 205.257037 -291.405034) (xy 205.280709 -291.455531) (xy 205.296777 -291.508938)
			(xy 205.304897 -291.564114) (xy 205.305406 -291.592) (xy 205.304897 -291.619886) (xy 205.296777 -291.675062)
			(xy 205.280709 -291.728469) (xy 205.257037 -291.778966) (xy 205.226264 -291.825479) (xy 205.189047 -291.867016)
			(xy 205.146179 -291.902691) (xy 205.098573 -291.931745) (xy 205.047244 -291.953557) (xy 204.993287 -291.967663)
			(xy 204.93785 -291.973763) (xy 204.882116 -291.971726) (xy 204.827273 -291.961596) (xy 204.774489 -291.943589)
			(xy 204.724889 -291.918088) (xy 204.679531 -291.885637) (xy 204.639382 -291.846928) (xy 204.605296 -291.802785)
			(xy 204.578 -291.75415) (xy 204.558077 -291.702059) (xy 204.545951 -291.647622) (xy 204.54188 -291.592)
			(xy 202.621384 -291.592) (xy 202.601986 -291.600243) (xy 202.548029 -291.614349) (xy 202.492592 -291.620449)
			(xy 202.436858 -291.618412) (xy 202.382015 -291.608282) (xy 202.329231 -291.590275) (xy 202.279631 -291.564774)
			(xy 202.234273 -291.532323) (xy 202.194124 -291.493614) (xy 202.160038 -291.449471) (xy 202.132742 -291.400836)
			(xy 202.112819 -291.348745) (xy 202.100693 -291.294308) (xy 202.096622 -291.238686) (xy 185.88736 -291.238686)
			(xy 185.88736 -291.308282) (xy 185.888008 -291.320787) (xy 185.899733 -291.34288) (xy 185.909712 -291.350446)
			(xy 185.93012 -291.364722) (xy 185.966803 -291.398408) (xy 185.99802 -291.437214) (xy 186.023064 -291.480263)
			(xy 186.04137 -291.52658) (xy 186.052522 -291.575119) (xy 186.056269 -291.624766) (xy 186.36921 -291.624766)
			(xy 186.37317 -291.575712) (xy 186.384947 -291.527928) (xy 186.404238 -291.482652) (xy 186.430541 -291.441056)
			(xy 186.463176 -291.404219) (xy 186.501297 -291.373094) (xy 186.543918 -291.348487) (xy 186.589934 -291.331035)
			(xy 186.638153 -291.321191) (xy 186.687328 -291.31921) (xy 186.736183 -291.325142) (xy 186.783454 -291.338834)
			(xy 186.827916 -291.359932) (xy 186.868419 -291.387888) (xy 186.903912 -291.42198) (xy 186.933477 -291.461324)
			(xy 186.956348 -291.504901) (xy 186.971932 -291.551582) (xy 186.979827 -291.600159) (xy 186.980322 -291.624766)
			(xy 187.31917 -291.624766) (xy 187.32313 -291.575712) (xy 187.334907 -291.527928) (xy 187.354198 -291.482652)
			(xy 187.380501 -291.441056) (xy 187.413136 -291.404219) (xy 187.451257 -291.373094) (xy 187.493878 -291.348487)
			(xy 187.539894 -291.331035) (xy 187.588113 -291.321191) (xy 187.637288 -291.31921) (xy 187.686143 -291.325142)
			(xy 187.733414 -291.338834) (xy 187.777876 -291.359932) (xy 187.818379 -291.387888) (xy 187.853872 -291.42198)
			(xy 187.883437 -291.461324) (xy 187.906308 -291.504901) (xy 187.921892 -291.551582) (xy 187.929787 -291.600159)
			(xy 187.930282 -291.624766) (xy 188.26913 -291.624766) (xy 188.27309 -291.575712) (xy 188.284867 -291.527928)
			(xy 188.304158 -291.482652) (xy 188.330461 -291.441056) (xy 188.363096 -291.404219) (xy 188.401217 -291.373094)
			(xy 188.443838 -291.348487) (xy 188.489854 -291.331035) (xy 188.538073 -291.321191) (xy 188.587248 -291.31921)
			(xy 188.636103 -291.325142) (xy 188.683374 -291.338834) (xy 188.727836 -291.359932) (xy 188.768339 -291.387888)
			(xy 188.803832 -291.42198) (xy 188.833397 -291.461324) (xy 188.856268 -291.504901) (xy 188.871852 -291.551582)
			(xy 188.879747 -291.600159) (xy 188.880242 -291.624766) (xy 189.21909 -291.624766) (xy 189.22305 -291.575712)
			(xy 189.234827 -291.527928) (xy 189.254118 -291.482652) (xy 189.280421 -291.441056) (xy 189.313056 -291.404219)
			(xy 189.351177 -291.373094) (xy 189.393798 -291.348487) (xy 189.439814 -291.331035) (xy 189.488033 -291.321191)
			(xy 189.537208 -291.31921) (xy 189.586063 -291.325142) (xy 189.633334 -291.338834) (xy 189.677796 -291.359932)
			(xy 189.718299 -291.387888) (xy 189.753792 -291.42198) (xy 189.783357 -291.461324) (xy 189.806228 -291.504901)
			(xy 189.821812 -291.551582) (xy 189.829707 -291.600159) (xy 189.830202 -291.624766) (xy 190.169304 -291.624766)
			(xy 190.173264 -291.575712) (xy 190.185041 -291.527928) (xy 190.204332 -291.482652) (xy 190.230635 -291.441056)
			(xy 190.26327 -291.404219) (xy 190.301391 -291.373094) (xy 190.344012 -291.348487) (xy 190.390028 -291.331035)
			(xy 190.438247 -291.321191) (xy 190.487422 -291.31921) (xy 190.536277 -291.325142) (xy 190.583548 -291.338834)
			(xy 190.62801 -291.359932) (xy 190.668513 -291.387888) (xy 190.704006 -291.42198) (xy 190.733571 -291.461324)
			(xy 190.756442 -291.504901) (xy 190.772026 -291.551582) (xy 190.779921 -291.600159) (xy 190.780416 -291.624766)
			(xy 192.069224 -291.624766) (xy 192.073184 -291.575712) (xy 192.084961 -291.527928) (xy 192.104252 -291.482652)
			(xy 192.130555 -291.441056) (xy 192.16319 -291.404219) (xy 192.201311 -291.373094) (xy 192.243932 -291.348487)
			(xy 192.289948 -291.331035) (xy 192.338167 -291.321191) (xy 192.387342 -291.31921) (xy 192.436197 -291.325142)
			(xy 192.483468 -291.338834) (xy 192.52793 -291.359932) (xy 192.568433 -291.387888) (xy 192.603926 -291.42198)
			(xy 192.633491 -291.461324) (xy 192.656362 -291.504901) (xy 192.671946 -291.551582) (xy 192.679841 -291.600159)
			(xy 192.680336 -291.624766) (xy 193.019184 -291.624766) (xy 193.023144 -291.575712) (xy 193.034921 -291.527928)
			(xy 193.054212 -291.482652) (xy 193.080515 -291.441056) (xy 193.11315 -291.404219) (xy 193.151271 -291.373094)
			(xy 193.193892 -291.348487) (xy 193.239908 -291.331035) (xy 193.288127 -291.321191) (xy 193.337302 -291.31921)
			(xy 193.386157 -291.325142) (xy 193.433428 -291.338834) (xy 193.47789 -291.359932) (xy 193.518393 -291.387888)
			(xy 193.553886 -291.42198) (xy 193.583451 -291.461324) (xy 193.606322 -291.504901) (xy 193.621906 -291.551582)
			(xy 193.629801 -291.600159) (xy 193.630296 -291.624766) (xy 193.969144 -291.624766) (xy 193.973104 -291.575712)
			(xy 193.984881 -291.527928) (xy 194.004172 -291.482652) (xy 194.030475 -291.441056) (xy 194.06311 -291.404219)
			(xy 194.101231 -291.373094) (xy 194.143852 -291.348487) (xy 194.189868 -291.331035) (xy 194.238087 -291.321191)
			(xy 194.287262 -291.31921) (xy 194.336117 -291.325142) (xy 194.383388 -291.338834) (xy 194.42785 -291.359932)
			(xy 194.468353 -291.387888) (xy 194.503846 -291.42198) (xy 194.533411 -291.461324) (xy 194.556282 -291.504901)
			(xy 194.571866 -291.551582) (xy 194.579761 -291.600159) (xy 194.580256 -291.624766) (xy 194.919104 -291.624766)
			(xy 194.923064 -291.575712) (xy 194.934841 -291.527928) (xy 194.954132 -291.482652) (xy 194.980435 -291.441056)
			(xy 195.01307 -291.404219) (xy 195.051191 -291.373094) (xy 195.093812 -291.348487) (xy 195.139828 -291.331035)
			(xy 195.188047 -291.321191) (xy 195.237222 -291.31921) (xy 195.286077 -291.325142) (xy 195.333348 -291.338834)
			(xy 195.37781 -291.359932) (xy 195.418313 -291.387888) (xy 195.453806 -291.42198) (xy 195.483371 -291.461324)
			(xy 195.506242 -291.504901) (xy 195.521826 -291.551582) (xy 195.529721 -291.600159) (xy 195.530216 -291.624766)
			(xy 195.869064 -291.624766) (xy 195.873024 -291.575712) (xy 195.884801 -291.527928) (xy 195.904092 -291.482652)
			(xy 195.930395 -291.441056) (xy 195.96303 -291.404219) (xy 196.001151 -291.373094) (xy 196.043772 -291.348487)
			(xy 196.089788 -291.331035) (xy 196.138007 -291.321191) (xy 196.187182 -291.31921) (xy 196.236037 -291.325142)
			(xy 196.283308 -291.338834) (xy 196.32777 -291.359932) (xy 196.368273 -291.387888) (xy 196.403766 -291.42198)
			(xy 196.433331 -291.461324) (xy 196.456202 -291.504901) (xy 196.471786 -291.551582) (xy 196.479681 -291.600159)
			(xy 196.480176 -291.624766) (xy 196.819278 -291.624766) (xy 196.823238 -291.575712) (xy 196.835015 -291.527928)
			(xy 196.854306 -291.482652) (xy 196.880609 -291.441056) (xy 196.913244 -291.404219) (xy 196.951365 -291.373094)
			(xy 196.993986 -291.348487) (xy 197.040002 -291.331035) (xy 197.088221 -291.321191) (xy 197.137396 -291.31921)
			(xy 197.186251 -291.325142) (xy 197.233522 -291.338834) (xy 197.277984 -291.359932) (xy 197.318487 -291.387888)
			(xy 197.35398 -291.42198) (xy 197.383545 -291.461324) (xy 197.406416 -291.504901) (xy 197.422 -291.551582)
			(xy 197.429895 -291.600159) (xy 197.43039 -291.624766) (xy 197.769238 -291.624766) (xy 197.773198 -291.575712)
			(xy 197.784975 -291.527928) (xy 197.804266 -291.482652) (xy 197.830569 -291.441056) (xy 197.863204 -291.404219)
			(xy 197.901325 -291.373094) (xy 197.943946 -291.348487) (xy 197.989962 -291.331035) (xy 198.038181 -291.321191)
			(xy 198.087356 -291.31921) (xy 198.136211 -291.325142) (xy 198.183482 -291.338834) (xy 198.227944 -291.359932)
			(xy 198.268447 -291.387888) (xy 198.30394 -291.42198) (xy 198.333505 -291.461324) (xy 198.356376 -291.504901)
			(xy 198.37196 -291.551582) (xy 198.379855 -291.600159) (xy 198.38035 -291.624766) (xy 198.719198 -291.624766)
			(xy 198.723158 -291.575712) (xy 198.734935 -291.527928) (xy 198.754226 -291.482652) (xy 198.780529 -291.441056)
			(xy 198.813164 -291.404219) (xy 198.851285 -291.373094) (xy 198.893906 -291.348487) (xy 198.939922 -291.331035)
			(xy 198.988141 -291.321191) (xy 199.037316 -291.31921) (xy 199.086171 -291.325142) (xy 199.133442 -291.338834)
			(xy 199.177904 -291.359932) (xy 199.218407 -291.387888) (xy 199.2539 -291.42198) (xy 199.283465 -291.461324)
			(xy 199.306336 -291.504901) (xy 199.32192 -291.551582) (xy 199.329815 -291.600159) (xy 199.33031 -291.624766)
			(xy 199.329815 -291.649373) (xy 199.32192 -291.69795) (xy 199.306336 -291.744631) (xy 199.283465 -291.788208)
			(xy 199.2539 -291.827552) (xy 199.218407 -291.861644) (xy 199.177904 -291.8896) (xy 199.133442 -291.910698)
			(xy 199.086171 -291.92439) (xy 199.037316 -291.930322) (xy 198.988141 -291.928341) (xy 198.939922 -291.918497)
			(xy 198.893906 -291.901045) (xy 198.851285 -291.876438) (xy 198.813164 -291.845313) (xy 198.780529 -291.808476)
			(xy 198.754226 -291.76688) (xy 198.734935 -291.721604) (xy 198.723158 -291.67382) (xy 198.719198 -291.624766)
			(xy 198.38035 -291.624766) (xy 198.379855 -291.649373) (xy 198.37196 -291.69795) (xy 198.356376 -291.744631)
			(xy 198.333505 -291.788208) (xy 198.30394 -291.827552) (xy 198.268447 -291.861644) (xy 198.227944 -291.8896)
			(xy 198.183482 -291.910698) (xy 198.136211 -291.92439) (xy 198.087356 -291.930322) (xy 198.038181 -291.928341)
			(xy 197.989962 -291.918497) (xy 197.943946 -291.901045) (xy 197.901325 -291.876438) (xy 197.863204 -291.845313)
			(xy 197.830569 -291.808476) (xy 197.804266 -291.76688) (xy 197.784975 -291.721604) (xy 197.773198 -291.67382)
			(xy 197.769238 -291.624766) (xy 197.43039 -291.624766) (xy 197.429895 -291.649373) (xy 197.422 -291.69795)
			(xy 197.406416 -291.744631) (xy 197.383545 -291.788208) (xy 197.35398 -291.827552) (xy 197.318487 -291.861644)
			(xy 197.277984 -291.8896) (xy 197.233522 -291.910698) (xy 197.186251 -291.92439) (xy 197.137396 -291.930322)
			(xy 197.088221 -291.928341) (xy 197.040002 -291.918497) (xy 196.993986 -291.901045) (xy 196.951365 -291.876438)
			(xy 196.913244 -291.845313) (xy 196.880609 -291.808476) (xy 196.854306 -291.76688) (xy 196.835015 -291.721604)
			(xy 196.823238 -291.67382) (xy 196.819278 -291.624766) (xy 196.480176 -291.624766) (xy 196.479681 -291.649373)
			(xy 196.471786 -291.69795) (xy 196.456202 -291.744631) (xy 196.433331 -291.788208) (xy 196.403766 -291.827552)
			(xy 196.368273 -291.861644) (xy 196.32777 -291.8896) (xy 196.283308 -291.910698) (xy 196.236037 -291.92439)
			(xy 196.187182 -291.930322) (xy 196.138007 -291.928341) (xy 196.089788 -291.918497) (xy 196.043772 -291.901045)
			(xy 196.001151 -291.876438) (xy 195.96303 -291.845313) (xy 195.930395 -291.808476) (xy 195.904092 -291.76688)
			(xy 195.884801 -291.721604) (xy 195.873024 -291.67382) (xy 195.869064 -291.624766) (xy 195.530216 -291.624766)
			(xy 195.529721 -291.649373) (xy 195.521826 -291.69795) (xy 195.506242 -291.744631) (xy 195.483371 -291.788208)
			(xy 195.453806 -291.827552) (xy 195.418313 -291.861644) (xy 195.37781 -291.8896) (xy 195.333348 -291.910698)
			(xy 195.286077 -291.92439) (xy 195.237222 -291.930322) (xy 195.188047 -291.928341) (xy 195.139828 -291.918497)
			(xy 195.093812 -291.901045) (xy 195.051191 -291.876438) (xy 195.01307 -291.845313) (xy 194.980435 -291.808476)
			(xy 194.954132 -291.76688) (xy 194.934841 -291.721604) (xy 194.923064 -291.67382) (xy 194.919104 -291.624766)
			(xy 194.580256 -291.624766) (xy 194.579761 -291.649373) (xy 194.571866 -291.69795) (xy 194.556282 -291.744631)
			(xy 194.533411 -291.788208) (xy 194.503846 -291.827552) (xy 194.468353 -291.861644) (xy 194.42785 -291.8896)
			(xy 194.383388 -291.910698) (xy 194.336117 -291.92439) (xy 194.287262 -291.930322) (xy 194.238087 -291.928341)
			(xy 194.189868 -291.918497) (xy 194.143852 -291.901045) (xy 194.101231 -291.876438) (xy 194.06311 -291.845313)
			(xy 194.030475 -291.808476) (xy 194.004172 -291.76688) (xy 193.984881 -291.721604) (xy 193.973104 -291.67382)
			(xy 193.969144 -291.624766) (xy 193.630296 -291.624766) (xy 193.629801 -291.649373) (xy 193.621906 -291.69795)
			(xy 193.606322 -291.744631) (xy 193.583451 -291.788208) (xy 193.553886 -291.827552) (xy 193.518393 -291.861644)
			(xy 193.47789 -291.8896) (xy 193.433428 -291.910698) (xy 193.386157 -291.92439) (xy 193.337302 -291.930322)
			(xy 193.288127 -291.928341) (xy 193.239908 -291.918497) (xy 193.193892 -291.901045) (xy 193.151271 -291.876438)
			(xy 193.11315 -291.845313) (xy 193.080515 -291.808476) (xy 193.054212 -291.76688) (xy 193.034921 -291.721604)
			(xy 193.023144 -291.67382) (xy 193.019184 -291.624766) (xy 192.680336 -291.624766) (xy 192.679841 -291.649373)
			(xy 192.671946 -291.69795) (xy 192.656362 -291.744631) (xy 192.633491 -291.788208) (xy 192.603926 -291.827552)
			(xy 192.568433 -291.861644) (xy 192.52793 -291.8896) (xy 192.483468 -291.910698) (xy 192.436197 -291.92439)
			(xy 192.387342 -291.930322) (xy 192.338167 -291.928341) (xy 192.289948 -291.918497) (xy 192.243932 -291.901045)
			(xy 192.201311 -291.876438) (xy 192.16319 -291.845313) (xy 192.130555 -291.808476) (xy 192.104252 -291.76688)
			(xy 192.084961 -291.721604) (xy 192.073184 -291.67382) (xy 192.069224 -291.624766) (xy 190.780416 -291.624766)
			(xy 190.779921 -291.649373) (xy 190.772026 -291.69795) (xy 190.756442 -291.744631) (xy 190.733571 -291.788208)
			(xy 190.704006 -291.827552) (xy 190.668513 -291.861644) (xy 190.62801 -291.8896) (xy 190.583548 -291.910698)
			(xy 190.536277 -291.92439) (xy 190.487422 -291.930322) (xy 190.438247 -291.928341) (xy 190.390028 -291.918497)
			(xy 190.344012 -291.901045) (xy 190.301391 -291.876438) (xy 190.26327 -291.845313) (xy 190.230635 -291.808476)
			(xy 190.204332 -291.76688) (xy 190.185041 -291.721604) (xy 190.173264 -291.67382) (xy 190.169304 -291.624766)
			(xy 189.830202 -291.624766) (xy 189.829707 -291.649373) (xy 189.821812 -291.69795) (xy 189.806228 -291.744631)
			(xy 189.783357 -291.788208) (xy 189.753792 -291.827552) (xy 189.718299 -291.861644) (xy 189.677796 -291.8896)
			(xy 189.633334 -291.910698) (xy 189.586063 -291.92439) (xy 189.537208 -291.930322) (xy 189.488033 -291.928341)
			(xy 189.439814 -291.918497) (xy 189.393798 -291.901045) (xy 189.351177 -291.876438) (xy 189.313056 -291.845313)
			(xy 189.280421 -291.808476) (xy 189.254118 -291.76688) (xy 189.234827 -291.721604) (xy 189.22305 -291.67382)
			(xy 189.21909 -291.624766) (xy 188.880242 -291.624766) (xy 188.879747 -291.649373) (xy 188.871852 -291.69795)
			(xy 188.856268 -291.744631) (xy 188.833397 -291.788208) (xy 188.803832 -291.827552) (xy 188.768339 -291.861644)
			(xy 188.727836 -291.8896) (xy 188.683374 -291.910698) (xy 188.636103 -291.92439) (xy 188.587248 -291.930322)
			(xy 188.538073 -291.928341) (xy 188.489854 -291.918497) (xy 188.443838 -291.901045) (xy 188.401217 -291.876438)
			(xy 188.363096 -291.845313) (xy 188.330461 -291.808476) (xy 188.304158 -291.76688) (xy 188.284867 -291.721604)
			(xy 188.27309 -291.67382) (xy 188.26913 -291.624766) (xy 187.930282 -291.624766) (xy 187.929787 -291.649373)
			(xy 187.921892 -291.69795) (xy 187.906308 -291.744631) (xy 187.883437 -291.788208) (xy 187.853872 -291.827552)
			(xy 187.818379 -291.861644) (xy 187.777876 -291.8896) (xy 187.733414 -291.910698) (xy 187.686143 -291.92439)
			(xy 187.637288 -291.930322) (xy 187.588113 -291.928341) (xy 187.539894 -291.918497) (xy 187.493878 -291.901045)
			(xy 187.451257 -291.876438) (xy 187.413136 -291.845313) (xy 187.380501 -291.808476) (xy 187.354198 -291.76688)
			(xy 187.334907 -291.721604) (xy 187.32313 -291.67382) (xy 187.31917 -291.624766) (xy 186.980322 -291.624766)
			(xy 186.979827 -291.649373) (xy 186.971932 -291.69795) (xy 186.956348 -291.744631) (xy 186.933477 -291.788208)
			(xy 186.903912 -291.827552) (xy 186.868419 -291.861644) (xy 186.827916 -291.8896) (xy 186.783454 -291.910698)
			(xy 186.736183 -291.92439) (xy 186.687328 -291.930322) (xy 186.638153 -291.928341) (xy 186.589934 -291.918497)
			(xy 186.543918 -291.901045) (xy 186.501297 -291.876438) (xy 186.463176 -291.845313) (xy 186.430541 -291.808476)
			(xy 186.404238 -291.76688) (xy 186.384947 -291.721604) (xy 186.37317 -291.67382) (xy 186.36921 -291.624766)
			(xy 186.056269 -291.624766) (xy 186.05627 -291.624781) (xy 186.052528 -291.674444) (xy 186.041381 -291.722984)
			(xy 186.023081 -291.769303) (xy 185.998041 -291.812355) (xy 185.966829 -291.851164) (xy 185.93015 -291.884854)
			(xy 185.909712 -291.899086) (xy 185.899692 -291.906615) (xy 185.887963 -291.928731) (xy 185.88736 -291.94125)
			(xy 185.88736 -292.122098) (xy 209.357468 -292.122098) (xy 209.357886 -292.095493) (xy 209.365269 -292.042797)
			(xy 209.379907 -291.991639) (xy 209.401514 -291.943013) (xy 209.429671 -291.897863) (xy 209.463831 -291.857065)
			(xy 209.503331 -291.821413) (xy 209.525108 -291.806122) (xy 209.536541 -291.797728) (xy 209.554741 -291.775997)
			(xy 209.56626 -291.750097) (xy 209.570205 -291.722027) (xy 209.566274 -291.693955) (xy 209.55477 -291.668049)
			(xy 209.536581 -291.646309) (xy 209.525108 -291.637974) (xy 209.50331 -291.622718) (xy 209.463833 -291.587044)
			(xy 209.429693 -291.546233) (xy 209.401551 -291.501076) (xy 209.379953 -291.452449) (xy 209.365318 -291.401294)
			(xy 209.357929 -291.348602) (xy 209.357468 -291.321998) (xy 209.357954 -291.294747) (xy 209.36571 -291.240799)
			(xy 209.381065 -291.188504) (xy 209.403707 -291.138927) (xy 209.433173 -291.093077) (xy 209.468864 -291.051886)
			(xy 209.510055 -291.016195) (xy 209.555905 -290.986729) (xy 209.605482 -290.964087) (xy 209.657777 -290.948732)
			(xy 209.711725 -290.940976) (xy 209.766227 -290.940976) (xy 209.820175 -290.948732) (xy 209.87247 -290.964087)
			(xy 209.922047 -290.986729) (xy 209.967897 -291.016195) (xy 210.009088 -291.051886) (xy 210.044779 -291.093077)
			(xy 210.074245 -291.138927) (xy 210.096887 -291.188504) (xy 210.112242 -291.240799) (xy 210.119998 -291.294747)
			(xy 210.120484 -291.321998) (xy 210.120041 -291.348602) (xy 210.112659 -291.401296) (xy 210.098024 -291.452452)
			(xy 210.076421 -291.501077) (xy 210.048268 -291.546227) (xy 210.014113 -291.587026) (xy 209.974619 -291.622681)
			(xy 209.952844 -291.637974) (xy 209.941313 -291.646246) (xy 209.9231 -291.668001) (xy 209.911581 -291.693929)
			(xy 209.907644 -291.722027) (xy 209.911595 -291.750123) (xy 209.923129 -291.776045) (xy 209.941353 -291.79779)
			(xy 209.952844 -291.806122) (xy 209.97463 -291.821396) (xy 210.014109 -291.857065) (xy 210.048252 -291.897872)
			(xy 210.076396 -291.943026) (xy 210.097996 -291.991651) (xy 210.112633 -292.042804) (xy 210.120023 -292.095495)
			(xy 210.120484 -292.122098) (xy 210.119998 -292.149349) (xy 210.112242 -292.203297) (xy 210.096887 -292.255592)
			(xy 210.074245 -292.305169) (xy 210.044779 -292.351019) (xy 210.009088 -292.39221) (xy 209.967897 -292.427901)
			(xy 209.922047 -292.457367) (xy 209.87247 -292.480009) (xy 209.820175 -292.495364) (xy 209.766227 -292.50312)
			(xy 209.711725 -292.50312) (xy 209.657777 -292.495364) (xy 209.605482 -292.480009) (xy 209.555905 -292.457367)
			(xy 209.510055 -292.427901) (xy 209.468864 -292.39221) (xy 209.433173 -292.351019) (xy 209.403707 -292.305169)
			(xy 209.381065 -292.255592) (xy 209.36571 -292.203297) (xy 209.357954 -292.149349) (xy 209.357468 -292.122098)
			(xy 185.88736 -292.122098) (xy 185.88736 -292.258242) (xy 185.887999 -292.270752) (xy 185.899715 -292.292859)
			(xy 185.909712 -292.300406) (xy 185.930116 -292.314682) (xy 185.96679 -292.348367) (xy 185.997998 -292.38717)
			(xy 186.023034 -292.430215) (xy 186.041332 -292.476527) (xy 186.052478 -292.525059) (xy 186.05622 -292.574715)
			(xy 186.0562 -292.57498) (xy 186.36921 -292.57498) (xy 186.37317 -292.525926) (xy 186.384947 -292.478142)
			(xy 186.404238 -292.432866) (xy 186.430541 -292.39127) (xy 186.463176 -292.354433) (xy 186.501297 -292.323308)
			(xy 186.543918 -292.298701) (xy 186.589934 -292.281249) (xy 186.638153 -292.271405) (xy 186.687328 -292.269424)
			(xy 186.736183 -292.275356) (xy 186.783454 -292.289048) (xy 186.827916 -292.310146) (xy 186.868419 -292.338102)
			(xy 186.903912 -292.372194) (xy 186.933477 -292.411538) (xy 186.956348 -292.455115) (xy 186.971932 -292.501796)
			(xy 186.979827 -292.550373) (xy 186.980317 -292.574726) (xy 187.31917 -292.574726) (xy 187.32313 -292.525672)
			(xy 187.334907 -292.477888) (xy 187.354198 -292.432612) (xy 187.380501 -292.391016) (xy 187.413136 -292.354179)
			(xy 187.451257 -292.323054) (xy 187.493878 -292.298447) (xy 187.539894 -292.280995) (xy 187.588113 -292.271151)
			(xy 187.637288 -292.26917) (xy 187.686143 -292.275102) (xy 187.733414 -292.288794) (xy 187.777876 -292.309892)
			(xy 187.818379 -292.337848) (xy 187.853872 -292.37194) (xy 187.883437 -292.411284) (xy 187.906308 -292.454861)
			(xy 187.921892 -292.501542) (xy 187.929787 -292.550119) (xy 187.930282 -292.574726) (xy 188.26913 -292.574726)
			(xy 188.27309 -292.525672) (xy 188.284867 -292.477888) (xy 188.304158 -292.432612) (xy 188.330461 -292.391016)
			(xy 188.363096 -292.354179) (xy 188.401217 -292.323054) (xy 188.443838 -292.298447) (xy 188.489854 -292.280995)
			(xy 188.538073 -292.271151) (xy 188.587248 -292.26917) (xy 188.636103 -292.275102) (xy 188.683374 -292.288794)
			(xy 188.727836 -292.309892) (xy 188.768339 -292.337848) (xy 188.803832 -292.37194) (xy 188.833397 -292.411284)
			(xy 188.856268 -292.454861) (xy 188.871852 -292.501542) (xy 188.879747 -292.550119) (xy 188.880242 -292.574726)
			(xy 189.21909 -292.574726) (xy 189.22305 -292.525672) (xy 189.234827 -292.477888) (xy 189.254118 -292.432612)
			(xy 189.280421 -292.391016) (xy 189.313056 -292.354179) (xy 189.351177 -292.323054) (xy 189.393798 -292.298447)
			(xy 189.439814 -292.280995) (xy 189.488033 -292.271151) (xy 189.537208 -292.26917) (xy 189.586063 -292.275102)
			(xy 189.633334 -292.288794) (xy 189.677796 -292.309892) (xy 189.718299 -292.337848) (xy 189.753792 -292.37194)
			(xy 189.783357 -292.411284) (xy 189.806228 -292.454861) (xy 189.821812 -292.501542) (xy 189.829707 -292.550119)
			(xy 189.830202 -292.574726) (xy 190.16905 -292.574726) (xy 190.17301 -292.525672) (xy 190.184787 -292.477888)
			(xy 190.204078 -292.432612) (xy 190.230381 -292.391016) (xy 190.263016 -292.354179) (xy 190.301137 -292.323054)
			(xy 190.343758 -292.298447) (xy 190.389774 -292.280995) (xy 190.437993 -292.271151) (xy 190.487168 -292.26917)
			(xy 190.536023 -292.275102) (xy 190.583294 -292.288794) (xy 190.627756 -292.309892) (xy 190.668259 -292.337848)
			(xy 190.703752 -292.37194) (xy 190.733317 -292.411284) (xy 190.756188 -292.454861) (xy 190.771772 -292.501542)
			(xy 190.779667 -292.550119) (xy 190.780162 -292.574726) (xy 191.119264 -292.574726) (xy 191.123224 -292.525672)
			(xy 191.135001 -292.477888) (xy 191.154292 -292.432612) (xy 191.180595 -292.391016) (xy 191.21323 -292.354179)
			(xy 191.251351 -292.323054) (xy 191.293972 -292.298447) (xy 191.339988 -292.280995) (xy 191.388207 -292.271151)
			(xy 191.437382 -292.26917) (xy 191.486237 -292.275102) (xy 191.533508 -292.288794) (xy 191.57797 -292.309892)
			(xy 191.618473 -292.337848) (xy 191.653966 -292.37194) (xy 191.683531 -292.411284) (xy 191.706402 -292.454861)
			(xy 191.721986 -292.501542) (xy 191.729881 -292.550119) (xy 191.730376 -292.574726) (xy 192.069224 -292.574726)
			(xy 192.073184 -292.525672) (xy 192.084961 -292.477888) (xy 192.104252 -292.432612) (xy 192.130555 -292.391016)
			(xy 192.16319 -292.354179) (xy 192.201311 -292.323054) (xy 192.243932 -292.298447) (xy 192.289948 -292.280995)
			(xy 192.338167 -292.271151) (xy 192.387342 -292.26917) (xy 192.436197 -292.275102) (xy 192.483468 -292.288794)
			(xy 192.52793 -292.309892) (xy 192.568433 -292.337848) (xy 192.603926 -292.37194) (xy 192.633491 -292.411284)
			(xy 192.656362 -292.454861) (xy 192.671946 -292.501542) (xy 192.679841 -292.550119) (xy 192.680336 -292.574726)
			(xy 193.019184 -292.574726) (xy 193.023144 -292.525672) (xy 193.034921 -292.477888) (xy 193.054212 -292.432612)
			(xy 193.080515 -292.391016) (xy 193.11315 -292.354179) (xy 193.151271 -292.323054) (xy 193.193892 -292.298447)
			(xy 193.239908 -292.280995) (xy 193.288127 -292.271151) (xy 193.337302 -292.26917) (xy 193.386157 -292.275102)
			(xy 193.433428 -292.288794) (xy 193.47789 -292.309892) (xy 193.518393 -292.337848) (xy 193.553886 -292.37194)
			(xy 193.583451 -292.411284) (xy 193.606322 -292.454861) (xy 193.621906 -292.501542) (xy 193.629801 -292.550119)
			(xy 193.630296 -292.574726) (xy 193.969144 -292.574726) (xy 193.973104 -292.525672) (xy 193.984881 -292.477888)
			(xy 194.004172 -292.432612) (xy 194.030475 -292.391016) (xy 194.06311 -292.354179) (xy 194.101231 -292.323054)
			(xy 194.143852 -292.298447) (xy 194.189868 -292.280995) (xy 194.238087 -292.271151) (xy 194.287262 -292.26917)
			(xy 194.336117 -292.275102) (xy 194.383388 -292.288794) (xy 194.42785 -292.309892) (xy 194.468353 -292.337848)
			(xy 194.503846 -292.37194) (xy 194.533411 -292.411284) (xy 194.556282 -292.454861) (xy 194.571866 -292.501542)
			(xy 194.579761 -292.550119) (xy 194.580256 -292.574726) (xy 194.919104 -292.574726) (xy 194.923064 -292.525672)
			(xy 194.934841 -292.477888) (xy 194.954132 -292.432612) (xy 194.980435 -292.391016) (xy 195.01307 -292.354179)
			(xy 195.051191 -292.323054) (xy 195.093812 -292.298447) (xy 195.139828 -292.280995) (xy 195.188047 -292.271151)
			(xy 195.237222 -292.26917) (xy 195.286077 -292.275102) (xy 195.333348 -292.288794) (xy 195.37781 -292.309892)
			(xy 195.418313 -292.337848) (xy 195.453806 -292.37194) (xy 195.483371 -292.411284) (xy 195.506242 -292.454861)
			(xy 195.521826 -292.501542) (xy 195.529721 -292.550119) (xy 195.530216 -292.574726) (xy 195.869064 -292.574726)
			(xy 195.873024 -292.525672) (xy 195.884801 -292.477888) (xy 195.904092 -292.432612) (xy 195.930395 -292.391016)
			(xy 195.96303 -292.354179) (xy 196.001151 -292.323054) (xy 196.043772 -292.298447) (xy 196.089788 -292.280995)
			(xy 196.138007 -292.271151) (xy 196.187182 -292.26917) (xy 196.236037 -292.275102) (xy 196.283308 -292.288794)
			(xy 196.32777 -292.309892) (xy 196.368273 -292.337848) (xy 196.403766 -292.37194) (xy 196.433331 -292.411284)
			(xy 196.456202 -292.454861) (xy 196.471786 -292.501542) (xy 196.479681 -292.550119) (xy 196.480176 -292.574726)
			(xy 196.819278 -292.574726) (xy 196.823238 -292.525672) (xy 196.835015 -292.477888) (xy 196.854306 -292.432612)
			(xy 196.880609 -292.391016) (xy 196.913244 -292.354179) (xy 196.951365 -292.323054) (xy 196.993986 -292.298447)
			(xy 197.040002 -292.280995) (xy 197.088221 -292.271151) (xy 197.137396 -292.26917) (xy 197.186251 -292.275102)
			(xy 197.233522 -292.288794) (xy 197.277984 -292.309892) (xy 197.318487 -292.337848) (xy 197.35398 -292.37194)
			(xy 197.383545 -292.411284) (xy 197.406416 -292.454861) (xy 197.422 -292.501542) (xy 197.429895 -292.550119)
			(xy 197.43039 -292.574726) (xy 197.430385 -292.57498) (xy 197.769238 -292.57498) (xy 197.773198 -292.525926)
			(xy 197.784975 -292.478142) (xy 197.804266 -292.432866) (xy 197.830569 -292.39127) (xy 197.863204 -292.354433)
			(xy 197.901325 -292.323308) (xy 197.943946 -292.298701) (xy 197.989962 -292.281249) (xy 198.038181 -292.271405)
			(xy 198.087356 -292.269424) (xy 198.136211 -292.275356) (xy 198.183482 -292.289048) (xy 198.227944 -292.310146)
			(xy 198.268447 -292.338102) (xy 198.30394 -292.372194) (xy 198.333505 -292.411538) (xy 198.356376 -292.455115)
			(xy 198.37196 -292.501796) (xy 198.379855 -292.550373) (xy 198.38035 -292.57498) (xy 198.719198 -292.57498)
			(xy 198.723158 -292.525926) (xy 198.734935 -292.478142) (xy 198.754226 -292.432866) (xy 198.780529 -292.39127)
			(xy 198.813164 -292.354433) (xy 198.851285 -292.323308) (xy 198.893906 -292.298701) (xy 198.939922 -292.281249)
			(xy 198.988141 -292.271405) (xy 199.037316 -292.269424) (xy 199.086171 -292.275356) (xy 199.133442 -292.289048)
			(xy 199.177904 -292.310146) (xy 199.218407 -292.338102) (xy 199.2539 -292.372194) (xy 199.283465 -292.411538)
			(xy 199.306336 -292.455115) (xy 199.32192 -292.501796) (xy 199.329815 -292.550373) (xy 199.33031 -292.57498)
			(xy 199.329815 -292.599587) (xy 199.32192 -292.648164) (xy 199.306336 -292.694845) (xy 199.283465 -292.738422)
			(xy 199.2539 -292.777766) (xy 199.218407 -292.811858) (xy 199.177904 -292.839814) (xy 199.133442 -292.860912)
			(xy 199.086171 -292.874604) (xy 199.037316 -292.880536) (xy 198.988141 -292.878555) (xy 198.939922 -292.868711)
			(xy 198.893906 -292.851259) (xy 198.851285 -292.826652) (xy 198.813164 -292.795527) (xy 198.780529 -292.75869)
			(xy 198.754226 -292.717094) (xy 198.734935 -292.671818) (xy 198.723158 -292.624034) (xy 198.719198 -292.57498)
			(xy 198.38035 -292.57498) (xy 198.379855 -292.599587) (xy 198.37196 -292.648164) (xy 198.356376 -292.694845)
			(xy 198.333505 -292.738422) (xy 198.30394 -292.777766) (xy 198.268447 -292.811858) (xy 198.227944 -292.839814)
			(xy 198.183482 -292.860912) (xy 198.136211 -292.874604) (xy 198.087356 -292.880536) (xy 198.038181 -292.878555)
			(xy 197.989962 -292.868711) (xy 197.943946 -292.851259) (xy 197.901325 -292.826652) (xy 197.863204 -292.795527)
			(xy 197.830569 -292.75869) (xy 197.804266 -292.717094) (xy 197.784975 -292.671818) (xy 197.773198 -292.624034)
			(xy 197.769238 -292.57498) (xy 197.430385 -292.57498) (xy 197.429895 -292.599333) (xy 197.422 -292.64791)
			(xy 197.406416 -292.694591) (xy 197.383545 -292.738168) (xy 197.35398 -292.777512) (xy 197.318487 -292.811604)
			(xy 197.277984 -292.83956) (xy 197.233522 -292.860658) (xy 197.186251 -292.87435) (xy 197.137396 -292.880282)
			(xy 197.088221 -292.878301) (xy 197.040002 -292.868457) (xy 196.993986 -292.851005) (xy 196.951365 -292.826398)
			(xy 196.913244 -292.795273) (xy 196.880609 -292.758436) (xy 196.854306 -292.71684) (xy 196.835015 -292.671564)
			(xy 196.823238 -292.62378) (xy 196.819278 -292.574726) (xy 196.480176 -292.574726) (xy 196.479681 -292.599333)
			(xy 196.471786 -292.64791) (xy 196.456202 -292.694591) (xy 196.433331 -292.738168) (xy 196.403766 -292.777512)
			(xy 196.368273 -292.811604) (xy 196.32777 -292.83956) (xy 196.283308 -292.860658) (xy 196.236037 -292.87435)
			(xy 196.187182 -292.880282) (xy 196.138007 -292.878301) (xy 196.089788 -292.868457) (xy 196.043772 -292.851005)
			(xy 196.001151 -292.826398) (xy 195.96303 -292.795273) (xy 195.930395 -292.758436) (xy 195.904092 -292.71684)
			(xy 195.884801 -292.671564) (xy 195.873024 -292.62378) (xy 195.869064 -292.574726) (xy 195.530216 -292.574726)
			(xy 195.529721 -292.599333) (xy 195.521826 -292.64791) (xy 195.506242 -292.694591) (xy 195.483371 -292.738168)
			(xy 195.453806 -292.777512) (xy 195.418313 -292.811604) (xy 195.37781 -292.83956) (xy 195.333348 -292.860658)
			(xy 195.286077 -292.87435) (xy 195.237222 -292.880282) (xy 195.188047 -292.878301) (xy 195.139828 -292.868457)
			(xy 195.093812 -292.851005) (xy 195.051191 -292.826398) (xy 195.01307 -292.795273) (xy 194.980435 -292.758436)
			(xy 194.954132 -292.71684) (xy 194.934841 -292.671564) (xy 194.923064 -292.62378) (xy 194.919104 -292.574726)
			(xy 194.580256 -292.574726) (xy 194.579761 -292.599333) (xy 194.571866 -292.64791) (xy 194.556282 -292.694591)
			(xy 194.533411 -292.738168) (xy 194.503846 -292.777512) (xy 194.468353 -292.811604) (xy 194.42785 -292.83956)
			(xy 194.383388 -292.860658) (xy 194.336117 -292.87435) (xy 194.287262 -292.880282) (xy 194.238087 -292.878301)
			(xy 194.189868 -292.868457) (xy 194.143852 -292.851005) (xy 194.101231 -292.826398) (xy 194.06311 -292.795273)
			(xy 194.030475 -292.758436) (xy 194.004172 -292.71684) (xy 193.984881 -292.671564) (xy 193.973104 -292.62378)
			(xy 193.969144 -292.574726) (xy 193.630296 -292.574726) (xy 193.629801 -292.599333) (xy 193.621906 -292.64791)
			(xy 193.606322 -292.694591) (xy 193.583451 -292.738168) (xy 193.553886 -292.777512) (xy 193.518393 -292.811604)
			(xy 193.47789 -292.83956) (xy 193.433428 -292.860658) (xy 193.386157 -292.87435) (xy 193.337302 -292.880282)
			(xy 193.288127 -292.878301) (xy 193.239908 -292.868457) (xy 193.193892 -292.851005) (xy 193.151271 -292.826398)
			(xy 193.11315 -292.795273) (xy 193.080515 -292.758436) (xy 193.054212 -292.71684) (xy 193.034921 -292.671564)
			(xy 193.023144 -292.62378) (xy 193.019184 -292.574726) (xy 192.680336 -292.574726) (xy 192.679841 -292.599333)
			(xy 192.671946 -292.64791) (xy 192.656362 -292.694591) (xy 192.633491 -292.738168) (xy 192.603926 -292.777512)
			(xy 192.568433 -292.811604) (xy 192.52793 -292.83956) (xy 192.483468 -292.860658) (xy 192.436197 -292.87435)
			(xy 192.387342 -292.880282) (xy 192.338167 -292.878301) (xy 192.289948 -292.868457) (xy 192.243932 -292.851005)
			(xy 192.201311 -292.826398) (xy 192.16319 -292.795273) (xy 192.130555 -292.758436) (xy 192.104252 -292.71684)
			(xy 192.084961 -292.671564) (xy 192.073184 -292.62378) (xy 192.069224 -292.574726) (xy 191.730376 -292.574726)
			(xy 191.729881 -292.599333) (xy 191.721986 -292.64791) (xy 191.706402 -292.694591) (xy 191.683531 -292.738168)
			(xy 191.653966 -292.777512) (xy 191.618473 -292.811604) (xy 191.57797 -292.83956) (xy 191.533508 -292.860658)
			(xy 191.486237 -292.87435) (xy 191.437382 -292.880282) (xy 191.388207 -292.878301) (xy 191.339988 -292.868457)
			(xy 191.293972 -292.851005) (xy 191.251351 -292.826398) (xy 191.21323 -292.795273) (xy 191.180595 -292.758436)
			(xy 191.154292 -292.71684) (xy 191.135001 -292.671564) (xy 191.123224 -292.62378) (xy 191.119264 -292.574726)
			(xy 190.780162 -292.574726) (xy 190.779667 -292.599333) (xy 190.771772 -292.64791) (xy 190.756188 -292.694591)
			(xy 190.733317 -292.738168) (xy 190.703752 -292.777512) (xy 190.668259 -292.811604) (xy 190.627756 -292.83956)
			(xy 190.583294 -292.860658) (xy 190.536023 -292.87435) (xy 190.487168 -292.880282) (xy 190.437993 -292.878301)
			(xy 190.389774 -292.868457) (xy 190.343758 -292.851005) (xy 190.301137 -292.826398) (xy 190.263016 -292.795273)
			(xy 190.230381 -292.758436) (xy 190.204078 -292.71684) (xy 190.184787 -292.671564) (xy 190.17301 -292.62378)
			(xy 190.16905 -292.574726) (xy 189.830202 -292.574726) (xy 189.829707 -292.599333) (xy 189.821812 -292.64791)
			(xy 189.806228 -292.694591) (xy 189.783357 -292.738168) (xy 189.753792 -292.777512) (xy 189.718299 -292.811604)
			(xy 189.677796 -292.83956) (xy 189.633334 -292.860658) (xy 189.586063 -292.87435) (xy 189.537208 -292.880282)
			(xy 189.488033 -292.878301) (xy 189.439814 -292.868457) (xy 189.393798 -292.851005) (xy 189.351177 -292.826398)
			(xy 189.313056 -292.795273) (xy 189.280421 -292.758436) (xy 189.254118 -292.71684) (xy 189.234827 -292.671564)
			(xy 189.22305 -292.62378) (xy 189.21909 -292.574726) (xy 188.880242 -292.574726) (xy 188.879747 -292.599333)
			(xy 188.871852 -292.64791) (xy 188.856268 -292.694591) (xy 188.833397 -292.738168) (xy 188.803832 -292.777512)
			(xy 188.768339 -292.811604) (xy 188.727836 -292.83956) (xy 188.683374 -292.860658) (xy 188.636103 -292.87435)
			(xy 188.587248 -292.880282) (xy 188.538073 -292.878301) (xy 188.489854 -292.868457) (xy 188.443838 -292.851005)
			(xy 188.401217 -292.826398) (xy 188.363096 -292.795273) (xy 188.330461 -292.758436) (xy 188.304158 -292.71684)
			(xy 188.284867 -292.671564) (xy 188.27309 -292.62378) (xy 188.26913 -292.574726) (xy 187.930282 -292.574726)
			(xy 187.929787 -292.599333) (xy 187.921892 -292.64791) (xy 187.906308 -292.694591) (xy 187.883437 -292.738168)
			(xy 187.853872 -292.777512) (xy 187.818379 -292.811604) (xy 187.777876 -292.83956) (xy 187.733414 -292.860658)
			(xy 187.686143 -292.87435) (xy 187.637288 -292.880282) (xy 187.588113 -292.878301) (xy 187.539894 -292.868457)
			(xy 187.493878 -292.851005) (xy 187.451257 -292.826398) (xy 187.413136 -292.795273) (xy 187.380501 -292.758436)
			(xy 187.354198 -292.71684) (xy 187.334907 -292.671564) (xy 187.32313 -292.62378) (xy 187.31917 -292.574726)
			(xy 186.980317 -292.574726) (xy 186.980322 -292.57498) (xy 186.979827 -292.599587) (xy 186.971932 -292.648164)
			(xy 186.956348 -292.694845) (xy 186.933477 -292.738422) (xy 186.903912 -292.777766) (xy 186.868419 -292.811858)
			(xy 186.827916 -292.839814) (xy 186.783454 -292.860912) (xy 186.736183 -292.874604) (xy 186.687328 -292.880536)
			(xy 186.638153 -292.878555) (xy 186.589934 -292.868711) (xy 186.543918 -292.851259) (xy 186.501297 -292.826652)
			(xy 186.463176 -292.795527) (xy 186.430541 -292.75869) (xy 186.404238 -292.717094) (xy 186.384947 -292.671818)
			(xy 186.37317 -292.624034) (xy 186.36921 -292.57498) (xy 186.0562 -292.57498) (xy 186.052474 -292.624369)
			(xy 186.041323 -292.672901) (xy 186.023021 -292.719212) (xy 185.997981 -292.762254) (xy 185.96677 -292.801055)
			(xy 185.930093 -292.834736) (xy 185.909712 -292.849046) (xy 185.899702 -292.85658) (xy 185.887999 -292.878696)
			(xy 185.88736 -292.89121) (xy 185.88736 -293.208456) (xy 185.888002 -293.220964) (xy 185.899722 -293.243066)
			(xy 185.909712 -293.25062) (xy 185.930115 -293.264896) (xy 185.966787 -293.29858) (xy 185.997993 -293.337383)
			(xy 186.023027 -293.380427) (xy 186.041323 -293.426738) (xy 186.052468 -293.475269) (xy 186.056209 -293.524922)
			(xy 186.056208 -293.52494) (xy 186.36921 -293.52494) (xy 186.37317 -293.475886) (xy 186.384947 -293.428102)
			(xy 186.404238 -293.382826) (xy 186.430541 -293.34123) (xy 186.463176 -293.304393) (xy 186.501297 -293.273268)
			(xy 186.543918 -293.248661) (xy 186.589934 -293.231209) (xy 186.638153 -293.221365) (xy 186.687328 -293.219384)
			(xy 186.736183 -293.225316) (xy 186.783454 -293.239008) (xy 186.827916 -293.260106) (xy 186.868419 -293.288062)
			(xy 186.903912 -293.322154) (xy 186.933477 -293.361498) (xy 186.956348 -293.405075) (xy 186.971932 -293.451756)
			(xy 186.979827 -293.500333) (xy 186.980322 -293.52494) (xy 187.31917 -293.52494) (xy 187.32313 -293.475886)
			(xy 187.334907 -293.428102) (xy 187.354198 -293.382826) (xy 187.380501 -293.34123) (xy 187.413136 -293.304393)
			(xy 187.451257 -293.273268) (xy 187.493878 -293.248661) (xy 187.539894 -293.231209) (xy 187.588113 -293.221365)
			(xy 187.637288 -293.219384) (xy 187.686143 -293.225316) (xy 187.733414 -293.239008) (xy 187.777876 -293.260106)
			(xy 187.818379 -293.288062) (xy 187.853872 -293.322154) (xy 187.883437 -293.361498) (xy 187.906308 -293.405075)
			(xy 187.921892 -293.451756) (xy 187.929787 -293.500333) (xy 187.930282 -293.52494) (xy 188.26913 -293.52494)
			(xy 188.27309 -293.475886) (xy 188.284867 -293.428102) (xy 188.304158 -293.382826) (xy 188.330461 -293.34123)
			(xy 188.363096 -293.304393) (xy 188.401217 -293.273268) (xy 188.443838 -293.248661) (xy 188.489854 -293.231209)
			(xy 188.538073 -293.221365) (xy 188.587248 -293.219384) (xy 188.636103 -293.225316) (xy 188.683374 -293.239008)
			(xy 188.727836 -293.260106) (xy 188.768339 -293.288062) (xy 188.803832 -293.322154) (xy 188.833397 -293.361498)
			(xy 188.856268 -293.405075) (xy 188.871852 -293.451756) (xy 188.879747 -293.500333) (xy 188.880242 -293.52494)
			(xy 189.21909 -293.52494) (xy 189.22305 -293.475886) (xy 189.234827 -293.428102) (xy 189.254118 -293.382826)
			(xy 189.280421 -293.34123) (xy 189.313056 -293.304393) (xy 189.351177 -293.273268) (xy 189.393798 -293.248661)
			(xy 189.439814 -293.231209) (xy 189.488033 -293.221365) (xy 189.537208 -293.219384) (xy 189.586063 -293.225316)
			(xy 189.633334 -293.239008) (xy 189.677796 -293.260106) (xy 189.718299 -293.288062) (xy 189.753792 -293.322154)
			(xy 189.783357 -293.361498) (xy 189.806228 -293.405075) (xy 189.821812 -293.451756) (xy 189.829707 -293.500333)
			(xy 189.830202 -293.52494) (xy 190.169304 -293.52494) (xy 190.173264 -293.475886) (xy 190.185041 -293.428102)
			(xy 190.204332 -293.382826) (xy 190.230635 -293.34123) (xy 190.26327 -293.304393) (xy 190.301391 -293.273268)
			(xy 190.344012 -293.248661) (xy 190.390028 -293.231209) (xy 190.438247 -293.221365) (xy 190.487422 -293.219384)
			(xy 190.536277 -293.225316) (xy 190.583548 -293.239008) (xy 190.62801 -293.260106) (xy 190.668513 -293.288062)
			(xy 190.704006 -293.322154) (xy 190.733571 -293.361498) (xy 190.756442 -293.405075) (xy 190.772026 -293.451756)
			(xy 190.779921 -293.500333) (xy 190.780416 -293.52494) (xy 191.119264 -293.52494) (xy 191.123224 -293.475886)
			(xy 191.135001 -293.428102) (xy 191.154292 -293.382826) (xy 191.180595 -293.34123) (xy 191.21323 -293.304393)
			(xy 191.251351 -293.273268) (xy 191.293972 -293.248661) (xy 191.339988 -293.231209) (xy 191.388207 -293.221365)
			(xy 191.437382 -293.219384) (xy 191.486237 -293.225316) (xy 191.533508 -293.239008) (xy 191.57797 -293.260106)
			(xy 191.618473 -293.288062) (xy 191.653966 -293.322154) (xy 191.683531 -293.361498) (xy 191.706402 -293.405075)
			(xy 191.721986 -293.451756) (xy 191.729881 -293.500333) (xy 191.730376 -293.52494) (xy 192.069224 -293.52494)
			(xy 192.073184 -293.475886) (xy 192.084961 -293.428102) (xy 192.104252 -293.382826) (xy 192.130555 -293.34123)
			(xy 192.16319 -293.304393) (xy 192.201311 -293.273268) (xy 192.243932 -293.248661) (xy 192.289948 -293.231209)
			(xy 192.338167 -293.221365) (xy 192.387342 -293.219384) (xy 192.436197 -293.225316) (xy 192.483468 -293.239008)
			(xy 192.52793 -293.260106) (xy 192.568433 -293.288062) (xy 192.603926 -293.322154) (xy 192.633491 -293.361498)
			(xy 192.656362 -293.405075) (xy 192.671946 -293.451756) (xy 192.679841 -293.500333) (xy 192.680336 -293.52494)
			(xy 193.019184 -293.52494) (xy 193.023144 -293.475886) (xy 193.034921 -293.428102) (xy 193.054212 -293.382826)
			(xy 193.080515 -293.34123) (xy 193.11315 -293.304393) (xy 193.151271 -293.273268) (xy 193.193892 -293.248661)
			(xy 193.239908 -293.231209) (xy 193.288127 -293.221365) (xy 193.337302 -293.219384) (xy 193.386157 -293.225316)
			(xy 193.433428 -293.239008) (xy 193.47789 -293.260106) (xy 193.518393 -293.288062) (xy 193.553886 -293.322154)
			(xy 193.583451 -293.361498) (xy 193.606322 -293.405075) (xy 193.621906 -293.451756) (xy 193.629801 -293.500333)
			(xy 193.630296 -293.52494) (xy 193.969144 -293.52494) (xy 193.973104 -293.475886) (xy 193.984881 -293.428102)
			(xy 194.004172 -293.382826) (xy 194.030475 -293.34123) (xy 194.06311 -293.304393) (xy 194.101231 -293.273268)
			(xy 194.143852 -293.248661) (xy 194.189868 -293.231209) (xy 194.238087 -293.221365) (xy 194.287262 -293.219384)
			(xy 194.336117 -293.225316) (xy 194.383388 -293.239008) (xy 194.42785 -293.260106) (xy 194.468353 -293.288062)
			(xy 194.503846 -293.322154) (xy 194.533411 -293.361498) (xy 194.556282 -293.405075) (xy 194.571866 -293.451756)
			(xy 194.579761 -293.500333) (xy 194.580256 -293.52494) (xy 194.919104 -293.52494) (xy 194.923064 -293.475886)
			(xy 194.934841 -293.428102) (xy 194.954132 -293.382826) (xy 194.980435 -293.34123) (xy 195.01307 -293.304393)
			(xy 195.051191 -293.273268) (xy 195.093812 -293.248661) (xy 195.139828 -293.231209) (xy 195.188047 -293.221365)
			(xy 195.237222 -293.219384) (xy 195.286077 -293.225316) (xy 195.333348 -293.239008) (xy 195.37781 -293.260106)
			(xy 195.418313 -293.288062) (xy 195.453806 -293.322154) (xy 195.483371 -293.361498) (xy 195.506242 -293.405075)
			(xy 195.521826 -293.451756) (xy 195.529721 -293.500333) (xy 195.530216 -293.52494) (xy 195.869064 -293.52494)
			(xy 195.873024 -293.475886) (xy 195.884801 -293.428102) (xy 195.904092 -293.382826) (xy 195.930395 -293.34123)
			(xy 195.96303 -293.304393) (xy 196.001151 -293.273268) (xy 196.043772 -293.248661) (xy 196.089788 -293.231209)
			(xy 196.138007 -293.221365) (xy 196.187182 -293.219384) (xy 196.236037 -293.225316) (xy 196.283308 -293.239008)
			(xy 196.32777 -293.260106) (xy 196.368273 -293.288062) (xy 196.403766 -293.322154) (xy 196.433331 -293.361498)
			(xy 196.456202 -293.405075) (xy 196.471786 -293.451756) (xy 196.479681 -293.500333) (xy 196.480176 -293.52494)
			(xy 196.819278 -293.52494) (xy 196.823238 -293.475886) (xy 196.835015 -293.428102) (xy 196.854306 -293.382826)
			(xy 196.880609 -293.34123) (xy 196.913244 -293.304393) (xy 196.951365 -293.273268) (xy 196.993986 -293.248661)
			(xy 197.040002 -293.231209) (xy 197.088221 -293.221365) (xy 197.137396 -293.219384) (xy 197.186251 -293.225316)
			(xy 197.233522 -293.239008) (xy 197.277984 -293.260106) (xy 197.318487 -293.288062) (xy 197.35398 -293.322154)
			(xy 197.383545 -293.361498) (xy 197.406416 -293.405075) (xy 197.422 -293.451756) (xy 197.429895 -293.500333)
			(xy 197.43039 -293.52494) (xy 197.769238 -293.52494) (xy 197.773198 -293.475886) (xy 197.784975 -293.428102)
			(xy 197.804266 -293.382826) (xy 197.830569 -293.34123) (xy 197.863204 -293.304393) (xy 197.901325 -293.273268)
			(xy 197.943946 -293.248661) (xy 197.989962 -293.231209) (xy 198.038181 -293.221365) (xy 198.087356 -293.219384)
			(xy 198.136211 -293.225316) (xy 198.183482 -293.239008) (xy 198.227944 -293.260106) (xy 198.268447 -293.288062)
			(xy 198.30394 -293.322154) (xy 198.333505 -293.361498) (xy 198.356376 -293.405075) (xy 198.37196 -293.451756)
			(xy 198.379855 -293.500333) (xy 198.38035 -293.52494) (xy 198.719198 -293.52494) (xy 198.723158 -293.475886)
			(xy 198.734935 -293.428102) (xy 198.754226 -293.382826) (xy 198.780529 -293.34123) (xy 198.813164 -293.304393)
			(xy 198.851285 -293.273268) (xy 198.893906 -293.248661) (xy 198.939922 -293.231209) (xy 198.988141 -293.221365)
			(xy 199.037316 -293.219384) (xy 199.086171 -293.225316) (xy 199.133442 -293.239008) (xy 199.177904 -293.260106)
			(xy 199.218407 -293.288062) (xy 199.2539 -293.322154) (xy 199.283465 -293.361498) (xy 199.306336 -293.405075)
			(xy 199.32192 -293.451756) (xy 199.329815 -293.500333) (xy 199.33031 -293.52494) (xy 199.329815 -293.549547)
			(xy 199.32192 -293.598124) (xy 199.306336 -293.644805) (xy 199.283465 -293.688382) (xy 199.2539 -293.727726)
			(xy 199.218407 -293.761818) (xy 199.177904 -293.789774) (xy 199.133442 -293.810872) (xy 199.086171 -293.824564)
			(xy 199.037316 -293.830496) (xy 198.988141 -293.828515) (xy 198.939922 -293.818671) (xy 198.893906 -293.801219)
			(xy 198.851285 -293.776612) (xy 198.813164 -293.745487) (xy 198.780529 -293.70865) (xy 198.754226 -293.667054)
			(xy 198.734935 -293.621778) (xy 198.723158 -293.573994) (xy 198.719198 -293.52494) (xy 198.38035 -293.52494)
			(xy 198.379855 -293.549547) (xy 198.37196 -293.598124) (xy 198.356376 -293.644805) (xy 198.333505 -293.688382)
			(xy 198.30394 -293.727726) (xy 198.268447 -293.761818) (xy 198.227944 -293.789774) (xy 198.183482 -293.810872)
			(xy 198.136211 -293.824564) (xy 198.087356 -293.830496) (xy 198.038181 -293.828515) (xy 197.989962 -293.818671)
			(xy 197.943946 -293.801219) (xy 197.901325 -293.776612) (xy 197.863204 -293.745487) (xy 197.830569 -293.70865)
			(xy 197.804266 -293.667054) (xy 197.784975 -293.621778) (xy 197.773198 -293.573994) (xy 197.769238 -293.52494)
			(xy 197.43039 -293.52494) (xy 197.429895 -293.549547) (xy 197.422 -293.598124) (xy 197.406416 -293.644805)
			(xy 197.383545 -293.688382) (xy 197.35398 -293.727726) (xy 197.318487 -293.761818) (xy 197.277984 -293.789774)
			(xy 197.233522 -293.810872) (xy 197.186251 -293.824564) (xy 197.137396 -293.830496) (xy 197.088221 -293.828515)
			(xy 197.040002 -293.818671) (xy 196.993986 -293.801219) (xy 196.951365 -293.776612) (xy 196.913244 -293.745487)
			(xy 196.880609 -293.70865) (xy 196.854306 -293.667054) (xy 196.835015 -293.621778) (xy 196.823238 -293.573994)
			(xy 196.819278 -293.52494) (xy 196.480176 -293.52494) (xy 196.479681 -293.549547) (xy 196.471786 -293.598124)
			(xy 196.456202 -293.644805) (xy 196.433331 -293.688382) (xy 196.403766 -293.727726) (xy 196.368273 -293.761818)
			(xy 196.32777 -293.789774) (xy 196.283308 -293.810872) (xy 196.236037 -293.824564) (xy 196.187182 -293.830496)
			(xy 196.138007 -293.828515) (xy 196.089788 -293.818671) (xy 196.043772 -293.801219) (xy 196.001151 -293.776612)
			(xy 195.96303 -293.745487) (xy 195.930395 -293.70865) (xy 195.904092 -293.667054) (xy 195.884801 -293.621778)
			(xy 195.873024 -293.573994) (xy 195.869064 -293.52494) (xy 195.530216 -293.52494) (xy 195.529721 -293.549547)
			(xy 195.521826 -293.598124) (xy 195.506242 -293.644805) (xy 195.483371 -293.688382) (xy 195.453806 -293.727726)
			(xy 195.418313 -293.761818) (xy 195.37781 -293.789774) (xy 195.333348 -293.810872) (xy 195.286077 -293.824564)
			(xy 195.237222 -293.830496) (xy 195.188047 -293.828515) (xy 195.139828 -293.818671) (xy 195.093812 -293.801219)
			(xy 195.051191 -293.776612) (xy 195.01307 -293.745487) (xy 194.980435 -293.70865) (xy 194.954132 -293.667054)
			(xy 194.934841 -293.621778) (xy 194.923064 -293.573994) (xy 194.919104 -293.52494) (xy 194.580256 -293.52494)
			(xy 194.579761 -293.549547) (xy 194.571866 -293.598124) (xy 194.556282 -293.644805) (xy 194.533411 -293.688382)
			(xy 194.503846 -293.727726) (xy 194.468353 -293.761818) (xy 194.42785 -293.789774) (xy 194.383388 -293.810872)
			(xy 194.336117 -293.824564) (xy 194.287262 -293.830496) (xy 194.238087 -293.828515) (xy 194.189868 -293.818671)
			(xy 194.143852 -293.801219) (xy 194.101231 -293.776612) (xy 194.06311 -293.745487) (xy 194.030475 -293.70865)
			(xy 194.004172 -293.667054) (xy 193.984881 -293.621778) (xy 193.973104 -293.573994) (xy 193.969144 -293.52494)
			(xy 193.630296 -293.52494) (xy 193.629801 -293.549547) (xy 193.621906 -293.598124) (xy 193.606322 -293.644805)
			(xy 193.583451 -293.688382) (xy 193.553886 -293.727726) (xy 193.518393 -293.761818) (xy 193.47789 -293.789774)
			(xy 193.433428 -293.810872) (xy 193.386157 -293.824564) (xy 193.337302 -293.830496) (xy 193.288127 -293.828515)
			(xy 193.239908 -293.818671) (xy 193.193892 -293.801219) (xy 193.151271 -293.776612) (xy 193.11315 -293.745487)
			(xy 193.080515 -293.70865) (xy 193.054212 -293.667054) (xy 193.034921 -293.621778) (xy 193.023144 -293.573994)
			(xy 193.019184 -293.52494) (xy 192.680336 -293.52494) (xy 192.679841 -293.549547) (xy 192.671946 -293.598124)
			(xy 192.656362 -293.644805) (xy 192.633491 -293.688382) (xy 192.603926 -293.727726) (xy 192.568433 -293.761818)
			(xy 192.52793 -293.789774) (xy 192.483468 -293.810872) (xy 192.436197 -293.824564) (xy 192.387342 -293.830496)
			(xy 192.338167 -293.828515) (xy 192.289948 -293.818671) (xy 192.243932 -293.801219) (xy 192.201311 -293.776612)
			(xy 192.16319 -293.745487) (xy 192.130555 -293.70865) (xy 192.104252 -293.667054) (xy 192.084961 -293.621778)
			(xy 192.073184 -293.573994) (xy 192.069224 -293.52494) (xy 191.730376 -293.52494) (xy 191.729881 -293.549547)
			(xy 191.721986 -293.598124) (xy 191.706402 -293.644805) (xy 191.683531 -293.688382) (xy 191.653966 -293.727726)
			(xy 191.618473 -293.761818) (xy 191.57797 -293.789774) (xy 191.533508 -293.810872) (xy 191.486237 -293.824564)
			(xy 191.437382 -293.830496) (xy 191.388207 -293.828515) (xy 191.339988 -293.818671) (xy 191.293972 -293.801219)
			(xy 191.251351 -293.776612) (xy 191.21323 -293.745487) (xy 191.180595 -293.70865) (xy 191.154292 -293.667054)
			(xy 191.135001 -293.621778) (xy 191.123224 -293.573994) (xy 191.119264 -293.52494) (xy 190.780416 -293.52494)
			(xy 190.779921 -293.549547) (xy 190.772026 -293.598124) (xy 190.756442 -293.644805) (xy 190.733571 -293.688382)
			(xy 190.704006 -293.727726) (xy 190.668513 -293.761818) (xy 190.62801 -293.789774) (xy 190.583548 -293.810872)
			(xy 190.536277 -293.824564) (xy 190.487422 -293.830496) (xy 190.438247 -293.828515) (xy 190.390028 -293.818671)
			(xy 190.344012 -293.801219) (xy 190.301391 -293.776612) (xy 190.26327 -293.745487) (xy 190.230635 -293.70865)
			(xy 190.204332 -293.667054) (xy 190.185041 -293.621778) (xy 190.173264 -293.573994) (xy 190.169304 -293.52494)
			(xy 189.830202 -293.52494) (xy 189.829707 -293.549547) (xy 189.821812 -293.598124) (xy 189.806228 -293.644805)
			(xy 189.783357 -293.688382) (xy 189.753792 -293.727726) (xy 189.718299 -293.761818) (xy 189.677796 -293.789774)
			(xy 189.633334 -293.810872) (xy 189.586063 -293.824564) (xy 189.537208 -293.830496) (xy 189.488033 -293.828515)
			(xy 189.439814 -293.818671) (xy 189.393798 -293.801219) (xy 189.351177 -293.776612) (xy 189.313056 -293.745487)
			(xy 189.280421 -293.70865) (xy 189.254118 -293.667054) (xy 189.234827 -293.621778) (xy 189.22305 -293.573994)
			(xy 189.21909 -293.52494) (xy 188.880242 -293.52494) (xy 188.879747 -293.549547) (xy 188.871852 -293.598124)
			(xy 188.856268 -293.644805) (xy 188.833397 -293.688382) (xy 188.803832 -293.727726) (xy 188.768339 -293.761818)
			(xy 188.727836 -293.789774) (xy 188.683374 -293.810872) (xy 188.636103 -293.824564) (xy 188.587248 -293.830496)
			(xy 188.538073 -293.828515) (xy 188.489854 -293.818671) (xy 188.443838 -293.801219) (xy 188.401217 -293.776612)
			(xy 188.363096 -293.745487) (xy 188.330461 -293.70865) (xy 188.304158 -293.667054) (xy 188.284867 -293.621778)
			(xy 188.27309 -293.573994) (xy 188.26913 -293.52494) (xy 187.930282 -293.52494) (xy 187.929787 -293.549547)
			(xy 187.921892 -293.598124) (xy 187.906308 -293.644805) (xy 187.883437 -293.688382) (xy 187.853872 -293.727726)
			(xy 187.818379 -293.761818) (xy 187.777876 -293.789774) (xy 187.733414 -293.810872) (xy 187.686143 -293.824564)
			(xy 187.637288 -293.830496) (xy 187.588113 -293.828515) (xy 187.539894 -293.818671) (xy 187.493878 -293.801219)
			(xy 187.451257 -293.776612) (xy 187.413136 -293.745487) (xy 187.380501 -293.70865) (xy 187.354198 -293.667054)
			(xy 187.334907 -293.621778) (xy 187.32313 -293.573994) (xy 187.31917 -293.52494) (xy 186.980322 -293.52494)
			(xy 186.979827 -293.549547) (xy 186.971932 -293.598124) (xy 186.956348 -293.644805) (xy 186.933477 -293.688382)
			(xy 186.903912 -293.727726) (xy 186.868419 -293.761818) (xy 186.827916 -293.789774) (xy 186.783454 -293.810872)
			(xy 186.736183 -293.824564) (xy 186.687328 -293.830496) (xy 186.638153 -293.828515) (xy 186.589934 -293.818671)
			(xy 186.543918 -293.801219) (xy 186.501297 -293.776612) (xy 186.463176 -293.745487) (xy 186.430541 -293.70865)
			(xy 186.404238 -293.667054) (xy 186.384947 -293.621778) (xy 186.37317 -293.573994) (xy 186.36921 -293.52494)
			(xy 186.056208 -293.52494) (xy 186.052461 -293.574575) (xy 186.04131 -293.623105) (xy 186.023007 -293.669414)
			(xy 185.997967 -293.712454) (xy 185.966756 -293.751252) (xy 185.930079 -293.784932) (xy 185.909712 -293.79926)
			(xy 185.899705 -293.806795) (xy 185.888007 -293.828911) (xy 185.88736 -293.841424) (xy 185.88736 -294.158416)
			(xy 185.888016 -294.170917) (xy 185.899749 -294.192997) (xy 185.909712 -294.20058) (xy 185.930118 -294.214856)
			(xy 185.966796 -294.248541) (xy 185.998007 -294.287346) (xy 186.023047 -294.330392) (xy 186.041348 -294.376707)
			(xy 186.052497 -294.425242) (xy 186.056242 -294.4749) (xy 186.36921 -294.4749) (xy 186.37317 -294.425846)
			(xy 186.384947 -294.378062) (xy 186.404238 -294.332786) (xy 186.430541 -294.29119) (xy 186.463176 -294.254353)
			(xy 186.501297 -294.223228) (xy 186.543918 -294.198621) (xy 186.589934 -294.181169) (xy 186.638153 -294.171325)
			(xy 186.687328 -294.169344) (xy 186.736183 -294.175276) (xy 186.783454 -294.188968) (xy 186.827916 -294.210066)
			(xy 186.868419 -294.238022) (xy 186.903912 -294.272114) (xy 186.933477 -294.311458) (xy 186.956348 -294.355035)
			(xy 186.971932 -294.401716) (xy 186.979827 -294.450293) (xy 186.980322 -294.4749) (xy 187.31917 -294.4749)
			(xy 187.32313 -294.425846) (xy 187.334907 -294.378062) (xy 187.354198 -294.332786) (xy 187.380501 -294.29119)
			(xy 187.413136 -294.254353) (xy 187.451257 -294.223228) (xy 187.493878 -294.198621) (xy 187.539894 -294.181169)
			(xy 187.588113 -294.171325) (xy 187.637288 -294.169344) (xy 187.686143 -294.175276) (xy 187.733414 -294.188968)
			(xy 187.777876 -294.210066) (xy 187.818379 -294.238022) (xy 187.853872 -294.272114) (xy 187.883437 -294.311458)
			(xy 187.906308 -294.355035) (xy 187.921892 -294.401716) (xy 187.929787 -294.450293) (xy 187.930282 -294.4749)
			(xy 188.26913 -294.4749) (xy 188.27309 -294.425846) (xy 188.284867 -294.378062) (xy 188.304158 -294.332786)
			(xy 188.330461 -294.29119) (xy 188.363096 -294.254353) (xy 188.401217 -294.223228) (xy 188.443838 -294.198621)
			(xy 188.489854 -294.181169) (xy 188.538073 -294.171325) (xy 188.587248 -294.169344) (xy 188.636103 -294.175276)
			(xy 188.683374 -294.188968) (xy 188.727836 -294.210066) (xy 188.768339 -294.238022) (xy 188.803832 -294.272114)
			(xy 188.833397 -294.311458) (xy 188.856268 -294.355035) (xy 188.871852 -294.401716) (xy 188.879747 -294.450293)
			(xy 188.880242 -294.4749) (xy 189.21909 -294.4749) (xy 189.22305 -294.425846) (xy 189.234827 -294.378062)
			(xy 189.254118 -294.332786) (xy 189.280421 -294.29119) (xy 189.313056 -294.254353) (xy 189.351177 -294.223228)
			(xy 189.393798 -294.198621) (xy 189.439814 -294.181169) (xy 189.488033 -294.171325) (xy 189.537208 -294.169344)
			(xy 189.586063 -294.175276) (xy 189.633334 -294.188968) (xy 189.677796 -294.210066) (xy 189.718299 -294.238022)
			(xy 189.753792 -294.272114) (xy 189.783357 -294.311458) (xy 189.806228 -294.355035) (xy 189.821812 -294.401716)
			(xy 189.829707 -294.450293) (xy 189.830202 -294.4749) (xy 190.16905 -294.4749) (xy 190.17301 -294.425846)
			(xy 190.184787 -294.378062) (xy 190.204078 -294.332786) (xy 190.230381 -294.29119) (xy 190.263016 -294.254353)
			(xy 190.301137 -294.223228) (xy 190.343758 -294.198621) (xy 190.389774 -294.181169) (xy 190.437993 -294.171325)
			(xy 190.487168 -294.169344) (xy 190.536023 -294.175276) (xy 190.583294 -294.188968) (xy 190.627756 -294.210066)
			(xy 190.668259 -294.238022) (xy 190.703752 -294.272114) (xy 190.733317 -294.311458) (xy 190.756188 -294.355035)
			(xy 190.771772 -294.401716) (xy 190.779667 -294.450293) (xy 190.780162 -294.4749) (xy 191.119264 -294.4749)
			(xy 191.123224 -294.425846) (xy 191.135001 -294.378062) (xy 191.154292 -294.332786) (xy 191.180595 -294.29119)
			(xy 191.21323 -294.254353) (xy 191.251351 -294.223228) (xy 191.293972 -294.198621) (xy 191.339988 -294.181169)
			(xy 191.388207 -294.171325) (xy 191.437382 -294.169344) (xy 191.486237 -294.175276) (xy 191.533508 -294.188968)
			(xy 191.57797 -294.210066) (xy 191.618473 -294.238022) (xy 191.653966 -294.272114) (xy 191.683531 -294.311458)
			(xy 191.706402 -294.355035) (xy 191.721986 -294.401716) (xy 191.729881 -294.450293) (xy 191.730376 -294.4749)
			(xy 192.069224 -294.4749) (xy 192.073184 -294.425846) (xy 192.084961 -294.378062) (xy 192.104252 -294.332786)
			(xy 192.130555 -294.29119) (xy 192.16319 -294.254353) (xy 192.201311 -294.223228) (xy 192.243932 -294.198621)
			(xy 192.289948 -294.181169) (xy 192.338167 -294.171325) (xy 192.387342 -294.169344) (xy 192.436197 -294.175276)
			(xy 192.483468 -294.188968) (xy 192.52793 -294.210066) (xy 192.568433 -294.238022) (xy 192.603926 -294.272114)
			(xy 192.633491 -294.311458) (xy 192.656362 -294.355035) (xy 192.671946 -294.401716) (xy 192.679841 -294.450293)
			(xy 192.680336 -294.4749) (xy 193.019184 -294.4749) (xy 193.023144 -294.425846) (xy 193.034921 -294.378062)
			(xy 193.054212 -294.332786) (xy 193.080515 -294.29119) (xy 193.11315 -294.254353) (xy 193.151271 -294.223228)
			(xy 193.193892 -294.198621) (xy 193.239908 -294.181169) (xy 193.288127 -294.171325) (xy 193.337302 -294.169344)
			(xy 193.386157 -294.175276) (xy 193.433428 -294.188968) (xy 193.47789 -294.210066) (xy 193.518393 -294.238022)
			(xy 193.553886 -294.272114) (xy 193.583451 -294.311458) (xy 193.606322 -294.355035) (xy 193.621906 -294.401716)
			(xy 193.629801 -294.450293) (xy 193.630296 -294.4749) (xy 193.969144 -294.4749) (xy 193.973104 -294.425846)
			(xy 193.984881 -294.378062) (xy 194.004172 -294.332786) (xy 194.030475 -294.29119) (xy 194.06311 -294.254353)
			(xy 194.101231 -294.223228) (xy 194.143852 -294.198621) (xy 194.189868 -294.181169) (xy 194.238087 -294.171325)
			(xy 194.287262 -294.169344) (xy 194.336117 -294.175276) (xy 194.383388 -294.188968) (xy 194.42785 -294.210066)
			(xy 194.468353 -294.238022) (xy 194.503846 -294.272114) (xy 194.533411 -294.311458) (xy 194.556282 -294.355035)
			(xy 194.571866 -294.401716) (xy 194.579761 -294.450293) (xy 194.580256 -294.4749) (xy 194.919104 -294.4749)
			(xy 194.923064 -294.425846) (xy 194.934841 -294.378062) (xy 194.954132 -294.332786) (xy 194.980435 -294.29119)
			(xy 195.01307 -294.254353) (xy 195.051191 -294.223228) (xy 195.093812 -294.198621) (xy 195.139828 -294.181169)
			(xy 195.188047 -294.171325) (xy 195.237222 -294.169344) (xy 195.286077 -294.175276) (xy 195.333348 -294.188968)
			(xy 195.37781 -294.210066) (xy 195.418313 -294.238022) (xy 195.453806 -294.272114) (xy 195.483371 -294.311458)
			(xy 195.506242 -294.355035) (xy 195.521826 -294.401716) (xy 195.529721 -294.450293) (xy 195.530216 -294.4749)
			(xy 195.869064 -294.4749) (xy 195.873024 -294.425846) (xy 195.884801 -294.378062) (xy 195.904092 -294.332786)
			(xy 195.930395 -294.29119) (xy 195.96303 -294.254353) (xy 196.001151 -294.223228) (xy 196.043772 -294.198621)
			(xy 196.089788 -294.181169) (xy 196.138007 -294.171325) (xy 196.187182 -294.169344) (xy 196.236037 -294.175276)
			(xy 196.283308 -294.188968) (xy 196.32777 -294.210066) (xy 196.368273 -294.238022) (xy 196.403766 -294.272114)
			(xy 196.433331 -294.311458) (xy 196.456202 -294.355035) (xy 196.471786 -294.401716) (xy 196.479681 -294.450293)
			(xy 196.480176 -294.4749) (xy 196.819278 -294.4749) (xy 196.823238 -294.425846) (xy 196.835015 -294.378062)
			(xy 196.854306 -294.332786) (xy 196.880609 -294.29119) (xy 196.913244 -294.254353) (xy 196.951365 -294.223228)
			(xy 196.993986 -294.198621) (xy 197.040002 -294.181169) (xy 197.088221 -294.171325) (xy 197.137396 -294.169344)
			(xy 197.186251 -294.175276) (xy 197.233522 -294.188968) (xy 197.277984 -294.210066) (xy 197.318487 -294.238022)
			(xy 197.35398 -294.272114) (xy 197.383545 -294.311458) (xy 197.406416 -294.355035) (xy 197.422 -294.401716)
			(xy 197.429895 -294.450293) (xy 197.43039 -294.4749) (xy 197.769238 -294.4749) (xy 197.773198 -294.425846)
			(xy 197.784975 -294.378062) (xy 197.804266 -294.332786) (xy 197.830569 -294.29119) (xy 197.863204 -294.254353)
			(xy 197.901325 -294.223228) (xy 197.943946 -294.198621) (xy 197.989962 -294.181169) (xy 198.038181 -294.171325)
			(xy 198.087356 -294.169344) (xy 198.136211 -294.175276) (xy 198.183482 -294.188968) (xy 198.227944 -294.210066)
			(xy 198.268447 -294.238022) (xy 198.30394 -294.272114) (xy 198.333505 -294.311458) (xy 198.356376 -294.355035)
			(xy 198.37196 -294.401716) (xy 198.379855 -294.450293) (xy 198.38035 -294.4749) (xy 198.719198 -294.4749)
			(xy 198.723158 -294.425846) (xy 198.734935 -294.378062) (xy 198.754226 -294.332786) (xy 198.780529 -294.29119)
			(xy 198.813164 -294.254353) (xy 198.851285 -294.223228) (xy 198.893906 -294.198621) (xy 198.939922 -294.181169)
			(xy 198.988141 -294.171325) (xy 199.037316 -294.169344) (xy 199.086171 -294.175276) (xy 199.133442 -294.188968)
			(xy 199.177904 -294.210066) (xy 199.218407 -294.238022) (xy 199.2539 -294.272114) (xy 199.283465 -294.311458)
			(xy 199.306336 -294.355035) (xy 199.32192 -294.401716) (xy 199.329815 -294.450293) (xy 199.33031 -294.4749)
			(xy 199.329815 -294.499507) (xy 199.32192 -294.548084) (xy 199.306336 -294.594765) (xy 199.283465 -294.638342)
			(xy 199.2539 -294.677686) (xy 199.220324 -294.709937) (xy 205.263126 -294.709937) (xy 205.263128 -294.655425)
			(xy 205.270889 -294.601469) (xy 205.28625 -294.549166) (xy 205.308898 -294.499582) (xy 205.338373 -294.453725)
			(xy 205.374074 -294.412531) (xy 205.415274 -294.376837) (xy 205.461135 -294.347369) (xy 205.510723 -294.324729)
			(xy 205.563028 -294.309376) (xy 205.616986 -294.301624) (xy 205.644242 -294.301164) (xy 205.669642 -294.301926)
			(xy 205.684375 -294.302413) (xy 205.713104 -294.29587) (xy 205.738771 -294.281399) (xy 205.759238 -294.260201)
			(xy 205.772802 -294.234043) (xy 205.778333 -294.205102) (xy 205.775372 -294.175786) (xy 205.770226 -294.161972)
			(xy 205.761062 -294.13877) (xy 205.748173 -294.090579) (xy 205.741674 -294.041119) (xy 205.74127 -294.016176)
			(xy 205.741804 -293.988927) (xy 205.749563 -293.934983) (xy 205.764921 -293.882692) (xy 205.787563 -293.83312)
			(xy 205.817031 -293.787274) (xy 205.852722 -293.746089) (xy 205.893912 -293.710402) (xy 205.939761 -293.680941)
			(xy 205.989337 -293.658304) (xy 206.041629 -293.642953) (xy 206.095574 -293.635201) (xy 206.150073 -293.635204)
			(xy 206.204017 -293.642963) (xy 206.256307 -293.65832) (xy 206.30588 -293.680963) (xy 206.351725 -293.71043)
			(xy 206.392911 -293.746122) (xy 206.428597 -293.787312) (xy 206.458059 -293.833161) (xy 206.480696 -293.882736)
			(xy 206.496047 -293.935028) (xy 206.502598 -293.980616) (xy 207.380838 -293.980616) (xy 207.384909 -293.924994)
			(xy 207.397035 -293.870557) (xy 207.416958 -293.818466) (xy 207.444254 -293.769831) (xy 207.47834 -293.725688)
			(xy 207.518489 -293.686979) (xy 207.563847 -293.654528) (xy 207.613447 -293.629027) (xy 207.666231 -293.61102)
			(xy 207.721074 -293.60089) (xy 207.776808 -293.598853) (xy 207.832245 -293.604953) (xy 207.886202 -293.619059)
			(xy 207.937531 -293.640871) (xy 207.985137 -293.669925) (xy 208.028005 -293.7056) (xy 208.065222 -293.747137)
			(xy 208.095995 -293.79365) (xy 208.119667 -293.844147) (xy 208.135735 -293.897554) (xy 208.143855 -293.95273)
			(xy 208.144364 -293.980616) (xy 208.143855 -294.008502) (xy 208.135735 -294.063678) (xy 208.119667 -294.117085)
			(xy 208.095995 -294.167582) (xy 208.065222 -294.214095) (xy 208.028005 -294.255632) (xy 207.985137 -294.291307)
			(xy 207.937531 -294.320361) (xy 207.886202 -294.342173) (xy 207.832245 -294.356279) (xy 207.776808 -294.362379)
			(xy 207.721074 -294.360342) (xy 207.666231 -294.350212) (xy 207.613447 -294.332205) (xy 207.563847 -294.306704)
			(xy 207.518489 -294.274253) (xy 207.47834 -294.235544) (xy 207.444254 -294.191401) (xy 207.416958 -294.142766)
			(xy 207.397035 -294.090675) (xy 207.384909 -294.036238) (xy 207.380838 -293.980616) (xy 206.502598 -293.980616)
			(xy 206.503799 -293.988973) (xy 206.503796 -294.043472) (xy 206.496037 -294.097416) (xy 206.48068 -294.149706)
			(xy 206.458037 -294.199279) (xy 206.42857 -294.245125) (xy 206.392878 -294.28631) (xy 206.351689 -294.321997)
			(xy 206.30584 -294.351459) (xy 206.256264 -294.374095) (xy 206.203972 -294.389446) (xy 206.150027 -294.397199)
			(xy 206.122778 -294.397684) (xy 206.097378 -294.396922) (xy 206.082647 -294.396524) (xy 206.05393 -294.403057)
			(xy 206.028272 -294.417516) (xy 206.00781 -294.438698) (xy 205.994245 -294.464839) (xy 205.988707 -294.493764)
			(xy 205.989493 -294.50157) (xy 206.636618 -294.50157) (xy 206.640689 -294.445948) (xy 206.652815 -294.391511)
			(xy 206.672738 -294.33942) (xy 206.700034 -294.290785) (xy 206.73412 -294.246642) (xy 206.774269 -294.207933)
			(xy 206.819627 -294.175482) (xy 206.869227 -294.149981) (xy 206.922011 -294.131974) (xy 206.976854 -294.121844)
			(xy 207.032588 -294.119807) (xy 207.088025 -294.125907) (xy 207.141982 -294.140013) (xy 207.193311 -294.161825)
			(xy 207.240917 -294.190879) (xy 207.283785 -294.226554) (xy 207.321002 -294.268091) (xy 207.351775 -294.314604)
			(xy 207.375447 -294.365101) (xy 207.391515 -294.418508) (xy 207.399635 -294.473684) (xy 207.400144 -294.50157)
			(xy 207.399635 -294.529456) (xy 207.391515 -294.584632) (xy 207.375447 -294.638039) (xy 207.351775 -294.688536)
			(xy 207.321002 -294.735049) (xy 207.283785 -294.776586) (xy 207.240917 -294.812261) (xy 207.193311 -294.841315)
			(xy 207.141982 -294.863127) (xy 207.088025 -294.877233) (xy 207.032588 -294.883333) (xy 206.976854 -294.881296)
			(xy 206.922011 -294.871166) (xy 206.869227 -294.853159) (xy 206.819627 -294.827658) (xy 206.774269 -294.795207)
			(xy 206.73412 -294.756498) (xy 206.700034 -294.712355) (xy 206.672738 -294.66372) (xy 206.652815 -294.611629)
			(xy 206.640689 -294.557192) (xy 206.636618 -294.50157) (xy 205.989493 -294.50157) (xy 205.991656 -294.523067)
			(xy 205.996794 -294.536876) (xy 206.005943 -294.560083) (xy 206.018838 -294.608272) (xy 206.025342 -294.65773)
			(xy 206.02575 -294.682672) (xy 206.025275 -294.709928) (xy 206.017521 -294.763886) (xy 206.002166 -294.81619)
			(xy 205.979524 -294.865777) (xy 205.950055 -294.911637) (xy 205.914359 -294.952836) (xy 205.873163 -294.988535)
			(xy 205.827306 -295.018008) (xy 205.777721 -295.040655) (xy 205.725418 -295.056014) (xy 205.671461 -295.063773)
			(xy 205.616949 -295.063773) (xy 205.562992 -295.056016) (xy 205.510688 -295.040658) (xy 205.461102 -295.018013)
			(xy 205.415244 -294.988541) (xy 205.374047 -294.952843) (xy 205.338351 -294.911645) (xy 205.30888 -294.865786)
			(xy 205.286237 -294.816199) (xy 205.270881 -294.763895) (xy 205.263126 -294.709937) (xy 199.220324 -294.709937)
			(xy 199.218407 -294.711778) (xy 199.177904 -294.739734) (xy 199.133442 -294.760832) (xy 199.086171 -294.774524)
			(xy 199.037316 -294.780456) (xy 198.988141 -294.778475) (xy 198.939922 -294.768631) (xy 198.893906 -294.751179)
			(xy 198.851285 -294.726572) (xy 198.813164 -294.695447) (xy 198.780529 -294.65861) (xy 198.754226 -294.617014)
			(xy 198.734935 -294.571738) (xy 198.723158 -294.523954) (xy 198.719198 -294.4749) (xy 198.38035 -294.4749)
			(xy 198.379855 -294.499507) (xy 198.37196 -294.548084) (xy 198.356376 -294.594765) (xy 198.333505 -294.638342)
			(xy 198.30394 -294.677686) (xy 198.268447 -294.711778) (xy 198.227944 -294.739734) (xy 198.183482 -294.760832)
			(xy 198.136211 -294.774524) (xy 198.087356 -294.780456) (xy 198.038181 -294.778475) (xy 197.989962 -294.768631)
			(xy 197.943946 -294.751179) (xy 197.901325 -294.726572) (xy 197.863204 -294.695447) (xy 197.830569 -294.65861)
			(xy 197.804266 -294.617014) (xy 197.784975 -294.571738) (xy 197.773198 -294.523954) (xy 197.769238 -294.4749)
			(xy 197.43039 -294.4749) (xy 197.429895 -294.499507) (xy 197.422 -294.548084) (xy 197.406416 -294.594765)
			(xy 197.383545 -294.638342) (xy 197.35398 -294.677686) (xy 197.318487 -294.711778) (xy 197.277984 -294.739734)
			(xy 197.233522 -294.760832) (xy 197.186251 -294.774524) (xy 197.137396 -294.780456) (xy 197.088221 -294.778475)
			(xy 197.040002 -294.768631) (xy 196.993986 -294.751179) (xy 196.951365 -294.726572) (xy 196.913244 -294.695447)
			(xy 196.880609 -294.65861) (xy 196.854306 -294.617014) (xy 196.835015 -294.571738) (xy 196.823238 -294.523954)
			(xy 196.819278 -294.4749) (xy 196.480176 -294.4749) (xy 196.479681 -294.499507) (xy 196.471786 -294.548084)
			(xy 196.456202 -294.594765) (xy 196.433331 -294.638342) (xy 196.403766 -294.677686) (xy 196.368273 -294.711778)
			(xy 196.32777 -294.739734) (xy 196.283308 -294.760832) (xy 196.236037 -294.774524) (xy 196.187182 -294.780456)
			(xy 196.138007 -294.778475) (xy 196.089788 -294.768631) (xy 196.043772 -294.751179) (xy 196.001151 -294.726572)
			(xy 195.96303 -294.695447) (xy 195.930395 -294.65861) (xy 195.904092 -294.617014) (xy 195.884801 -294.571738)
			(xy 195.873024 -294.523954) (xy 195.869064 -294.4749) (xy 195.530216 -294.4749) (xy 195.529721 -294.499507)
			(xy 195.521826 -294.548084) (xy 195.506242 -294.594765) (xy 195.483371 -294.638342) (xy 195.453806 -294.677686)
			(xy 195.418313 -294.711778) (xy 195.37781 -294.739734) (xy 195.333348 -294.760832) (xy 195.286077 -294.774524)
			(xy 195.237222 -294.780456) (xy 195.188047 -294.778475) (xy 195.139828 -294.768631) (xy 195.093812 -294.751179)
			(xy 195.051191 -294.726572) (xy 195.01307 -294.695447) (xy 194.980435 -294.65861) (xy 194.954132 -294.617014)
			(xy 194.934841 -294.571738) (xy 194.923064 -294.523954) (xy 194.919104 -294.4749) (xy 194.580256 -294.4749)
			(xy 194.579761 -294.499507) (xy 194.571866 -294.548084) (xy 194.556282 -294.594765) (xy 194.533411 -294.638342)
			(xy 194.503846 -294.677686) (xy 194.468353 -294.711778) (xy 194.42785 -294.739734) (xy 194.383388 -294.760832)
			(xy 194.336117 -294.774524) (xy 194.287262 -294.780456) (xy 194.238087 -294.778475) (xy 194.189868 -294.768631)
			(xy 194.143852 -294.751179) (xy 194.101231 -294.726572) (xy 194.06311 -294.695447) (xy 194.030475 -294.65861)
			(xy 194.004172 -294.617014) (xy 193.984881 -294.571738) (xy 193.973104 -294.523954) (xy 193.969144 -294.4749)
			(xy 193.630296 -294.4749) (xy 193.629801 -294.499507) (xy 193.621906 -294.548084) (xy 193.606322 -294.594765)
			(xy 193.583451 -294.638342) (xy 193.553886 -294.677686) (xy 193.518393 -294.711778) (xy 193.47789 -294.739734)
			(xy 193.433428 -294.760832) (xy 193.386157 -294.774524) (xy 193.337302 -294.780456) (xy 193.288127 -294.778475)
			(xy 193.239908 -294.768631) (xy 193.193892 -294.751179) (xy 193.151271 -294.726572) (xy 193.11315 -294.695447)
			(xy 193.080515 -294.65861) (xy 193.054212 -294.617014) (xy 193.034921 -294.571738) (xy 193.023144 -294.523954)
			(xy 193.019184 -294.4749) (xy 192.680336 -294.4749) (xy 192.679841 -294.499507) (xy 192.671946 -294.548084)
			(xy 192.656362 -294.594765) (xy 192.633491 -294.638342) (xy 192.603926 -294.677686) (xy 192.568433 -294.711778)
			(xy 192.52793 -294.739734) (xy 192.483468 -294.760832) (xy 192.436197 -294.774524) (xy 192.387342 -294.780456)
			(xy 192.338167 -294.778475) (xy 192.289948 -294.768631) (xy 192.243932 -294.751179) (xy 192.201311 -294.726572)
			(xy 192.16319 -294.695447) (xy 192.130555 -294.65861) (xy 192.104252 -294.617014) (xy 192.084961 -294.571738)
			(xy 192.073184 -294.523954) (xy 192.069224 -294.4749) (xy 191.730376 -294.4749) (xy 191.729881 -294.499507)
			(xy 191.721986 -294.548084) (xy 191.706402 -294.594765) (xy 191.683531 -294.638342) (xy 191.653966 -294.677686)
			(xy 191.618473 -294.711778) (xy 191.57797 -294.739734) (xy 191.533508 -294.760832) (xy 191.486237 -294.774524)
			(xy 191.437382 -294.780456) (xy 191.388207 -294.778475) (xy 191.339988 -294.768631) (xy 191.293972 -294.751179)
			(xy 191.251351 -294.726572) (xy 191.21323 -294.695447) (xy 191.180595 -294.65861) (xy 191.154292 -294.617014)
			(xy 191.135001 -294.571738) (xy 191.123224 -294.523954) (xy 191.119264 -294.4749) (xy 190.780162 -294.4749)
			(xy 190.779667 -294.499507) (xy 190.771772 -294.548084) (xy 190.756188 -294.594765) (xy 190.733317 -294.638342)
			(xy 190.703752 -294.677686) (xy 190.668259 -294.711778) (xy 190.627756 -294.739734) (xy 190.583294 -294.760832)
			(xy 190.536023 -294.774524) (xy 190.487168 -294.780456) (xy 190.437993 -294.778475) (xy 190.389774 -294.768631)
			(xy 190.343758 -294.751179) (xy 190.301137 -294.726572) (xy 190.263016 -294.695447) (xy 190.230381 -294.65861)
			(xy 190.204078 -294.617014) (xy 190.184787 -294.571738) (xy 190.17301 -294.523954) (xy 190.16905 -294.4749)
			(xy 189.830202 -294.4749) (xy 189.829707 -294.499507) (xy 189.821812 -294.548084) (xy 189.806228 -294.594765)
			(xy 189.783357 -294.638342) (xy 189.753792 -294.677686) (xy 189.718299 -294.711778) (xy 189.677796 -294.739734)
			(xy 189.633334 -294.760832) (xy 189.586063 -294.774524) (xy 189.537208 -294.780456) (xy 189.488033 -294.778475)
			(xy 189.439814 -294.768631) (xy 189.393798 -294.751179) (xy 189.351177 -294.726572) (xy 189.313056 -294.695447)
			(xy 189.280421 -294.65861) (xy 189.254118 -294.617014) (xy 189.234827 -294.571738) (xy 189.22305 -294.523954)
			(xy 189.21909 -294.4749) (xy 188.880242 -294.4749) (xy 188.879747 -294.499507) (xy 188.871852 -294.548084)
			(xy 188.856268 -294.594765) (xy 188.833397 -294.638342) (xy 188.803832 -294.677686) (xy 188.768339 -294.711778)
			(xy 188.727836 -294.739734) (xy 188.683374 -294.760832) (xy 188.636103 -294.774524) (xy 188.587248 -294.780456)
			(xy 188.538073 -294.778475) (xy 188.489854 -294.768631) (xy 188.443838 -294.751179) (xy 188.401217 -294.726572)
			(xy 188.363096 -294.695447) (xy 188.330461 -294.65861) (xy 188.304158 -294.617014) (xy 188.284867 -294.571738)
			(xy 188.27309 -294.523954) (xy 188.26913 -294.4749) (xy 187.930282 -294.4749) (xy 187.929787 -294.499507)
			(xy 187.921892 -294.548084) (xy 187.906308 -294.594765) (xy 187.883437 -294.638342) (xy 187.853872 -294.677686)
			(xy 187.818379 -294.711778) (xy 187.777876 -294.739734) (xy 187.733414 -294.760832) (xy 187.686143 -294.774524)
			(xy 187.637288 -294.780456) (xy 187.588113 -294.778475) (xy 187.539894 -294.768631) (xy 187.493878 -294.751179)
			(xy 187.451257 -294.726572) (xy 187.413136 -294.695447) (xy 187.380501 -294.65861) (xy 187.354198 -294.617014)
			(xy 187.334907 -294.571738) (xy 187.32313 -294.523954) (xy 187.31917 -294.4749) (xy 186.980322 -294.4749)
			(xy 186.979827 -294.499507) (xy 186.971932 -294.548084) (xy 186.956348 -294.594765) (xy 186.933477 -294.638342)
			(xy 186.903912 -294.677686) (xy 186.868419 -294.711778) (xy 186.827916 -294.739734) (xy 186.783454 -294.760832)
			(xy 186.736183 -294.774524) (xy 186.687328 -294.780456) (xy 186.638153 -294.778475) (xy 186.589934 -294.768631)
			(xy 186.543918 -294.751179) (xy 186.501297 -294.726572) (xy 186.463176 -294.695447) (xy 186.430541 -294.65861)
			(xy 186.404238 -294.617014) (xy 186.384947 -294.571738) (xy 186.37317 -294.523954) (xy 186.36921 -294.4749)
			(xy 186.056242 -294.4749) (xy 186.052497 -294.524558) (xy 186.041348 -294.573093) (xy 186.023047 -294.619408)
			(xy 185.998007 -294.662454) (xy 185.966796 -294.701259) (xy 185.930118 -294.734944) (xy 185.909712 -294.74922)
			(xy 185.899698 -294.756752) (xy 185.887983 -294.778868) (xy 185.88736 -294.791384) (xy 185.88736 -295.355518)
			(xy 208.715862 -295.355518) (xy 208.719933 -295.299896) (xy 208.732059 -295.245459) (xy 208.751982 -295.193368)
			(xy 208.779278 -295.144733) (xy 208.813364 -295.10059) (xy 208.853513 -295.061881) (xy 208.898871 -295.02943)
			(xy 208.948471 -295.003929) (xy 209.001255 -294.985922) (xy 209.056098 -294.975792) (xy 209.111832 -294.973755)
			(xy 209.167269 -294.979855) (xy 209.221226 -294.993961) (xy 209.272555 -295.015773) (xy 209.320161 -295.044827)
			(xy 209.363029 -295.080502) (xy 209.400246 -295.122039) (xy 209.431019 -295.168552) (xy 209.454691 -295.219049)
			(xy 209.470759 -295.272456) (xy 209.478879 -295.327632) (xy 209.479388 -295.355518) (xy 209.478879 -295.383404)
			(xy 209.470759 -295.43858) (xy 209.454691 -295.491987) (xy 209.431019 -295.542484) (xy 209.400246 -295.588997)
			(xy 209.363029 -295.630534) (xy 209.320161 -295.666209) (xy 209.272555 -295.695263) (xy 209.221226 -295.717075)
			(xy 209.167269 -295.731181) (xy 209.111832 -295.737281) (xy 209.056098 -295.735244) (xy 209.001255 -295.725114)
			(xy 208.948471 -295.707107) (xy 208.898871 -295.681606) (xy 208.853513 -295.649155) (xy 208.813364 -295.610446)
			(xy 208.779278 -295.566303) (xy 208.751982 -295.517668) (xy 208.732059 -295.465577) (xy 208.719933 -295.41114)
			(xy 208.715862 -295.355518) (xy 185.88736 -295.355518) (xy 185.88736 -296.058336) (xy 185.887998 -296.070846)
			(xy 185.899713 -296.092956) (xy 185.909712 -296.1005) (xy 185.931793 -296.116006) (xy 185.971068 -296.153)
			(xy 186.003819 -296.195876) (xy 186.029176 -296.2435) (xy 186.046469 -296.294607) (xy 186.055238 -296.347843)
			(xy 186.055762 -296.37482) (xy 186.36921 -296.37482) (xy 186.37317 -296.325766) (xy 186.384947 -296.277982)
			(xy 186.404238 -296.232706) (xy 186.430541 -296.19111) (xy 186.463176 -296.154273) (xy 186.501297 -296.123148)
			(xy 186.543918 -296.098541) (xy 186.589934 -296.081089) (xy 186.638153 -296.071245) (xy 186.687328 -296.069264)
			(xy 186.736183 -296.075196) (xy 186.783454 -296.088888) (xy 186.827916 -296.109986) (xy 186.868419 -296.137942)
			(xy 186.903912 -296.172034) (xy 186.933477 -296.211378) (xy 186.956348 -296.254955) (xy 186.971932 -296.301636)
			(xy 186.979827 -296.350213) (xy 186.980322 -296.37482) (xy 187.31917 -296.37482) (xy 187.32313 -296.325766)
			(xy 187.334907 -296.277982) (xy 187.354198 -296.232706) (xy 187.380501 -296.19111) (xy 187.413136 -296.154273)
			(xy 187.451257 -296.123148) (xy 187.493878 -296.098541) (xy 187.539894 -296.081089) (xy 187.588113 -296.071245)
			(xy 187.637288 -296.069264) (xy 187.686143 -296.075196) (xy 187.733414 -296.088888) (xy 187.777876 -296.109986)
			(xy 187.818379 -296.137942) (xy 187.853872 -296.172034) (xy 187.883437 -296.211378) (xy 187.906308 -296.254955)
			(xy 187.921892 -296.301636) (xy 187.929787 -296.350213) (xy 187.930282 -296.37482) (xy 188.26913 -296.37482)
			(xy 188.27309 -296.325766) (xy 188.284867 -296.277982) (xy 188.304158 -296.232706) (xy 188.330461 -296.19111)
			(xy 188.363096 -296.154273) (xy 188.401217 -296.123148) (xy 188.443838 -296.098541) (xy 188.489854 -296.081089)
			(xy 188.538073 -296.071245) (xy 188.587248 -296.069264) (xy 188.636103 -296.075196) (xy 188.683374 -296.088888)
			(xy 188.727836 -296.109986) (xy 188.768339 -296.137942) (xy 188.803832 -296.172034) (xy 188.833397 -296.211378)
			(xy 188.856268 -296.254955) (xy 188.871852 -296.301636) (xy 188.879747 -296.350213) (xy 188.880242 -296.37482)
			(xy 189.21909 -296.37482) (xy 189.22305 -296.325766) (xy 189.234827 -296.277982) (xy 189.254118 -296.232706)
			(xy 189.280421 -296.19111) (xy 189.313056 -296.154273) (xy 189.351177 -296.123148) (xy 189.393798 -296.098541)
			(xy 189.439814 -296.081089) (xy 189.488033 -296.071245) (xy 189.537208 -296.069264) (xy 189.586063 -296.075196)
			(xy 189.633334 -296.088888) (xy 189.677796 -296.109986) (xy 189.718299 -296.137942) (xy 189.753792 -296.172034)
			(xy 189.783357 -296.211378) (xy 189.806228 -296.254955) (xy 189.821812 -296.301636) (xy 189.829707 -296.350213)
			(xy 189.830202 -296.37482) (xy 190.16905 -296.37482) (xy 190.17301 -296.325766) (xy 190.184787 -296.277982)
			(xy 190.204078 -296.232706) (xy 190.230381 -296.19111) (xy 190.263016 -296.154273) (xy 190.301137 -296.123148)
			(xy 190.343758 -296.098541) (xy 190.389774 -296.081089) (xy 190.437993 -296.071245) (xy 190.487168 -296.069264)
			(xy 190.536023 -296.075196) (xy 190.583294 -296.088888) (xy 190.627756 -296.109986) (xy 190.668259 -296.137942)
			(xy 190.703752 -296.172034) (xy 190.733317 -296.211378) (xy 190.756188 -296.254955) (xy 190.771772 -296.301636)
			(xy 190.779667 -296.350213) (xy 190.780162 -296.37482) (xy 190.779667 -296.399427) (xy 190.771772 -296.448004)
			(xy 190.756188 -296.494685) (xy 190.733317 -296.538262) (xy 190.703752 -296.577606) (xy 190.668259 -296.611698)
			(xy 190.627756 -296.639654) (xy 190.583294 -296.660752) (xy 190.536023 -296.674444) (xy 190.487168 -296.680376)
			(xy 190.437993 -296.678395) (xy 190.389774 -296.668551) (xy 190.343758 -296.651099) (xy 190.301137 -296.626492)
			(xy 190.263016 -296.595367) (xy 190.230381 -296.55853) (xy 190.204078 -296.516934) (xy 190.184787 -296.471658)
			(xy 190.17301 -296.423874) (xy 190.16905 -296.37482) (xy 189.830202 -296.37482) (xy 189.829707 -296.399427)
			(xy 189.821812 -296.448004) (xy 189.806228 -296.494685) (xy 189.783357 -296.538262) (xy 189.753792 -296.577606)
			(xy 189.718299 -296.611698) (xy 189.677796 -296.639654) (xy 189.633334 -296.660752) (xy 189.586063 -296.674444)
			(xy 189.537208 -296.680376) (xy 189.488033 -296.678395) (xy 189.439814 -296.668551) (xy 189.393798 -296.651099)
			(xy 189.351177 -296.626492) (xy 189.313056 -296.595367) (xy 189.280421 -296.55853) (xy 189.254118 -296.516934)
			(xy 189.234827 -296.471658) (xy 189.22305 -296.423874) (xy 189.21909 -296.37482) (xy 188.880242 -296.37482)
			(xy 188.879747 -296.399427) (xy 188.871852 -296.448004) (xy 188.856268 -296.494685) (xy 188.833397 -296.538262)
			(xy 188.803832 -296.577606) (xy 188.768339 -296.611698) (xy 188.727836 -296.639654) (xy 188.683374 -296.660752)
			(xy 188.636103 -296.674444) (xy 188.587248 -296.680376) (xy 188.538073 -296.678395) (xy 188.489854 -296.668551)
			(xy 188.443838 -296.651099) (xy 188.401217 -296.626492) (xy 188.363096 -296.595367) (xy 188.330461 -296.55853)
			(xy 188.304158 -296.516934) (xy 188.284867 -296.471658) (xy 188.27309 -296.423874) (xy 188.26913 -296.37482)
			(xy 187.930282 -296.37482) (xy 187.929787 -296.399427) (xy 187.921892 -296.448004) (xy 187.906308 -296.494685)
			(xy 187.883437 -296.538262) (xy 187.853872 -296.577606) (xy 187.818379 -296.611698) (xy 187.777876 -296.639654)
			(xy 187.733414 -296.660752) (xy 187.686143 -296.674444) (xy 187.637288 -296.680376) (xy 187.588113 -296.678395)
			(xy 187.539894 -296.668551) (xy 187.493878 -296.651099) (xy 187.451257 -296.626492) (xy 187.413136 -296.595367)
			(xy 187.380501 -296.55853) (xy 187.354198 -296.516934) (xy 187.334907 -296.471658) (xy 187.32313 -296.423874)
			(xy 187.31917 -296.37482) (xy 186.980322 -296.37482) (xy 186.979827 -296.399427) (xy 186.971932 -296.448004)
			(xy 186.956348 -296.494685) (xy 186.933477 -296.538262) (xy 186.903912 -296.577606) (xy 186.868419 -296.611698)
			(xy 186.827916 -296.639654) (xy 186.783454 -296.660752) (xy 186.736183 -296.674444) (xy 186.687328 -296.680376)
			(xy 186.638153 -296.678395) (xy 186.589934 -296.668551) (xy 186.543918 -296.651099) (xy 186.501297 -296.626492)
			(xy 186.463176 -296.595367) (xy 186.430541 -296.55853) (xy 186.404238 -296.516934) (xy 186.384947 -296.471658)
			(xy 186.37317 -296.423874) (xy 186.36921 -296.37482) (xy 186.055762 -296.37482) (xy 186.055169 -296.403284)
			(xy 186.045431 -296.459373) (xy 186.026246 -296.512971) (xy 185.998178 -296.562499) (xy 185.980578 -296.584878)
			(xy 185.974482 -296.592244) (xy 185.96864 -296.60977) (xy 185.972196 -296.687494) (xy 185.972997 -296.696869)
			(xy 185.980578 -296.714076) (xy 185.986928 -296.721022) (xy 186.328812 -297.062906) (xy 186.33578 -297.069217)
			(xy 186.352979 -297.076766) (xy 186.36234 -297.077638) (xy 186.440064 -297.081194) (xy 186.45759 -297.075352)
			(xy 186.464956 -297.069256) (xy 186.487329 -297.051649) (xy 186.536857 -297.023581) (xy 186.590458 -297.004403)
			(xy 186.64655 -296.99468) (xy 186.675014 -296.994072) (xy 186.700098 -296.994538) (xy 186.749691 -297.002117)
			(xy 186.79757 -297.017099) (xy 186.842637 -297.039141) (xy 186.883858 -297.067737) (xy 186.920287 -297.10223)
			(xy 186.951089 -297.14183) (xy 186.975556 -297.185628) (xy 186.993128 -297.232618) (xy 187.003401 -297.281723)
			(xy 187.005214 -297.306746) (xy 187.005722 -297.316144) (xy 187.013342 -297.333162) (xy 187.041536 -297.361356)
			(xy 187.042044 -297.361864) (xy 187.049425 -297.368446) (xy 187.067724 -297.375898) (xy 187.077604 -297.376342)
			(xy 187.222384 -297.376342) (xy 187.230766 -297.37558) (xy 187.238373 -297.374069) (xy 187.252211 -297.367087)
			(xy 187.257944 -297.361864) (xy 187.286646 -297.333162) (xy 187.294266 -297.316144) (xy 187.294774 -297.306746)
			(xy 187.296729 -297.280409) (xy 187.307953 -297.228806) (xy 187.327235 -297.179642) (xy 187.354086 -297.134168)
			(xy 187.387822 -297.093539) (xy 187.427586 -297.058789) (xy 187.472368 -297.030799) (xy 187.521029 -297.010282)
			(xy 187.572333 -296.99776) (xy 187.624974 -296.99355) (xy 187.677615 -296.99776) (xy 187.728919 -297.010282)
			(xy 187.77758 -297.030799) (xy 187.822362 -297.058789) (xy 187.862126 -297.093539) (xy 187.895862 -297.134168)
			(xy 187.922713 -297.179642) (xy 187.941995 -297.228806) (xy 187.953219 -297.280409) (xy 187.955174 -297.306746)
			(xy 187.955682 -297.316144) (xy 187.963302 -297.333162) (xy 187.991496 -297.361356) (xy 187.992004 -297.361864)
			(xy 187.999388 -297.368437) (xy 188.017687 -297.375867) (xy 188.027564 -297.376342) (xy 188.072776 -297.376342)
			(xy 188.089794 -297.369992) (xy 188.096906 -297.363896) (xy 188.124534 -297.340728) (xy 188.184525 -297.300726)
			(xy 188.21654 -297.28414) (xy 188.226446 -297.279314) (xy 188.253624 -297.24604) (xy 188.256418 -297.23588)
			(xy 188.264142 -297.210152) (xy 188.286754 -297.161427) (xy 188.316941 -297.116996) (xy 188.353912 -297.078028)
			(xy 188.396693 -297.045545) (xy 188.444161 -297.020402) (xy 188.495068 -297.003261) (xy 188.548076 -296.99457)
			(xy 188.574934 -296.994072) (xy 188.602411 -296.994618) (xy 188.656608 -297.003707) (xy 188.708557 -297.021629)
			(xy 188.75683 -297.047891) (xy 188.800097 -297.081771) (xy 188.83717 -297.122337) (xy 188.867027 -297.168472)
			(xy 188.878464 -297.193462) (xy 188.88456 -297.207686) (xy 188.909706 -297.224196) (xy 189.190122 -297.224196)
			(xy 189.215268 -297.207686) (xy 189.221364 -297.193462) (xy 189.231989 -297.170118) (xy 189.259377 -297.126754)
			(xy 189.293131 -297.088138) (xy 189.332441 -297.055196) (xy 189.376366 -297.028718) (xy 189.423851 -297.009338)
			(xy 189.47376 -296.997521) (xy 189.524894 -296.99355) (xy 189.576028 -296.997521) (xy 189.625937 -297.009338)
			(xy 189.673422 -297.028718) (xy 189.717347 -297.055196) (xy 189.756657 -297.088138) (xy 189.790411 -297.126754)
			(xy 189.817799 -297.170118) (xy 189.828424 -297.193462) (xy 189.83452 -297.207686) (xy 189.859666 -297.224196)
			(xy 190.140082 -297.224196) (xy 190.165482 -297.207686) (xy 190.171578 -297.193462) (xy 190.181806 -297.170979)
			(xy 190.207944 -297.129071) (xy 190.240025 -297.091516) (xy 190.277333 -297.059149) (xy 190.319041 -297.032691)
			(xy 190.364219 -297.01273) (xy 190.411863 -296.99971) (xy 190.460915 -296.993921) (xy 190.510281 -296.995491)
			(xy 190.558865 -297.004385) (xy 190.605586 -297.020406) (xy 190.649405 -297.043198) (xy 190.669672 -297.057318)
			(xy 190.677699 -297.06268) (xy 190.696373 -297.067508) (xy 190.705994 -297.066716) (xy 190.738252 -297.062398)
			(xy 190.747243 -297.060877) (xy 190.763381 -297.052416) (xy 190.769748 -297.045888) (xy 190.77686 -297.038268)
			(xy 191.095884 -296.719244) (xy 191.104904 -296.710563) (xy 191.124912 -296.695516) (xy 191.135762 -296.689272)
			(xy 191.14516 -296.684192) (xy 191.15786 -296.667428) (xy 191.18072 -296.573702) (xy 191.17691 -296.553128)
			(xy 191.171068 -296.544238) (xy 191.158938 -296.525331) (xy 191.139763 -296.48471) (xy 191.126749 -296.441716)
			(xy 191.120176 -296.39728) (xy 191.11976 -296.37482) (xy 191.120282 -296.349565) (xy 191.128595 -296.299743)
			(xy 191.144996 -296.251969) (xy 191.169037 -296.207546) (xy 191.200061 -296.167686) (xy 191.237223 -296.133476)
			(xy 191.279509 -296.10585) (xy 191.325765 -296.08556) (xy 191.37473 -296.07316) (xy 191.425068 -296.068989)
			(xy 191.475406 -296.07316) (xy 191.524371 -296.08556) (xy 191.570627 -296.10585) (xy 191.612913 -296.133476)
			(xy 191.650075 -296.167686) (xy 191.681099 -296.207546) (xy 191.70514 -296.251969) (xy 191.721541 -296.299743)
			(xy 191.729854 -296.349565) (xy 191.730376 -296.37482) (xy 191.729876 -296.399597) (xy 191.721836 -296.448497)
			(xy 191.706004 -296.495455) (xy 191.694816 -296.517568) (xy 191.68872 -296.529506) (xy 191.689228 -296.556176)
			(xy 191.741044 -296.642282) (xy 191.74585 -296.649632) (xy 191.759414 -296.660767) (xy 191.775956 -296.666625)
			(xy 191.784732 -296.66692) (xy 192.015364 -296.66692) (xy 192.024121 -296.666541) (xy 192.040613 -296.660642)
			(xy 192.05419 -296.649575) (xy 192.059052 -296.642282) (xy 192.110868 -296.556176) (xy 192.111376 -296.529506)
			(xy 192.10528 -296.517568) (xy 192.094102 -296.49545) (xy 192.078271 -296.448494) (xy 192.070232 -296.399596)
			(xy 192.06972 -296.37482) (xy 192.070242 -296.349565) (xy 192.078555 -296.299743) (xy 192.094956 -296.251969)
			(xy 192.118997 -296.207546) (xy 192.150021 -296.167686) (xy 192.187183 -296.133476) (xy 192.229469 -296.10585)
			(xy 192.275725 -296.08556) (xy 192.32469 -296.07316) (xy 192.375028 -296.068989) (xy 192.425366 -296.07316)
			(xy 192.474331 -296.08556) (xy 192.520587 -296.10585) (xy 192.562873 -296.133476) (xy 192.600035 -296.167686)
			(xy 192.631059 -296.207546) (xy 192.6551 -296.251969) (xy 192.671501 -296.299743) (xy 192.679814 -296.349565)
			(xy 192.680336 -296.37482) (xy 192.679836 -296.399598) (xy 192.671798 -296.448497) (xy 192.655969 -296.495457)
			(xy 192.644776 -296.517568) (xy 192.63868 -296.529506) (xy 192.639188 -296.556176) (xy 192.691004 -296.642282)
			(xy 192.695808 -296.649637) (xy 192.70937 -296.660782) (xy 192.725913 -296.666653) (xy 192.734692 -296.66692)
			(xy 192.965324 -296.66692) (xy 192.974084 -296.666547) (xy 192.990586 -296.660657) (xy 193.004174 -296.649594)
			(xy 193.009012 -296.642282) (xy 193.060828 -296.556176) (xy 193.061336 -296.529506) (xy 193.05524 -296.517568)
			(xy 193.044064 -296.49545) (xy 193.028235 -296.448493) (xy 193.020197 -296.399596) (xy 193.01968 -296.37482)
			(xy 193.020202 -296.349565) (xy 193.028515 -296.299743) (xy 193.044916 -296.251969) (xy 193.068957 -296.207546)
			(xy 193.099981 -296.167686) (xy 193.137143 -296.133476) (xy 193.179429 -296.10585) (xy 193.225685 -296.08556)
			(xy 193.27465 -296.07316) (xy 193.324988 -296.068989) (xy 193.375326 -296.07316) (xy 193.424291 -296.08556)
			(xy 193.470547 -296.10585) (xy 193.512833 -296.133476) (xy 193.549995 -296.167686) (xy 193.581019 -296.207546)
			(xy 193.60506 -296.251969) (xy 193.621461 -296.299743) (xy 193.629774 -296.349565) (xy 193.630296 -296.37482)
			(xy 193.629796 -296.399597) (xy 193.621757 -296.448497) (xy 193.605926 -296.495456) (xy 193.594736 -296.517568)
			(xy 193.58864 -296.529506) (xy 193.589148 -296.556176) (xy 193.640964 -296.642282) (xy 193.645771 -296.64963)
			(xy 193.659336 -296.660759) (xy 193.675877 -296.666611) (xy 193.684652 -296.66692) (xy 193.915284 -296.66692)
			(xy 193.924048 -296.666554) (xy 193.94056 -296.660672) (xy 193.954158 -296.649612) (xy 193.958972 -296.642282)
			(xy 194.010788 -296.556176) (xy 194.011296 -296.529506) (xy 194.0052 -296.517568) (xy 193.994022 -296.495451)
			(xy 193.978189 -296.448494) (xy 193.97015 -296.399597) (xy 193.96964 -296.37482) (xy 193.970162 -296.349565)
			(xy 193.978475 -296.299743) (xy 193.994876 -296.251969) (xy 194.018917 -296.207546) (xy 194.049941 -296.167686)
			(xy 194.087103 -296.133476) (xy 194.129389 -296.10585) (xy 194.175645 -296.08556) (xy 194.22461 -296.07316)
			(xy 194.274948 -296.068989) (xy 194.325286 -296.07316) (xy 194.374251 -296.08556) (xy 194.420507 -296.10585)
			(xy 194.462793 -296.133476) (xy 194.499955 -296.167686) (xy 194.530979 -296.207546) (xy 194.55502 -296.251969)
			(xy 194.571421 -296.299743) (xy 194.579734 -296.349565) (xy 194.580256 -296.37482) (xy 194.579756 -296.399598)
			(xy 194.571719 -296.448498) (xy 194.55589 -296.495458) (xy 194.544696 -296.517568) (xy 194.5386 -296.529506)
			(xy 194.539108 -296.556176) (xy 194.590924 -296.642282) (xy 194.595729 -296.649635) (xy 194.609292 -296.660774)
			(xy 194.625834 -296.666639) (xy 194.634612 -296.66692) (xy 194.865244 -296.66692) (xy 194.874002 -296.666544)
			(xy 194.8905 -296.660649) (xy 194.904082 -296.649585) (xy 194.908932 -296.642282) (xy 194.960748 -296.556176)
			(xy 194.961256 -296.529506) (xy 194.95516 -296.517568) (xy 194.943983 -296.49545) (xy 194.928153 -296.448493)
			(xy 194.920114 -296.399596) (xy 194.9196 -296.37482) (xy 194.920122 -296.349565) (xy 194.928435 -296.299743)
			(xy 194.944836 -296.251969) (xy 194.968877 -296.207546) (xy 194.999901 -296.167686) (xy 195.037063 -296.133476)
			(xy 195.079349 -296.10585) (xy 195.125605 -296.08556) (xy 195.17457 -296.07316) (xy 195.224908 -296.068989)
			(xy 195.275246 -296.07316) (xy 195.324211 -296.08556) (xy 195.370467 -296.10585) (xy 195.412753 -296.133476)
			(xy 195.449915 -296.167686) (xy 195.480939 -296.207546) (xy 195.50498 -296.251969) (xy 195.521381 -296.299743)
			(xy 195.529694 -296.349565) (xy 195.530216 -296.37482) (xy 195.529716 -296.399598) (xy 195.521677 -296.448497)
			(xy 195.505847 -296.495456) (xy 195.494656 -296.517568) (xy 195.48856 -296.529506) (xy 195.489068 -296.556176)
			(xy 195.540884 -296.642282) (xy 195.545692 -296.649628) (xy 195.559257 -296.660752) (xy 195.575798 -296.666598)
			(xy 195.584572 -296.66692) (xy 195.815204 -296.66692) (xy 195.823966 -296.66655) (xy 195.840473 -296.660664)
			(xy 195.854066 -296.649603) (xy 195.858892 -296.642282) (xy 195.910708 -296.556176) (xy 195.911216 -296.529506)
			(xy 195.90512 -296.517568) (xy 195.893941 -296.495451) (xy 195.878108 -296.448494) (xy 195.870068 -296.399597)
			(xy 195.86956 -296.37482) (xy 195.870082 -296.349565) (xy 195.878395 -296.299743) (xy 195.894796 -296.251969)
			(xy 195.918837 -296.207546) (xy 195.949861 -296.167686) (xy 195.987023 -296.133476) (xy 196.029309 -296.10585)
			(xy 196.075565 -296.08556) (xy 196.12453 -296.07316) (xy 196.174868 -296.068989) (xy 196.225206 -296.07316)
			(xy 196.274171 -296.08556) (xy 196.320427 -296.10585) (xy 196.362713 -296.133476) (xy 196.399875 -296.167686)
			(xy 196.430899 -296.207546) (xy 196.45494 -296.251969) (xy 196.471341 -296.299743) (xy 196.479654 -296.349565)
			(xy 196.480176 -296.37482) (xy 196.479676 -296.399597) (xy 196.471636 -296.448497) (xy 196.455804 -296.495455)
			(xy 196.444616 -296.517568) (xy 196.43852 -296.529506) (xy 196.439028 -296.556176) (xy 196.490844 -296.642282)
			(xy 196.49565 -296.649632) (xy 196.509214 -296.660767) (xy 196.525756 -296.666625) (xy 196.534532 -296.66692)
			(xy 196.765418 -296.66692) (xy 196.774179 -296.666548) (xy 196.790682 -296.660659) (xy 196.804272 -296.649596)
			(xy 196.809106 -296.642282) (xy 196.860922 -296.556176) (xy 196.86143 -296.529506) (xy 196.855334 -296.517568)
			(xy 196.844158 -296.49545) (xy 196.828329 -296.448493) (xy 196.820291 -296.399596) (xy 196.819774 -296.37482)
			(xy 196.820296 -296.349565) (xy 196.828609 -296.299743) (xy 196.84501 -296.251969) (xy 196.869051 -296.207546)
			(xy 196.900075 -296.167686) (xy 196.937237 -296.133476) (xy 196.979523 -296.10585) (xy 197.025779 -296.08556)
			(xy 197.074744 -296.07316) (xy 197.125082 -296.068989) (xy 197.17542 -296.07316) (xy 197.224385 -296.08556)
			(xy 197.270641 -296.10585) (xy 197.312927 -296.133476) (xy 197.350089 -296.167686) (xy 197.381113 -296.207546)
			(xy 197.405154 -296.251969) (xy 197.421555 -296.299743) (xy 197.429868 -296.349565) (xy 197.43039 -296.37482)
			(xy 197.42989 -296.399597) (xy 197.421851 -296.448497) (xy 197.406019 -296.495455) (xy 197.39483 -296.517568)
			(xy 197.388734 -296.529506) (xy 197.389242 -296.556176) (xy 197.441058 -296.642282) (xy 197.445865 -296.649631)
			(xy 197.459429 -296.660762) (xy 197.47597 -296.666616) (xy 197.484746 -296.66692) (xy 197.715378 -296.66692)
			(xy 197.724142 -296.666555) (xy 197.740656 -296.660674) (xy 197.754256 -296.649615) (xy 197.759066 -296.642282)
			(xy 197.810882 -296.556176) (xy 197.81139 -296.529506) (xy 197.805294 -296.517568) (xy 197.794116 -296.495451)
			(xy 197.778284 -296.448494) (xy 197.770244 -296.399597) (xy 197.769734 -296.37482) (xy 197.770256 -296.349565)
			(xy 197.778569 -296.299743) (xy 197.79497 -296.251969) (xy 197.819011 -296.207546) (xy 197.850035 -296.167686)
			(xy 197.887197 -296.133476) (xy 197.929483 -296.10585) (xy 197.975739 -296.08556) (xy 198.024704 -296.07316)
			(xy 198.075042 -296.068989) (xy 198.12538 -296.07316) (xy 198.174345 -296.08556) (xy 198.220601 -296.10585)
			(xy 198.262887 -296.133476) (xy 198.300049 -296.167686) (xy 198.331073 -296.207546) (xy 198.355114 -296.251969)
			(xy 198.371515 -296.299743) (xy 198.379828 -296.349565) (xy 198.38035 -296.37482) (xy 198.37985 -296.399598)
			(xy 198.371812 -296.448498) (xy 198.355984 -296.495458) (xy 198.34479 -296.517568) (xy 198.338694 -296.529506)
			(xy 198.339202 -296.556176) (xy 198.391018 -296.642282) (xy 198.395823 -296.649635) (xy 198.409386 -296.660776)
			(xy 198.425928 -296.666643) (xy 198.434706 -296.66692) (xy 198.665338 -296.66692) (xy 198.674097 -296.666545)
			(xy 198.690596 -296.660651) (xy 198.70418 -296.649587) (xy 198.709026 -296.642282) (xy 198.760842 -296.556176)
			(xy 198.76135 -296.529506) (xy 198.755254 -296.517568) (xy 198.744077 -296.49545) (xy 198.728247 -296.448493)
			(xy 198.720209 -296.399596) (xy 198.719694 -296.37482) (xy 198.720216 -296.349565) (xy 198.728529 -296.299743)
			(xy 198.74493 -296.251969) (xy 198.768971 -296.207546) (xy 198.799995 -296.167686) (xy 198.837157 -296.133476)
			(xy 198.879443 -296.10585) (xy 198.925699 -296.08556) (xy 198.974664 -296.07316) (xy 199.025002 -296.068989)
			(xy 199.07534 -296.07316) (xy 199.124305 -296.08556) (xy 199.170561 -296.10585) (xy 199.212847 -296.133476)
			(xy 199.250009 -296.167686) (xy 199.281033 -296.207546) (xy 199.305074 -296.251969) (xy 199.321475 -296.299743)
			(xy 199.329788 -296.349565) (xy 199.33031 -296.37482) (xy 199.329889 -296.397549) (xy 199.323139 -296.442504)
			(xy 199.309792 -296.485959) (xy 199.290144 -296.526951) (xy 199.264628 -296.564574) (xy 199.249538 -296.581576)
			(xy 199.243188 -296.588688) (xy 199.23633 -296.606214) (xy 199.23633 -296.613072) (xy 205.362554 -296.613072)
			(xy 205.366625 -296.55745) (xy 205.378751 -296.503013) (xy 205.398674 -296.450922) (xy 205.42597 -296.402287)
			(xy 205.460056 -296.358144) (xy 205.500205 -296.319435) (xy 205.545563 -296.286984) (xy 205.595163 -296.261483)
			(xy 205.647947 -296.243476) (xy 205.70279 -296.233346) (xy 205.758524 -296.231309) (xy 205.813961 -296.237409)
			(xy 205.867918 -296.251515) (xy 205.919247 -296.273327) (xy 205.966853 -296.302381) (xy 206.009721 -296.338056)
			(xy 206.046938 -296.379593) (xy 206.077711 -296.426106) (xy 206.101383 -296.476603) (xy 206.117451 -296.53001)
			(xy 206.125571 -296.585186) (xy 206.12608 -296.613072) (xy 206.63738 -296.613072) (xy 206.641451 -296.55745)
			(xy 206.653577 -296.503013) (xy 206.6735 -296.450922) (xy 206.700796 -296.402287) (xy 206.734882 -296.358144)
			(xy 206.775031 -296.319435) (xy 206.820389 -296.286984) (xy 206.869989 -296.261483) (xy 206.922773 -296.243476)
			(xy 206.977616 -296.233346) (xy 207.03335 -296.231309) (xy 207.088787 -296.237409) (xy 207.142744 -296.251515)
			(xy 207.194073 -296.273327) (xy 207.241679 -296.302381) (xy 207.284547 -296.338056) (xy 207.321764 -296.379593)
			(xy 207.352537 -296.426106) (xy 207.376209 -296.476603) (xy 207.392277 -296.53001) (xy 207.400397 -296.585186)
			(xy 207.400906 -296.613072) (xy 207.400397 -296.640958) (xy 207.392277 -296.696134) (xy 207.376209 -296.749541)
			(xy 207.352537 -296.800038) (xy 207.321764 -296.846551) (xy 207.284547 -296.888088) (xy 207.241679 -296.923763)
			(xy 207.194073 -296.952817) (xy 207.142744 -296.974629) (xy 207.088787 -296.988735) (xy 207.03335 -296.994835)
			(xy 206.977616 -296.992798) (xy 206.922773 -296.982668) (xy 206.869989 -296.964661) (xy 206.820389 -296.93916)
			(xy 206.775031 -296.906709) (xy 206.734882 -296.868) (xy 206.700796 -296.823857) (xy 206.6735 -296.775222)
			(xy 206.653577 -296.723131) (xy 206.641451 -296.668694) (xy 206.63738 -296.613072) (xy 206.12608 -296.613072)
			(xy 206.125571 -296.640958) (xy 206.117451 -296.696134) (xy 206.101383 -296.749541) (xy 206.077711 -296.800038)
			(xy 206.046938 -296.846551) (xy 206.009721 -296.888088) (xy 205.966853 -296.923763) (xy 205.919247 -296.952817)
			(xy 205.867918 -296.974629) (xy 205.813961 -296.988735) (xy 205.758524 -296.994835) (xy 205.70279 -296.992798)
			(xy 205.647947 -296.982668) (xy 205.595163 -296.964661) (xy 205.545563 -296.93916) (xy 205.500205 -296.906709)
			(xy 205.460056 -296.868) (xy 205.42597 -296.823857) (xy 205.398674 -296.775222) (xy 205.378751 -296.723131)
			(xy 205.366625 -296.668694) (xy 205.362554 -296.613072) (xy 199.23633 -296.613072) (xy 199.23633 -296.61612)
			(xy 199.236754 -296.626136) (xy 199.244428 -296.644641) (xy 199.258601 -296.6588) (xy 199.277113 -296.666456)
			(xy 199.28713 -296.66692) (xy 199.295004 -296.66692) (xy 199.312636 -296.66733) (xy 199.34723 -296.674159)
			(xy 199.379833 -296.687594) (xy 199.409195 -296.70712) (xy 199.422004 -296.719244) (xy 199.91197 -297.20921)
			(xy 199.919319 -297.216009) (xy 199.937782 -297.223714) (xy 199.947784 -297.224196) (xy 200.249028 -297.224196)
			(xy 200.2824 -297.224694) (xy 200.348694 -297.232449) (xy 200.413645 -297.247817) (xy 200.476385 -297.270593)
			(xy 200.53607 -297.300469) (xy 200.5919 -297.337046) (xy 200.617836 -297.358054) (xy 200.62444 -297.363642)
			(xy 200.649078 -297.37304) (xy 200.653425 -297.374586) (xy 200.662499 -297.376254) (xy 200.667112 -297.376342)
			(xy 201.436986 -297.376342) (xy 201.447048 -297.376782) (xy 201.465626 -297.384523) (xy 201.473054 -297.391328)
			(xy 201.568812 -297.487086) (xy 201.572368 -297.489626) (xy 201.598137 -297.508512) (xy 201.645754 -297.551115)
			(xy 201.68836 -297.598728) (xy 201.707242 -297.6245) (xy 201.709782 -297.628056) (xy 201.71283 -297.631104)
			(xy 202.047094 -297.965368) (xy 202.054502 -297.972057) (xy 202.072938 -297.979646) (xy 202.082908 -297.9801)
			(xy 202.336654 -297.9801) (xy 202.349204 -297.979446) (xy 202.37132 -297.96758) (xy 202.378818 -297.957494)
			(xy 202.432666 -297.876214) (xy 202.435206 -297.850814) (xy 202.430126 -297.83913) (xy 202.420632 -297.815566)
			(xy 202.407269 -297.766552) (xy 202.400549 -297.716196) (xy 202.400154 -297.690794) (xy 202.40064 -297.663543)
			(xy 202.408396 -297.609595) (xy 202.423751 -297.5573) (xy 202.446393 -297.507723) (xy 202.475859 -297.461873)
			(xy 202.51155 -297.420682) (xy 202.552741 -297.384991) (xy 202.598591 -297.355525) (xy 202.648168 -297.332883)
			(xy 202.700463 -297.317528) (xy 202.754411 -297.309772) (xy 202.808913 -297.309772) (xy 202.862861 -297.317528)
			(xy 202.915156 -297.332883) (xy 202.964733 -297.355525) (xy 203.010583 -297.384991) (xy 203.051774 -297.420682)
			(xy 203.087465 -297.461873) (xy 203.116931 -297.507723) (xy 203.139573 -297.5573) (xy 203.154928 -297.609595)
			(xy 203.162684 -297.663543) (xy 203.16317 -297.690794) (xy 203.162725 -297.716292) (xy 203.155892 -297.766829)
			(xy 203.142386 -297.816004) (xy 203.122448 -297.862942) (xy 203.10983 -297.885104) (xy 203.104242 -297.894756)
			(xy 203.101956 -297.916854) (xy 203.13396 -298.011088) (xy 203.1492 -298.02709) (xy 203.159614 -298.031408)
			(xy 203.191066 -298.044487) (xy 203.250923 -298.077005) (xy 203.306523 -298.116359) (xy 203.357092 -298.161999)
			(xy 203.401921 -298.213288) (xy 203.440384 -298.269508) (xy 203.471944 -298.329875) (xy 203.49616 -298.393544)
			(xy 203.512693 -298.459626) (xy 203.521313 -298.527198) (xy 203.522072 -298.561252) (xy 203.523342 -298.571666)
			(xy 203.528676 -298.599606) (xy 203.531724 -298.618148) (xy 203.559918 -298.642024) (xy 204.016356 -298.642024)
			(xy 204.023602 -298.641805) (xy 204.037531 -298.637811) (xy 204.043788 -298.63415) (xy 204.072017 -298.616782)
			(xy 204.131634 -298.587815) (xy 204.194138 -298.56576) (xy 204.258733 -298.550899) (xy 204.324591 -298.543423)
			(xy 204.357732 -298.542964) (xy 204.678534 -298.542964) (xy 204.711407 -298.543393) (xy 204.776743 -298.550728)
			(xy 204.840846 -298.565336) (xy 204.90291 -298.587032) (xy 204.962152 -298.615543) (xy 205.017828 -298.650511)
			(xy 205.069236 -298.691496) (xy 205.092808 -298.714414) (xy 205.170532 -298.792138) (xy 205.177929 -298.798986)
			(xy 205.196528 -298.806719) (xy 205.2066 -298.807124) (xy 205.58506 -298.807124) (xy 205.610262 -298.807656)
			(xy 205.660038 -298.815595) (xy 205.707969 -298.831191) (xy 205.752886 -298.854063) (xy 205.793692 -298.883653)
			(xy 205.811882 -298.901104) (xy 206.301086 -299.390562) (xy 206.308429 -299.397379) (xy 206.326891 -299.405122)
			(xy 206.3369 -299.405548) (xy 207.499712 -299.405548) (xy 207.5353 -299.406059) (xy 207.605957 -299.414651)
			(xy 207.675053 -299.431731) (xy 207.7085 -299.443902) (xy 207.717136 -299.447204) (xy 207.840834 -299.447204)
			(xy 207.866124 -299.447701) (xy 207.916081 -299.455613) (xy 207.964187 -299.471235) (xy 208.00926 -299.494186)
			(xy 208.050192 -299.523899) (xy 208.068418 -299.541438) (xy 208.23174 -299.70476) (xy 208.232248 -299.705268)
			(xy 208.23963 -299.711849) (xy 208.257928 -299.719299) (xy 208.267808 -299.719746) (xy 208.702656 -299.719746)
			(xy 208.713784 -299.719189) (xy 208.73396 -299.7098) (xy 208.748276 -299.692762) (xy 208.751678 -299.682154)
			(xy 208.751678 -299.6819) (xy 208.75929 -299.655141) (xy 208.781199 -299.604006) (xy 208.810304 -299.556595)
			(xy 208.845988 -299.513915) (xy 208.887493 -299.476871) (xy 208.933938 -299.44625) (xy 208.984339 -299.422699)
			(xy 209.037627 -299.406721) (xy 209.09267 -299.398652) (xy 209.120486 -299.398182) (xy 209.14774 -299.398644)
			(xy 209.201693 -299.406399) (xy 209.253993 -299.421754) (xy 209.303576 -299.444396) (xy 209.349431 -299.473863)
			(xy 209.390626 -299.509557) (xy 209.426323 -299.55075) (xy 209.455793 -299.596603) (xy 209.478438 -299.646184)
			(xy 209.493796 -299.698484) (xy 209.501554 -299.752436) (xy 209.501994 -299.77969) (xy 209.501994 -299.779944)
			(xy 209.501658 -299.801863) (xy 209.496564 -299.845406) (xy 209.491834 -299.866812) (xy 209.491326 -299.869352)
			(xy 209.489802 -299.88129) (xy 209.491072 -299.891704) (xy 209.49158 -299.894752) (xy 209.491834 -299.896276)
			(xy 209.49652 -299.91756) (xy 209.501609 -299.960845) (xy 209.501994 -299.982636) (xy 209.501994 -299.98289)
			(xy 209.501551 -300.009535) (xy 209.494134 -300.062306) (xy 209.479444 -300.113531) (xy 209.457765 -300.162212)
			(xy 209.429521 -300.207401) (xy 209.395262 -300.248219) (xy 209.355654 -300.28387) (xy 209.311468 -300.31366)
			(xy 209.263566 -300.33701) (xy 209.238342 -300.345602) (xy 209.222594 -300.350682) (xy 209.20329 -300.377352)
			(xy 209.20329 -300.438312) (xy 209.228436 -300.467014) (xy 209.24774 -300.4693) (xy 209.281225 -300.474101)
			(xy 209.346875 -300.49042) (xy 209.410209 -300.51419) (xy 209.470385 -300.545095) (xy 209.526602 -300.582723)
			(xy 209.578113 -300.626574) (xy 209.624231 -300.676065) (xy 209.664344 -300.730537) (xy 209.697917 -300.789266)
			(xy 209.724505 -300.85147) (xy 209.743753 -300.916322) (xy 209.755406 -300.982959) (xy 209.759308 -301.050494)
			(xy 209.755407 -301.118029) (xy 209.743756 -301.184666) (xy 209.724509 -301.249519) (xy 209.697923 -301.311723)
			(xy 209.664351 -301.370453) (xy 209.624239 -301.424925) (xy 209.578122 -301.474417) (xy 209.526612 -301.51827)
			(xy 209.470396 -301.555899) (xy 209.410221 -301.586805) (xy 209.346887 -301.610576) (xy 209.281237 -301.626897)
			(xy 209.24774 -301.631604) (xy 209.228436 -301.63389) (xy 209.20329 -301.662592) (xy 209.20329 -302.603154)
			(xy 209.203706 -302.613205) (xy 209.211402 -302.631775) (xy 209.225635 -302.645971) (xy 209.234786 -302.650144)
			(xy 209.24139 -302.652938) (xy 209.245708 -302.6537) (xy 209.273792 -302.660259) (xy 209.327721 -302.680696)
			(xy 209.377957 -302.70902) (xy 209.423356 -302.744585) (xy 209.462883 -302.78658) (xy 209.495635 -302.834047)
			(xy 209.520868 -302.885906) (xy 209.538004 -302.940972) (xy 209.546653 -302.99799) (xy 209.547206 -303.026826)
			(xy 209.546674 -303.055769) (xy 209.537936 -303.112991) (xy 209.520649 -303.168236) (xy 209.49521 -303.220232)
			(xy 209.462204 -303.267786) (xy 209.42239 -303.309805) (xy 209.376682 -303.345323) (xy 209.326131 -303.373524)
			(xy 209.271898 -303.393761) (xy 209.243676 -303.400206) (xy 209.225896 -303.404016) (xy 209.20329 -303.431956)
			(xy 209.20329 -304.465228) (xy 209.202828 -304.475104) (xy 209.195381 -304.493399) (xy 209.188812 -304.500788)
			(xy 209.188558 -304.501042) (xy 209.182564 -304.507793) (xy 209.17531 -304.524312) (xy 209.17418 -304.542319)
			(xy 209.176366 -304.55108) (xy 209.202274 -304.636932) (xy 209.204488 -304.643426) (xy 209.211835 -304.655006)
			(xy 209.216752 -304.659792) (xy 209.221983 -304.664222) (xy 209.234212 -304.670402) (xy 209.240882 -304.671984)
			(xy 209.269342 -304.678227) (xy 209.32408 -304.698188) (xy 209.375147 -304.72624) (xy 209.421353 -304.761731)
			(xy 209.461626 -304.803835) (xy 209.495029 -304.851574) (xy 209.520784 -304.903836) (xy 209.538293 -304.959407)
			(xy 209.547149 -305.016994) (xy 209.547714 -305.046126) (xy 209.547226 -305.073376) (xy 209.539467 -305.127321)
			(xy 209.52411 -305.179613) (xy 209.501467 -305.229188) (xy 209.472 -305.275035) (xy 209.436309 -305.316223)
			(xy 209.395119 -305.351912) (xy 209.34927 -305.381377) (xy 209.299695 -305.404017) (xy 209.247402 -305.419371)
			(xy 209.193456 -305.427128) (xy 209.166206 -305.427634) (xy 209.137073 -305.427084) (xy 209.079485 -305.418226)
			(xy 209.023913 -305.400714) (xy 208.97165 -305.374957) (xy 208.92391 -305.341553) (xy 208.881805 -305.301279)
			(xy 208.846313 -305.255071) (xy 208.818259 -305.204004) (xy 208.798295 -305.149266) (xy 208.792064 -305.120802)
			(xy 208.78927 -305.106832) (xy 208.770474 -305.086258) (xy 208.67116 -305.056286) (xy 208.662286 -305.053985)
			(xy 208.644008 -305.055174) (xy 208.627331 -305.062749) (xy 208.620614 -305.068986) (xy 208.515712 -305.173888)
			(xy 208.511902 -305.185318) (xy 208.502045 -305.212985) (xy 208.475044 -305.26514) (xy 208.44037 -305.312542)
			(xy 208.398842 -305.35407) (xy 208.35144 -305.388744) (xy 208.299285 -305.415745) (xy 208.271618 -305.425602)
			(xy 208.260188 -305.429412) (xy 208.10601 -305.58359) (xy 208.099161 -305.590987) (xy 208.091421 -305.609585)
			(xy 208.091024 -305.619658) (xy 208.091024 -307.40731) (xy 208.091444 -307.416917) (xy 208.098503 -307.434788)
			(xy 208.10474 -307.442108) (xy 208.158842 -307.500274) (xy 208.17586 -307.508402) (xy 208.185766 -307.509164)
			(xy 208.214269 -307.511719) (xy 208.270096 -307.524288) (xy 208.32342 -307.545054) (xy 208.373045 -307.573551)
			(xy 208.417857 -307.60914) (xy 208.456851 -307.651023) (xy 208.489152 -307.69826) (xy 208.514035 -307.749792)
			(xy 208.530944 -307.804462) (xy 208.539497 -307.861044) (xy 208.540096 -307.889656) (xy 208.539932 -307.906508)
			(xy 208.537005 -307.940085) (xy 208.534254 -307.956712) (xy 208.531968 -307.969158) (xy 208.539334 -307.99278)
			(xy 208.592674 -308.04612) (xy 208.600073 -308.052963) (xy 208.618672 -308.060683) (xy 208.628742 -308.061106)
		)
		(stroke
			(width 0)
			(type solid)
		)
		(fill yes)
		(layer "In5.Cu")
		(net "P1V8_PEX")
	)
	(gr_poly
		(pts
			(xy 442.745876 -308.061106) (xy 442.755901 -308.060691) (xy 442.774427 -308.053025) (xy 442.788608 -308.038852)
			(xy 442.796285 -308.020331) (xy 442.796676 -308.010306) (xy 442.796676 -305.305206) (xy 442.797136 -305.272352)
			(xy 442.804492 -305.207057) (xy 442.819111 -305.142997) (xy 442.840811 -305.080975) (xy 442.869318 -305.021774)
			(xy 442.904273 -304.966135) (xy 442.945238 -304.91476) (xy 442.968126 -304.891186) (xy 442.97727 -304.882042)
			(xy 442.98411 -304.874642) (xy 442.991828 -304.856043) (xy 442.992256 -304.845974) (xy 442.992256 -288.142172)
			(xy 442.992162 -288.137294) (xy 442.990378 -288.127703) (xy 442.9887 -288.123122) (xy 442.98489 -288.113978)
			(xy 442.37148 -287.500568) (xy 442.368629 -287.497862) (xy 442.362251 -287.493268) (xy 442.35878 -287.491424)
			(xy 442.353354 -287.488837) (xy 442.341674 -287.486007) (xy 442.335666 -287.485836) (xy 440.072526 -287.485836)
			(xy 440.05881 -287.487868) (xy 440.052839 -287.489919) (xy 440.042054 -287.496476) (xy 440.037474 -287.500822)
			(xy 440.01563 -287.52419) (xy 439.985658 -287.556194) (xy 439.982235 -287.560069) (xy 439.976865 -287.568902)
			(xy 439.97499 -287.57372) (xy 439.971434 -287.583626) (xy 439.972196 -287.594294) (xy 439.972958 -287.619694)
			(xy 439.972958 -287.620202) (xy 439.972543 -287.645069) (xy 439.96605 -287.694376) (xy 439.960004 -287.7185)
			(xy 439.959496 -287.720786) (xy 439.957532 -287.729192) (xy 439.958725 -287.746403) (xy 439.965553 -287.762247)
			(xy 439.97118 -287.768792) (xy 440.030108 -287.831784) (xy 440.037683 -287.839196) (xy 440.057111 -287.847597)
			(xy 440.0677 -287.84804) (xy 440.077098 -287.847024) (xy 440.079384 -287.846516) (xy 440.097305 -287.843278)
			(xy 440.133563 -287.839839) (xy 440.151774 -287.839658) (xy 440.15406 -287.839658) (xy 440.181207 -287.840297)
			(xy 440.234912 -287.848314) (xy 440.286938 -287.863863) (xy 440.336234 -287.886632) (xy 440.381804 -287.916159)
			(xy 440.422727 -287.951849) (xy 440.458178 -287.99298) (xy 440.487439 -288.038721) (xy 440.509919 -288.088149)
			(xy 440.525165 -288.140265) (xy 440.532868 -288.194016) (xy 440.533282 -288.221166) (xy 440.532796 -288.248417)
			(xy 440.52504 -288.302365) (xy 440.509685 -288.35466) (xy 440.487043 -288.404237) (xy 440.457577 -288.450087)
			(xy 440.421886 -288.491278) (xy 440.380695 -288.526969) (xy 440.334845 -288.556435) (xy 440.285268 -288.579077)
			(xy 440.232973 -288.594432) (xy 440.179025 -288.602188) (xy 440.124523 -288.602188) (xy 440.070575 -288.594432)
			(xy 440.01828 -288.579077) (xy 439.968703 -288.556435) (xy 439.922853 -288.526969) (xy 439.881662 -288.491278)
			(xy 439.845971 -288.450087) (xy 439.816505 -288.404237) (xy 439.793863 -288.35466) (xy 439.778508 -288.302365)
			(xy 439.770752 -288.248417) (xy 439.770266 -288.221166) (xy 439.770266 -288.220404) (xy 439.770696 -288.195602)
			(xy 439.777194 -288.146423) (xy 439.78322 -288.12236) (xy 439.783728 -288.120074) (xy 439.783728 -288.09315)
			(xy 439.781943 -288.087324) (xy 439.776042 -288.076667) (xy 439.772044 -288.072068) (xy 439.713116 -288.008822)
			(xy 439.7085 -288.004201) (xy 439.697436 -287.997267) (xy 439.691272 -287.995106) (xy 439.67908 -287.991296)
			(xy 439.671206 -287.99282) (xy 439.666126 -287.993836) (xy 439.660792 -287.994852) (xy 439.660284 -287.994852)
			(xy 439.626502 -287.999678) (xy 439.615326 -288.000694) (xy 439.605674 -288.006282) (xy 439.601008 -288.009171)
			(xy 439.592932 -288.016599) (xy 439.589672 -288.021014) (xy 439.545222 -288.084006) (xy 439.539574 -288.09296)
			(xy 439.535389 -288.113688) (xy 439.537094 -288.124138) (xy 439.537602 -288.126424) (xy 439.542444 -288.146487)
			(xy 439.548301 -288.187343) (xy 439.549286 -288.207958) (xy 439.54954 -288.218626) (xy 439.54954 -288.22396)
			(xy 439.548867 -288.251083) (xy 439.540793 -288.304734) (xy 439.525201 -288.3567) (xy 439.502404 -288.405934)
			(xy 439.472863 -288.451441) (xy 439.437174 -288.492305) (xy 439.396056 -288.527702) (xy 439.350338 -288.556916)
			(xy 439.300943 -288.57936) (xy 439.248867 -288.594581) (xy 439.195159 -288.602271) (xy 439.168032 -288.602674)
			(xy 439.140927 -288.602201) (xy 439.087264 -288.594534) (xy 439.035225 -288.579348) (xy 438.985859 -288.556951)
			(xy 438.94016 -288.527792) (xy 438.899048 -288.492459) (xy 438.863351 -288.451664) (xy 438.833786 -288.406227)
			(xy 438.810949 -288.357063) (xy 438.795301 -288.305161) (xy 438.787155 -288.251568) (xy 438.786524 -288.224468)
			(xy 438.786524 -288.220912) (xy 438.786968 -288.194531) (xy 438.794228 -288.142272) (xy 438.801002 -288.116772)
			(xy 438.803675 -288.105113) (xy 438.799168 -288.081653) (xy 438.792366 -288.071814) (xy 438.764172 -288.03854)
			(xy 438.736486 -288.005774) (xy 438.732257 -288.001085) (xy 438.721981 -287.993755) (xy 438.716166 -287.991296)
			(xy 438.704736 -287.986724) (xy 438.691782 -287.987994) (xy 438.681025 -287.989166) (xy 438.659422 -287.990437)
			(xy 438.648602 -287.990534) (xy 438.648094 -287.990534) (xy 438.628536 -287.990026) (xy 438.616598 -287.989518)
			(xy 438.60593 -287.99409) (xy 438.60049 -287.996553) (xy 438.590856 -288.003605) (xy 438.58688 -288.00806)
			(xy 438.53481 -288.07029) (xy 438.531196 -288.074858) (xy 438.525928 -288.085245) (xy 438.524396 -288.090864)
			(xy 438.521602 -288.10204) (xy 438.524142 -288.113724) (xy 438.528523 -288.134402) (xy 438.533238 -288.176409)
			(xy 438.53354 -288.197544) (xy 438.533051 -288.224797) (xy 438.525288 -288.278748) (xy 438.509925 -288.331045)
			(xy 438.487277 -288.380624) (xy 438.457803 -288.426475) (xy 438.422104 -288.467664) (xy 438.380907 -288.503354)
			(xy 438.33505 -288.532817) (xy 438.285467 -288.555455) (xy 438.233166 -288.570806) (xy 438.179213 -288.578557)
			(xy 438.124707 -288.578551) (xy 438.070756 -288.570789) (xy 438.018458 -288.555427) (xy 437.96888 -288.532779)
			(xy 437.923029 -288.503306) (xy 437.881839 -288.467607) (xy 437.846149 -288.42641) (xy 437.816685 -288.380554)
			(xy 437.794047 -288.33097) (xy 437.778695 -288.27867) (xy 437.770943 -288.224717) (xy 437.770948 -288.170211)
			(xy 437.778711 -288.11626) (xy 437.794072 -288.063962) (xy 437.816719 -288.014383) (xy 437.846192 -287.968532)
			(xy 437.88189 -287.927342) (xy 437.923086 -287.891651) (xy 437.968943 -287.862187) (xy 438.018526 -287.839548)
			(xy 438.070826 -287.824196) (xy 438.124779 -287.816444) (xy 438.152032 -287.816036) (xy 438.15254 -287.816036)
			(xy 438.172098 -287.816544) (xy 438.184036 -287.817052) (xy 438.194704 -287.81248) (xy 438.200141 -287.810012)
			(xy 438.209766 -287.802953) (xy 438.213754 -287.79851) (xy 438.265824 -287.73628) (xy 438.269433 -287.731709)
			(xy 438.274692 -287.721321) (xy 438.276238 -287.715706) (xy 438.279032 -287.70453) (xy 438.276492 -287.692846)
			(xy 438.272134 -287.672229) (xy 438.267423 -287.63035) (xy 438.267094 -287.60928) (xy 438.267094 -287.608772)
			(xy 438.267348 -287.592008) (xy 438.267856 -287.581594) (xy 438.2643 -287.572196) (xy 438.262389 -287.567353)
			(xy 438.256885 -287.558518) (xy 438.253378 -287.55467) (xy 438.202578 -287.501584) (xy 438.195103 -287.494423)
			(xy 438.176089 -287.486289) (xy 438.165748 -287.485836) (xy 437.18734 -287.485836) (xy 437.177554 -287.486285)
			(xy 437.159399 -287.493601) (xy 437.152034 -287.50006) (xy 436.727092 -287.91027) (xy 436.706917 -287.929519)
			(xy 436.664728 -287.965989) (xy 436.642764 -287.983168) (xy 436.633112 -287.990534) (xy 436.622952 -288.011362)
			(xy 436.622952 -288.036508) (xy 436.623078 -288.042011) (xy 436.625394 -288.052768) (xy 436.627524 -288.057844)
			(xy 436.630572 -288.064194) (xy 436.634636 -288.066734) (xy 436.640689 -288.070176) (xy 436.654092 -288.073929)
			(xy 436.661052 -288.0741) (xy 436.75173 -288.0741) (xy 436.758769 -288.073875) (xy 436.772303 -288.070005)
			(xy 436.7784 -288.06648) (xy 436.78394 -288.062808) (xy 436.793082 -288.053168) (xy 436.796434 -288.04743)
			(xy 436.796942 -288.046668) (xy 436.809265 -288.023621) (xy 436.839272 -287.980831) (xy 436.874842 -287.94254)
			(xy 436.915308 -287.909466) (xy 436.959912 -287.882229) (xy 437.007819 -287.861339) (xy 437.058129 -287.847188)
			(xy 437.109901 -287.840041) (xy 437.136032 -287.839658) (xy 437.163284 -287.840146) (xy 437.217233 -287.847907)
			(xy 437.269529 -287.863266) (xy 437.319106 -287.885911) (xy 437.364957 -287.915381) (xy 437.406147 -287.951076)
			(xy 437.441838 -287.992269) (xy 437.471304 -288.038122) (xy 437.493945 -288.087701) (xy 437.5093 -288.139998)
			(xy 437.517056 -288.193948) (xy 437.517056 -288.248452) (xy 437.5093 -288.302402) (xy 437.493945 -288.354699)
			(xy 437.471304 -288.404278) (xy 437.441838 -288.450131) (xy 437.406147 -288.491324) (xy 437.364957 -288.527019)
			(xy 437.319106 -288.556489) (xy 437.269529 -288.579134) (xy 437.217233 -288.594493) (xy 437.163284 -288.602254)
			(xy 437.136032 -288.602674) (xy 437.109937 -288.602249) (xy 437.058235 -288.595133) (xy 437.007987 -288.581029)
			(xy 436.960132 -288.560202) (xy 436.915567 -288.533042) (xy 436.875124 -288.500054) (xy 436.83956 -288.461858)
			(xy 436.809539 -288.419167) (xy 436.797196 -288.396172) (xy 436.796688 -288.395156) (xy 436.796434 -288.394902)
			(xy 436.793108 -288.389142) (xy 436.783971 -288.379485) (xy 436.7784 -288.375852) (xy 436.772293 -288.372353)
			(xy 436.758764 -288.368493) (xy 436.75173 -288.368232) (xy 436.661052 -288.368232) (xy 436.6541 -288.368469)
			(xy 436.640706 -288.3722) (xy 436.634636 -288.375598) (xy 436.630572 -288.378138) (xy 436.618811 -288.403432)
			(xy 436.589092 -288.450638) (xy 436.552902 -288.493085) (xy 436.510989 -288.529895) (xy 436.464225 -288.560302)
			(xy 436.413577 -288.583678) (xy 436.360098 -288.599536) (xy 436.304895 -288.607549) (xy 436.277004 -288.608008)
			(xy 436.248119 -288.607465) (xy 436.190993 -288.598864) (xy 436.13578 -288.581866) (xy 436.083708 -288.556849)
			(xy 436.035932 -288.52437) (xy 435.993516 -288.48515) (xy 435.974998 -288.462974) (xy 435.968863 -288.455975)
			(xy 435.952825 -288.446564) (xy 435.934486 -288.443485) (xy 435.916253 -288.447144) (xy 435.908196 -288.451798)
			(xy 435.341014 -288.80943) (xy 435.306391 -288.830766) (xy 441.453014 -288.830766) (xy 441.457085 -288.775144)
			(xy 441.469211 -288.720707) (xy 441.489134 -288.668616) (xy 441.51643 -288.619981) (xy 441.550516 -288.575838)
			(xy 441.590665 -288.537129) (xy 441.636023 -288.504678) (xy 441.685623 -288.479177) (xy 441.738407 -288.46117)
			(xy 441.79325 -288.45104) (xy 441.848984 -288.449003) (xy 441.904421 -288.455103) (xy 441.958378 -288.469209)
			(xy 442.009707 -288.491021) (xy 442.057313 -288.520075) (xy 442.100181 -288.55575) (xy 442.137398 -288.597287)
			(xy 442.168171 -288.6438) (xy 442.191843 -288.694297) (xy 442.207911 -288.747704) (xy 442.216031 -288.80288)
			(xy 442.21654 -288.830766) (xy 442.216031 -288.858652) (xy 442.207911 -288.913828) (xy 442.191843 -288.967235)
			(xy 442.168171 -289.017732) (xy 442.137398 -289.064245) (xy 442.100181 -289.105782) (xy 442.057313 -289.141457)
			(xy 442.009707 -289.170511) (xy 441.958378 -289.192323) (xy 441.904421 -289.206429) (xy 441.848984 -289.212529)
			(xy 441.79325 -289.210492) (xy 441.738407 -289.200362) (xy 441.685623 -289.182355) (xy 441.636023 -289.156854)
			(xy 441.590665 -289.124403) (xy 441.550516 -289.085694) (xy 441.51643 -289.041551) (xy 441.489134 -288.992916)
			(xy 441.469211 -288.940825) (xy 441.457085 -288.886388) (xy 441.453014 -288.830766) (xy 435.306391 -288.830766)
			(xy 435.304303 -288.832053) (xy 435.227666 -288.871599) (xy 435.147898 -288.904373) (xy 435.065595 -288.930129)
			(xy 434.981374 -288.948676) (xy 434.938678 -288.954718) (xy 434.929026 -288.955988) (xy 434.912516 -288.965132)
			(xy 434.86197 -289.026092) (xy 434.856198 -289.033772) (xy 434.850318 -289.052048) (xy 434.85054 -289.061652)
			(xy 434.851302 -289.08502) (xy 434.850816 -289.112271) (xy 434.84306 -289.166219) (xy 434.827705 -289.218514)
			(xy 434.805063 -289.268091) (xy 434.775597 -289.313941) (xy 434.739906 -289.355132) (xy 434.698715 -289.390823)
			(xy 434.652865 -289.420289) (xy 434.603288 -289.442931) (xy 434.550993 -289.458286) (xy 434.497045 -289.466042)
			(xy 434.442543 -289.466042) (xy 434.388595 -289.458286) (xy 434.3363 -289.442931) (xy 434.286723 -289.420289)
			(xy 434.240873 -289.390823) (xy 434.199682 -289.355132) (xy 434.163991 -289.313941) (xy 434.134525 -289.268091)
			(xy 434.111883 -289.218514) (xy 434.096528 -289.166219) (xy 434.088772 -289.112271) (xy 434.088286 -289.08502)
			(xy 434.08854 -289.069018) (xy 434.089048 -289.058604) (xy 434.081936 -289.0393) (xy 434.02377 -288.978848)
			(xy 434.016345 -288.971729) (xy 433.997468 -288.963607) (xy 433.987194 -288.9631) (xy 432.22418 -288.9631)
			(xy 432.16195 -288.961068) (xy 432.149599 -288.960908) (xy 432.127091 -288.971019) (xy 432.119024 -288.980372)
			(xy 432.103252 -288.999546) (xy 432.066937 -289.033399) (xy 432.025972 -289.061446) (xy 431.981276 -289.083058)
			(xy 431.933853 -289.097748) (xy 431.884767 -289.105188) (xy 431.859944 -289.105594) (xy 431.832662 -289.105031)
			(xy 431.778839 -289.096068) (xy 431.727217 -289.078393) (xy 431.679196 -289.052487) (xy 431.636077 -289.019051)
			(xy 431.61712 -288.999422) (xy 431.616612 -288.998914) (xy 431.589434 -288.98723) (xy 431.584594 -288.985228)
			(xy 431.57435 -288.983054) (xy 431.569114 -288.982912) (xy 431.515774 -288.982912) (xy 431.51054 -288.983069)
			(xy 431.5003 -288.985246) (xy 431.495454 -288.98723) (xy 431.468276 -288.998914) (xy 431.467768 -288.999422)
			(xy 431.448836 -289.019078) (xy 431.405716 -289.052522) (xy 431.357689 -289.078431) (xy 431.306059 -289.096101)
			(xy 431.252229 -289.105053) (xy 431.224944 -289.105594) (xy 431.198316 -289.10509) (xy 431.145749 -289.096553)
			(xy 431.095233 -289.079693) (xy 431.048076 -289.054946) (xy 431.005501 -289.022954) (xy 430.96861 -288.984545)
			(xy 430.938359 -288.940716) (xy 430.926494 -288.916872) (xy 430.925986 -288.916364) (xy 430.921668 -288.90722)
			(xy 430.89703 -288.89198) (xy 430.602898 -288.89198) (xy 430.57826 -288.90722) (xy 430.573688 -288.916618)
			(xy 430.561792 -288.94045) (xy 430.531545 -288.984289) (xy 430.494658 -289.02271) (xy 430.452087 -289.054717)
			(xy 430.404934 -289.079482) (xy 430.354419 -289.096364) (xy 430.30185 -289.104925) (xy 430.248589 -289.104944)
			(xy 430.196014 -289.096421) (xy 430.145487 -289.079576) (xy 430.098315 -289.054845) (xy 430.055721 -289.022868)
			(xy 430.018806 -288.984475) (xy 429.988528 -288.940657) (xy 429.976534 -288.916872) (xy 429.976026 -288.916364)
			(xy 429.971708 -288.90722) (xy 429.94707 -288.89198) (xy 429.652938 -288.89198) (xy 429.6283 -288.90722)
			(xy 429.62449 -288.915094) (xy 429.612015 -288.940382) (xy 429.579791 -288.98665) (xy 429.540194 -289.026789)
			(xy 429.494368 -289.059639) (xy 429.443639 -289.084249) (xy 429.416718 -289.09264) (xy 429.412808 -289.093819)
			(xy 429.405404 -289.097263) (xy 429.401986 -289.099498) (xy 429.367218 -289.123003) (xy 429.294327 -289.164609)
			(xy 429.218118 -289.199773) (xy 429.139161 -289.228233) (xy 429.058043 -289.249777) (xy 428.975369 -289.264243)
			(xy 428.891755 -289.271524) (xy 428.84979 -289.271964) (xy 428.58436 -289.271964) (xy 428.53421 -289.271349)
			(xy 428.434441 -289.26104) (xy 428.385224 -289.25139) (xy 428.380059 -289.250443) (xy 428.369561 -289.250443)
			(xy 428.364396 -289.25139) (xy 428.315179 -289.261041) (xy 428.21541 -289.271353) (xy 428.16526 -289.271964)
			(xy 427.89983 -289.271964) (xy 427.85783 -289.271521) (xy 427.774142 -289.264271) (xy 427.691393 -289.249825)
			(xy 427.6102 -289.228288) (xy 427.531169 -289.199823) (xy 427.454891 -289.164642) (xy 427.381934 -289.123006)
			(xy 427.347126 -289.099498) (xy 427.343702 -289.097273) (xy 427.336301 -289.093825) (xy 427.332394 -289.09264)
			(xy 427.305933 -289.084358) (xy 427.256022 -289.060221) (xy 427.210832 -289.028102) (xy 427.171627 -288.988902)
			(xy 427.139502 -288.943716) (xy 427.115358 -288.893808) (xy 427.107096 -288.867342) (xy 427.10592 -288.863431)
			(xy 427.102481 -288.856023) (xy 427.100238 -288.85261) (xy 427.077653 -288.819193) (xy 427.037466 -288.749253)
			(xy 427.019974 -288.71291) (xy 427.016081 -288.705249) (xy 427.004143 -288.692905) (xy 426.996606 -288.68878)
			(xy 426.95622 -288.667698) (xy 426.950124 -288.664396) (xy 426.936916 -288.661094) (xy 426.930566 -288.661094)
			(xy 426.92386 -288.661519) (xy 426.910993 -288.66537) (xy 426.905166 -288.668714) (xy 426.82922 -288.715704)
			(xy 426.823623 -288.719389) (xy 426.814473 -288.72917) (xy 426.811186 -288.735008) (xy 426.804836 -288.746692)
			(xy 426.805344 -288.760916) (xy 426.805598 -288.76625) (xy 426.805598 -288.766758) (xy 426.805852 -288.774378)
			(xy 426.805852 -288.775394) (xy 426.805305 -288.801375) (xy 426.797107 -288.852689) (xy 426.78099 -288.902091)
			(xy 426.757349 -288.948367) (xy 426.726767 -288.990379) (xy 426.689995 -289.027095) (xy 426.647936 -289.057613)
			(xy 426.601625 -289.081183) (xy 426.552198 -289.097225) (xy 426.500872 -289.105345) (xy 426.47489 -289.105848)
			(xy 425.52493 -289.105848) (xy 425.49892 -289.105367) (xy 425.447539 -289.097233) (xy 425.398063 -289.081161)
			(xy 425.351711 -289.057546) (xy 425.309625 -289.026971) (xy 425.272839 -288.990188) (xy 425.242262 -288.948102)
			(xy 425.218645 -288.901752) (xy 425.202571 -288.852277) (xy 425.194434 -288.800896) (xy 425.193968 -288.774886)
			(xy 425.194157 -288.759811) (xy 425.196958 -288.729792) (xy 425.199556 -288.714942) (xy 425.199556 -288.713926)
			(xy 425.200572 -288.708592) (xy 425.19346 -288.685986) (xy 425.120562 -288.609786) (xy 425.09821 -288.601658)
			(xy 425.086272 -288.603182) (xy 425.077225 -288.604172) (xy 425.059051 -288.60519) (xy 425.04995 -288.605214)
			(xy 425.035767 -288.60503) (xy 425.007527 -288.602361) (xy 424.993562 -288.59988) (xy 424.981116 -288.597594)
			(xy 424.957494 -288.60496) (xy 424.880024 -288.68243) (xy 424.872658 -288.706052) (xy 424.874944 -288.718498)
			(xy 424.87743 -288.732463) (xy 424.880104 -288.760703) (xy 424.880278 -288.774886) (xy 424.879756 -288.800141)
			(xy 424.871443 -288.849963) (xy 424.855042 -288.897737) (xy 424.831001 -288.94216) (xy 424.799977 -288.98202)
			(xy 424.762815 -289.01623) (xy 424.720529 -289.043856) (xy 424.674273 -289.064146) (xy 424.625308 -289.076546)
			(xy 424.57497 -289.080717) (xy 424.524632 -289.076546) (xy 424.475667 -289.064146) (xy 424.429411 -289.043856)
			(xy 424.387125 -289.01623) (xy 424.349963 -288.98202) (xy 424.318939 -288.94216) (xy 424.294898 -288.897737)
			(xy 424.278497 -288.849963) (xy 424.270184 -288.800141) (xy 424.269662 -288.774886) (xy 424.269849 -288.760704)
			(xy 424.272524 -288.732465) (xy 424.274996 -288.718498) (xy 424.277282 -288.706052) (xy 424.269916 -288.68243)
			(xy 424.192446 -288.60496) (xy 424.168824 -288.597594) (xy 424.156378 -288.59988) (xy 424.142413 -288.602365)
			(xy 424.114173 -288.605036) (xy 424.09999 -288.605214) (xy 424.075169 -288.604727) (xy 424.02618 -288.596694)
			(xy 423.979137 -288.580842) (xy 423.935278 -288.557588) (xy 423.895759 -288.527544) (xy 423.861621 -288.491503)
			(xy 423.833763 -288.450413) (xy 423.81292 -288.405358) (xy 423.799641 -288.357525) (xy 423.794275 -288.308173)
			(xy 423.796964 -288.258604) (xy 423.807637 -288.210122) (xy 423.826013 -288.164006) (xy 423.851607 -288.12147)
			(xy 423.883746 -288.083635) (xy 423.921583 -288.051498) (xy 423.96412 -288.025906) (xy 424.010237 -288.007532)
			(xy 424.058719 -287.996862) (xy 424.108289 -287.994175) (xy 424.157641 -287.999544) (xy 424.205473 -288.012826)
			(xy 424.250527 -288.033671) (xy 424.291615 -288.061531) (xy 424.327655 -288.095671) (xy 424.357696 -288.135191)
			(xy 424.380948 -288.179052) (xy 424.396798 -288.226096) (xy 424.404829 -288.275085) (xy 424.405298 -288.299906)
			(xy 424.405111 -288.314088) (xy 424.402437 -288.342328) (xy 424.399964 -288.356294) (xy 424.397678 -288.36874)
			(xy 424.405044 -288.392362) (xy 424.482514 -288.469832) (xy 424.506136 -288.477198) (xy 424.518582 -288.474912)
			(xy 424.532547 -288.472425) (xy 424.560787 -288.469751) (xy 424.57497 -288.469578) (xy 424.589153 -288.469763)
			(xy 424.617392 -288.472434) (xy 424.631358 -288.474912) (xy 424.643804 -288.477198) (xy 424.667426 -288.469832)
			(xy 424.744896 -288.392362) (xy 424.752262 -288.36874) (xy 424.749976 -288.356294) (xy 424.74749 -288.342329)
			(xy 424.744817 -288.314089) (xy 424.744642 -288.299906) (xy 424.745164 -288.274651) (xy 424.753477 -288.224829)
			(xy 424.769878 -288.177055) (xy 424.793919 -288.132632) (xy 424.824943 -288.092772) (xy 424.862105 -288.058562)
			(xy 424.904391 -288.030936) (xy 424.950647 -288.010646) (xy 424.999612 -287.998246) (xy 425.04995 -287.994075)
			(xy 425.100288 -287.998246) (xy 425.149253 -288.010646) (xy 425.195509 -288.030936) (xy 425.237795 -288.058562)
			(xy 425.274957 -288.092772) (xy 425.305981 -288.132632) (xy 425.330022 -288.177055) (xy 425.346423 -288.224829)
			(xy 425.354736 -288.274651) (xy 425.355258 -288.299906) (xy 425.355219 -288.309007) (xy 425.354202 -288.32718)
			(xy 425.353226 -288.336228) (xy 425.351702 -288.348166) (xy 425.35983 -288.370518) (xy 425.43603 -288.443416)
			(xy 425.458636 -288.450528) (xy 425.464478 -288.449512) (xy 425.479455 -288.446904) (xy 425.509729 -288.444103)
			(xy 425.52493 -288.443924) (xy 425.595288 -288.443924) (xy 425.605984 -288.443368) (xy 425.625552 -288.434721)
			(xy 425.633134 -288.42716) (xy 425.68368 -288.371026) (xy 425.690458 -288.362803) (xy 425.697023 -288.342548)
			(xy 425.69638 -288.33191) (xy 425.69638 -288.331656) (xy 425.694602 -288.299906) (xy 425.695048 -288.275913)
			(xy 425.702554 -288.228517) (xy 425.717382 -288.182879) (xy 425.739167 -288.140123) (xy 425.767373 -288.101301)
			(xy 425.801304 -288.06737) (xy 425.840127 -288.039165) (xy 425.882883 -288.01738) (xy 425.928521 -288.002553)
			(xy 425.975917 -287.995047) (xy 425.99991 -287.994598) (xy 426.009014 -287.994695) (xy 426.027188 -287.995837)
			(xy 426.036232 -287.996884) (xy 426.048124 -287.997677) (xy 426.070512 -287.989594) (xy 426.079158 -287.98139)
			(xy 426.143674 -287.913826) (xy 426.150786 -287.89122) (xy 426.14977 -287.885124) (xy 426.147175 -287.870209)
			(xy 426.144375 -287.840064) (xy 426.144182 -287.824926) (xy 426.144379 -287.809915) (xy 426.147175 -287.780022)
			(xy 426.14977 -287.765236) (xy 426.14977 -287.76422) (xy 426.150786 -287.758632) (xy 426.143674 -287.736026)
			(xy 426.079158 -287.668462) (xy 426.070518 -287.660254) (xy 426.048126 -287.652188) (xy 426.036232 -287.652968)
			(xy 426.027188 -287.654017) (xy 426.009014 -287.655161) (xy 425.99991 -287.655254) (xy 425.975917 -287.654784)
			(xy 425.928521 -287.64728) (xy 425.882883 -287.632454) (xy 425.840126 -287.610671) (xy 425.801302 -287.582469)
			(xy 425.767367 -287.548541) (xy 425.739158 -287.509722) (xy 425.717368 -287.466969) (xy 425.702533 -287.421333)
			(xy 425.69502 -287.373939) (xy 425.694602 -287.349946) (xy 425.69638 -287.317942) (xy 425.69638 -287.317434)
			(xy 425.697396 -287.30702) (xy 425.690792 -287.2867) (xy 425.633134 -287.222184) (xy 425.625622 -287.214513)
			(xy 425.606016 -287.205809) (xy 425.595288 -287.20542) (xy 425.53382 -287.20542) (xy 425.533566 -287.205674)
			(xy 425.52493 -287.205674) (xy 425.510046 -287.205454) (xy 425.48041 -287.202656) (xy 425.465748 -287.200086)
			(xy 425.464224 -287.200086) (xy 425.458382 -287.19907) (xy 425.435776 -287.206182) (xy 425.368212 -287.270698)
			(xy 425.360135 -287.279334) (xy 425.352178 -287.301573) (xy 425.352972 -287.31337) (xy 425.352972 -287.313624)
			(xy 425.354019 -287.322668) (xy 425.35516 -287.340842) (xy 425.355258 -287.349946) (xy 425.354769 -287.374761)
			(xy 425.346733 -287.423736) (xy 425.330879 -287.470767) (xy 425.307627 -287.514613) (xy 425.277588 -287.55412)
			(xy 425.241553 -287.588247) (xy 425.200472 -287.616096) (xy 425.155428 -287.636931) (xy 425.107605 -287.650206)
			(xy 425.058266 -287.655569) (xy 425.008708 -287.65288) (xy 424.960239 -287.64221) (xy 424.914134 -287.623839)
			(xy 424.871608 -287.598251) (xy 424.833782 -287.566121) (xy 424.801651 -287.528295) (xy 424.776063 -287.48577)
			(xy 424.757692 -287.439665) (xy 424.74702 -287.391196) (xy 424.744331 -287.341638) (xy 424.749693 -287.292299)
			(xy 424.762967 -287.244476) (xy 424.783802 -287.199431) (xy 424.81165 -287.15835) (xy 424.845777 -287.122315)
			(xy 424.885284 -287.092275) (xy 424.92913 -287.069022) (xy 424.97616 -287.053168) (xy 425.025135 -287.045132)
			(xy 425.04995 -287.044638) (xy 425.058991 -287.044742) (xy 425.077037 -287.045883) (xy 425.086018 -287.046924)
			(xy 425.086526 -287.046924) (xy 425.09821 -287.048194) (xy 425.120562 -287.040066) (xy 425.19346 -286.963866)
			(xy 425.200572 -286.941006) (xy 425.199048 -286.932624) (xy 425.196683 -286.918327) (xy 425.194144 -286.889457)
			(xy 425.193968 -286.874966) (xy 425.193968 -286.874712) (xy 425.194127 -286.859446) (xy 425.196928 -286.829045)
			(xy 425.199556 -286.814006) (xy 425.19981 -286.812482) (xy 425.200572 -286.808418) (xy 425.19346 -286.785812)
			(xy 425.120562 -286.709866) (xy 425.09821 -286.701738) (xy 425.086272 -286.703262) (xy 425.077225 -286.704252)
			(xy 425.059051 -286.705269) (xy 425.04995 -286.705294) (xy 425.025131 -286.704804) (xy 424.976149 -286.696766)
			(xy 424.929113 -286.68091) (xy 424.885261 -286.657653) (xy 424.845749 -286.627609) (xy 424.811618 -286.591568)
			(xy 424.783768 -286.55048) (xy 424.762931 -286.505428) (xy 424.749656 -286.457599) (xy 424.744294 -286.408252)
			(xy 424.746986 -286.358688) (xy 424.757661 -286.310212) (xy 424.776037 -286.264102) (xy 424.801631 -286.221572)
			(xy 424.833767 -286.183742) (xy 424.871601 -286.15161) (xy 424.914134 -286.126021) (xy 424.960247 -286.10765)
			(xy 425.008724 -286.096981) (xy 425.058288 -286.094295) (xy 425.107634 -286.099663) (xy 425.155462 -286.112943)
			(xy 425.200512 -286.133785) (xy 425.241596 -286.161641) (xy 425.277633 -286.195776) (xy 425.307673 -286.235291)
			(xy 425.330924 -286.279146) (xy 425.346775 -286.326184) (xy 425.354807 -286.375167) (xy 425.355258 -286.399986)
			(xy 425.355219 -286.409087) (xy 425.354203 -286.42726) (xy 425.353226 -286.436308) (xy 425.351702 -286.448246)
			(xy 425.35983 -286.470598) (xy 425.435776 -286.543496) (xy 425.458382 -286.550608) (xy 425.463208 -286.549846)
			(xy 425.478367 -286.547134) (xy 425.509024 -286.54421) (xy 425.524422 -286.544004) (xy 425.595288 -286.544004)
			(xy 425.605983 -286.543447) (xy 425.625549 -286.534798) (xy 425.633134 -286.52724) (xy 425.68368 -286.471106)
			(xy 425.690454 -286.462882) (xy 425.697011 -286.442628) (xy 425.69638 -286.43199) (xy 425.69638 -286.431736)
			(xy 425.694602 -286.399986) (xy 425.695074 -286.375996) (xy 425.702582 -286.328606) (xy 425.71741 -286.282975)
			(xy 425.739195 -286.240225) (xy 425.767399 -286.201409) (xy 425.801327 -286.167483) (xy 425.840145 -286.139282)
			(xy 425.882897 -286.117501) (xy 425.92853 -286.102676) (xy 425.97592 -286.095172) (xy 425.99991 -286.094678)
			(xy 426.009078 -286.094771) (xy 426.027378 -286.095915) (xy 426.036486 -286.096964) (xy 426.04817 -286.098488)
			(xy 426.07103 -286.09036) (xy 426.143674 -286.013906) (xy 426.150786 -285.9913) (xy 426.148754 -285.979362)
			(xy 426.144944 -285.94685) (xy 426.143927 -285.926915) (xy 426.146092 -285.887056) (xy 426.149262 -285.867348)
			(xy 426.149262 -285.86684) (xy 426.150786 -285.858458) (xy 426.143674 -285.835852) (xy 426.07103 -285.759398)
			(xy 426.04817 -285.75127) (xy 426.036486 -285.752794) (xy 426.027378 -285.753848) (xy 426.009078 -285.754991)
			(xy 425.99991 -285.75508) (xy 425.975917 -285.754635) (xy 425.928522 -285.747129) (xy 425.882885 -285.732301)
			(xy 425.840129 -285.710516) (xy 425.801309 -285.68231) (xy 425.767379 -285.648378) (xy 425.739175 -285.609555)
			(xy 425.717392 -285.566798) (xy 425.702567 -285.52116) (xy 425.695064 -285.473765) (xy 425.694602 -285.449772)
			(xy 425.69638 -285.418022) (xy 425.69638 -285.417514) (xy 425.696896 -285.406893) (xy 425.69034 -285.386687)
			(xy 425.68368 -285.378398) (xy 425.633134 -285.322264) (xy 425.62562 -285.314596) (xy 425.606015 -285.305895)
			(xy 425.595288 -285.3055) (xy 425.52493 -285.3055) (xy 425.509919 -285.305302) (xy 425.480027 -285.302502)
			(xy 425.46524 -285.299912) (xy 425.464224 -285.299912) (xy 425.458636 -285.298896) (xy 425.43603 -285.306008)
			(xy 425.368466 -285.370524) (xy 425.360254 -285.379163) (xy 425.352179 -285.401556) (xy 425.352972 -285.41345)
			(xy 425.354021 -285.422494) (xy 425.355166 -285.440668) (xy 425.355258 -285.449772) (xy 425.354775 -285.474588)
			(xy 425.34675 -285.523568) (xy 425.330906 -285.570604) (xy 425.307662 -285.614458) (xy 425.27763 -285.653973)
			(xy 425.2416 -285.68811) (xy 425.200522 -285.715967) (xy 425.155479 -285.736813) (xy 425.107657 -285.750096)
			(xy 425.058316 -285.755468) (xy 425.008755 -285.752787) (xy 424.960282 -285.742123) (xy 424.914172 -285.723757)
			(xy 424.87164 -285.698174) (xy 424.833808 -285.666047) (xy 424.801671 -285.628223) (xy 424.776077 -285.585698)
			(xy 424.7577 -285.539593) (xy 424.747024 -285.491122) (xy 424.74433 -285.441562) (xy 424.749689 -285.39222)
			(xy 424.762961 -285.344394) (xy 424.783794 -285.299346) (xy 424.811641 -285.258261) (xy 424.845768 -285.222223)
			(xy 424.885276 -285.19218) (xy 424.929124 -285.168925) (xy 424.976156 -285.153069) (xy 425.025134 -285.145032)
			(xy 425.04995 -285.144464) (xy 425.059054 -285.144562) (xy 425.077227 -285.145706) (xy 425.086272 -285.14675)
			(xy 425.098169 -285.147556) (xy 425.120573 -285.139487) (xy 425.129198 -285.131256) (xy 425.193714 -285.063692)
			(xy 425.200826 -285.041086) (xy 425.19981 -285.03499) (xy 425.197216 -285.020075) (xy 425.194419 -284.989929)
			(xy 425.194222 -284.974792) (xy 425.194417 -284.959781) (xy 425.197211 -284.929888) (xy 425.19981 -284.915102)
			(xy 425.19981 -284.914086) (xy 425.200826 -284.908498) (xy 425.193714 -284.885892) (xy 425.129198 -284.818328)
			(xy 425.120558 -284.810116) (xy 425.098166 -284.802039) (xy 425.086272 -284.802834) (xy 425.077228 -284.803884)
			(xy 425.059054 -284.805031) (xy 425.04995 -284.80512) (xy 425.025129 -284.80463) (xy 424.976142 -284.796591)
			(xy 424.929101 -284.780733) (xy 424.885244 -284.757473) (xy 424.845729 -284.727425) (xy 424.811595 -284.69138)
			(xy 424.783742 -284.650288) (xy 424.762904 -284.605231) (xy 424.749629 -284.557396) (xy 424.744268 -284.508044)
			(xy 424.746962 -284.458475) (xy 424.757639 -284.409995) (xy 424.776019 -284.36388) (xy 424.801617 -284.321347)
			(xy 424.833758 -284.283514) (xy 424.871597 -284.25138) (xy 424.914136 -284.225791) (xy 424.960254 -284.207421)
			(xy 425.008737 -284.196753) (xy 425.058307 -284.19407) (xy 425.107657 -284.199441) (xy 425.155489 -284.212725)
			(xy 425.200542 -284.233573) (xy 425.241629 -284.261434) (xy 425.277667 -284.295575) (xy 425.307707 -284.335097)
			(xy 425.330957 -284.378958) (xy 425.346806 -284.426002) (xy 425.354835 -284.474991) (xy 425.355258 -284.499812)
			(xy 425.355161 -284.508916) (xy 425.354019 -284.52709) (xy 425.352972 -284.536134) (xy 425.35218 -284.548025)
			(xy 425.36027 -284.570407) (xy 425.368466 -284.57906) (xy 425.43603 -284.643576) (xy 425.458636 -284.650688)
			(xy 425.464732 -284.649672) (xy 425.479647 -284.647079) (xy 425.509793 -284.644284) (xy 425.52493 -284.644084)
			(xy 425.595288 -284.644084) (xy 425.605983 -284.643527) (xy 425.625546 -284.634875) (xy 425.633134 -284.62732)
			(xy 425.68368 -284.571186) (xy 425.690469 -284.562966) (xy 425.697057 -284.542709) (xy 425.69638 -284.53207)
			(xy 425.69638 -284.531816) (xy 425.694602 -284.499812) (xy 425.695047 -284.475819) (xy 425.702553 -284.428422)
			(xy 425.71738 -284.382784) (xy 425.739165 -284.340026) (xy 425.767371 -284.301204) (xy 425.801302 -284.267272)
			(xy 425.840125 -284.239066) (xy 425.882882 -284.217281) (xy 425.92852 -284.202453) (xy 425.975917 -284.194947)
			(xy 425.99991 -284.194504) (xy 426.009078 -284.194597) (xy 426.027378 -284.195741) (xy 426.036486 -284.19679)
			(xy 426.04817 -284.198314) (xy 426.07103 -284.190186) (xy 426.143674 -284.113732) (xy 426.150786 -284.091126)
			(xy 426.149262 -284.08249) (xy 426.14487 -284.053889) (xy 426.144877 -283.99603) (xy 426.149262 -283.967428)
			(xy 426.149262 -283.96692) (xy 426.150786 -283.958538) (xy 426.143674 -283.935932) (xy 426.07103 -283.859478)
			(xy 426.04817 -283.85135) (xy 426.036486 -283.852874) (xy 426.027378 -283.853928) (xy 426.009078 -283.85507)
			(xy 425.99991 -283.85516) (xy 425.975918 -283.854715) (xy 425.928524 -283.847209) (xy 425.882888 -283.83238)
			(xy 425.840134 -283.810595) (xy 425.801315 -283.782389) (xy 425.767387 -283.748456) (xy 425.739185 -283.709634)
			(xy 425.717405 -283.666877) (xy 425.702582 -283.621239) (xy 425.695083 -283.573844) (xy 425.694602 -283.549852)
			(xy 425.69638 -283.518102) (xy 425.69638 -283.517594) (xy 425.696892 -283.506974) (xy 425.690331 -283.486774)
			(xy 425.68368 -283.478478) (xy 425.633134 -283.422344) (xy 425.625619 -283.414678) (xy 425.606014 -283.40598)
			(xy 425.595288 -283.40558) (xy 425.52493 -283.40558) (xy 425.509919 -283.405382) (xy 425.480027 -283.402582)
			(xy 425.46524 -283.399992) (xy 425.464224 -283.399992) (xy 425.458636 -283.398976) (xy 425.43603 -283.406088)
			(xy 425.368466 -283.470604) (xy 425.36025 -283.479242) (xy 425.352167 -283.501636) (xy 425.352972 -283.51353)
			(xy 425.354022 -283.522574) (xy 425.355168 -283.540748) (xy 425.355258 -283.549852) (xy 425.354776 -283.574669)
			(xy 425.346754 -283.62365) (xy 425.330913 -283.670688) (xy 425.307672 -283.714543) (xy 425.277641 -283.754061)
			(xy 425.241613 -283.788199) (xy 425.200536 -283.81606) (xy 425.155493 -283.836907) (xy 425.107671 -283.850193)
			(xy 425.058329 -283.855568) (xy 425.008768 -283.852888) (xy 424.960293 -283.842226) (xy 424.914182 -283.823862)
			(xy 424.871649 -283.798281) (xy 424.833815 -283.766155) (xy 424.801677 -283.728331) (xy 424.776081 -283.685806)
			(xy 424.757702 -283.639701) (xy 424.747025 -283.591229) (xy 424.74433 -283.541669) (xy 424.749688 -283.492326)
			(xy 424.762959 -283.444499) (xy 424.783792 -283.39945) (xy 424.811639 -283.358364) (xy 424.845766 -283.322325)
			(xy 424.885274 -283.292281) (xy 424.929122 -283.269025) (xy 424.976155 -283.25317) (xy 425.025133 -283.245132)
			(xy 425.04995 -283.244544) (xy 425.059054 -283.244642) (xy 425.077227 -283.245786) (xy 425.086272 -283.24683)
			(xy 425.098168 -283.247636) (xy 425.120571 -283.239564) (xy 425.129198 -283.231336) (xy 425.193714 -283.163772)
			(xy 425.200826 -283.141166) (xy 425.19981 -283.13507) (xy 425.197217 -283.120155) (xy 425.194421 -283.090009)
			(xy 425.194222 -283.074872) (xy 425.194418 -283.059861) (xy 425.197214 -283.029968) (xy 425.19981 -283.015182)
			(xy 425.19981 -283.014166) (xy 425.200826 -283.008578) (xy 425.193714 -282.985972) (xy 425.129198 -282.918408)
			(xy 425.120557 -282.910199) (xy 425.098165 -282.902125) (xy 425.086272 -282.902914) (xy 425.077228 -282.903964)
			(xy 425.059054 -282.905111) (xy 425.04995 -282.9052) (xy 425.025131 -282.90471) (xy 424.976148 -282.896672)
			(xy 424.92911 -282.880815) (xy 424.885257 -282.857558) (xy 424.845745 -282.827512) (xy 424.811613 -282.791471)
			(xy 424.783762 -282.750382) (xy 424.762924 -282.705329) (xy 424.74965 -282.657498) (xy 424.744288 -282.60815)
			(xy 424.746981 -282.558585) (xy 424.757656 -282.510108) (xy 424.776033 -282.463997) (xy 424.801627 -282.421466)
			(xy 424.833765 -282.383636) (xy 424.8716 -282.351503) (xy 424.914135 -282.325914) (xy 424.960248 -282.307543)
			(xy 425.008727 -282.296875) (xy 425.058293 -282.294189) (xy 425.10764 -282.299558) (xy 425.155469 -282.312839)
			(xy 425.200519 -282.333682) (xy 425.241604 -282.361539) (xy 425.277641 -282.395676) (xy 425.30768 -282.435193)
			(xy 425.330932 -282.479049) (xy 425.346782 -282.526088) (xy 425.354814 -282.575073) (xy 425.355258 -282.599892)
			(xy 425.355159 -282.608996) (xy 425.354012 -282.627169) (xy 425.352972 -282.636214) (xy 425.352176 -282.648106)
			(xy 425.36026 -282.670495) (xy 425.368466 -282.67914) (xy 425.43603 -282.743656) (xy 425.458636 -282.750768)
			(xy 425.464732 -282.749752) (xy 425.479647 -282.747159) (xy 425.509793 -282.744365) (xy 425.52493 -282.744164)
			(xy 425.595288 -282.744164) (xy 425.605982 -282.743607) (xy 425.625544 -282.734952) (xy 425.633134 -282.7274)
			(xy 425.68368 -282.671266) (xy 425.690465 -282.663044) (xy 425.697045 -282.642789) (xy 425.69638 -282.63215)
			(xy 425.69638 -282.631896) (xy 425.694602 -282.599892) (xy 425.695049 -282.5759) (xy 425.702557 -282.528506)
			(xy 425.717386 -282.48287) (xy 425.739172 -282.440115) (xy 425.767378 -282.401296) (xy 425.801309 -282.367366)
			(xy 425.840131 -282.339162) (xy 425.882886 -282.317379) (xy 425.928523 -282.302552) (xy 425.975918 -282.295047)
			(xy 425.99991 -282.294584) (xy 426.009078 -282.294677) (xy 426.027378 -282.295821) (xy 426.036486 -282.29687)
			(xy 426.04817 -282.298394) (xy 426.07103 -282.290266) (xy 426.143674 -282.213812) (xy 426.150786 -282.191206)
			(xy 426.149262 -282.18257) (xy 426.146059 -282.162802) (xy 426.143897 -282.122813) (xy 426.144944 -282.102814)
			(xy 426.148754 -282.070302) (xy 426.150786 -282.058618) (xy 426.143674 -282.035758) (xy 426.079158 -281.96794)
			(xy 426.070516 -281.95988) (xy 426.048281 -281.951954) (xy 426.036486 -281.9527) (xy 426.036232 -281.9527)
			(xy 426.027125 -281.953755) (xy 426.008824 -281.954901) (xy 425.999656 -281.954986) (xy 425.975668 -281.954512)
			(xy 425.928283 -281.947) (xy 425.882656 -281.932169) (xy 425.839911 -281.910383) (xy 425.8011 -281.882178)
			(xy 425.767179 -281.84825) (xy 425.738983 -281.809433) (xy 425.717206 -281.766683) (xy 425.702384 -281.721053)
			(xy 425.694883 -281.673666) (xy 425.694348 -281.649678) (xy 425.694393 -281.640641) (xy 425.695407 -281.622595)
			(xy 425.69638 -281.61361) (xy 425.697904 -281.601672) (xy 425.689776 -281.57932) (xy 425.613576 -281.506422)
			(xy 425.59097 -281.49931) (xy 425.584874 -281.500326) (xy 425.569959 -281.502919) (xy 425.539813 -281.505714)
			(xy 425.524676 -281.505914) (xy 425.50941 -281.505758) (xy 425.479007 -281.502963) (xy 425.46397 -281.500326)
			(xy 425.462446 -281.500072) (xy 425.458382 -281.49931) (xy 425.435776 -281.506422) (xy 425.35983 -281.57932)
			(xy 425.351702 -281.601672) (xy 425.353226 -281.61361) (xy 425.354216 -281.622657) (xy 425.355235 -281.640831)
			(xy 425.355258 -281.649932) (xy 425.354736 -281.675187) (xy 425.346423 -281.725009) (xy 425.330022 -281.772783)
			(xy 425.305981 -281.817206) (xy 425.274957 -281.857066) (xy 425.237795 -281.891276) (xy 425.195509 -281.918902)
			(xy 425.149253 -281.939192) (xy 425.100288 -281.951592) (xy 425.04995 -281.955763) (xy 424.999612 -281.951592)
			(xy 424.950647 -281.939192) (xy 424.904391 -281.918902) (xy 424.862105 -281.891276) (xy 424.824943 -281.857066)
			(xy 424.793919 -281.817206) (xy 424.769878 -281.772783) (xy 424.753477 -281.725009) (xy 424.745164 -281.675187)
			(xy 424.744642 -281.649932) (xy 424.744741 -281.640828) (xy 424.745886 -281.622655) (xy 424.746928 -281.61361)
			(xy 424.74773 -281.601716) (xy 424.739653 -281.579319) (xy 424.731434 -281.570684) (xy 424.66387 -281.506168)
			(xy 424.641264 -281.499056) (xy 424.635168 -281.500072) (xy 424.620253 -281.502665) (xy 424.590107 -281.505461)
			(xy 424.57497 -281.50566) (xy 424.559959 -281.505464) (xy 424.530066 -281.502668) (xy 424.51528 -281.500072)
			(xy 424.514264 -281.500072) (xy 424.508676 -281.499056) (xy 424.48607 -281.506168) (xy 424.418506 -281.570684)
			(xy 424.410294 -281.579324) (xy 424.402212 -281.601717) (xy 424.403012 -281.61361) (xy 424.404059 -281.622654)
			(xy 424.405201 -281.640828) (xy 424.405298 -281.649932) (xy 424.404776 -281.675187) (xy 424.396463 -281.725009)
			(xy 424.380062 -281.772783) (xy 424.356021 -281.817206) (xy 424.324997 -281.857066) (xy 424.287835 -281.891276)
			(xy 424.245549 -281.918902) (xy 424.199293 -281.939192) (xy 424.150328 -281.951592) (xy 424.09999 -281.955763)
			(xy 424.049652 -281.951592) (xy 424.000687 -281.939192) (xy 423.954431 -281.918902) (xy 423.912145 -281.891276)
			(xy 423.874983 -281.857066) (xy 423.843959 -281.817206) (xy 423.819918 -281.772783) (xy 423.803517 -281.725009)
			(xy 423.795204 -281.675187) (xy 423.794682 -281.649932) (xy 423.794786 -281.640891) (xy 423.795929 -281.622845)
			(xy 423.796968 -281.613864) (xy 423.796968 -281.613356) (xy 423.798238 -281.601672) (xy 423.79011 -281.57932)
			(xy 423.71391 -281.506422) (xy 423.691304 -281.499564) (xy 423.684446 -281.50058) (xy 423.669653 -281.503101)
			(xy 423.639762 -281.505775) (xy 423.624756 -281.505914) (xy 423.60949 -281.505757) (xy 423.579088 -281.50296)
			(xy 423.56405 -281.500326) (xy 423.562526 -281.500072) (xy 423.558462 -281.49931) (xy 423.535856 -281.506422)
			(xy 423.45991 -281.57932) (xy 423.451782 -281.601672) (xy 423.453306 -281.61361) (xy 423.454296 -281.622657)
			(xy 423.455315 -281.640831) (xy 423.455338 -281.649932) (xy 423.454816 -281.675187) (xy 423.446503 -281.725009)
			(xy 423.430102 -281.772783) (xy 423.406061 -281.817206) (xy 423.375037 -281.857066) (xy 423.337875 -281.891276)
			(xy 423.295589 -281.918902) (xy 423.249333 -281.939192) (xy 423.200368 -281.951592) (xy 423.15003 -281.955763)
			(xy 423.099692 -281.951592) (xy 423.050727 -281.939192) (xy 423.004471 -281.918902) (xy 422.962185 -281.891276)
			(xy 422.925023 -281.857066) (xy 422.893999 -281.817206) (xy 422.869958 -281.772783) (xy 422.853557 -281.725009)
			(xy 422.845244 -281.675187) (xy 422.844722 -281.649932) (xy 422.844814 -281.640764) (xy 422.845955 -281.622464)
			(xy 422.847008 -281.613356) (xy 422.848532 -281.601672) (xy 422.840404 -281.578812) (xy 422.76395 -281.506168)
			(xy 422.741344 -281.499056) (xy 422.732708 -281.50058) (xy 422.718411 -281.502949) (xy 422.689541 -281.505494)
			(xy 422.67505 -281.50566) (xy 422.674796 -281.50566) (xy 422.659785 -281.505461) (xy 422.629894 -281.502658)
			(xy 422.615106 -281.500072) (xy 422.61409 -281.500072) (xy 422.608502 -281.499056) (xy 422.585896 -281.506168)
			(xy 422.518332 -281.570684) (xy 422.510117 -281.579323) (xy 422.502031 -281.601716) (xy 422.502838 -281.61361)
			(xy 422.503885 -281.622654) (xy 422.505027 -281.640828) (xy 422.505124 -281.649932) (xy 422.504602 -281.675187)
			(xy 422.496289 -281.725009) (xy 422.479888 -281.772783) (xy 422.455847 -281.817206) (xy 422.424823 -281.857066)
			(xy 422.387661 -281.891276) (xy 422.345375 -281.918902) (xy 422.299119 -281.939192) (xy 422.250154 -281.951592)
			(xy 422.199816 -281.955763) (xy 422.149478 -281.951592) (xy 422.100513 -281.939192) (xy 422.054257 -281.918902)
			(xy 422.011971 -281.891276) (xy 421.974809 -281.857066) (xy 421.943785 -281.817206) (xy 421.919744 -281.772783)
			(xy 421.903343 -281.725009) (xy 421.89503 -281.675187) (xy 421.894508 -281.649932) (xy 421.894546 -281.640831)
			(xy 421.895561 -281.622658) (xy 421.89654 -281.61361) (xy 421.898064 -281.601672) (xy 421.889936 -281.57932)
			(xy 421.813736 -281.506422) (xy 421.79113 -281.49931) (xy 421.785034 -281.500326) (xy 421.770119 -281.502922)
			(xy 421.739974 -281.505723) (xy 421.724836 -281.505914) (xy 421.709825 -281.505716) (xy 421.679933 -281.502917)
			(xy 421.665146 -281.500326) (xy 421.66413 -281.500326) (xy 421.658542 -281.49931) (xy 421.635936 -281.506422)
			(xy 421.559736 -281.57932) (xy 421.551608 -281.601672) (xy 421.553132 -281.61361) (xy 421.554122 -281.622657)
			(xy 421.555141 -281.640831) (xy 421.555164 -281.649932) (xy 421.554642 -281.675187) (xy 421.546329 -281.725009)
			(xy 421.529928 -281.772783) (xy 421.505887 -281.817206) (xy 421.474863 -281.857066) (xy 421.437701 -281.891276)
			(xy 421.395415 -281.918902) (xy 421.349159 -281.939192) (xy 421.300194 -281.951592) (xy 421.249856 -281.955763)
			(xy 421.199518 -281.951592) (xy 421.150553 -281.939192) (xy 421.104297 -281.918902) (xy 421.062011 -281.891276)
			(xy 421.024849 -281.857066) (xy 420.993825 -281.817206) (xy 420.969784 -281.772783) (xy 420.953383 -281.725009)
			(xy 420.94507 -281.675187) (xy 420.944548 -281.649932) (xy 420.944647 -281.640828) (xy 420.945792 -281.622655)
			(xy 420.946834 -281.61361) (xy 420.947636 -281.601715) (xy 420.939559 -281.579318) (xy 420.93134 -281.570684)
			(xy 420.863776 -281.506168) (xy 420.84117 -281.499056) (xy 420.835074 -281.500072) (xy 420.820159 -281.502665)
			(xy 420.790013 -281.505461) (xy 420.774876 -281.50566) (xy 420.759865 -281.505464) (xy 420.729972 -281.502669)
			(xy 420.715186 -281.500072) (xy 420.71417 -281.500072) (xy 420.708582 -281.499056) (xy 420.685976 -281.506168)
			(xy 420.618412 -281.570684) (xy 420.610199 -281.579324) (xy 420.602116 -281.601716) (xy 420.602918 -281.61361)
			(xy 420.603965 -281.622654) (xy 420.605107 -281.640828) (xy 420.605204 -281.649932) (xy 420.604682 -281.675187)
			(xy 420.596369 -281.725009) (xy 420.579968 -281.772783) (xy 420.555927 -281.817206) (xy 420.524903 -281.857066)
			(xy 420.487741 -281.891276) (xy 420.445455 -281.918902) (xy 420.399199 -281.939192) (xy 420.350234 -281.951592)
			(xy 420.299896 -281.955763) (xy 420.249558 -281.951592) (xy 420.200593 -281.939192) (xy 420.154337 -281.918902)
			(xy 420.112051 -281.891276) (xy 420.074889 -281.857066) (xy 420.043865 -281.817206) (xy 420.019824 -281.772783)
			(xy 420.003423 -281.725009) (xy 419.99511 -281.675187) (xy 419.994588 -281.649932) (xy 419.994634 -281.640895)
			(xy 419.995651 -281.622849) (xy 419.99662 -281.613864) (xy 419.998144 -281.601926) (xy 419.990016 -281.579574)
			(xy 419.913816 -281.506676) (xy 419.89121 -281.499564) (xy 419.884606 -281.50058) (xy 419.869754 -281.503165)
			(xy 419.839736 -281.505964) (xy 419.824662 -281.506168) (xy 419.824408 -281.506168) (xy 419.80901 -281.505958)
			(xy 419.778353 -281.503035) (xy 419.763194 -281.500326) (xy 419.762178 -281.500326) (xy 419.758622 -281.499564)
			(xy 419.736016 -281.506676) (xy 419.659816 -281.579574) (xy 419.651688 -281.601926) (xy 419.653212 -281.613864)
			(xy 419.654195 -281.622848) (xy 419.655213 -281.640894) (xy 419.655244 -281.649932) (xy 419.654722 -281.675187)
			(xy 419.646409 -281.725009) (xy 419.630008 -281.772783) (xy 419.605967 -281.817206) (xy 419.574943 -281.857066)
			(xy 419.537781 -281.891276) (xy 419.495495 -281.918902) (xy 419.449239 -281.939192) (xy 419.400274 -281.951592)
			(xy 419.349936 -281.955763) (xy 419.299598 -281.951592) (xy 419.250633 -281.939192) (xy 419.204377 -281.918902)
			(xy 419.162091 -281.891276) (xy 419.124929 -281.857066) (xy 419.093905 -281.817206) (xy 419.069864 -281.772783)
			(xy 419.053463 -281.725009) (xy 419.04515 -281.675187) (xy 419.044628 -281.649932) (xy 419.04472 -281.640764)
			(xy 419.045861 -281.622464) (xy 419.046914 -281.613356) (xy 419.046914 -281.613102) (xy 419.047723 -281.601301)
			(xy 419.039769 -281.579056) (xy 419.031674 -281.57043) (xy 418.96411 -281.505914) (xy 418.941504 -281.499056)
			(xy 418.934646 -281.500072) (xy 418.919853 -281.502593) (xy 418.889962 -281.505267) (xy 418.874956 -281.505406)
			(xy 418.860014 -281.505253) (xy 418.83025 -281.502584) (xy 418.81552 -281.500072) (xy 418.815012 -281.500072)
			(xy 418.808408 -281.499056) (xy 418.785802 -281.505914) (xy 418.718238 -281.57043) (xy 418.710177 -281.579072)
			(xy 418.702245 -281.601307) (xy 418.702998 -281.613102) (xy 418.702998 -281.613356) (xy 418.704054 -281.622463)
			(xy 418.7052 -281.640764) (xy 418.705284 -281.649932) (xy 418.704811 -281.673921) (xy 418.697301 -281.721307)
			(xy 418.68247 -281.766936) (xy 418.660685 -281.809682) (xy 418.63248 -281.848494) (xy 418.598552 -281.882417)
			(xy 418.559734 -281.910614) (xy 418.516984 -281.932392) (xy 418.471353 -281.947214) (xy 418.423965 -281.954715)
			(xy 418.399976 -281.95524) (xy 418.390808 -281.955147) (xy 418.372508 -281.954002) (xy 418.3634 -281.952954)
			(xy 418.351462 -281.95143) (xy 418.32911 -281.959558) (xy 418.255958 -282.035758) (xy 418.248846 -282.058364)
			(xy 418.249608 -282.063444) (xy 418.254157 -282.090561) (xy 418.255248 -282.145531) (xy 418.247233 -282.199925)
			(xy 418.230334 -282.252244) (xy 418.205014 -282.301048) (xy 418.171973 -282.344993) (xy 418.132118 -282.382868)
			(xy 418.109654 -282.398724) (xy 418.102875 -282.403744) (xy 418.09275 -282.417222) (xy 418.089842 -282.42514)
			(xy 418.088692 -282.428912) (xy 418.08741 -282.436692) (xy 418.087302 -282.440634) (xy 418.087302 -282.599892)
			(xy 422.843972 -282.599892) (xy 422.847932 -282.550838) (xy 422.859709 -282.503054) (xy 422.879 -282.457778)
			(xy 422.905303 -282.416182) (xy 422.937938 -282.379345) (xy 422.976059 -282.34822) (xy 423.01868 -282.323613)
			(xy 423.064696 -282.306161) (xy 423.112915 -282.296317) (xy 423.16209 -282.294336) (xy 423.210945 -282.300268)
			(xy 423.258216 -282.31396) (xy 423.302678 -282.335058) (xy 423.343181 -282.363014) (xy 423.378674 -282.397106)
			(xy 423.408239 -282.43645) (xy 423.43111 -282.480027) (xy 423.446694 -282.526708) (xy 423.454589 -282.575285)
			(xy 423.455084 -282.599892) (xy 423.794186 -282.599892) (xy 423.798146 -282.550838) (xy 423.809923 -282.503054)
			(xy 423.829214 -282.457778) (xy 423.855517 -282.416182) (xy 423.888152 -282.379345) (xy 423.926273 -282.34822)
			(xy 423.968894 -282.323613) (xy 424.01491 -282.306161) (xy 424.063129 -282.296317) (xy 424.112304 -282.294336)
			(xy 424.161159 -282.300268) (xy 424.20843 -282.31396) (xy 424.252892 -282.335058) (xy 424.293395 -282.363014)
			(xy 424.328888 -282.397106) (xy 424.358453 -282.43645) (xy 424.381324 -282.480027) (xy 424.396908 -282.526708)
			(xy 424.404803 -282.575285) (xy 424.405298 -282.599892) (xy 424.404803 -282.624499) (xy 424.396908 -282.673076)
			(xy 424.381324 -282.719757) (xy 424.358453 -282.763334) (xy 424.328888 -282.802678) (xy 424.293395 -282.83677)
			(xy 424.252892 -282.864726) (xy 424.20843 -282.885824) (xy 424.161159 -282.899516) (xy 424.112304 -282.905448)
			(xy 424.063129 -282.903467) (xy 424.01491 -282.893623) (xy 423.968894 -282.876171) (xy 423.926273 -282.851564)
			(xy 423.888152 -282.820439) (xy 423.855517 -282.783602) (xy 423.829214 -282.742006) (xy 423.809923 -282.69673)
			(xy 423.798146 -282.648946) (xy 423.794186 -282.599892) (xy 423.455084 -282.599892) (xy 423.454589 -282.624499)
			(xy 423.446694 -282.673076) (xy 423.43111 -282.719757) (xy 423.408239 -282.763334) (xy 423.378674 -282.802678)
			(xy 423.343181 -282.83677) (xy 423.302678 -282.864726) (xy 423.258216 -282.885824) (xy 423.210945 -282.899516)
			(xy 423.16209 -282.905448) (xy 423.112915 -282.903467) (xy 423.064696 -282.893623) (xy 423.01868 -282.876171)
			(xy 422.976059 -282.851564) (xy 422.937938 -282.820439) (xy 422.905303 -282.783602) (xy 422.879 -282.742006)
			(xy 422.859709 -282.69673) (xy 422.847932 -282.648946) (xy 422.843972 -282.599892) (xy 418.087302 -282.599892)
			(xy 418.087302 -282.758642) (xy 418.087995 -282.771083) (xy 418.09971 -282.793044) (xy 418.109654 -282.800552)
			(xy 418.130059 -282.81483) (xy 418.166737 -282.848518) (xy 418.197949 -282.887324) (xy 418.222989 -282.930372)
			(xy 418.241292 -282.976688) (xy 418.252442 -283.025225) (xy 418.256188 -283.074872) (xy 418.569152 -283.074872)
			(xy 418.573112 -283.025818) (xy 418.584889 -282.978034) (xy 418.60418 -282.932758) (xy 418.630483 -282.891162)
			(xy 418.663118 -282.854325) (xy 418.701239 -282.8232) (xy 418.74386 -282.798593) (xy 418.789876 -282.781141)
			(xy 418.838095 -282.771297) (xy 418.88727 -282.769316) (xy 418.936125 -282.775248) (xy 418.983396 -282.78894)
			(xy 419.027858 -282.810038) (xy 419.068361 -282.837994) (xy 419.103854 -282.872086) (xy 419.133419 -282.91143)
			(xy 419.15629 -282.955007) (xy 419.171874 -283.001688) (xy 419.179769 -283.050265) (xy 419.180264 -283.074872)
			(xy 419.519112 -283.074872) (xy 419.523072 -283.025818) (xy 419.534849 -282.978034) (xy 419.55414 -282.932758)
			(xy 419.580443 -282.891162) (xy 419.613078 -282.854325) (xy 419.651199 -282.8232) (xy 419.69382 -282.798593)
			(xy 419.739836 -282.781141) (xy 419.788055 -282.771297) (xy 419.83723 -282.769316) (xy 419.886085 -282.775248)
			(xy 419.933356 -282.78894) (xy 419.977818 -282.810038) (xy 420.018321 -282.837994) (xy 420.053814 -282.872086)
			(xy 420.083379 -282.91143) (xy 420.10625 -282.955007) (xy 420.121834 -283.001688) (xy 420.129729 -283.050265)
			(xy 420.130224 -283.074872) (xy 420.469072 -283.074872) (xy 420.473032 -283.025818) (xy 420.484809 -282.978034)
			(xy 420.5041 -282.932758) (xy 420.530403 -282.891162) (xy 420.563038 -282.854325) (xy 420.601159 -282.8232)
			(xy 420.64378 -282.798593) (xy 420.689796 -282.781141) (xy 420.738015 -282.771297) (xy 420.78719 -282.769316)
			(xy 420.836045 -282.775248) (xy 420.883316 -282.78894) (xy 420.927778 -282.810038) (xy 420.968281 -282.837994)
			(xy 421.003774 -282.872086) (xy 421.033339 -282.91143) (xy 421.05621 -282.955007) (xy 421.071794 -283.001688)
			(xy 421.079689 -283.050265) (xy 421.080184 -283.074872) (xy 421.079689 -283.099479) (xy 421.071794 -283.148056)
			(xy 421.05621 -283.194737) (xy 421.033339 -283.238314) (xy 421.003774 -283.277658) (xy 420.968281 -283.31175)
			(xy 420.927778 -283.339706) (xy 420.883316 -283.360804) (xy 420.836045 -283.374496) (xy 420.78719 -283.380428)
			(xy 420.738015 -283.378447) (xy 420.689796 -283.368603) (xy 420.64378 -283.351151) (xy 420.601159 -283.326544)
			(xy 420.563038 -283.295419) (xy 420.530403 -283.258582) (xy 420.5041 -283.216986) (xy 420.484809 -283.17171)
			(xy 420.473032 -283.123926) (xy 420.469072 -283.074872) (xy 420.130224 -283.074872) (xy 420.129729 -283.099479)
			(xy 420.121834 -283.148056) (xy 420.10625 -283.194737) (xy 420.083379 -283.238314) (xy 420.053814 -283.277658)
			(xy 420.018321 -283.31175) (xy 419.977818 -283.339706) (xy 419.933356 -283.360804) (xy 419.886085 -283.374496)
			(xy 419.83723 -283.380428) (xy 419.788055 -283.378447) (xy 419.739836 -283.368603) (xy 419.69382 -283.351151)
			(xy 419.651199 -283.326544) (xy 419.613078 -283.295419) (xy 419.580443 -283.258582) (xy 419.55414 -283.216986)
			(xy 419.534849 -283.17171) (xy 419.523072 -283.123926) (xy 419.519112 -283.074872) (xy 419.180264 -283.074872)
			(xy 419.179769 -283.099479) (xy 419.171874 -283.148056) (xy 419.15629 -283.194737) (xy 419.133419 -283.238314)
			(xy 419.103854 -283.277658) (xy 419.068361 -283.31175) (xy 419.027858 -283.339706) (xy 418.983396 -283.360804)
			(xy 418.936125 -283.374496) (xy 418.88727 -283.380428) (xy 418.838095 -283.378447) (xy 418.789876 -283.368603)
			(xy 418.74386 -283.351151) (xy 418.701239 -283.326544) (xy 418.663118 -283.295419) (xy 418.630483 -283.258582)
			(xy 418.60418 -283.216986) (xy 418.584889 -283.17171) (xy 418.573112 -283.123926) (xy 418.569152 -283.074872)
			(xy 418.256188 -283.074872) (xy 418.256189 -283.074884) (xy 418.252447 -283.124544) (xy 418.241301 -283.173082)
			(xy 418.223003 -283.2194) (xy 418.197967 -283.26245) (xy 418.166759 -283.30126) (xy 418.130084 -283.334951)
			(xy 418.109654 -283.349192) (xy 418.099672 -283.35667) (xy 418.087939 -283.378647) (xy 418.087302 -283.391102)
			(xy 418.087302 -283.549852) (xy 421.894012 -283.549852) (xy 421.897972 -283.500798) (xy 421.909749 -283.453014)
			(xy 421.92904 -283.407738) (xy 421.955343 -283.366142) (xy 421.987978 -283.329305) (xy 422.026099 -283.29818)
			(xy 422.06872 -283.273573) (xy 422.114736 -283.256121) (xy 422.162955 -283.246277) (xy 422.21213 -283.244296)
			(xy 422.260985 -283.250228) (xy 422.308256 -283.26392) (xy 422.352718 -283.285018) (xy 422.393221 -283.312974)
			(xy 422.428714 -283.347066) (xy 422.458279 -283.38641) (xy 422.48115 -283.429987) (xy 422.496734 -283.476668)
			(xy 422.504629 -283.525245) (xy 422.505124 -283.549852) (xy 422.843972 -283.549852) (xy 422.847932 -283.500798)
			(xy 422.859709 -283.453014) (xy 422.879 -283.407738) (xy 422.905303 -283.366142) (xy 422.937938 -283.329305)
			(xy 422.976059 -283.29818) (xy 423.01868 -283.273573) (xy 423.064696 -283.256121) (xy 423.112915 -283.246277)
			(xy 423.16209 -283.244296) (xy 423.210945 -283.250228) (xy 423.258216 -283.26392) (xy 423.302678 -283.285018)
			(xy 423.343181 -283.312974) (xy 423.378674 -283.347066) (xy 423.408239 -283.38641) (xy 423.43111 -283.429987)
			(xy 423.446694 -283.476668) (xy 423.454589 -283.525245) (xy 423.455084 -283.549852) (xy 423.794186 -283.549852)
			(xy 423.798146 -283.500798) (xy 423.809923 -283.453014) (xy 423.829214 -283.407738) (xy 423.855517 -283.366142)
			(xy 423.888152 -283.329305) (xy 423.926273 -283.29818) (xy 423.968894 -283.273573) (xy 424.01491 -283.256121)
			(xy 424.063129 -283.246277) (xy 424.112304 -283.244296) (xy 424.161159 -283.250228) (xy 424.20843 -283.26392)
			(xy 424.252892 -283.285018) (xy 424.293395 -283.312974) (xy 424.328888 -283.347066) (xy 424.358453 -283.38641)
			(xy 424.381324 -283.429987) (xy 424.396908 -283.476668) (xy 424.404803 -283.525245) (xy 424.405298 -283.549852)
			(xy 424.404803 -283.574459) (xy 424.396908 -283.623036) (xy 424.381324 -283.669717) (xy 424.358453 -283.713294)
			(xy 424.328888 -283.752638) (xy 424.293395 -283.78673) (xy 424.252892 -283.814686) (xy 424.20843 -283.835784)
			(xy 424.161159 -283.849476) (xy 424.112304 -283.855408) (xy 424.063129 -283.853427) (xy 424.01491 -283.843583)
			(xy 423.968894 -283.826131) (xy 423.926273 -283.801524) (xy 423.888152 -283.770399) (xy 423.855517 -283.733562)
			(xy 423.829214 -283.691966) (xy 423.809923 -283.64669) (xy 423.798146 -283.598906) (xy 423.794186 -283.549852)
			(xy 423.455084 -283.549852) (xy 423.454589 -283.574459) (xy 423.446694 -283.623036) (xy 423.43111 -283.669717)
			(xy 423.408239 -283.713294) (xy 423.378674 -283.752638) (xy 423.343181 -283.78673) (xy 423.302678 -283.814686)
			(xy 423.258216 -283.835784) (xy 423.210945 -283.849476) (xy 423.16209 -283.855408) (xy 423.112915 -283.853427)
			(xy 423.064696 -283.843583) (xy 423.01868 -283.826131) (xy 422.976059 -283.801524) (xy 422.937938 -283.770399)
			(xy 422.905303 -283.733562) (xy 422.879 -283.691966) (xy 422.859709 -283.64669) (xy 422.847932 -283.598906)
			(xy 422.843972 -283.549852) (xy 422.505124 -283.549852) (xy 422.504629 -283.574459) (xy 422.496734 -283.623036)
			(xy 422.48115 -283.669717) (xy 422.458279 -283.713294) (xy 422.428714 -283.752638) (xy 422.393221 -283.78673)
			(xy 422.352718 -283.814686) (xy 422.308256 -283.835784) (xy 422.260985 -283.849476) (xy 422.21213 -283.855408)
			(xy 422.162955 -283.853427) (xy 422.114736 -283.843583) (xy 422.06872 -283.826131) (xy 422.026099 -283.801524)
			(xy 421.987978 -283.770399) (xy 421.955343 -283.733562) (xy 421.92904 -283.691966) (xy 421.909749 -283.64669)
			(xy 421.897972 -283.598906) (xy 421.894012 -283.549852) (xy 418.087302 -283.549852) (xy 418.087302 -283.708602)
			(xy 418.087986 -283.721048) (xy 418.099692 -283.743023) (xy 418.109654 -283.750512) (xy 418.130055 -283.76479)
			(xy 418.166724 -283.798476) (xy 418.197927 -283.83728) (xy 418.222959 -283.880324) (xy 418.241254 -283.926635)
			(xy 418.252398 -283.975165) (xy 418.256139 -284.024818) (xy 418.256138 -284.024832) (xy 418.569152 -284.024832)
			(xy 418.573112 -283.975778) (xy 418.584889 -283.927994) (xy 418.60418 -283.882718) (xy 418.630483 -283.841122)
			(xy 418.663118 -283.804285) (xy 418.701239 -283.77316) (xy 418.74386 -283.748553) (xy 418.789876 -283.731101)
			(xy 418.838095 -283.721257) (xy 418.88727 -283.719276) (xy 418.936125 -283.725208) (xy 418.983396 -283.7389)
			(xy 419.027858 -283.759998) (xy 419.068361 -283.787954) (xy 419.103854 -283.822046) (xy 419.133419 -283.86139)
			(xy 419.15629 -283.904967) (xy 419.171874 -283.951648) (xy 419.179769 -284.000225) (xy 419.180264 -284.024832)
			(xy 419.179769 -284.049439) (xy 419.171874 -284.098016) (xy 419.15629 -284.144697) (xy 419.133419 -284.188274)
			(xy 419.103854 -284.227618) (xy 419.068361 -284.26171) (xy 419.027858 -284.289666) (xy 418.983396 -284.310764)
			(xy 418.936125 -284.324456) (xy 418.88727 -284.330388) (xy 418.838095 -284.328407) (xy 418.789876 -284.318563)
			(xy 418.74386 -284.301111) (xy 418.701239 -284.276504) (xy 418.663118 -284.245379) (xy 418.630483 -284.208542)
			(xy 418.60418 -284.166946) (xy 418.584889 -284.12167) (xy 418.573112 -284.073886) (xy 418.569152 -284.024832)
			(xy 418.256138 -284.024832) (xy 418.252392 -284.07447) (xy 418.241243 -284.122999) (xy 418.222944 -284.169308)
			(xy 418.197907 -284.212349) (xy 418.166699 -284.25115) (xy 418.130027 -284.284833) (xy 418.109654 -284.299152)
			(xy 418.099682 -284.306634) (xy 418.087975 -284.328612) (xy 418.087302 -284.341062) (xy 418.087302 -284.499812)
			(xy 421.894012 -284.499812) (xy 421.897972 -284.450758) (xy 421.909749 -284.402974) (xy 421.92904 -284.357698)
			(xy 421.955343 -284.316102) (xy 421.987978 -284.279265) (xy 422.026099 -284.24814) (xy 422.06872 -284.223533)
			(xy 422.114736 -284.206081) (xy 422.162955 -284.196237) (xy 422.21213 -284.194256) (xy 422.260985 -284.200188)
			(xy 422.308256 -284.21388) (xy 422.352718 -284.234978) (xy 422.393221 -284.262934) (xy 422.428714 -284.297026)
			(xy 422.458279 -284.33637) (xy 422.48115 -284.379947) (xy 422.496734 -284.426628) (xy 422.504629 -284.475205)
			(xy 422.505124 -284.499812) (xy 422.843972 -284.499812) (xy 422.847932 -284.450758) (xy 422.859709 -284.402974)
			(xy 422.879 -284.357698) (xy 422.905303 -284.316102) (xy 422.937938 -284.279265) (xy 422.976059 -284.24814)
			(xy 423.01868 -284.223533) (xy 423.064696 -284.206081) (xy 423.112915 -284.196237) (xy 423.16209 -284.194256)
			(xy 423.210945 -284.200188) (xy 423.258216 -284.21388) (xy 423.302678 -284.234978) (xy 423.343181 -284.262934)
			(xy 423.378674 -284.297026) (xy 423.408239 -284.33637) (xy 423.43111 -284.379947) (xy 423.446694 -284.426628)
			(xy 423.454589 -284.475205) (xy 423.455084 -284.499812) (xy 423.794186 -284.499812) (xy 423.798146 -284.450758)
			(xy 423.809923 -284.402974) (xy 423.829214 -284.357698) (xy 423.855517 -284.316102) (xy 423.888152 -284.279265)
			(xy 423.926273 -284.24814) (xy 423.968894 -284.223533) (xy 424.01491 -284.206081) (xy 424.063129 -284.196237)
			(xy 424.112304 -284.194256) (xy 424.161159 -284.200188) (xy 424.20843 -284.21388) (xy 424.252892 -284.234978)
			(xy 424.293395 -284.262934) (xy 424.328888 -284.297026) (xy 424.358453 -284.33637) (xy 424.381324 -284.379947)
			(xy 424.396908 -284.426628) (xy 424.404803 -284.475205) (xy 424.405298 -284.499812) (xy 424.404803 -284.524419)
			(xy 424.396908 -284.572996) (xy 424.381324 -284.619677) (xy 424.358453 -284.663254) (xy 424.328888 -284.702598)
			(xy 424.293395 -284.73669) (xy 424.252892 -284.764646) (xy 424.20843 -284.785744) (xy 424.161159 -284.799436)
			(xy 424.112304 -284.805368) (xy 424.063129 -284.803387) (xy 424.01491 -284.793543) (xy 423.968894 -284.776091)
			(xy 423.926273 -284.751484) (xy 423.888152 -284.720359) (xy 423.855517 -284.683522) (xy 423.829214 -284.641926)
			(xy 423.809923 -284.59665) (xy 423.798146 -284.548866) (xy 423.794186 -284.499812) (xy 423.455084 -284.499812)
			(xy 423.454589 -284.524419) (xy 423.446694 -284.572996) (xy 423.43111 -284.619677) (xy 423.408239 -284.663254)
			(xy 423.378674 -284.702598) (xy 423.343181 -284.73669) (xy 423.302678 -284.764646) (xy 423.258216 -284.785744)
			(xy 423.210945 -284.799436) (xy 423.16209 -284.805368) (xy 423.112915 -284.803387) (xy 423.064696 -284.793543)
			(xy 423.01868 -284.776091) (xy 422.976059 -284.751484) (xy 422.937938 -284.720359) (xy 422.905303 -284.683522)
			(xy 422.879 -284.641926) (xy 422.859709 -284.59665) (xy 422.847932 -284.548866) (xy 422.843972 -284.499812)
			(xy 422.505124 -284.499812) (xy 422.504629 -284.524419) (xy 422.496734 -284.572996) (xy 422.48115 -284.619677)
			(xy 422.458279 -284.663254) (xy 422.428714 -284.702598) (xy 422.393221 -284.73669) (xy 422.352718 -284.764646)
			(xy 422.308256 -284.785744) (xy 422.260985 -284.799436) (xy 422.21213 -284.805368) (xy 422.162955 -284.803387)
			(xy 422.114736 -284.793543) (xy 422.06872 -284.776091) (xy 422.026099 -284.751484) (xy 421.987978 -284.720359)
			(xy 421.955343 -284.683522) (xy 421.92904 -284.641926) (xy 421.909749 -284.59665) (xy 421.897972 -284.548866)
			(xy 421.894012 -284.499812) (xy 418.087302 -284.499812) (xy 418.087302 -284.658562) (xy 418.088132 -284.670967)
			(xy 418.099821 -284.692863) (xy 418.109654 -284.700472) (xy 418.130058 -284.71475) (xy 418.166733 -284.748437)
			(xy 418.197942 -284.787243) (xy 418.222979 -284.830289) (xy 418.241279 -284.876604) (xy 418.252427 -284.925138)
			(xy 418.256172 -284.974792) (xy 418.569152 -284.974792) (xy 418.573112 -284.925738) (xy 418.584889 -284.877954)
			(xy 418.60418 -284.832678) (xy 418.630483 -284.791082) (xy 418.663118 -284.754245) (xy 418.701239 -284.72312)
			(xy 418.74386 -284.698513) (xy 418.789876 -284.681061) (xy 418.838095 -284.671217) (xy 418.88727 -284.669236)
			(xy 418.936125 -284.675168) (xy 418.983396 -284.68886) (xy 419.027858 -284.709958) (xy 419.068361 -284.737914)
			(xy 419.103854 -284.772006) (xy 419.133419 -284.81135) (xy 419.15629 -284.854927) (xy 419.171874 -284.901608)
			(xy 419.179769 -284.950185) (xy 419.180264 -284.974792) (xy 419.179769 -284.999399) (xy 419.171874 -285.047976)
			(xy 419.15629 -285.094657) (xy 419.133419 -285.138234) (xy 419.103854 -285.177578) (xy 419.068361 -285.21167)
			(xy 419.027858 -285.239626) (xy 418.983396 -285.260724) (xy 418.936125 -285.274416) (xy 418.88727 -285.280348)
			(xy 418.838095 -285.278367) (xy 418.789876 -285.268523) (xy 418.74386 -285.251071) (xy 418.701239 -285.226464)
			(xy 418.663118 -285.195339) (xy 418.630483 -285.158502) (xy 418.60418 -285.116906) (xy 418.584889 -285.07163)
			(xy 418.573112 -285.023846) (xy 418.569152 -284.974792) (xy 418.256172 -284.974792) (xy 418.256172 -284.974796)
			(xy 418.252429 -285.024453) (xy 418.241282 -285.072988) (xy 418.222983 -285.119303) (xy 418.197947 -285.16235)
			(xy 418.166739 -285.201156) (xy 418.130065 -285.234845) (xy 418.109654 -285.249112) (xy 418.099675 -285.256592)
			(xy 418.087951 -285.278569) (xy 418.087302 -285.291022) (xy 418.087302 -285.449772) (xy 421.894012 -285.449772)
			(xy 421.897972 -285.400718) (xy 421.909749 -285.352934) (xy 421.92904 -285.307658) (xy 421.955343 -285.266062)
			(xy 421.987978 -285.229225) (xy 422.026099 -285.1981) (xy 422.06872 -285.173493) (xy 422.114736 -285.156041)
			(xy 422.162955 -285.146197) (xy 422.21213 -285.144216) (xy 422.260985 -285.150148) (xy 422.308256 -285.16384)
			(xy 422.352718 -285.184938) (xy 422.393221 -285.212894) (xy 422.428714 -285.246986) (xy 422.458279 -285.28633)
			(xy 422.48115 -285.329907) (xy 422.496734 -285.376588) (xy 422.504629 -285.425165) (xy 422.505124 -285.449772)
			(xy 422.843972 -285.449772) (xy 422.847932 -285.400718) (xy 422.859709 -285.352934) (xy 422.879 -285.307658)
			(xy 422.905303 -285.266062) (xy 422.937938 -285.229225) (xy 422.976059 -285.1981) (xy 423.01868 -285.173493)
			(xy 423.064696 -285.156041) (xy 423.112915 -285.146197) (xy 423.16209 -285.144216) (xy 423.210945 -285.150148)
			(xy 423.258216 -285.16384) (xy 423.302678 -285.184938) (xy 423.343181 -285.212894) (xy 423.378674 -285.246986)
			(xy 423.408239 -285.28633) (xy 423.43111 -285.329907) (xy 423.446694 -285.376588) (xy 423.454589 -285.425165)
			(xy 423.455084 -285.449772) (xy 423.794186 -285.449772) (xy 423.798146 -285.400718) (xy 423.809923 -285.352934)
			(xy 423.829214 -285.307658) (xy 423.855517 -285.266062) (xy 423.888152 -285.229225) (xy 423.926273 -285.1981)
			(xy 423.968894 -285.173493) (xy 424.01491 -285.156041) (xy 424.063129 -285.146197) (xy 424.112304 -285.144216)
			(xy 424.161159 -285.150148) (xy 424.20843 -285.16384) (xy 424.252892 -285.184938) (xy 424.293395 -285.212894)
			(xy 424.328888 -285.246986) (xy 424.358453 -285.28633) (xy 424.381324 -285.329907) (xy 424.396908 -285.376588)
			(xy 424.404803 -285.425165) (xy 424.405298 -285.449772) (xy 424.404803 -285.474379) (xy 424.396908 -285.522956)
			(xy 424.381324 -285.569637) (xy 424.358453 -285.613214) (xy 424.328888 -285.652558) (xy 424.293395 -285.68665)
			(xy 424.252892 -285.714606) (xy 424.20843 -285.735704) (xy 424.161159 -285.749396) (xy 424.112304 -285.755328)
			(xy 424.063129 -285.753347) (xy 424.01491 -285.743503) (xy 423.968894 -285.726051) (xy 423.926273 -285.701444)
			(xy 423.888152 -285.670319) (xy 423.855517 -285.633482) (xy 423.829214 -285.591886) (xy 423.809923 -285.54661)
			(xy 423.798146 -285.498826) (xy 423.794186 -285.449772) (xy 423.455084 -285.449772) (xy 423.454589 -285.474379)
			(xy 423.446694 -285.522956) (xy 423.43111 -285.569637) (xy 423.408239 -285.613214) (xy 423.378674 -285.652558)
			(xy 423.343181 -285.68665) (xy 423.302678 -285.714606) (xy 423.258216 -285.735704) (xy 423.210945 -285.749396)
			(xy 423.16209 -285.755328) (xy 423.112915 -285.753347) (xy 423.064696 -285.743503) (xy 423.01868 -285.726051)
			(xy 422.976059 -285.701444) (xy 422.937938 -285.670319) (xy 422.905303 -285.633482) (xy 422.879 -285.591886)
			(xy 422.859709 -285.54661) (xy 422.847932 -285.498826) (xy 422.843972 -285.449772) (xy 422.505124 -285.449772)
			(xy 422.504629 -285.474379) (xy 422.496734 -285.522956) (xy 422.48115 -285.569637) (xy 422.458279 -285.613214)
			(xy 422.428714 -285.652558) (xy 422.393221 -285.68665) (xy 422.352718 -285.714606) (xy 422.308256 -285.735704)
			(xy 422.260985 -285.749396) (xy 422.21213 -285.755328) (xy 422.162955 -285.753347) (xy 422.114736 -285.743503)
			(xy 422.06872 -285.726051) (xy 422.026099 -285.701444) (xy 421.987978 -285.670319) (xy 421.955343 -285.633482)
			(xy 421.92904 -285.591886) (xy 421.909749 -285.54661) (xy 421.897972 -285.498826) (xy 421.894012 -285.449772)
			(xy 418.087302 -285.449772) (xy 418.087302 -285.608522) (xy 418.087991 -285.620965) (xy 418.099701 -285.642934)
			(xy 418.109654 -285.650432) (xy 418.130061 -285.66471) (xy 418.166742 -285.698398) (xy 418.197956 -285.737206)
			(xy 418.222999 -285.780255) (xy 418.241304 -285.826572) (xy 418.252457 -285.875111) (xy 418.256203 -285.924752)
			(xy 418.569152 -285.924752) (xy 418.573112 -285.875698) (xy 418.584889 -285.827914) (xy 418.60418 -285.782638)
			(xy 418.630483 -285.741042) (xy 418.663118 -285.704205) (xy 418.701239 -285.67308) (xy 418.74386 -285.648473)
			(xy 418.789876 -285.631021) (xy 418.838095 -285.621177) (xy 418.88727 -285.619196) (xy 418.936125 -285.625128)
			(xy 418.983396 -285.63882) (xy 419.027858 -285.659918) (xy 419.068361 -285.687874) (xy 419.103854 -285.721966)
			(xy 419.133419 -285.76131) (xy 419.15629 -285.804887) (xy 419.171874 -285.851568) (xy 419.179769 -285.900145)
			(xy 419.180264 -285.924752) (xy 419.179769 -285.949359) (xy 419.171874 -285.997936) (xy 419.15629 -286.044617)
			(xy 419.133419 -286.088194) (xy 419.103854 -286.127538) (xy 419.068361 -286.16163) (xy 419.027858 -286.189586)
			(xy 418.983396 -286.210684) (xy 418.936125 -286.224376) (xy 418.88727 -286.230308) (xy 418.838095 -286.228327)
			(xy 418.789876 -286.218483) (xy 418.74386 -286.201031) (xy 418.701239 -286.176424) (xy 418.663118 -286.145299)
			(xy 418.630483 -286.108462) (xy 418.60418 -286.066866) (xy 418.584889 -286.02159) (xy 418.573112 -285.973806)
			(xy 418.569152 -285.924752) (xy 418.256203 -285.924752) (xy 418.256205 -285.924773) (xy 418.252465 -285.974436)
			(xy 418.24132 -286.022976) (xy 418.223023 -286.069297) (xy 418.197987 -286.11235) (xy 418.166778 -286.151163)
			(xy 418.130103 -286.184857) (xy 418.109654 -286.199072) (xy 418.099686 -286.206556) (xy 418.087987 -286.228534)
			(xy 418.087302 -286.240982) (xy 418.087302 -286.399732) (xy 421.894012 -286.399732) (xy 421.897972 -286.350678)
			(xy 421.909749 -286.302894) (xy 421.92904 -286.257618) (xy 421.955343 -286.216022) (xy 421.987978 -286.179185)
			(xy 422.026099 -286.14806) (xy 422.06872 -286.123453) (xy 422.114736 -286.106001) (xy 422.162955 -286.096157)
			(xy 422.21213 -286.094176) (xy 422.260985 -286.100108) (xy 422.308256 -286.1138) (xy 422.352718 -286.134898)
			(xy 422.393221 -286.162854) (xy 422.428714 -286.196946) (xy 422.458279 -286.23629) (xy 422.48115 -286.279867)
			(xy 422.496734 -286.326548) (xy 422.504629 -286.375125) (xy 422.505124 -286.399732) (xy 422.844226 -286.399732)
			(xy 422.848186 -286.350678) (xy 422.859963 -286.302894) (xy 422.879254 -286.257618) (xy 422.905557 -286.216022)
			(xy 422.938192 -286.179185) (xy 422.976313 -286.14806) (xy 423.018934 -286.123453) (xy 423.06495 -286.106001)
			(xy 423.113169 -286.096157) (xy 423.162344 -286.094176) (xy 423.211199 -286.100108) (xy 423.25847 -286.1138)
			(xy 423.302932 -286.134898) (xy 423.343435 -286.162854) (xy 423.378928 -286.196946) (xy 423.408493 -286.23629)
			(xy 423.431364 -286.279867) (xy 423.446948 -286.326548) (xy 423.454843 -286.375125) (xy 423.455338 -286.399732)
			(xy 423.794186 -286.399732) (xy 423.798146 -286.350678) (xy 423.809923 -286.302894) (xy 423.829214 -286.257618)
			(xy 423.855517 -286.216022) (xy 423.888152 -286.179185) (xy 423.926273 -286.14806) (xy 423.968894 -286.123453)
			(xy 424.01491 -286.106001) (xy 424.063129 -286.096157) (xy 424.112304 -286.094176) (xy 424.161159 -286.100108)
			(xy 424.20843 -286.1138) (xy 424.252892 -286.134898) (xy 424.293395 -286.162854) (xy 424.328888 -286.196946)
			(xy 424.358453 -286.23629) (xy 424.381324 -286.279867) (xy 424.396908 -286.326548) (xy 424.404803 -286.375125)
			(xy 424.405298 -286.399732) (xy 424.404803 -286.424339) (xy 424.396908 -286.472916) (xy 424.381324 -286.519597)
			(xy 424.358453 -286.563174) (xy 424.328888 -286.602518) (xy 424.293395 -286.63661) (xy 424.252892 -286.664566)
			(xy 424.20843 -286.685664) (xy 424.161159 -286.699356) (xy 424.112304 -286.705288) (xy 424.063129 -286.703307)
			(xy 424.01491 -286.693463) (xy 423.968894 -286.676011) (xy 423.926273 -286.651404) (xy 423.888152 -286.620279)
			(xy 423.855517 -286.583442) (xy 423.829214 -286.541846) (xy 423.809923 -286.49657) (xy 423.798146 -286.448786)
			(xy 423.794186 -286.399732) (xy 423.455338 -286.399732) (xy 423.454843 -286.424339) (xy 423.446948 -286.472916)
			(xy 423.431364 -286.519597) (xy 423.408493 -286.563174) (xy 423.378928 -286.602518) (xy 423.343435 -286.63661)
			(xy 423.302932 -286.664566) (xy 423.25847 -286.685664) (xy 423.211199 -286.699356) (xy 423.162344 -286.705288)
			(xy 423.113169 -286.703307) (xy 423.06495 -286.693463) (xy 423.018934 -286.676011) (xy 422.976313 -286.651404)
			(xy 422.938192 -286.620279) (xy 422.905557 -286.583442) (xy 422.879254 -286.541846) (xy 422.859963 -286.49657)
			(xy 422.848186 -286.448786) (xy 422.844226 -286.399732) (xy 422.505124 -286.399732) (xy 422.504629 -286.424339)
			(xy 422.496734 -286.472916) (xy 422.48115 -286.519597) (xy 422.458279 -286.563174) (xy 422.428714 -286.602518)
			(xy 422.393221 -286.63661) (xy 422.352718 -286.664566) (xy 422.308256 -286.685664) (xy 422.260985 -286.699356)
			(xy 422.21213 -286.705288) (xy 422.162955 -286.703307) (xy 422.114736 -286.693463) (xy 422.06872 -286.676011)
			(xy 422.026099 -286.651404) (xy 421.987978 -286.620279) (xy 421.955343 -286.583442) (xy 421.92904 -286.541846)
			(xy 421.909749 -286.49657) (xy 421.897972 -286.448786) (xy 421.894012 -286.399732) (xy 418.087302 -286.399732)
			(xy 418.087302 -286.558736) (xy 418.087994 -286.571178) (xy 418.099707 -286.593141) (xy 418.109654 -286.600646)
			(xy 418.13006 -286.614924) (xy 418.166739 -286.648612) (xy 418.197951 -286.687419) (xy 418.222992 -286.730467)
			(xy 418.241295 -286.776783) (xy 418.252446 -286.82532) (xy 418.256193 -286.874966) (xy 418.569152 -286.874966)
			(xy 418.573112 -286.825912) (xy 418.584889 -286.778128) (xy 418.60418 -286.732852) (xy 418.630483 -286.691256)
			(xy 418.663118 -286.654419) (xy 418.701239 -286.623294) (xy 418.74386 -286.598687) (xy 418.789876 -286.581235)
			(xy 418.838095 -286.571391) (xy 418.88727 -286.56941) (xy 418.936125 -286.575342) (xy 418.983396 -286.589034)
			(xy 419.027858 -286.610132) (xy 419.068361 -286.638088) (xy 419.103854 -286.67218) (xy 419.133419 -286.711524)
			(xy 419.15629 -286.755101) (xy 419.171874 -286.801782) (xy 419.179769 -286.850359) (xy 419.180264 -286.874966)
			(xy 419.179769 -286.899573) (xy 419.171874 -286.94815) (xy 419.15629 -286.994831) (xy 419.133419 -287.038408)
			(xy 419.103854 -287.077752) (xy 419.068361 -287.111844) (xy 419.027858 -287.1398) (xy 418.983396 -287.160898)
			(xy 418.936125 -287.17459) (xy 418.88727 -287.180522) (xy 418.838095 -287.178541) (xy 418.789876 -287.168697)
			(xy 418.74386 -287.151245) (xy 418.701239 -287.126638) (xy 418.663118 -287.095513) (xy 418.630483 -287.058676)
			(xy 418.60418 -287.01708) (xy 418.584889 -286.971804) (xy 418.573112 -286.92402) (xy 418.569152 -286.874966)
			(xy 418.256193 -286.874966) (xy 418.256194 -286.874981) (xy 418.252452 -286.924642) (xy 418.241307 -286.97318)
			(xy 418.223009 -287.019499) (xy 418.197973 -287.06255) (xy 418.166765 -287.101361) (xy 418.13009 -287.135053)
			(xy 418.109654 -287.149286) (xy 418.099671 -287.156764) (xy 418.087935 -287.17874) (xy 418.087302 -287.191196)
			(xy 418.087302 -287.349946) (xy 421.894012 -287.349946) (xy 421.897972 -287.300892) (xy 421.909749 -287.253108)
			(xy 421.92904 -287.207832) (xy 421.955343 -287.166236) (xy 421.987978 -287.129399) (xy 422.026099 -287.098274)
			(xy 422.06872 -287.073667) (xy 422.114736 -287.056215) (xy 422.162955 -287.046371) (xy 422.21213 -287.04439)
			(xy 422.260985 -287.050322) (xy 422.308256 -287.064014) (xy 422.352718 -287.085112) (xy 422.393221 -287.113068)
			(xy 422.428714 -287.14716) (xy 422.458279 -287.186504) (xy 422.48115 -287.230081) (xy 422.496734 -287.276762)
			(xy 422.504629 -287.325339) (xy 422.505124 -287.349946) (xy 422.843972 -287.349946) (xy 422.847932 -287.300892)
			(xy 422.859709 -287.253108) (xy 422.879 -287.207832) (xy 422.905303 -287.166236) (xy 422.937938 -287.129399)
			(xy 422.976059 -287.098274) (xy 423.01868 -287.073667) (xy 423.064696 -287.056215) (xy 423.112915 -287.046371)
			(xy 423.16209 -287.04439) (xy 423.210945 -287.050322) (xy 423.258216 -287.064014) (xy 423.302678 -287.085112)
			(xy 423.343181 -287.113068) (xy 423.378674 -287.14716) (xy 423.408239 -287.186504) (xy 423.43111 -287.230081)
			(xy 423.446694 -287.276762) (xy 423.454589 -287.325339) (xy 423.455084 -287.349946) (xy 423.794186 -287.349946)
			(xy 423.798146 -287.300892) (xy 423.809923 -287.253108) (xy 423.829214 -287.207832) (xy 423.855517 -287.166236)
			(xy 423.888152 -287.129399) (xy 423.926273 -287.098274) (xy 423.968894 -287.073667) (xy 424.01491 -287.056215)
			(xy 424.063129 -287.046371) (xy 424.112304 -287.04439) (xy 424.161159 -287.050322) (xy 424.20843 -287.064014)
			(xy 424.252892 -287.085112) (xy 424.293395 -287.113068) (xy 424.328888 -287.14716) (xy 424.358453 -287.186504)
			(xy 424.381324 -287.230081) (xy 424.396908 -287.276762) (xy 424.404803 -287.325339) (xy 424.405298 -287.349946)
			(xy 424.404803 -287.374553) (xy 424.396908 -287.42313) (xy 424.381324 -287.469811) (xy 424.358453 -287.513388)
			(xy 424.328888 -287.552732) (xy 424.293395 -287.586824) (xy 424.252892 -287.61478) (xy 424.20843 -287.635878)
			(xy 424.161159 -287.64957) (xy 424.112304 -287.655502) (xy 424.063129 -287.653521) (xy 424.01491 -287.643677)
			(xy 423.968894 -287.626225) (xy 423.926273 -287.601618) (xy 423.888152 -287.570493) (xy 423.855517 -287.533656)
			(xy 423.829214 -287.49206) (xy 423.809923 -287.446784) (xy 423.798146 -287.399) (xy 423.794186 -287.349946)
			(xy 423.455084 -287.349946) (xy 423.454589 -287.374553) (xy 423.446694 -287.42313) (xy 423.43111 -287.469811)
			(xy 423.408239 -287.513388) (xy 423.378674 -287.552732) (xy 423.343181 -287.586824) (xy 423.302678 -287.61478)
			(xy 423.258216 -287.635878) (xy 423.210945 -287.64957) (xy 423.16209 -287.655502) (xy 423.112915 -287.653521)
			(xy 423.064696 -287.643677) (xy 423.01868 -287.626225) (xy 422.976059 -287.601618) (xy 422.937938 -287.570493)
			(xy 422.905303 -287.533656) (xy 422.879 -287.49206) (xy 422.859709 -287.446784) (xy 422.847932 -287.399)
			(xy 422.843972 -287.349946) (xy 422.505124 -287.349946) (xy 422.504629 -287.374553) (xy 422.496734 -287.42313)
			(xy 422.48115 -287.469811) (xy 422.458279 -287.513388) (xy 422.428714 -287.552732) (xy 422.393221 -287.586824)
			(xy 422.352718 -287.61478) (xy 422.308256 -287.635878) (xy 422.260985 -287.64957) (xy 422.21213 -287.655502)
			(xy 422.162955 -287.653521) (xy 422.114736 -287.643677) (xy 422.06872 -287.626225) (xy 422.026099 -287.601618)
			(xy 421.987978 -287.570493) (xy 421.955343 -287.533656) (xy 421.92904 -287.49206) (xy 421.909749 -287.446784)
			(xy 421.897972 -287.399) (xy 421.894012 -287.349946) (xy 418.087302 -287.349946) (xy 418.087302 -287.824926)
			(xy 418.569152 -287.824926) (xy 418.573112 -287.775872) (xy 418.584889 -287.728088) (xy 418.60418 -287.682812)
			(xy 418.630483 -287.641216) (xy 418.663118 -287.604379) (xy 418.701239 -287.573254) (xy 418.74386 -287.548647)
			(xy 418.789876 -287.531195) (xy 418.838095 -287.521351) (xy 418.88727 -287.51937) (xy 418.936125 -287.525302)
			(xy 418.983396 -287.538994) (xy 419.027858 -287.560092) (xy 419.068361 -287.588048) (xy 419.103854 -287.62214)
			(xy 419.133419 -287.661484) (xy 419.15629 -287.705061) (xy 419.171874 -287.751742) (xy 419.179769 -287.800319)
			(xy 419.180264 -287.824926) (xy 420.469072 -287.824926) (xy 420.473032 -287.775872) (xy 420.484809 -287.728088)
			(xy 420.5041 -287.682812) (xy 420.530403 -287.641216) (xy 420.563038 -287.604379) (xy 420.601159 -287.573254)
			(xy 420.64378 -287.548647) (xy 420.689796 -287.531195) (xy 420.738015 -287.521351) (xy 420.78719 -287.51937)
			(xy 420.836045 -287.525302) (xy 420.883316 -287.538994) (xy 420.927778 -287.560092) (xy 420.968281 -287.588048)
			(xy 421.003774 -287.62214) (xy 421.033339 -287.661484) (xy 421.05621 -287.705061) (xy 421.071794 -287.751742)
			(xy 421.079689 -287.800319) (xy 421.080184 -287.824926) (xy 421.079689 -287.849533) (xy 421.071794 -287.89811)
			(xy 421.05621 -287.944791) (xy 421.033339 -287.988368) (xy 421.003774 -288.027712) (xy 420.968281 -288.061804)
			(xy 420.927778 -288.08976) (xy 420.883316 -288.110858) (xy 420.836045 -288.12455) (xy 420.78719 -288.130482)
			(xy 420.738015 -288.128501) (xy 420.689796 -288.118657) (xy 420.64378 -288.101205) (xy 420.601159 -288.076598)
			(xy 420.563038 -288.045473) (xy 420.530403 -288.008636) (xy 420.5041 -287.96704) (xy 420.484809 -287.921764)
			(xy 420.473032 -287.87398) (xy 420.469072 -287.824926) (xy 419.180264 -287.824926) (xy 419.179769 -287.849533)
			(xy 419.171874 -287.89811) (xy 419.15629 -287.944791) (xy 419.133419 -287.988368) (xy 419.103854 -288.027712)
			(xy 419.068361 -288.061804) (xy 419.027858 -288.08976) (xy 418.983396 -288.110858) (xy 418.936125 -288.12455)
			(xy 418.88727 -288.130482) (xy 418.838095 -288.128501) (xy 418.789876 -288.118657) (xy 418.74386 -288.101205)
			(xy 418.701239 -288.076598) (xy 418.663118 -288.045473) (xy 418.630483 -288.008636) (xy 418.60418 -287.96704)
			(xy 418.584889 -287.921764) (xy 418.573112 -287.87398) (xy 418.569152 -287.824926) (xy 418.087302 -287.824926)
			(xy 418.087302 -288.299906) (xy 421.894012 -288.299906) (xy 421.897972 -288.250852) (xy 421.909749 -288.203068)
			(xy 421.92904 -288.157792) (xy 421.955343 -288.116196) (xy 421.987978 -288.079359) (xy 422.026099 -288.048234)
			(xy 422.06872 -288.023627) (xy 422.114736 -288.006175) (xy 422.162955 -287.996331) (xy 422.21213 -287.99435)
			(xy 422.260985 -288.000282) (xy 422.308256 -288.013974) (xy 422.352718 -288.035072) (xy 422.393221 -288.063028)
			(xy 422.428714 -288.09712) (xy 422.458279 -288.136464) (xy 422.48115 -288.180041) (xy 422.496734 -288.226722)
			(xy 422.504629 -288.275299) (xy 422.505124 -288.299906) (xy 422.844226 -288.299906) (xy 422.848186 -288.250852)
			(xy 422.859963 -288.203068) (xy 422.879254 -288.157792) (xy 422.905557 -288.116196) (xy 422.938192 -288.079359)
			(xy 422.976313 -288.048234) (xy 423.018934 -288.023627) (xy 423.06495 -288.006175) (xy 423.113169 -287.996331)
			(xy 423.162344 -287.99435) (xy 423.211199 -288.000282) (xy 423.25847 -288.013974) (xy 423.302932 -288.035072)
			(xy 423.343435 -288.063028) (xy 423.378928 -288.09712) (xy 423.408493 -288.136464) (xy 423.431364 -288.180041)
			(xy 423.446948 -288.226722) (xy 423.454843 -288.275299) (xy 423.455338 -288.299906) (xy 423.454843 -288.324513)
			(xy 423.446948 -288.37309) (xy 423.431364 -288.419771) (xy 423.408493 -288.463348) (xy 423.378928 -288.502692)
			(xy 423.343435 -288.536784) (xy 423.302932 -288.56474) (xy 423.25847 -288.585838) (xy 423.211199 -288.59953)
			(xy 423.162344 -288.605462) (xy 423.113169 -288.603481) (xy 423.06495 -288.593637) (xy 423.018934 -288.576185)
			(xy 422.976313 -288.551578) (xy 422.938192 -288.520453) (xy 422.905557 -288.483616) (xy 422.879254 -288.44202)
			(xy 422.859963 -288.396744) (xy 422.848186 -288.34896) (xy 422.844226 -288.299906) (xy 422.505124 -288.299906)
			(xy 422.504629 -288.324513) (xy 422.496734 -288.37309) (xy 422.48115 -288.419771) (xy 422.458279 -288.463348)
			(xy 422.428714 -288.502692) (xy 422.393221 -288.536784) (xy 422.352718 -288.56474) (xy 422.308256 -288.585838)
			(xy 422.260985 -288.59953) (xy 422.21213 -288.605462) (xy 422.162955 -288.603481) (xy 422.114736 -288.593637)
			(xy 422.06872 -288.576185) (xy 422.026099 -288.551578) (xy 421.987978 -288.520453) (xy 421.955343 -288.483616)
			(xy 421.92904 -288.44202) (xy 421.909749 -288.396744) (xy 421.897972 -288.34896) (xy 421.894012 -288.299906)
			(xy 418.087302 -288.299906) (xy 418.087302 -288.458656) (xy 418.088131 -288.471061) (xy 418.099818 -288.49296)
			(xy 418.109654 -288.500566) (xy 418.130058 -288.514844) (xy 418.166734 -288.548531) (xy 418.197944 -288.587337)
			(xy 418.222982 -288.630384) (xy 418.241283 -288.676699) (xy 418.252432 -288.725234) (xy 418.256177 -288.774886)
			(xy 418.569152 -288.774886) (xy 418.573112 -288.725832) (xy 418.584889 -288.678048) (xy 418.60418 -288.632772)
			(xy 418.630483 -288.591176) (xy 418.663118 -288.554339) (xy 418.701239 -288.523214) (xy 418.74386 -288.498607)
			(xy 418.789876 -288.481155) (xy 418.838095 -288.471311) (xy 418.88727 -288.46933) (xy 418.936125 -288.475262)
			(xy 418.983396 -288.488954) (xy 419.027858 -288.510052) (xy 419.068361 -288.538008) (xy 419.103854 -288.5721)
			(xy 419.133419 -288.611444) (xy 419.15629 -288.655021) (xy 419.171874 -288.701702) (xy 419.179769 -288.750279)
			(xy 419.180264 -288.774886) (xy 419.519112 -288.774886) (xy 419.523072 -288.725832) (xy 419.534849 -288.678048)
			(xy 419.55414 -288.632772) (xy 419.580443 -288.591176) (xy 419.613078 -288.554339) (xy 419.651199 -288.523214)
			(xy 419.69382 -288.498607) (xy 419.739836 -288.481155) (xy 419.788055 -288.471311) (xy 419.83723 -288.46933)
			(xy 419.886085 -288.475262) (xy 419.933356 -288.488954) (xy 419.977818 -288.510052) (xy 420.018321 -288.538008)
			(xy 420.053814 -288.5721) (xy 420.083379 -288.611444) (xy 420.10625 -288.655021) (xy 420.121834 -288.701702)
			(xy 420.129729 -288.750279) (xy 420.130224 -288.774886) (xy 420.469072 -288.774886) (xy 420.473032 -288.725832)
			(xy 420.484809 -288.678048) (xy 420.5041 -288.632772) (xy 420.530403 -288.591176) (xy 420.563038 -288.554339)
			(xy 420.601159 -288.523214) (xy 420.64378 -288.498607) (xy 420.689796 -288.481155) (xy 420.738015 -288.471311)
			(xy 420.78719 -288.46933) (xy 420.836045 -288.475262) (xy 420.883316 -288.488954) (xy 420.927778 -288.510052)
			(xy 420.968281 -288.538008) (xy 421.003774 -288.5721) (xy 421.033339 -288.611444) (xy 421.05621 -288.655021)
			(xy 421.071794 -288.701702) (xy 421.079689 -288.750279) (xy 421.080184 -288.774886) (xy 421.079689 -288.799493)
			(xy 421.071794 -288.84807) (xy 421.05621 -288.894751) (xy 421.033339 -288.938328) (xy 421.003774 -288.977672)
			(xy 420.968281 -289.011764) (xy 420.927778 -289.03972) (xy 420.883316 -289.060818) (xy 420.836045 -289.07451)
			(xy 420.78719 -289.080442) (xy 420.738015 -289.078461) (xy 420.689796 -289.068617) (xy 420.64378 -289.051165)
			(xy 420.601159 -289.026558) (xy 420.563038 -288.995433) (xy 420.530403 -288.958596) (xy 420.5041 -288.917)
			(xy 420.484809 -288.871724) (xy 420.473032 -288.82394) (xy 420.469072 -288.774886) (xy 420.130224 -288.774886)
			(xy 420.129729 -288.799493) (xy 420.121834 -288.84807) (xy 420.10625 -288.894751) (xy 420.083379 -288.938328)
			(xy 420.053814 -288.977672) (xy 420.018321 -289.011764) (xy 419.977818 -289.03972) (xy 419.933356 -289.060818)
			(xy 419.886085 -289.07451) (xy 419.83723 -289.080442) (xy 419.788055 -289.078461) (xy 419.739836 -289.068617)
			(xy 419.69382 -289.051165) (xy 419.651199 -289.026558) (xy 419.613078 -288.995433) (xy 419.580443 -288.958596)
			(xy 419.55414 -288.917) (xy 419.534849 -288.871724) (xy 419.523072 -288.82394) (xy 419.519112 -288.774886)
			(xy 419.180264 -288.774886) (xy 419.179769 -288.799493) (xy 419.171874 -288.84807) (xy 419.15629 -288.894751)
			(xy 419.133419 -288.938328) (xy 419.103854 -288.977672) (xy 419.068361 -289.011764) (xy 419.027858 -289.03972)
			(xy 418.983396 -289.060818) (xy 418.936125 -289.07451) (xy 418.88727 -289.080442) (xy 418.838095 -289.078461)
			(xy 418.789876 -289.068617) (xy 418.74386 -289.051165) (xy 418.701239 -289.026558) (xy 418.663118 -288.995433)
			(xy 418.630483 -288.958596) (xy 418.60418 -288.917) (xy 418.584889 -288.871724) (xy 418.573112 -288.82394)
			(xy 418.569152 -288.774886) (xy 418.256177 -288.774886) (xy 418.256177 -288.774892) (xy 418.252434 -288.82455)
			(xy 418.241287 -288.873086) (xy 418.222989 -288.919402) (xy 418.197953 -288.96245) (xy 418.166745 -289.001257)
			(xy 418.130071 -289.034947) (xy 418.109654 -289.049206) (xy 418.099674 -289.056685) (xy 418.087947 -289.078662)
			(xy 418.087302 -289.091116) (xy 418.087302 -289.408616) (xy 418.087989 -289.42106) (xy 418.099698 -289.443031)
			(xy 418.109654 -289.450526) (xy 418.130054 -289.464804) (xy 418.166721 -289.49849) (xy 418.197922 -289.537293)
			(xy 418.222952 -289.580336) (xy 418.241245 -289.626646) (xy 418.252388 -289.675175) (xy 418.256127 -289.724826)
			(xy 418.256125 -289.724846) (xy 418.569152 -289.724846) (xy 418.573112 -289.675792) (xy 418.584889 -289.628008)
			(xy 418.60418 -289.582732) (xy 418.630483 -289.541136) (xy 418.663118 -289.504299) (xy 418.701239 -289.473174)
			(xy 418.74386 -289.448567) (xy 418.789876 -289.431115) (xy 418.838095 -289.421271) (xy 418.88727 -289.41929)
			(xy 418.936125 -289.425222) (xy 418.983396 -289.438914) (xy 419.027858 -289.460012) (xy 419.068361 -289.487968)
			(xy 419.103854 -289.52206) (xy 419.133419 -289.561404) (xy 419.15629 -289.604981) (xy 419.171874 -289.651662)
			(xy 419.179769 -289.700239) (xy 419.180264 -289.724846) (xy 419.519112 -289.724846) (xy 419.523072 -289.675792)
			(xy 419.534849 -289.628008) (xy 419.55414 -289.582732) (xy 419.580443 -289.541136) (xy 419.613078 -289.504299)
			(xy 419.651199 -289.473174) (xy 419.69382 -289.448567) (xy 419.739836 -289.431115) (xy 419.788055 -289.421271)
			(xy 419.83723 -289.41929) (xy 419.886085 -289.425222) (xy 419.933356 -289.438914) (xy 419.977818 -289.460012)
			(xy 420.018321 -289.487968) (xy 420.053814 -289.52206) (xy 420.083379 -289.561404) (xy 420.10625 -289.604981)
			(xy 420.121834 -289.651662) (xy 420.129729 -289.700239) (xy 420.130224 -289.724846) (xy 420.469072 -289.724846)
			(xy 420.473032 -289.675792) (xy 420.484809 -289.628008) (xy 420.5041 -289.582732) (xy 420.530403 -289.541136)
			(xy 420.563038 -289.504299) (xy 420.601159 -289.473174) (xy 420.64378 -289.448567) (xy 420.689796 -289.431115)
			(xy 420.738015 -289.421271) (xy 420.78719 -289.41929) (xy 420.836045 -289.425222) (xy 420.883316 -289.438914)
			(xy 420.927778 -289.460012) (xy 420.968281 -289.487968) (xy 421.003774 -289.52206) (xy 421.033339 -289.561404)
			(xy 421.05621 -289.604981) (xy 421.071794 -289.651662) (xy 421.079689 -289.700239) (xy 421.080016 -289.71648)
			(xy 421.419128 -289.71648) (xy 421.424501 -289.667138) (xy 421.437785 -289.619315) (xy 421.458632 -289.574271)
			(xy 421.486491 -289.533193) (xy 421.520629 -289.497163) (xy 421.560145 -289.467131) (xy 421.604 -289.443887)
			(xy 421.651038 -289.428045) (xy 421.700019 -289.420021) (xy 421.724836 -289.419538) (xy 421.739019 -289.419709)
			(xy 421.767259 -289.422385) (xy 421.781224 -289.424872) (xy 421.79367 -289.427158) (xy 421.817292 -289.419792)
			(xy 421.894762 -289.342322) (xy 421.902128 -289.3187) (xy 421.899842 -289.306254) (xy 421.897364 -289.292288)
			(xy 421.894693 -289.264049) (xy 421.894508 -289.249866) (xy 421.89503 -289.224611) (xy 421.903343 -289.174789)
			(xy 421.919744 -289.127015) (xy 421.943785 -289.082592) (xy 421.974809 -289.042732) (xy 422.011971 -289.008522)
			(xy 422.054257 -288.980896) (xy 422.100513 -288.960606) (xy 422.149478 -288.948206) (xy 422.199816 -288.944035)
			(xy 422.250154 -288.948206) (xy 422.299119 -288.960606) (xy 422.345375 -288.980896) (xy 422.387661 -289.008522)
			(xy 422.424823 -289.042732) (xy 422.455847 -289.082592) (xy 422.479888 -289.127015) (xy 422.496289 -289.174789)
			(xy 422.504602 -289.224611) (xy 422.505124 -289.249866) (xy 422.504942 -289.264049) (xy 422.502274 -289.292289)
			(xy 422.49979 -289.306254) (xy 422.49979 -289.306508) (xy 422.498345 -289.318739) (xy 422.505623 -289.342223)
			(xy 422.51376 -289.351466) (xy 422.58234 -289.419792) (xy 422.605962 -289.427158) (xy 422.618408 -289.424872)
			(xy 422.632437 -289.422389) (xy 422.660804 -289.419716) (xy 422.67505 -289.419538) (xy 422.699865 -289.420032)
			(xy 422.74884 -289.428068) (xy 422.79587 -289.443922) (xy 422.839716 -289.467175) (xy 422.879223 -289.497215)
			(xy 422.91335 -289.53325) (xy 422.941198 -289.574331) (xy 422.962033 -289.619376) (xy 422.975307 -289.667199)
			(xy 422.980669 -289.716538) (xy 422.980218 -289.724846) (xy 424.269166 -289.724846) (xy 424.273126 -289.675792)
			(xy 424.284903 -289.628008) (xy 424.304194 -289.582732) (xy 424.330497 -289.541136) (xy 424.363132 -289.504299)
			(xy 424.401253 -289.473174) (xy 424.443874 -289.448567) (xy 424.48989 -289.431115) (xy 424.538109 -289.421271)
			(xy 424.587284 -289.41929) (xy 424.636139 -289.425222) (xy 424.68341 -289.438914) (xy 424.727872 -289.460012)
			(xy 424.768375 -289.487968) (xy 424.803868 -289.52206) (xy 424.833433 -289.561404) (xy 424.856304 -289.604981)
			(xy 424.871888 -289.651662) (xy 424.879783 -289.700239) (xy 424.880278 -289.724846) (xy 425.219126 -289.724846)
			(xy 425.223086 -289.675792) (xy 425.234863 -289.628008) (xy 425.254154 -289.582732) (xy 425.280457 -289.541136)
			(xy 425.313092 -289.504299) (xy 425.351213 -289.473174) (xy 425.393834 -289.448567) (xy 425.43985 -289.431115)
			(xy 425.488069 -289.421271) (xy 425.537244 -289.41929) (xy 425.586099 -289.425222) (xy 425.63337 -289.438914)
			(xy 425.677832 -289.460012) (xy 425.718335 -289.487968) (xy 425.753828 -289.52206) (xy 425.783393 -289.561404)
			(xy 425.806264 -289.604981) (xy 425.821848 -289.651662) (xy 425.829743 -289.700239) (xy 425.830238 -289.724846)
			(xy 426.169086 -289.724846) (xy 426.173046 -289.675792) (xy 426.184823 -289.628008) (xy 426.204114 -289.582732)
			(xy 426.230417 -289.541136) (xy 426.263052 -289.504299) (xy 426.301173 -289.473174) (xy 426.343794 -289.448567)
			(xy 426.38981 -289.431115) (xy 426.438029 -289.421271) (xy 426.487204 -289.41929) (xy 426.536059 -289.425222)
			(xy 426.58333 -289.438914) (xy 426.627792 -289.460012) (xy 426.668295 -289.487968) (xy 426.703788 -289.52206)
			(xy 426.733353 -289.561404) (xy 426.756224 -289.604981) (xy 426.771808 -289.651662) (xy 426.779703 -289.700239)
			(xy 426.780198 -289.724846) (xy 427.119046 -289.724846) (xy 427.123006 -289.675792) (xy 427.134783 -289.628008)
			(xy 427.154074 -289.582732) (xy 427.180377 -289.541136) (xy 427.213012 -289.504299) (xy 427.251133 -289.473174)
			(xy 427.293754 -289.448567) (xy 427.33977 -289.431115) (xy 427.387989 -289.421271) (xy 427.437164 -289.41929)
			(xy 427.486019 -289.425222) (xy 427.53329 -289.438914) (xy 427.577752 -289.460012) (xy 427.618255 -289.487968)
			(xy 427.653748 -289.52206) (xy 427.683313 -289.561404) (xy 427.706184 -289.604981) (xy 427.721768 -289.651662)
			(xy 427.729663 -289.700239) (xy 427.730158 -289.724846) (xy 428.069006 -289.724846) (xy 428.072966 -289.675792)
			(xy 428.084743 -289.628008) (xy 428.104034 -289.582732) (xy 428.130337 -289.541136) (xy 428.162972 -289.504299)
			(xy 428.201093 -289.473174) (xy 428.243714 -289.448567) (xy 428.28973 -289.431115) (xy 428.337949 -289.421271)
			(xy 428.387124 -289.41929) (xy 428.435979 -289.425222) (xy 428.48325 -289.438914) (xy 428.527712 -289.460012)
			(xy 428.568215 -289.487968) (xy 428.603708 -289.52206) (xy 428.633273 -289.561404) (xy 428.656144 -289.604981)
			(xy 428.671728 -289.651662) (xy 428.679623 -289.700239) (xy 428.680118 -289.724846) (xy 429.01922 -289.724846)
			(xy 429.02318 -289.675792) (xy 429.034957 -289.628008) (xy 429.054248 -289.582732) (xy 429.080551 -289.541136)
			(xy 429.113186 -289.504299) (xy 429.151307 -289.473174) (xy 429.193928 -289.448567) (xy 429.239944 -289.431115)
			(xy 429.288163 -289.421271) (xy 429.337338 -289.41929) (xy 429.386193 -289.425222) (xy 429.433464 -289.438914)
			(xy 429.477926 -289.460012) (xy 429.518429 -289.487968) (xy 429.553922 -289.52206) (xy 429.583487 -289.561404)
			(xy 429.606358 -289.604981) (xy 429.621942 -289.651662) (xy 429.629837 -289.700239) (xy 429.630332 -289.724846)
			(xy 429.96918 -289.724846) (xy 429.97314 -289.675792) (xy 429.984917 -289.628008) (xy 430.004208 -289.582732)
			(xy 430.030511 -289.541136) (xy 430.063146 -289.504299) (xy 430.101267 -289.473174) (xy 430.143888 -289.448567)
			(xy 430.189904 -289.431115) (xy 430.238123 -289.421271) (xy 430.287298 -289.41929) (xy 430.336153 -289.425222)
			(xy 430.383424 -289.438914) (xy 430.427886 -289.460012) (xy 430.468389 -289.487968) (xy 430.503882 -289.52206)
			(xy 430.533447 -289.561404) (xy 430.556318 -289.604981) (xy 430.571902 -289.651662) (xy 430.579797 -289.700239)
			(xy 430.580292 -289.724846) (xy 430.91914 -289.724846) (xy 430.9231 -289.675792) (xy 430.934877 -289.628008)
			(xy 430.954168 -289.582732) (xy 430.980471 -289.541136) (xy 431.013106 -289.504299) (xy 431.051227 -289.473174)
			(xy 431.093848 -289.448567) (xy 431.139864 -289.431115) (xy 431.188083 -289.421271) (xy 431.237258 -289.41929)
			(xy 431.286113 -289.425222) (xy 431.333384 -289.438914) (xy 431.377846 -289.460012) (xy 431.418349 -289.487968)
			(xy 431.453842 -289.52206) (xy 431.483407 -289.561404) (xy 431.506278 -289.604981) (xy 431.521862 -289.651662)
			(xy 431.529757 -289.700239) (xy 431.530252 -289.724846) (xy 431.529757 -289.749453) (xy 431.521862 -289.79803)
			(xy 431.506278 -289.844711) (xy 431.483407 -289.888288) (xy 431.453842 -289.927632) (xy 431.418349 -289.961724)
			(xy 431.377846 -289.98968) (xy 431.333384 -290.010778) (xy 431.286113 -290.02447) (xy 431.237258 -290.030402)
			(xy 431.188083 -290.028421) (xy 431.139864 -290.018577) (xy 431.093848 -290.001125) (xy 431.051227 -289.976518)
			(xy 431.013106 -289.945393) (xy 430.980471 -289.908556) (xy 430.954168 -289.86696) (xy 430.934877 -289.821684)
			(xy 430.9231 -289.7739) (xy 430.91914 -289.724846) (xy 430.580292 -289.724846) (xy 430.579797 -289.749453)
			(xy 430.571902 -289.79803) (xy 430.556318 -289.844711) (xy 430.533447 -289.888288) (xy 430.503882 -289.927632)
			(xy 430.468389 -289.961724) (xy 430.427886 -289.98968) (xy 430.383424 -290.010778) (xy 430.336153 -290.02447)
			(xy 430.287298 -290.030402) (xy 430.238123 -290.028421) (xy 430.189904 -290.018577) (xy 430.143888 -290.001125)
			(xy 430.101267 -289.976518) (xy 430.063146 -289.945393) (xy 430.030511 -289.908556) (xy 430.004208 -289.86696)
			(xy 429.984917 -289.821684) (xy 429.97314 -289.7739) (xy 429.96918 -289.724846) (xy 429.630332 -289.724846)
			(xy 429.629837 -289.749453) (xy 429.621942 -289.79803) (xy 429.606358 -289.844711) (xy 429.583487 -289.888288)
			(xy 429.553922 -289.927632) (xy 429.518429 -289.961724) (xy 429.477926 -289.98968) (xy 429.433464 -290.010778)
			(xy 429.386193 -290.02447) (xy 429.337338 -290.030402) (xy 429.288163 -290.028421) (xy 429.239944 -290.018577)
			(xy 429.193928 -290.001125) (xy 429.151307 -289.976518) (xy 429.113186 -289.945393) (xy 429.080551 -289.908556)
			(xy 429.054248 -289.86696) (xy 429.034957 -289.821684) (xy 429.02318 -289.7739) (xy 429.01922 -289.724846)
			(xy 428.680118 -289.724846) (xy 428.679623 -289.749453) (xy 428.671728 -289.79803) (xy 428.656144 -289.844711)
			(xy 428.633273 -289.888288) (xy 428.603708 -289.927632) (xy 428.568215 -289.961724) (xy 428.527712 -289.98968)
			(xy 428.48325 -290.010778) (xy 428.435979 -290.02447) (xy 428.387124 -290.030402) (xy 428.337949 -290.028421)
			(xy 428.28973 -290.018577) (xy 428.243714 -290.001125) (xy 428.201093 -289.976518) (xy 428.162972 -289.945393)
			(xy 428.130337 -289.908556) (xy 428.104034 -289.86696) (xy 428.084743 -289.821684) (xy 428.072966 -289.7739)
			(xy 428.069006 -289.724846) (xy 427.730158 -289.724846) (xy 427.729663 -289.749453) (xy 427.721768 -289.79803)
			(xy 427.706184 -289.844711) (xy 427.683313 -289.888288) (xy 427.653748 -289.927632) (xy 427.618255 -289.961724)
			(xy 427.577752 -289.98968) (xy 427.53329 -290.010778) (xy 427.486019 -290.02447) (xy 427.437164 -290.030402)
			(xy 427.387989 -290.028421) (xy 427.33977 -290.018577) (xy 427.293754 -290.001125) (xy 427.251133 -289.976518)
			(xy 427.213012 -289.945393) (xy 427.180377 -289.908556) (xy 427.154074 -289.86696) (xy 427.134783 -289.821684)
			(xy 427.123006 -289.7739) (xy 427.119046 -289.724846) (xy 426.780198 -289.724846) (xy 426.779703 -289.749453)
			(xy 426.771808 -289.79803) (xy 426.756224 -289.844711) (xy 426.733353 -289.888288) (xy 426.703788 -289.927632)
			(xy 426.668295 -289.961724) (xy 426.627792 -289.98968) (xy 426.58333 -290.010778) (xy 426.536059 -290.02447)
			(xy 426.487204 -290.030402) (xy 426.438029 -290.028421) (xy 426.38981 -290.018577) (xy 426.343794 -290.001125)
			(xy 426.301173 -289.976518) (xy 426.263052 -289.945393) (xy 426.230417 -289.908556) (xy 426.204114 -289.86696)
			(xy 426.184823 -289.821684) (xy 426.173046 -289.7739) (xy 426.169086 -289.724846) (xy 425.830238 -289.724846)
			(xy 425.829743 -289.749453) (xy 425.821848 -289.79803) (xy 425.806264 -289.844711) (xy 425.783393 -289.888288)
			(xy 425.753828 -289.927632) (xy 425.718335 -289.961724) (xy 425.677832 -289.98968) (xy 425.63337 -290.010778)
			(xy 425.586099 -290.02447) (xy 425.537244 -290.030402) (xy 425.488069 -290.028421) (xy 425.43985 -290.018577)
			(xy 425.393834 -290.001125) (xy 425.351213 -289.976518) (xy 425.313092 -289.945393) (xy 425.280457 -289.908556)
			(xy 425.254154 -289.86696) (xy 425.234863 -289.821684) (xy 425.223086 -289.7739) (xy 425.219126 -289.724846)
			(xy 424.880278 -289.724846) (xy 424.879783 -289.749453) (xy 424.871888 -289.79803) (xy 424.856304 -289.844711)
			(xy 424.833433 -289.888288) (xy 424.803868 -289.927632) (xy 424.768375 -289.961724) (xy 424.727872 -289.98968)
			(xy 424.68341 -290.010778) (xy 424.636139 -290.02447) (xy 424.587284 -290.030402) (xy 424.538109 -290.028421)
			(xy 424.48989 -290.018577) (xy 424.443874 -290.001125) (xy 424.401253 -289.976518) (xy 424.363132 -289.945393)
			(xy 424.330497 -289.908556) (xy 424.304194 -289.86696) (xy 424.284903 -289.821684) (xy 424.273126 -289.7739)
			(xy 424.269166 -289.724846) (xy 422.980218 -289.724846) (xy 422.97798 -289.766096) (xy 422.967308 -289.814565)
			(xy 422.948937 -289.86067) (xy 422.923349 -289.903195) (xy 422.891218 -289.941021) (xy 422.853392 -289.973151)
			(xy 422.810866 -289.998739) (xy 422.764761 -290.01711) (xy 422.716292 -290.02778) (xy 422.666734 -290.030469)
			(xy 422.617395 -290.025106) (xy 422.569572 -290.011831) (xy 422.524528 -289.990996) (xy 422.483447 -289.963147)
			(xy 422.447412 -289.92902) (xy 422.417373 -289.889513) (xy 422.394121 -289.845667) (xy 422.378267 -289.798636)
			(xy 422.370231 -289.749661) (xy 422.369742 -289.724846) (xy 422.369924 -289.710663) (xy 422.372592 -289.682423)
			(xy 422.375076 -289.668458) (xy 422.375076 -289.668204) (xy 422.376523 -289.655972) (xy 422.369245 -289.632488)
			(xy 422.361106 -289.623246) (xy 422.292526 -289.55492) (xy 422.268904 -289.547554) (xy 422.256458 -289.54984)
			(xy 422.24243 -289.552328) (xy 422.214062 -289.554998) (xy 422.199816 -289.555174) (xy 422.185633 -289.554996)
			(xy 422.157393 -289.552325) (xy 422.143428 -289.54984) (xy 422.130982 -289.547554) (xy 422.10736 -289.55492)
			(xy 422.02989 -289.63239) (xy 422.022524 -289.656012) (xy 422.02481 -289.668458) (xy 422.027291 -289.682423)
			(xy 422.02996 -289.710663) (xy 422.030144 -289.724846) (xy 422.029573 -289.749663) (xy 422.021535 -289.798642)
			(xy 422.00568 -289.845675) (xy 421.982425 -289.889524) (xy 421.952382 -289.929033) (xy 421.916343 -289.963161)
			(xy 421.875257 -289.991009) (xy 421.830208 -290.011843) (xy 421.782381 -290.025115) (xy 421.733038 -290.030474)
			(xy 421.683477 -290.02778) (xy 421.635005 -290.017103) (xy 421.588899 -289.998726) (xy 421.546373 -289.973131)
			(xy 421.508548 -289.940994) (xy 421.476421 -289.90316) (xy 421.450838 -289.860628) (xy 421.432472 -289.814517)
			(xy 421.421809 -289.766042) (xy 421.419128 -289.71648) (xy 421.080016 -289.71648) (xy 421.080184 -289.724846)
			(xy 421.079689 -289.749453) (xy 421.071794 -289.79803) (xy 421.05621 -289.844711) (xy 421.033339 -289.888288)
			(xy 421.003774 -289.927632) (xy 420.968281 -289.961724) (xy 420.927778 -289.98968) (xy 420.883316 -290.010778)
			(xy 420.836045 -290.02447) (xy 420.78719 -290.030402) (xy 420.738015 -290.028421) (xy 420.689796 -290.018577)
			(xy 420.64378 -290.001125) (xy 420.601159 -289.976518) (xy 420.563038 -289.945393) (xy 420.530403 -289.908556)
			(xy 420.5041 -289.86696) (xy 420.484809 -289.821684) (xy 420.473032 -289.7739) (xy 420.469072 -289.724846)
			(xy 420.130224 -289.724846) (xy 420.129729 -289.749453) (xy 420.121834 -289.79803) (xy 420.10625 -289.844711)
			(xy 420.083379 -289.888288) (xy 420.053814 -289.927632) (xy 420.018321 -289.961724) (xy 419.977818 -289.98968)
			(xy 419.933356 -290.010778) (xy 419.886085 -290.02447) (xy 419.83723 -290.030402) (xy 419.788055 -290.028421)
			(xy 419.739836 -290.018577) (xy 419.69382 -290.001125) (xy 419.651199 -289.976518) (xy 419.613078 -289.945393)
			(xy 419.580443 -289.908556) (xy 419.55414 -289.86696) (xy 419.534849 -289.821684) (xy 419.523072 -289.7739)
			(xy 419.519112 -289.724846) (xy 419.180264 -289.724846) (xy 419.179769 -289.749453) (xy 419.171874 -289.79803)
			(xy 419.15629 -289.844711) (xy 419.133419 -289.888288) (xy 419.103854 -289.927632) (xy 419.068361 -289.961724)
			(xy 419.027858 -289.98968) (xy 418.983396 -290.010778) (xy 418.936125 -290.02447) (xy 418.88727 -290.030402)
			(xy 418.838095 -290.028421) (xy 418.789876 -290.018577) (xy 418.74386 -290.001125) (xy 418.701239 -289.976518)
			(xy 418.663118 -289.945393) (xy 418.630483 -289.908556) (xy 418.60418 -289.86696) (xy 418.584889 -289.821684)
			(xy 418.573112 -289.7739) (xy 418.569152 -289.724846) (xy 418.256125 -289.724846) (xy 418.25238 -289.774476)
			(xy 418.24123 -289.823003) (xy 418.22293 -289.86931) (xy 418.197893 -289.912349) (xy 418.166686 -289.951148)
			(xy 418.130014 -289.984828) (xy 418.109654 -289.999166) (xy 418.099684 -290.006649) (xy 418.087983 -290.028627)
			(xy 418.087302 -290.041076) (xy 418.087302 -290.2458) (xy 433.453792 -290.2458) (xy 433.457863 -290.190178)
			(xy 433.469989 -290.135741) (xy 433.489912 -290.08365) (xy 433.517208 -290.035015) (xy 433.551294 -289.990872)
			(xy 433.591443 -289.952163) (xy 433.636801 -289.919712) (xy 433.686401 -289.894211) (xy 433.739185 -289.876204)
			(xy 433.794028 -289.866074) (xy 433.849762 -289.864037) (xy 433.905199 -289.870137) (xy 433.959156 -289.884243)
			(xy 434.010485 -289.906055) (xy 434.058091 -289.935109) (xy 434.100959 -289.970784) (xy 434.138176 -290.012321)
			(xy 434.168949 -290.058834) (xy 434.192621 -290.109331) (xy 434.208689 -290.162738) (xy 434.216809 -290.217914)
			(xy 434.21716 -290.237164) (xy 437.464452 -290.237164) (xy 437.468523 -290.181542) (xy 437.480649 -290.127105)
			(xy 437.500572 -290.075014) (xy 437.527868 -290.026379) (xy 437.561954 -289.982236) (xy 437.602103 -289.943527)
			(xy 437.647461 -289.911076) (xy 437.697061 -289.885575) (xy 437.749845 -289.867568) (xy 437.804688 -289.857438)
			(xy 437.860422 -289.855401) (xy 437.915859 -289.861501) (xy 437.969816 -289.875607) (xy 438.021145 -289.897419)
			(xy 438.068751 -289.926473) (xy 438.111619 -289.962148) (xy 438.148836 -290.003685) (xy 438.179609 -290.050198)
			(xy 438.203281 -290.100695) (xy 438.219349 -290.154102) (xy 438.227469 -290.209278) (xy 438.227978 -290.237164)
			(xy 438.227469 -290.26505) (xy 438.219349 -290.320226) (xy 438.203281 -290.373633) (xy 438.179609 -290.42413)
			(xy 438.148836 -290.470643) (xy 438.111619 -290.51218) (xy 438.068751 -290.547855) (xy 438.021145 -290.576909)
			(xy 437.969816 -290.598721) (xy 437.915859 -290.612827) (xy 437.860422 -290.618927) (xy 437.804688 -290.61689)
			(xy 437.749845 -290.60676) (xy 437.697061 -290.588753) (xy 437.647461 -290.563252) (xy 437.602103 -290.530801)
			(xy 437.561954 -290.492092) (xy 437.527868 -290.447949) (xy 437.500572 -290.399314) (xy 437.480649 -290.347223)
			(xy 437.468523 -290.292786) (xy 437.464452 -290.237164) (xy 434.21716 -290.237164) (xy 434.217318 -290.2458)
			(xy 434.216809 -290.273686) (xy 434.208689 -290.328862) (xy 434.192621 -290.382269) (xy 434.168949 -290.432766)
			(xy 434.138176 -290.479279) (xy 434.100959 -290.520816) (xy 434.058091 -290.556491) (xy 434.010485 -290.585545)
			(xy 433.959156 -290.607357) (xy 433.905199 -290.621463) (xy 433.849762 -290.627563) (xy 433.794028 -290.625526)
			(xy 433.739185 -290.615396) (xy 433.686401 -290.597389) (xy 433.636801 -290.571888) (xy 433.591443 -290.539437)
			(xy 433.551294 -290.500728) (xy 433.517208 -290.456585) (xy 433.489912 -290.40795) (xy 433.469989 -290.355859)
			(xy 433.457863 -290.301422) (xy 433.453792 -290.2458) (xy 418.087302 -290.2458) (xy 418.087302 -290.358576)
			(xy 418.087981 -290.371025) (xy 418.09968 -290.39301) (xy 418.109654 -290.400486) (xy 418.130057 -290.414764)
			(xy 418.16673 -290.448451) (xy 418.197937 -290.487256) (xy 418.222972 -290.530302) (xy 418.24127 -290.576614)
			(xy 418.252417 -290.625148) (xy 418.25616 -290.674803) (xy 418.25616 -290.674806) (xy 418.569152 -290.674806)
			(xy 418.573112 -290.625752) (xy 418.584889 -290.577968) (xy 418.60418 -290.532692) (xy 418.630483 -290.491096)
			(xy 418.663118 -290.454259) (xy 418.701239 -290.423134) (xy 418.74386 -290.398527) (xy 418.789876 -290.381075)
			(xy 418.838095 -290.371231) (xy 418.88727 -290.36925) (xy 418.936125 -290.375182) (xy 418.983396 -290.388874)
			(xy 419.027858 -290.409972) (xy 419.068361 -290.437928) (xy 419.103854 -290.47202) (xy 419.133419 -290.511364)
			(xy 419.15629 -290.554941) (xy 419.171874 -290.601622) (xy 419.179769 -290.650199) (xy 419.180264 -290.674806)
			(xy 419.519112 -290.674806) (xy 419.523072 -290.625752) (xy 419.534849 -290.577968) (xy 419.55414 -290.532692)
			(xy 419.580443 -290.491096) (xy 419.613078 -290.454259) (xy 419.651199 -290.423134) (xy 419.69382 -290.398527)
			(xy 419.739836 -290.381075) (xy 419.788055 -290.371231) (xy 419.83723 -290.36925) (xy 419.886085 -290.375182)
			(xy 419.933356 -290.388874) (xy 419.977818 -290.409972) (xy 420.018321 -290.437928) (xy 420.053814 -290.47202)
			(xy 420.083379 -290.511364) (xy 420.10625 -290.554941) (xy 420.121834 -290.601622) (xy 420.129729 -290.650199)
			(xy 420.130224 -290.674806) (xy 420.469072 -290.674806) (xy 420.473032 -290.625752) (xy 420.484809 -290.577968)
			(xy 420.5041 -290.532692) (xy 420.530403 -290.491096) (xy 420.563038 -290.454259) (xy 420.601159 -290.423134)
			(xy 420.64378 -290.398527) (xy 420.689796 -290.381075) (xy 420.738015 -290.371231) (xy 420.78719 -290.36925)
			(xy 420.836045 -290.375182) (xy 420.883316 -290.388874) (xy 420.927778 -290.409972) (xy 420.968281 -290.437928)
			(xy 421.003774 -290.47202) (xy 421.033339 -290.511364) (xy 421.05621 -290.554941) (xy 421.071794 -290.601622)
			(xy 421.079689 -290.650199) (xy 421.080184 -290.674806) (xy 421.419032 -290.674806) (xy 421.422992 -290.625752)
			(xy 421.434769 -290.577968) (xy 421.45406 -290.532692) (xy 421.480363 -290.491096) (xy 421.512998 -290.454259)
			(xy 421.551119 -290.423134) (xy 421.59374 -290.398527) (xy 421.639756 -290.381075) (xy 421.687975 -290.371231)
			(xy 421.73715 -290.36925) (xy 421.786005 -290.375182) (xy 421.833276 -290.388874) (xy 421.877738 -290.409972)
			(xy 421.918241 -290.437928) (xy 421.953734 -290.47202) (xy 421.983299 -290.511364) (xy 422.00617 -290.554941)
			(xy 422.021754 -290.601622) (xy 422.029649 -290.650199) (xy 422.030144 -290.674806) (xy 422.368992 -290.674806)
			(xy 422.372952 -290.625752) (xy 422.384729 -290.577968) (xy 422.40402 -290.532692) (xy 422.430323 -290.491096)
			(xy 422.462958 -290.454259) (xy 422.501079 -290.423134) (xy 422.5437 -290.398527) (xy 422.589716 -290.381075)
			(xy 422.637935 -290.371231) (xy 422.68711 -290.36925) (xy 422.735965 -290.375182) (xy 422.783236 -290.388874)
			(xy 422.827698 -290.409972) (xy 422.868201 -290.437928) (xy 422.903694 -290.47202) (xy 422.933259 -290.511364)
			(xy 422.95613 -290.554941) (xy 422.971714 -290.601622) (xy 422.979609 -290.650199) (xy 422.980104 -290.674806)
			(xy 423.319206 -290.674806) (xy 423.323166 -290.625752) (xy 423.334943 -290.577968) (xy 423.354234 -290.532692)
			(xy 423.380537 -290.491096) (xy 423.413172 -290.454259) (xy 423.451293 -290.423134) (xy 423.493914 -290.398527)
			(xy 423.53993 -290.381075) (xy 423.588149 -290.371231) (xy 423.637324 -290.36925) (xy 423.686179 -290.375182)
			(xy 423.73345 -290.388874) (xy 423.777912 -290.409972) (xy 423.818415 -290.437928) (xy 423.853908 -290.47202)
			(xy 423.883473 -290.511364) (xy 423.906344 -290.554941) (xy 423.921928 -290.601622) (xy 423.929823 -290.650199)
			(xy 423.930318 -290.674806) (xy 424.269166 -290.674806) (xy 424.273126 -290.625752) (xy 424.284903 -290.577968)
			(xy 424.304194 -290.532692) (xy 424.330497 -290.491096) (xy 424.363132 -290.454259) (xy 424.401253 -290.423134)
			(xy 424.443874 -290.398527) (xy 424.48989 -290.381075) (xy 424.538109 -290.371231) (xy 424.587284 -290.36925)
			(xy 424.636139 -290.375182) (xy 424.68341 -290.388874) (xy 424.727872 -290.409972) (xy 424.768375 -290.437928)
			(xy 424.803868 -290.47202) (xy 424.833433 -290.511364) (xy 424.856304 -290.554941) (xy 424.871888 -290.601622)
			(xy 424.879783 -290.650199) (xy 424.880278 -290.674806) (xy 425.219126 -290.674806) (xy 425.223086 -290.625752)
			(xy 425.234863 -290.577968) (xy 425.254154 -290.532692) (xy 425.280457 -290.491096) (xy 425.313092 -290.454259)
			(xy 425.351213 -290.423134) (xy 425.393834 -290.398527) (xy 425.43985 -290.381075) (xy 425.488069 -290.371231)
			(xy 425.537244 -290.36925) (xy 425.586099 -290.375182) (xy 425.63337 -290.388874) (xy 425.677832 -290.409972)
			(xy 425.718335 -290.437928) (xy 425.753828 -290.47202) (xy 425.783393 -290.511364) (xy 425.806264 -290.554941)
			(xy 425.821848 -290.601622) (xy 425.829743 -290.650199) (xy 425.830238 -290.674806) (xy 426.169086 -290.674806)
			(xy 426.173046 -290.625752) (xy 426.184823 -290.577968) (xy 426.204114 -290.532692) (xy 426.230417 -290.491096)
			(xy 426.263052 -290.454259) (xy 426.301173 -290.423134) (xy 426.343794 -290.398527) (xy 426.38981 -290.381075)
			(xy 426.438029 -290.371231) (xy 426.487204 -290.36925) (xy 426.536059 -290.375182) (xy 426.58333 -290.388874)
			(xy 426.627792 -290.409972) (xy 426.668295 -290.437928) (xy 426.703788 -290.47202) (xy 426.733353 -290.511364)
			(xy 426.756224 -290.554941) (xy 426.771808 -290.601622) (xy 426.779703 -290.650199) (xy 426.780198 -290.674806)
			(xy 427.119046 -290.674806) (xy 427.123006 -290.625752) (xy 427.134783 -290.577968) (xy 427.154074 -290.532692)
			(xy 427.180377 -290.491096) (xy 427.213012 -290.454259) (xy 427.251133 -290.423134) (xy 427.293754 -290.398527)
			(xy 427.33977 -290.381075) (xy 427.387989 -290.371231) (xy 427.437164 -290.36925) (xy 427.486019 -290.375182)
			(xy 427.53329 -290.388874) (xy 427.577752 -290.409972) (xy 427.618255 -290.437928) (xy 427.653748 -290.47202)
			(xy 427.683313 -290.511364) (xy 427.706184 -290.554941) (xy 427.721768 -290.601622) (xy 427.729663 -290.650199)
			(xy 427.730158 -290.674806) (xy 428.069006 -290.674806) (xy 428.072966 -290.625752) (xy 428.084743 -290.577968)
			(xy 428.104034 -290.532692) (xy 428.130337 -290.491096) (xy 428.162972 -290.454259) (xy 428.201093 -290.423134)
			(xy 428.243714 -290.398527) (xy 428.28973 -290.381075) (xy 428.337949 -290.371231) (xy 428.387124 -290.36925)
			(xy 428.435979 -290.375182) (xy 428.48325 -290.388874) (xy 428.527712 -290.409972) (xy 428.568215 -290.437928)
			(xy 428.603708 -290.47202) (xy 428.633273 -290.511364) (xy 428.656144 -290.554941) (xy 428.671728 -290.601622)
			(xy 428.679623 -290.650199) (xy 428.680118 -290.674806) (xy 429.01922 -290.674806) (xy 429.02318 -290.625752)
			(xy 429.034957 -290.577968) (xy 429.054248 -290.532692) (xy 429.080551 -290.491096) (xy 429.113186 -290.454259)
			(xy 429.151307 -290.423134) (xy 429.193928 -290.398527) (xy 429.239944 -290.381075) (xy 429.288163 -290.371231)
			(xy 429.337338 -290.36925) (xy 429.386193 -290.375182) (xy 429.433464 -290.388874) (xy 429.477926 -290.409972)
			(xy 429.518429 -290.437928) (xy 429.553922 -290.47202) (xy 429.583487 -290.511364) (xy 429.606358 -290.554941)
			(xy 429.621942 -290.601622) (xy 429.629837 -290.650199) (xy 429.630332 -290.674806) (xy 429.96918 -290.674806)
			(xy 429.97314 -290.625752) (xy 429.984917 -290.577968) (xy 430.004208 -290.532692) (xy 430.030511 -290.491096)
			(xy 430.063146 -290.454259) (xy 430.101267 -290.423134) (xy 430.143888 -290.398527) (xy 430.189904 -290.381075)
			(xy 430.238123 -290.371231) (xy 430.287298 -290.36925) (xy 430.336153 -290.375182) (xy 430.383424 -290.388874)
			(xy 430.427886 -290.409972) (xy 430.468389 -290.437928) (xy 430.503882 -290.47202) (xy 430.533447 -290.511364)
			(xy 430.556318 -290.554941) (xy 430.571902 -290.601622) (xy 430.579797 -290.650199) (xy 430.580292 -290.674806)
			(xy 430.91914 -290.674806) (xy 430.9231 -290.625752) (xy 430.934877 -290.577968) (xy 430.954168 -290.532692)
			(xy 430.980471 -290.491096) (xy 431.013106 -290.454259) (xy 431.051227 -290.423134) (xy 431.093848 -290.398527)
			(xy 431.139864 -290.381075) (xy 431.188083 -290.371231) (xy 431.237258 -290.36925) (xy 431.286113 -290.375182)
			(xy 431.333384 -290.388874) (xy 431.377846 -290.409972) (xy 431.418349 -290.437928) (xy 431.453842 -290.47202)
			(xy 431.483407 -290.511364) (xy 431.506278 -290.554941) (xy 431.521862 -290.601622) (xy 431.529757 -290.650199)
			(xy 431.530252 -290.674806) (xy 431.529757 -290.699413) (xy 431.521862 -290.74799) (xy 431.506278 -290.794671)
			(xy 431.483407 -290.838248) (xy 431.453842 -290.877592) (xy 431.418349 -290.911684) (xy 431.377846 -290.93964)
			(xy 431.333384 -290.960738) (xy 431.286113 -290.97443) (xy 431.237258 -290.980362) (xy 431.188083 -290.978381)
			(xy 431.139864 -290.968537) (xy 431.093848 -290.951085) (xy 431.051227 -290.926478) (xy 431.013106 -290.895353)
			(xy 430.980471 -290.858516) (xy 430.954168 -290.81692) (xy 430.934877 -290.771644) (xy 430.9231 -290.72386)
			(xy 430.91914 -290.674806) (xy 430.580292 -290.674806) (xy 430.579797 -290.699413) (xy 430.571902 -290.74799)
			(xy 430.556318 -290.794671) (xy 430.533447 -290.838248) (xy 430.503882 -290.877592) (xy 430.468389 -290.911684)
			(xy 430.427886 -290.93964) (xy 430.383424 -290.960738) (xy 430.336153 -290.97443) (xy 430.287298 -290.980362)
			(xy 430.238123 -290.978381) (xy 430.189904 -290.968537) (xy 430.143888 -290.951085) (xy 430.101267 -290.926478)
			(xy 430.063146 -290.895353) (xy 430.030511 -290.858516) (xy 430.004208 -290.81692) (xy 429.984917 -290.771644)
			(xy 429.97314 -290.72386) (xy 429.96918 -290.674806) (xy 429.630332 -290.674806) (xy 429.629837 -290.699413)
			(xy 429.621942 -290.74799) (xy 429.606358 -290.794671) (xy 429.583487 -290.838248) (xy 429.553922 -290.877592)
			(xy 429.518429 -290.911684) (xy 429.477926 -290.93964) (xy 429.433464 -290.960738) (xy 429.386193 -290.97443)
			(xy 429.337338 -290.980362) (xy 429.288163 -290.978381) (xy 429.239944 -290.968537) (xy 429.193928 -290.951085)
			(xy 429.151307 -290.926478) (xy 429.113186 -290.895353) (xy 429.080551 -290.858516) (xy 429.054248 -290.81692)
			(xy 429.034957 -290.771644) (xy 429.02318 -290.72386) (xy 429.01922 -290.674806) (xy 428.680118 -290.674806)
			(xy 428.679623 -290.699413) (xy 428.671728 -290.74799) (xy 428.656144 -290.794671) (xy 428.633273 -290.838248)
			(xy 428.603708 -290.877592) (xy 428.568215 -290.911684) (xy 428.527712 -290.93964) (xy 428.48325 -290.960738)
			(xy 428.435979 -290.97443) (xy 428.387124 -290.980362) (xy 428.337949 -290.978381) (xy 428.28973 -290.968537)
			(xy 428.243714 -290.951085) (xy 428.201093 -290.926478) (xy 428.162972 -290.895353) (xy 428.130337 -290.858516)
			(xy 428.104034 -290.81692) (xy 428.084743 -290.771644) (xy 428.072966 -290.72386) (xy 428.069006 -290.674806)
			(xy 427.730158 -290.674806) (xy 427.729663 -290.699413) (xy 427.721768 -290.74799) (xy 427.706184 -290.794671)
			(xy 427.683313 -290.838248) (xy 427.653748 -290.877592) (xy 427.618255 -290.911684) (xy 427.577752 -290.93964)
			(xy 427.53329 -290.960738) (xy 427.486019 -290.97443) (xy 427.437164 -290.980362) (xy 427.387989 -290.978381)
			(xy 427.33977 -290.968537) (xy 427.293754 -290.951085) (xy 427.251133 -290.926478) (xy 427.213012 -290.895353)
			(xy 427.180377 -290.858516) (xy 427.154074 -290.81692) (xy 427.134783 -290.771644) (xy 427.123006 -290.72386)
			(xy 427.119046 -290.674806) (xy 426.780198 -290.674806) (xy 426.779703 -290.699413) (xy 426.771808 -290.74799)
			(xy 426.756224 -290.794671) (xy 426.733353 -290.838248) (xy 426.703788 -290.877592) (xy 426.668295 -290.911684)
			(xy 426.627792 -290.93964) (xy 426.58333 -290.960738) (xy 426.536059 -290.97443) (xy 426.487204 -290.980362)
			(xy 426.438029 -290.978381) (xy 426.38981 -290.968537) (xy 426.343794 -290.951085) (xy 426.301173 -290.926478)
			(xy 426.263052 -290.895353) (xy 426.230417 -290.858516) (xy 426.204114 -290.81692) (xy 426.184823 -290.771644)
			(xy 426.173046 -290.72386) (xy 426.169086 -290.674806) (xy 425.830238 -290.674806) (xy 425.829743 -290.699413)
			(xy 425.821848 -290.74799) (xy 425.806264 -290.794671) (xy 425.783393 -290.838248) (xy 425.753828 -290.877592)
			(xy 425.718335 -290.911684) (xy 425.677832 -290.93964) (xy 425.63337 -290.960738) (xy 425.586099 -290.97443)
			(xy 425.537244 -290.980362) (xy 425.488069 -290.978381) (xy 425.43985 -290.968537) (xy 425.393834 -290.951085)
			(xy 425.351213 -290.926478) (xy 425.313092 -290.895353) (xy 425.280457 -290.858516) (xy 425.254154 -290.81692)
			(xy 425.234863 -290.771644) (xy 425.223086 -290.72386) (xy 425.219126 -290.674806) (xy 424.880278 -290.674806)
			(xy 424.879783 -290.699413) (xy 424.871888 -290.74799) (xy 424.856304 -290.794671) (xy 424.833433 -290.838248)
			(xy 424.803868 -290.877592) (xy 424.768375 -290.911684) (xy 424.727872 -290.93964) (xy 424.68341 -290.960738)
			(xy 424.636139 -290.97443) (xy 424.587284 -290.980362) (xy 424.538109 -290.978381) (xy 424.48989 -290.968537)
			(xy 424.443874 -290.951085) (xy 424.401253 -290.926478) (xy 424.363132 -290.895353) (xy 424.330497 -290.858516)
			(xy 424.304194 -290.81692) (xy 424.284903 -290.771644) (xy 424.273126 -290.72386) (xy 424.269166 -290.674806)
			(xy 423.930318 -290.674806) (xy 423.929823 -290.699413) (xy 423.921928 -290.74799) (xy 423.906344 -290.794671)
			(xy 423.883473 -290.838248) (xy 423.853908 -290.877592) (xy 423.818415 -290.911684) (xy 423.777912 -290.93964)
			(xy 423.73345 -290.960738) (xy 423.686179 -290.97443) (xy 423.637324 -290.980362) (xy 423.588149 -290.978381)
			(xy 423.53993 -290.968537) (xy 423.493914 -290.951085) (xy 423.451293 -290.926478) (xy 423.413172 -290.895353)
			(xy 423.380537 -290.858516) (xy 423.354234 -290.81692) (xy 423.334943 -290.771644) (xy 423.323166 -290.72386)
			(xy 423.319206 -290.674806) (xy 422.980104 -290.674806) (xy 422.979609 -290.699413) (xy 422.971714 -290.74799)
			(xy 422.95613 -290.794671) (xy 422.933259 -290.838248) (xy 422.903694 -290.877592) (xy 422.868201 -290.911684)
			(xy 422.827698 -290.93964) (xy 422.783236 -290.960738) (xy 422.735965 -290.97443) (xy 422.68711 -290.980362)
			(xy 422.637935 -290.978381) (xy 422.589716 -290.968537) (xy 422.5437 -290.951085) (xy 422.501079 -290.926478)
			(xy 422.462958 -290.895353) (xy 422.430323 -290.858516) (xy 422.40402 -290.81692) (xy 422.384729 -290.771644)
			(xy 422.372952 -290.72386) (xy 422.368992 -290.674806) (xy 422.030144 -290.674806) (xy 422.029649 -290.699413)
			(xy 422.021754 -290.74799) (xy 422.00617 -290.794671) (xy 421.983299 -290.838248) (xy 421.953734 -290.877592)
			(xy 421.918241 -290.911684) (xy 421.877738 -290.93964) (xy 421.833276 -290.960738) (xy 421.786005 -290.97443)
			(xy 421.73715 -290.980362) (xy 421.687975 -290.978381) (xy 421.639756 -290.968537) (xy 421.59374 -290.951085)
			(xy 421.551119 -290.926478) (xy 421.512998 -290.895353) (xy 421.480363 -290.858516) (xy 421.45406 -290.81692)
			(xy 421.434769 -290.771644) (xy 421.422992 -290.72386) (xy 421.419032 -290.674806) (xy 421.080184 -290.674806)
			(xy 421.079689 -290.699413) (xy 421.071794 -290.74799) (xy 421.05621 -290.794671) (xy 421.033339 -290.838248)
			(xy 421.003774 -290.877592) (xy 420.968281 -290.911684) (xy 420.927778 -290.93964) (xy 420.883316 -290.960738)
			(xy 420.836045 -290.97443) (xy 420.78719 -290.980362) (xy 420.738015 -290.978381) (xy 420.689796 -290.968537)
			(xy 420.64378 -290.951085) (xy 420.601159 -290.926478) (xy 420.563038 -290.895353) (xy 420.530403 -290.858516)
			(xy 420.5041 -290.81692) (xy 420.484809 -290.771644) (xy 420.473032 -290.72386) (xy 420.469072 -290.674806)
			(xy 420.130224 -290.674806) (xy 420.129729 -290.699413) (xy 420.121834 -290.74799) (xy 420.10625 -290.794671)
			(xy 420.083379 -290.838248) (xy 420.053814 -290.877592) (xy 420.018321 -290.911684) (xy 419.977818 -290.93964)
			(xy 419.933356 -290.960738) (xy 419.886085 -290.97443) (xy 419.83723 -290.980362) (xy 419.788055 -290.978381)
			(xy 419.739836 -290.968537) (xy 419.69382 -290.951085) (xy 419.651199 -290.926478) (xy 419.613078 -290.895353)
			(xy 419.580443 -290.858516) (xy 419.55414 -290.81692) (xy 419.534849 -290.771644) (xy 419.523072 -290.72386)
			(xy 419.519112 -290.674806) (xy 419.180264 -290.674806) (xy 419.179769 -290.699413) (xy 419.171874 -290.74799)
			(xy 419.15629 -290.794671) (xy 419.133419 -290.838248) (xy 419.103854 -290.877592) (xy 419.068361 -290.911684)
			(xy 419.027858 -290.93964) (xy 418.983396 -290.960738) (xy 418.936125 -290.97443) (xy 418.88727 -290.980362)
			(xy 418.838095 -290.978381) (xy 418.789876 -290.968537) (xy 418.74386 -290.951085) (xy 418.701239 -290.926478)
			(xy 418.663118 -290.895353) (xy 418.630483 -290.858516) (xy 418.60418 -290.81692) (xy 418.584889 -290.771644)
			(xy 418.573112 -290.72386) (xy 418.569152 -290.674806) (xy 418.25616 -290.674806) (xy 418.252416 -290.724459)
			(xy 418.241268 -290.772992) (xy 418.222969 -290.819305) (xy 418.197933 -290.86235) (xy 418.166725 -290.901154)
			(xy 418.130052 -290.934841) (xy 418.109654 -290.949126) (xy 418.099678 -290.956606) (xy 418.087959 -290.978584)
			(xy 418.087302 -290.991036) (xy 418.087302 -291.238686) (xy 434.296564 -291.238686) (xy 434.300635 -291.183064)
			(xy 434.312761 -291.128627) (xy 434.332684 -291.076536) (xy 434.35998 -291.027901) (xy 434.394066 -290.983758)
			(xy 434.434215 -290.945049) (xy 434.479573 -290.912598) (xy 434.529173 -290.887097) (xy 434.581957 -290.86909)
			(xy 434.6368 -290.85896) (xy 434.692534 -290.856923) (xy 434.747971 -290.863023) (xy 434.801928 -290.877129)
			(xy 434.853257 -290.898941) (xy 434.900863 -290.927995) (xy 434.943731 -290.96367) (xy 434.980948 -291.005207)
			(xy 435.011721 -291.05172) (xy 435.035393 -291.102217) (xy 435.051461 -291.155624) (xy 435.059581 -291.2108)
			(xy 435.06009 -291.238686) (xy 435.059581 -291.266572) (xy 435.051461 -291.321748) (xy 435.035393 -291.375155)
			(xy 435.011721 -291.425652) (xy 434.980948 -291.472165) (xy 434.943731 -291.513702) (xy 434.900863 -291.549377)
			(xy 434.853257 -291.578431) (xy 434.821326 -291.592) (xy 436.741822 -291.592) (xy 436.745893 -291.536378)
			(xy 436.758019 -291.481941) (xy 436.777942 -291.42985) (xy 436.805238 -291.381215) (xy 436.839324 -291.337072)
			(xy 436.879473 -291.298363) (xy 436.924831 -291.265912) (xy 436.974431 -291.240411) (xy 437.027215 -291.222404)
			(xy 437.082058 -291.212274) (xy 437.137792 -291.210237) (xy 437.193229 -291.216337) (xy 437.247186 -291.230443)
			(xy 437.298515 -291.252255) (xy 437.346121 -291.281309) (xy 437.388989 -291.316984) (xy 437.426206 -291.358521)
			(xy 437.456979 -291.405034) (xy 437.480651 -291.455531) (xy 437.496719 -291.508938) (xy 437.504839 -291.564114)
			(xy 437.505348 -291.592) (xy 437.504839 -291.619886) (xy 437.496719 -291.675062) (xy 437.480651 -291.728469)
			(xy 437.456979 -291.778966) (xy 437.426206 -291.825479) (xy 437.388989 -291.867016) (xy 437.346121 -291.902691)
			(xy 437.298515 -291.931745) (xy 437.247186 -291.953557) (xy 437.193229 -291.967663) (xy 437.137792 -291.973763)
			(xy 437.082058 -291.971726) (xy 437.027215 -291.961596) (xy 436.974431 -291.943589) (xy 436.924831 -291.918088)
			(xy 436.879473 -291.885637) (xy 436.839324 -291.846928) (xy 436.805238 -291.802785) (xy 436.777942 -291.75415)
			(xy 436.758019 -291.702059) (xy 436.745893 -291.647622) (xy 436.741822 -291.592) (xy 434.821326 -291.592)
			(xy 434.801928 -291.600243) (xy 434.747971 -291.614349) (xy 434.692534 -291.620449) (xy 434.6368 -291.618412)
			(xy 434.581957 -291.608282) (xy 434.529173 -291.590275) (xy 434.479573 -291.564774) (xy 434.434215 -291.532323)
			(xy 434.394066 -291.493614) (xy 434.35998 -291.449471) (xy 434.332684 -291.400836) (xy 434.312761 -291.348745)
			(xy 434.300635 -291.294308) (xy 434.296564 -291.238686) (xy 418.087302 -291.238686) (xy 418.087302 -291.308536)
			(xy 418.087994 -291.320978) (xy 418.099707 -291.342941) (xy 418.109654 -291.350446) (xy 418.13006 -291.364724)
			(xy 418.166739 -291.398412) (xy 418.197951 -291.437219) (xy 418.222992 -291.480267) (xy 418.241295 -291.526583)
			(xy 418.252446 -291.57512) (xy 418.256193 -291.624766) (xy 418.569152 -291.624766) (xy 418.573112 -291.575712)
			(xy 418.584889 -291.527928) (xy 418.60418 -291.482652) (xy 418.630483 -291.441056) (xy 418.663118 -291.404219)
			(xy 418.701239 -291.373094) (xy 418.74386 -291.348487) (xy 418.789876 -291.331035) (xy 418.838095 -291.321191)
			(xy 418.88727 -291.31921) (xy 418.936125 -291.325142) (xy 418.983396 -291.338834) (xy 419.027858 -291.359932)
			(xy 419.068361 -291.387888) (xy 419.103854 -291.42198) (xy 419.133419 -291.461324) (xy 419.15629 -291.504901)
			(xy 419.171874 -291.551582) (xy 419.179769 -291.600159) (xy 419.180264 -291.624766) (xy 419.519112 -291.624766)
			(xy 419.523072 -291.575712) (xy 419.534849 -291.527928) (xy 419.55414 -291.482652) (xy 419.580443 -291.441056)
			(xy 419.613078 -291.404219) (xy 419.651199 -291.373094) (xy 419.69382 -291.348487) (xy 419.739836 -291.331035)
			(xy 419.788055 -291.321191) (xy 419.83723 -291.31921) (xy 419.886085 -291.325142) (xy 419.933356 -291.338834)
			(xy 419.977818 -291.359932) (xy 420.018321 -291.387888) (xy 420.053814 -291.42198) (xy 420.083379 -291.461324)
			(xy 420.10625 -291.504901) (xy 420.121834 -291.551582) (xy 420.129729 -291.600159) (xy 420.130224 -291.624766)
			(xy 420.469072 -291.624766) (xy 420.473032 -291.575712) (xy 420.484809 -291.527928) (xy 420.5041 -291.482652)
			(xy 420.530403 -291.441056) (xy 420.563038 -291.404219) (xy 420.601159 -291.373094) (xy 420.64378 -291.348487)
			(xy 420.689796 -291.331035) (xy 420.738015 -291.321191) (xy 420.78719 -291.31921) (xy 420.836045 -291.325142)
			(xy 420.883316 -291.338834) (xy 420.927778 -291.359932) (xy 420.968281 -291.387888) (xy 421.003774 -291.42198)
			(xy 421.033339 -291.461324) (xy 421.05621 -291.504901) (xy 421.071794 -291.551582) (xy 421.079689 -291.600159)
			(xy 421.080184 -291.624766) (xy 421.419032 -291.624766) (xy 421.422992 -291.575712) (xy 421.434769 -291.527928)
			(xy 421.45406 -291.482652) (xy 421.480363 -291.441056) (xy 421.512998 -291.404219) (xy 421.551119 -291.373094)
			(xy 421.59374 -291.348487) (xy 421.639756 -291.331035) (xy 421.687975 -291.321191) (xy 421.73715 -291.31921)
			(xy 421.786005 -291.325142) (xy 421.833276 -291.338834) (xy 421.877738 -291.359932) (xy 421.918241 -291.387888)
			(xy 421.953734 -291.42198) (xy 421.983299 -291.461324) (xy 422.00617 -291.504901) (xy 422.021754 -291.551582)
			(xy 422.029649 -291.600159) (xy 422.030144 -291.624766) (xy 422.369246 -291.624766) (xy 422.373206 -291.575712)
			(xy 422.384983 -291.527928) (xy 422.404274 -291.482652) (xy 422.430577 -291.441056) (xy 422.463212 -291.404219)
			(xy 422.501333 -291.373094) (xy 422.543954 -291.348487) (xy 422.58997 -291.331035) (xy 422.638189 -291.321191)
			(xy 422.687364 -291.31921) (xy 422.736219 -291.325142) (xy 422.78349 -291.338834) (xy 422.827952 -291.359932)
			(xy 422.868455 -291.387888) (xy 422.903948 -291.42198) (xy 422.933513 -291.461324) (xy 422.956384 -291.504901)
			(xy 422.971968 -291.551582) (xy 422.979863 -291.600159) (xy 422.980358 -291.624766) (xy 424.269166 -291.624766)
			(xy 424.273126 -291.575712) (xy 424.284903 -291.527928) (xy 424.304194 -291.482652) (xy 424.330497 -291.441056)
			(xy 424.363132 -291.404219) (xy 424.401253 -291.373094) (xy 424.443874 -291.348487) (xy 424.48989 -291.331035)
			(xy 424.538109 -291.321191) (xy 424.587284 -291.31921) (xy 424.636139 -291.325142) (xy 424.68341 -291.338834)
			(xy 424.727872 -291.359932) (xy 424.768375 -291.387888) (xy 424.803868 -291.42198) (xy 424.833433 -291.461324)
			(xy 424.856304 -291.504901) (xy 424.871888 -291.551582) (xy 424.879783 -291.600159) (xy 424.880278 -291.624766)
			(xy 425.219126 -291.624766) (xy 425.223086 -291.575712) (xy 425.234863 -291.527928) (xy 425.254154 -291.482652)
			(xy 425.280457 -291.441056) (xy 425.313092 -291.404219) (xy 425.351213 -291.373094) (xy 425.393834 -291.348487)
			(xy 425.43985 -291.331035) (xy 425.488069 -291.321191) (xy 425.537244 -291.31921) (xy 425.586099 -291.325142)
			(xy 425.63337 -291.338834) (xy 425.677832 -291.359932) (xy 425.718335 -291.387888) (xy 425.753828 -291.42198)
			(xy 425.783393 -291.461324) (xy 425.806264 -291.504901) (xy 425.821848 -291.551582) (xy 425.829743 -291.600159)
			(xy 425.830238 -291.624766) (xy 426.169086 -291.624766) (xy 426.173046 -291.575712) (xy 426.184823 -291.527928)
			(xy 426.204114 -291.482652) (xy 426.230417 -291.441056) (xy 426.263052 -291.404219) (xy 426.301173 -291.373094)
			(xy 426.343794 -291.348487) (xy 426.38981 -291.331035) (xy 426.438029 -291.321191) (xy 426.487204 -291.31921)
			(xy 426.536059 -291.325142) (xy 426.58333 -291.338834) (xy 426.627792 -291.359932) (xy 426.668295 -291.387888)
			(xy 426.703788 -291.42198) (xy 426.733353 -291.461324) (xy 426.756224 -291.504901) (xy 426.771808 -291.551582)
			(xy 426.779703 -291.600159) (xy 426.780198 -291.624766) (xy 427.119046 -291.624766) (xy 427.123006 -291.575712)
			(xy 427.134783 -291.527928) (xy 427.154074 -291.482652) (xy 427.180377 -291.441056) (xy 427.213012 -291.404219)
			(xy 427.251133 -291.373094) (xy 427.293754 -291.348487) (xy 427.33977 -291.331035) (xy 427.387989 -291.321191)
			(xy 427.437164 -291.31921) (xy 427.486019 -291.325142) (xy 427.53329 -291.338834) (xy 427.577752 -291.359932)
			(xy 427.618255 -291.387888) (xy 427.653748 -291.42198) (xy 427.683313 -291.461324) (xy 427.706184 -291.504901)
			(xy 427.721768 -291.551582) (xy 427.729663 -291.600159) (xy 427.730158 -291.624766) (xy 428.069006 -291.624766)
			(xy 428.072966 -291.575712) (xy 428.084743 -291.527928) (xy 428.104034 -291.482652) (xy 428.130337 -291.441056)
			(xy 428.162972 -291.404219) (xy 428.201093 -291.373094) (xy 428.243714 -291.348487) (xy 428.28973 -291.331035)
			(xy 428.337949 -291.321191) (xy 428.387124 -291.31921) (xy 428.435979 -291.325142) (xy 428.48325 -291.338834)
			(xy 428.527712 -291.359932) (xy 428.568215 -291.387888) (xy 428.603708 -291.42198) (xy 428.633273 -291.461324)
			(xy 428.656144 -291.504901) (xy 428.671728 -291.551582) (xy 428.679623 -291.600159) (xy 428.680118 -291.624766)
			(xy 429.01922 -291.624766) (xy 429.02318 -291.575712) (xy 429.034957 -291.527928) (xy 429.054248 -291.482652)
			(xy 429.080551 -291.441056) (xy 429.113186 -291.404219) (xy 429.151307 -291.373094) (xy 429.193928 -291.348487)
			(xy 429.239944 -291.331035) (xy 429.288163 -291.321191) (xy 429.337338 -291.31921) (xy 429.386193 -291.325142)
			(xy 429.433464 -291.338834) (xy 429.477926 -291.359932) (xy 429.518429 -291.387888) (xy 429.553922 -291.42198)
			(xy 429.583487 -291.461324) (xy 429.606358 -291.504901) (xy 429.621942 -291.551582) (xy 429.629837 -291.600159)
			(xy 429.630332 -291.624766) (xy 429.96918 -291.624766) (xy 429.97314 -291.575712) (xy 429.984917 -291.527928)
			(xy 430.004208 -291.482652) (xy 430.030511 -291.441056) (xy 430.063146 -291.404219) (xy 430.101267 -291.373094)
			(xy 430.143888 -291.348487) (xy 430.189904 -291.331035) (xy 430.238123 -291.321191) (xy 430.287298 -291.31921)
			(xy 430.336153 -291.325142) (xy 430.383424 -291.338834) (xy 430.427886 -291.359932) (xy 430.468389 -291.387888)
			(xy 430.503882 -291.42198) (xy 430.533447 -291.461324) (xy 430.556318 -291.504901) (xy 430.571902 -291.551582)
			(xy 430.579797 -291.600159) (xy 430.580292 -291.624766) (xy 430.91914 -291.624766) (xy 430.9231 -291.575712)
			(xy 430.934877 -291.527928) (xy 430.954168 -291.482652) (xy 430.980471 -291.441056) (xy 431.013106 -291.404219)
			(xy 431.051227 -291.373094) (xy 431.093848 -291.348487) (xy 431.139864 -291.331035) (xy 431.188083 -291.321191)
			(xy 431.237258 -291.31921) (xy 431.286113 -291.325142) (xy 431.333384 -291.338834) (xy 431.377846 -291.359932)
			(xy 431.418349 -291.387888) (xy 431.453842 -291.42198) (xy 431.483407 -291.461324) (xy 431.506278 -291.504901)
			(xy 431.521862 -291.551582) (xy 431.529757 -291.600159) (xy 431.530252 -291.624766) (xy 431.529757 -291.649373)
			(xy 431.521862 -291.69795) (xy 431.506278 -291.744631) (xy 431.483407 -291.788208) (xy 431.453842 -291.827552)
			(xy 431.418349 -291.861644) (xy 431.377846 -291.8896) (xy 431.333384 -291.910698) (xy 431.286113 -291.92439)
			(xy 431.237258 -291.930322) (xy 431.188083 -291.928341) (xy 431.139864 -291.918497) (xy 431.093848 -291.901045)
			(xy 431.051227 -291.876438) (xy 431.013106 -291.845313) (xy 430.980471 -291.808476) (xy 430.954168 -291.76688)
			(xy 430.934877 -291.721604) (xy 430.9231 -291.67382) (xy 430.91914 -291.624766) (xy 430.580292 -291.624766)
			(xy 430.579797 -291.649373) (xy 430.571902 -291.69795) (xy 430.556318 -291.744631) (xy 430.533447 -291.788208)
			(xy 430.503882 -291.827552) (xy 430.468389 -291.861644) (xy 430.427886 -291.8896) (xy 430.383424 -291.910698)
			(xy 430.336153 -291.92439) (xy 430.287298 -291.930322) (xy 430.238123 -291.928341) (xy 430.189904 -291.918497)
			(xy 430.143888 -291.901045) (xy 430.101267 -291.876438) (xy 430.063146 -291.845313) (xy 430.030511 -291.808476)
			(xy 430.004208 -291.76688) (xy 429.984917 -291.721604) (xy 429.97314 -291.67382) (xy 429.96918 -291.624766)
			(xy 429.630332 -291.624766) (xy 429.629837 -291.649373) (xy 429.621942 -291.69795) (xy 429.606358 -291.744631)
			(xy 429.583487 -291.788208) (xy 429.553922 -291.827552) (xy 429.518429 -291.861644) (xy 429.477926 -291.8896)
			(xy 429.433464 -291.910698) (xy 429.386193 -291.92439) (xy 429.337338 -291.930322) (xy 429.288163 -291.928341)
			(xy 429.239944 -291.918497) (xy 429.193928 -291.901045) (xy 429.151307 -291.876438) (xy 429.113186 -291.845313)
			(xy 429.080551 -291.808476) (xy 429.054248 -291.76688) (xy 429.034957 -291.721604) (xy 429.02318 -291.67382)
			(xy 429.01922 -291.624766) (xy 428.680118 -291.624766) (xy 428.679623 -291.649373) (xy 428.671728 -291.69795)
			(xy 428.656144 -291.744631) (xy 428.633273 -291.788208) (xy 428.603708 -291.827552) (xy 428.568215 -291.861644)
			(xy 428.527712 -291.8896) (xy 428.48325 -291.910698) (xy 428.435979 -291.92439) (xy 428.387124 -291.930322)
			(xy 428.337949 -291.928341) (xy 428.28973 -291.918497) (xy 428.243714 -291.901045) (xy 428.201093 -291.876438)
			(xy 428.162972 -291.845313) (xy 428.130337 -291.808476) (xy 428.104034 -291.76688) (xy 428.084743 -291.721604)
			(xy 428.072966 -291.67382) (xy 428.069006 -291.624766) (xy 427.730158 -291.624766) (xy 427.729663 -291.649373)
			(xy 427.721768 -291.69795) (xy 427.706184 -291.744631) (xy 427.683313 -291.788208) (xy 427.653748 -291.827552)
			(xy 427.618255 -291.861644) (xy 427.577752 -291.8896) (xy 427.53329 -291.910698) (xy 427.486019 -291.92439)
			(xy 427.437164 -291.930322) (xy 427.387989 -291.928341) (xy 427.33977 -291.918497) (xy 427.293754 -291.901045)
			(xy 427.251133 -291.876438) (xy 427.213012 -291.845313) (xy 427.180377 -291.808476) (xy 427.154074 -291.76688)
			(xy 427.134783 -291.721604) (xy 427.123006 -291.67382) (xy 427.119046 -291.624766) (xy 426.780198 -291.624766)
			(xy 426.779703 -291.649373) (xy 426.771808 -291.69795) (xy 426.756224 -291.744631) (xy 426.733353 -291.788208)
			(xy 426.703788 -291.827552) (xy 426.668295 -291.861644) (xy 426.627792 -291.8896) (xy 426.58333 -291.910698)
			(xy 426.536059 -291.92439) (xy 426.487204 -291.930322) (xy 426.438029 -291.928341) (xy 426.38981 -291.918497)
			(xy 426.343794 -291.901045) (xy 426.301173 -291.876438) (xy 426.263052 -291.845313) (xy 426.230417 -291.808476)
			(xy 426.204114 -291.76688) (xy 426.184823 -291.721604) (xy 426.173046 -291.67382) (xy 426.169086 -291.624766)
			(xy 425.830238 -291.624766) (xy 425.829743 -291.649373) (xy 425.821848 -291.69795) (xy 425.806264 -291.744631)
			(xy 425.783393 -291.788208) (xy 425.753828 -291.827552) (xy 425.718335 -291.861644) (xy 425.677832 -291.8896)
			(xy 425.63337 -291.910698) (xy 425.586099 -291.92439) (xy 425.537244 -291.930322) (xy 425.488069 -291.928341)
			(xy 425.43985 -291.918497) (xy 425.393834 -291.901045) (xy 425.351213 -291.876438) (xy 425.313092 -291.845313)
			(xy 425.280457 -291.808476) (xy 425.254154 -291.76688) (xy 425.234863 -291.721604) (xy 425.223086 -291.67382)
			(xy 425.219126 -291.624766) (xy 424.880278 -291.624766) (xy 424.879783 -291.649373) (xy 424.871888 -291.69795)
			(xy 424.856304 -291.744631) (xy 424.833433 -291.788208) (xy 424.803868 -291.827552) (xy 424.768375 -291.861644)
			(xy 424.727872 -291.8896) (xy 424.68341 -291.910698) (xy 424.636139 -291.92439) (xy 424.587284 -291.930322)
			(xy 424.538109 -291.928341) (xy 424.48989 -291.918497) (xy 424.443874 -291.901045) (xy 424.401253 -291.876438)
			(xy 424.363132 -291.845313) (xy 424.330497 -291.808476) (xy 424.304194 -291.76688) (xy 424.284903 -291.721604)
			(xy 424.273126 -291.67382) (xy 424.269166 -291.624766) (xy 422.980358 -291.624766) (xy 422.979863 -291.649373)
			(xy 422.971968 -291.69795) (xy 422.956384 -291.744631) (xy 422.933513 -291.788208) (xy 422.903948 -291.827552)
			(xy 422.868455 -291.861644) (xy 422.827952 -291.8896) (xy 422.78349 -291.910698) (xy 422.736219 -291.92439)
			(xy 422.687364 -291.930322) (xy 422.638189 -291.928341) (xy 422.58997 -291.918497) (xy 422.543954 -291.901045)
			(xy 422.501333 -291.876438) (xy 422.463212 -291.845313) (xy 422.430577 -291.808476) (xy 422.404274 -291.76688)
			(xy 422.384983 -291.721604) (xy 422.373206 -291.67382) (xy 422.369246 -291.624766) (xy 422.030144 -291.624766)
			(xy 422.029649 -291.649373) (xy 422.021754 -291.69795) (xy 422.00617 -291.744631) (xy 421.983299 -291.788208)
			(xy 421.953734 -291.827552) (xy 421.918241 -291.861644) (xy 421.877738 -291.8896) (xy 421.833276 -291.910698)
			(xy 421.786005 -291.92439) (xy 421.73715 -291.930322) (xy 421.687975 -291.928341) (xy 421.639756 -291.918497)
			(xy 421.59374 -291.901045) (xy 421.551119 -291.876438) (xy 421.512998 -291.845313) (xy 421.480363 -291.808476)
			(xy 421.45406 -291.76688) (xy 421.434769 -291.721604) (xy 421.422992 -291.67382) (xy 421.419032 -291.624766)
			(xy 421.080184 -291.624766) (xy 421.079689 -291.649373) (xy 421.071794 -291.69795) (xy 421.05621 -291.744631)
			(xy 421.033339 -291.788208) (xy 421.003774 -291.827552) (xy 420.968281 -291.861644) (xy 420.927778 -291.8896)
			(xy 420.883316 -291.910698) (xy 420.836045 -291.92439) (xy 420.78719 -291.930322) (xy 420.738015 -291.928341)
			(xy 420.689796 -291.918497) (xy 420.64378 -291.901045) (xy 420.601159 -291.876438) (xy 420.563038 -291.845313)
			(xy 420.530403 -291.808476) (xy 420.5041 -291.76688) (xy 420.484809 -291.721604) (xy 420.473032 -291.67382)
			(xy 420.469072 -291.624766) (xy 420.130224 -291.624766) (xy 420.129729 -291.649373) (xy 420.121834 -291.69795)
			(xy 420.10625 -291.744631) (xy 420.083379 -291.788208) (xy 420.053814 -291.827552) (xy 420.018321 -291.861644)
			(xy 419.977818 -291.8896) (xy 419.933356 -291.910698) (xy 419.886085 -291.92439) (xy 419.83723 -291.930322)
			(xy 419.788055 -291.928341) (xy 419.739836 -291.918497) (xy 419.69382 -291.901045) (xy 419.651199 -291.876438)
			(xy 419.613078 -291.845313) (xy 419.580443 -291.808476) (xy 419.55414 -291.76688) (xy 419.534849 -291.721604)
			(xy 419.523072 -291.67382) (xy 419.519112 -291.624766) (xy 419.180264 -291.624766) (xy 419.179769 -291.649373)
			(xy 419.171874 -291.69795) (xy 419.15629 -291.744631) (xy 419.133419 -291.788208) (xy 419.103854 -291.827552)
			(xy 419.068361 -291.861644) (xy 419.027858 -291.8896) (xy 418.983396 -291.910698) (xy 418.936125 -291.92439)
			(xy 418.88727 -291.930322) (xy 418.838095 -291.928341) (xy 418.789876 -291.918497) (xy 418.74386 -291.901045)
			(xy 418.701239 -291.876438) (xy 418.663118 -291.845313) (xy 418.630483 -291.808476) (xy 418.60418 -291.76688)
			(xy 418.584889 -291.721604) (xy 418.573112 -291.67382) (xy 418.569152 -291.624766) (xy 418.256193 -291.624766)
			(xy 418.256194 -291.624781) (xy 418.252452 -291.674442) (xy 418.241307 -291.72298) (xy 418.223009 -291.769299)
			(xy 418.197973 -291.81235) (xy 418.166765 -291.851161) (xy 418.13009 -291.884853) (xy 418.109654 -291.899086)
			(xy 418.099671 -291.906564) (xy 418.087935 -291.92854) (xy 418.087302 -291.940996) (xy 418.087302 -292.122098)
			(xy 441.55741 -292.122098) (xy 441.557853 -292.095494) (xy 441.565235 -292.0428) (xy 441.57987 -291.991644)
			(xy 441.601474 -291.943019) (xy 441.629626 -291.897869) (xy 441.663781 -291.85707) (xy 441.703276 -291.821415)
			(xy 441.72505 -291.806122) (xy 441.736488 -291.797731) (xy 441.754699 -291.776003) (xy 441.766224 -291.750101)
			(xy 441.770172 -291.722027) (xy 441.766239 -291.693951) (xy 441.754727 -291.668043) (xy 441.736528 -291.646305)
			(xy 441.72505 -291.637974) (xy 441.703261 -291.622704) (xy 441.663782 -291.587034) (xy 441.62964 -291.546226)
			(xy 441.601496 -291.501072) (xy 441.579897 -291.452447) (xy 441.565261 -291.401293) (xy 441.557871 -291.348601)
			(xy 441.55741 -291.321998) (xy 441.557896 -291.294747) (xy 441.565652 -291.240799) (xy 441.581007 -291.188504)
			(xy 441.603649 -291.138927) (xy 441.633115 -291.093077) (xy 441.668806 -291.051886) (xy 441.709997 -291.016195)
			(xy 441.755847 -290.986729) (xy 441.805424 -290.964087) (xy 441.857719 -290.948732) (xy 441.911667 -290.940976)
			(xy 441.966169 -290.940976) (xy 442.020117 -290.948732) (xy 442.072412 -290.964087) (xy 442.121989 -290.986729)
			(xy 442.167839 -291.016195) (xy 442.20903 -291.051886) (xy 442.244721 -291.093077) (xy 442.274187 -291.138927)
			(xy 442.296829 -291.188504) (xy 442.312184 -291.240799) (xy 442.31994 -291.294747) (xy 442.320426 -291.321998)
			(xy 442.320008 -291.348603) (xy 442.312625 -291.401299) (xy 442.297988 -291.452457) (xy 442.276381 -291.501083)
			(xy 442.248224 -291.546233) (xy 442.214064 -291.587031) (xy 442.174563 -291.622683) (xy 442.152786 -291.637974)
			(xy 442.141261 -291.64625) (xy 442.123058 -291.668007) (xy 442.111546 -291.693934) (xy 442.107612 -291.722027)
			(xy 442.11156 -291.750118) (xy 442.123087 -291.776039) (xy 442.141301 -291.797786) (xy 442.152786 -291.806122)
			(xy 442.174581 -291.821383) (xy 442.214058 -291.857056) (xy 442.248199 -291.897866) (xy 442.276341 -291.943021)
			(xy 442.297939 -291.991648) (xy 442.312575 -292.042803) (xy 442.319965 -292.095494) (xy 442.320426 -292.122098)
			(xy 442.31994 -292.149349) (xy 442.312184 -292.203297) (xy 442.296829 -292.255592) (xy 442.274187 -292.305169)
			(xy 442.244721 -292.351019) (xy 442.20903 -292.39221) (xy 442.167839 -292.427901) (xy 442.121989 -292.457367)
			(xy 442.072412 -292.480009) (xy 442.020117 -292.495364) (xy 441.966169 -292.50312) (xy 441.911667 -292.50312)
			(xy 441.857719 -292.495364) (xy 441.805424 -292.480009) (xy 441.755847 -292.457367) (xy 441.709997 -292.427901)
			(xy 441.668806 -292.39221) (xy 441.633115 -292.351019) (xy 441.603649 -292.305169) (xy 441.581007 -292.255592)
			(xy 441.565652 -292.203297) (xy 441.557896 -292.149349) (xy 441.55741 -292.122098) (xy 418.087302 -292.122098)
			(xy 418.087302 -292.258496) (xy 418.087985 -292.270942) (xy 418.099689 -292.29292) (xy 418.109654 -292.300406)
			(xy 418.130055 -292.314684) (xy 418.166725 -292.34837) (xy 418.197929 -292.387174) (xy 418.222962 -292.430219)
			(xy 418.241258 -292.47653) (xy 418.252402 -292.525061) (xy 418.256144 -292.574715) (xy 418.256124 -292.57498)
			(xy 418.569152 -292.57498) (xy 418.573112 -292.525926) (xy 418.584889 -292.478142) (xy 418.60418 -292.432866)
			(xy 418.630483 -292.39127) (xy 418.663118 -292.354433) (xy 418.701239 -292.323308) (xy 418.74386 -292.298701)
			(xy 418.789876 -292.281249) (xy 418.838095 -292.271405) (xy 418.88727 -292.269424) (xy 418.936125 -292.275356)
			(xy 418.983396 -292.289048) (xy 419.027858 -292.310146) (xy 419.068361 -292.338102) (xy 419.103854 -292.372194)
			(xy 419.133419 -292.411538) (xy 419.15629 -292.455115) (xy 419.171874 -292.501796) (xy 419.179769 -292.550373)
			(xy 419.180259 -292.574726) (xy 419.519112 -292.574726) (xy 419.523072 -292.525672) (xy 419.534849 -292.477888)
			(xy 419.55414 -292.432612) (xy 419.580443 -292.391016) (xy 419.613078 -292.354179) (xy 419.651199 -292.323054)
			(xy 419.69382 -292.298447) (xy 419.739836 -292.280995) (xy 419.788055 -292.271151) (xy 419.83723 -292.26917)
			(xy 419.886085 -292.275102) (xy 419.933356 -292.288794) (xy 419.977818 -292.309892) (xy 420.018321 -292.337848)
			(xy 420.053814 -292.37194) (xy 420.083379 -292.411284) (xy 420.10625 -292.454861) (xy 420.121834 -292.501542)
			(xy 420.129729 -292.550119) (xy 420.130224 -292.574726) (xy 420.469072 -292.574726) (xy 420.473032 -292.525672)
			(xy 420.484809 -292.477888) (xy 420.5041 -292.432612) (xy 420.530403 -292.391016) (xy 420.563038 -292.354179)
			(xy 420.601159 -292.323054) (xy 420.64378 -292.298447) (xy 420.689796 -292.280995) (xy 420.738015 -292.271151)
			(xy 420.78719 -292.26917) (xy 420.836045 -292.275102) (xy 420.883316 -292.288794) (xy 420.927778 -292.309892)
			(xy 420.968281 -292.337848) (xy 421.003774 -292.37194) (xy 421.033339 -292.411284) (xy 421.05621 -292.454861)
			(xy 421.071794 -292.501542) (xy 421.079689 -292.550119) (xy 421.080184 -292.574726) (xy 421.419032 -292.574726)
			(xy 421.422992 -292.525672) (xy 421.434769 -292.477888) (xy 421.45406 -292.432612) (xy 421.480363 -292.391016)
			(xy 421.512998 -292.354179) (xy 421.551119 -292.323054) (xy 421.59374 -292.298447) (xy 421.639756 -292.280995)
			(xy 421.687975 -292.271151) (xy 421.73715 -292.26917) (xy 421.786005 -292.275102) (xy 421.833276 -292.288794)
			(xy 421.877738 -292.309892) (xy 421.918241 -292.337848) (xy 421.953734 -292.37194) (xy 421.983299 -292.411284)
			(xy 422.00617 -292.454861) (xy 422.021754 -292.501542) (xy 422.029649 -292.550119) (xy 422.030144 -292.574726)
			(xy 422.368992 -292.574726) (xy 422.372952 -292.525672) (xy 422.384729 -292.477888) (xy 422.40402 -292.432612)
			(xy 422.430323 -292.391016) (xy 422.462958 -292.354179) (xy 422.501079 -292.323054) (xy 422.5437 -292.298447)
			(xy 422.589716 -292.280995) (xy 422.637935 -292.271151) (xy 422.68711 -292.26917) (xy 422.735965 -292.275102)
			(xy 422.783236 -292.288794) (xy 422.827698 -292.309892) (xy 422.868201 -292.337848) (xy 422.903694 -292.37194)
			(xy 422.933259 -292.411284) (xy 422.95613 -292.454861) (xy 422.971714 -292.501542) (xy 422.979609 -292.550119)
			(xy 422.980104 -292.574726) (xy 423.319206 -292.574726) (xy 423.323166 -292.525672) (xy 423.334943 -292.477888)
			(xy 423.354234 -292.432612) (xy 423.380537 -292.391016) (xy 423.413172 -292.354179) (xy 423.451293 -292.323054)
			(xy 423.493914 -292.298447) (xy 423.53993 -292.280995) (xy 423.588149 -292.271151) (xy 423.637324 -292.26917)
			(xy 423.686179 -292.275102) (xy 423.73345 -292.288794) (xy 423.777912 -292.309892) (xy 423.818415 -292.337848)
			(xy 423.853908 -292.37194) (xy 423.883473 -292.411284) (xy 423.906344 -292.454861) (xy 423.921928 -292.501542)
			(xy 423.929823 -292.550119) (xy 423.930318 -292.574726) (xy 424.269166 -292.574726) (xy 424.273126 -292.525672)
			(xy 424.284903 -292.477888) (xy 424.304194 -292.432612) (xy 424.330497 -292.391016) (xy 424.363132 -292.354179)
			(xy 424.401253 -292.323054) (xy 424.443874 -292.298447) (xy 424.48989 -292.280995) (xy 424.538109 -292.271151)
			(xy 424.587284 -292.26917) (xy 424.636139 -292.275102) (xy 424.68341 -292.288794) (xy 424.727872 -292.309892)
			(xy 424.768375 -292.337848) (xy 424.803868 -292.37194) (xy 424.833433 -292.411284) (xy 424.856304 -292.454861)
			(xy 424.871888 -292.501542) (xy 424.879783 -292.550119) (xy 424.880278 -292.574726) (xy 425.219126 -292.574726)
			(xy 425.223086 -292.525672) (xy 425.234863 -292.477888) (xy 425.254154 -292.432612) (xy 425.280457 -292.391016)
			(xy 425.313092 -292.354179) (xy 425.351213 -292.323054) (xy 425.393834 -292.298447) (xy 425.43985 -292.280995)
			(xy 425.488069 -292.271151) (xy 425.537244 -292.26917) (xy 425.586099 -292.275102) (xy 425.63337 -292.288794)
			(xy 425.677832 -292.309892) (xy 425.718335 -292.337848) (xy 425.753828 -292.37194) (xy 425.783393 -292.411284)
			(xy 425.806264 -292.454861) (xy 425.821848 -292.501542) (xy 425.829743 -292.550119) (xy 425.830238 -292.574726)
			(xy 426.169086 -292.574726) (xy 426.173046 -292.525672) (xy 426.184823 -292.477888) (xy 426.204114 -292.432612)
			(xy 426.230417 -292.391016) (xy 426.263052 -292.354179) (xy 426.301173 -292.323054) (xy 426.343794 -292.298447)
			(xy 426.38981 -292.280995) (xy 426.438029 -292.271151) (xy 426.487204 -292.26917) (xy 426.536059 -292.275102)
			(xy 426.58333 -292.288794) (xy 426.627792 -292.309892) (xy 426.668295 -292.337848) (xy 426.703788 -292.37194)
			(xy 426.733353 -292.411284) (xy 426.756224 -292.454861) (xy 426.771808 -292.501542) (xy 426.779703 -292.550119)
			(xy 426.780198 -292.574726) (xy 427.119046 -292.574726) (xy 427.123006 -292.525672) (xy 427.134783 -292.477888)
			(xy 427.154074 -292.432612) (xy 427.180377 -292.391016) (xy 427.213012 -292.354179) (xy 427.251133 -292.323054)
			(xy 427.293754 -292.298447) (xy 427.33977 -292.280995) (xy 427.387989 -292.271151) (xy 427.437164 -292.26917)
			(xy 427.486019 -292.275102) (xy 427.53329 -292.288794) (xy 427.577752 -292.309892) (xy 427.618255 -292.337848)
			(xy 427.653748 -292.37194) (xy 427.683313 -292.411284) (xy 427.706184 -292.454861) (xy 427.721768 -292.501542)
			(xy 427.729663 -292.550119) (xy 427.730158 -292.574726) (xy 428.069006 -292.574726) (xy 428.072966 -292.525672)
			(xy 428.084743 -292.477888) (xy 428.104034 -292.432612) (xy 428.130337 -292.391016) (xy 428.162972 -292.354179)
			(xy 428.201093 -292.323054) (xy 428.243714 -292.298447) (xy 428.28973 -292.280995) (xy 428.337949 -292.271151)
			(xy 428.387124 -292.26917) (xy 428.435979 -292.275102) (xy 428.48325 -292.288794) (xy 428.527712 -292.309892)
			(xy 428.568215 -292.337848) (xy 428.603708 -292.37194) (xy 428.633273 -292.411284) (xy 428.656144 -292.454861)
			(xy 428.671728 -292.501542) (xy 428.679623 -292.550119) (xy 428.680118 -292.574726) (xy 429.01922 -292.574726)
			(xy 429.02318 -292.525672) (xy 429.034957 -292.477888) (xy 429.054248 -292.432612) (xy 429.080551 -292.391016)
			(xy 429.113186 -292.354179) (xy 429.151307 -292.323054) (xy 429.193928 -292.298447) (xy 429.239944 -292.280995)
			(xy 429.288163 -292.271151) (xy 429.337338 -292.26917) (xy 429.386193 -292.275102) (xy 429.433464 -292.288794)
			(xy 429.477926 -292.309892) (xy 429.518429 -292.337848) (xy 429.553922 -292.37194) (xy 429.583487 -292.411284)
			(xy 429.606358 -292.454861) (xy 429.621942 -292.501542) (xy 429.629837 -292.550119) (xy 429.630332 -292.574726)
			(xy 429.630327 -292.57498) (xy 429.96918 -292.57498) (xy 429.97314 -292.525926) (xy 429.984917 -292.478142)
			(xy 430.004208 -292.432866) (xy 430.030511 -292.39127) (xy 430.063146 -292.354433) (xy 430.101267 -292.323308)
			(xy 430.143888 -292.298701) (xy 430.189904 -292.281249) (xy 430.238123 -292.271405) (xy 430.287298 -292.269424)
			(xy 430.336153 -292.275356) (xy 430.383424 -292.289048) (xy 430.427886 -292.310146) (xy 430.468389 -292.338102)
			(xy 430.503882 -292.372194) (xy 430.533447 -292.411538) (xy 430.556318 -292.455115) (xy 430.571902 -292.501796)
			(xy 430.579797 -292.550373) (xy 430.580292 -292.57498) (xy 430.91914 -292.57498) (xy 430.9231 -292.525926)
			(xy 430.934877 -292.478142) (xy 430.954168 -292.432866) (xy 430.980471 -292.39127) (xy 431.013106 -292.354433)
			(xy 431.051227 -292.323308) (xy 431.093848 -292.298701) (xy 431.139864 -292.281249) (xy 431.188083 -292.271405)
			(xy 431.237258 -292.269424) (xy 431.286113 -292.275356) (xy 431.333384 -292.289048) (xy 431.377846 -292.310146)
			(xy 431.418349 -292.338102) (xy 431.453842 -292.372194) (xy 431.483407 -292.411538) (xy 431.506278 -292.455115)
			(xy 431.521862 -292.501796) (xy 431.529757 -292.550373) (xy 431.530252 -292.57498) (xy 431.529757 -292.599587)
			(xy 431.521862 -292.648164) (xy 431.506278 -292.694845) (xy 431.483407 -292.738422) (xy 431.453842 -292.777766)
			(xy 431.418349 -292.811858) (xy 431.377846 -292.839814) (xy 431.333384 -292.860912) (xy 431.286113 -292.874604)
			(xy 431.237258 -292.880536) (xy 431.188083 -292.878555) (xy 431.139864 -292.868711) (xy 431.093848 -292.851259)
			(xy 431.051227 -292.826652) (xy 431.013106 -292.795527) (xy 430.980471 -292.75869) (xy 430.954168 -292.717094)
			(xy 430.934877 -292.671818) (xy 430.9231 -292.624034) (xy 430.91914 -292.57498) (xy 430.580292 -292.57498)
			(xy 430.579797 -292.599587) (xy 430.571902 -292.648164) (xy 430.556318 -292.694845) (xy 430.533447 -292.738422)
			(xy 430.503882 -292.777766) (xy 430.468389 -292.811858) (xy 430.427886 -292.839814) (xy 430.383424 -292.860912)
			(xy 430.336153 -292.874604) (xy 430.287298 -292.880536) (xy 430.238123 -292.878555) (xy 430.189904 -292.868711)
			(xy 430.143888 -292.851259) (xy 430.101267 -292.826652) (xy 430.063146 -292.795527) (xy 430.030511 -292.75869)
			(xy 430.004208 -292.717094) (xy 429.984917 -292.671818) (xy 429.97314 -292.624034) (xy 429.96918 -292.57498)
			(xy 429.630327 -292.57498) (xy 429.629837 -292.599333) (xy 429.621942 -292.64791) (xy 429.606358 -292.694591)
			(xy 429.583487 -292.738168) (xy 429.553922 -292.777512) (xy 429.518429 -292.811604) (xy 429.477926 -292.83956)
			(xy 429.433464 -292.860658) (xy 429.386193 -292.87435) (xy 429.337338 -292.880282) (xy 429.288163 -292.878301)
			(xy 429.239944 -292.868457) (xy 429.193928 -292.851005) (xy 429.151307 -292.826398) (xy 429.113186 -292.795273)
			(xy 429.080551 -292.758436) (xy 429.054248 -292.71684) (xy 429.034957 -292.671564) (xy 429.02318 -292.62378)
			(xy 429.01922 -292.574726) (xy 428.680118 -292.574726) (xy 428.679623 -292.599333) (xy 428.671728 -292.64791)
			(xy 428.656144 -292.694591) (xy 428.633273 -292.738168) (xy 428.603708 -292.777512) (xy 428.568215 -292.811604)
			(xy 428.527712 -292.83956) (xy 428.48325 -292.860658) (xy 428.435979 -292.87435) (xy 428.387124 -292.880282)
			(xy 428.337949 -292.878301) (xy 428.28973 -292.868457) (xy 428.243714 -292.851005) (xy 428.201093 -292.826398)
			(xy 428.162972 -292.795273) (xy 428.130337 -292.758436) (xy 428.104034 -292.71684) (xy 428.084743 -292.671564)
			(xy 428.072966 -292.62378) (xy 428.069006 -292.574726) (xy 427.730158 -292.574726) (xy 427.729663 -292.599333)
			(xy 427.721768 -292.64791) (xy 427.706184 -292.694591) (xy 427.683313 -292.738168) (xy 427.653748 -292.777512)
			(xy 427.618255 -292.811604) (xy 427.577752 -292.83956) (xy 427.53329 -292.860658) (xy 427.486019 -292.87435)
			(xy 427.437164 -292.880282) (xy 427.387989 -292.878301) (xy 427.33977 -292.868457) (xy 427.293754 -292.851005)
			(xy 427.251133 -292.826398) (xy 427.213012 -292.795273) (xy 427.180377 -292.758436) (xy 427.154074 -292.71684)
			(xy 427.134783 -292.671564) (xy 427.123006 -292.62378) (xy 427.119046 -292.574726) (xy 426.780198 -292.574726)
			(xy 426.779703 -292.599333) (xy 426.771808 -292.64791) (xy 426.756224 -292.694591) (xy 426.733353 -292.738168)
			(xy 426.703788 -292.777512) (xy 426.668295 -292.811604) (xy 426.627792 -292.83956) (xy 426.58333 -292.860658)
			(xy 426.536059 -292.87435) (xy 426.487204 -292.880282) (xy 426.438029 -292.878301) (xy 426.38981 -292.868457)
			(xy 426.343794 -292.851005) (xy 426.301173 -292.826398) (xy 426.263052 -292.795273) (xy 426.230417 -292.758436)
			(xy 426.204114 -292.71684) (xy 426.184823 -292.671564) (xy 426.173046 -292.62378) (xy 426.169086 -292.574726)
			(xy 425.830238 -292.574726) (xy 425.829743 -292.599333) (xy 425.821848 -292.64791) (xy 425.806264 -292.694591)
			(xy 425.783393 -292.738168) (xy 425.753828 -292.777512) (xy 425.718335 -292.811604) (xy 425.677832 -292.83956)
			(xy 425.63337 -292.860658) (xy 425.586099 -292.87435) (xy 425.537244 -292.880282) (xy 425.488069 -292.878301)
			(xy 425.43985 -292.868457) (xy 425.393834 -292.851005) (xy 425.351213 -292.826398) (xy 425.313092 -292.795273)
			(xy 425.280457 -292.758436) (xy 425.254154 -292.71684) (xy 425.234863 -292.671564) (xy 425.223086 -292.62378)
			(xy 425.219126 -292.574726) (xy 424.880278 -292.574726) (xy 424.879783 -292.599333) (xy 424.871888 -292.64791)
			(xy 424.856304 -292.694591) (xy 424.833433 -292.738168) (xy 424.803868 -292.777512) (xy 424.768375 -292.811604)
			(xy 424.727872 -292.83956) (xy 424.68341 -292.860658) (xy 424.636139 -292.87435) (xy 424.587284 -292.880282)
			(xy 424.538109 -292.878301) (xy 424.48989 -292.868457) (xy 424.443874 -292.851005) (xy 424.401253 -292.826398)
			(xy 424.363132 -292.795273) (xy 424.330497 -292.758436) (xy 424.304194 -292.71684) (xy 424.284903 -292.671564)
			(xy 424.273126 -292.62378) (xy 424.269166 -292.574726) (xy 423.930318 -292.574726) (xy 423.929823 -292.599333)
			(xy 423.921928 -292.64791) (xy 423.906344 -292.694591) (xy 423.883473 -292.738168) (xy 423.853908 -292.777512)
			(xy 423.818415 -292.811604) (xy 423.777912 -292.83956) (xy 423.73345 -292.860658) (xy 423.686179 -292.87435)
			(xy 423.637324 -292.880282) (xy 423.588149 -292.878301) (xy 423.53993 -292.868457) (xy 423.493914 -292.851005)
			(xy 423.451293 -292.826398) (xy 423.413172 -292.795273) (xy 423.380537 -292.758436) (xy 423.354234 -292.71684)
			(xy 423.334943 -292.671564) (xy 423.323166 -292.62378) (xy 423.319206 -292.574726) (xy 422.980104 -292.574726)
			(xy 422.979609 -292.599333) (xy 422.971714 -292.64791) (xy 422.95613 -292.694591) (xy 422.933259 -292.738168)
			(xy 422.903694 -292.777512) (xy 422.868201 -292.811604) (xy 422.827698 -292.83956) (xy 422.783236 -292.860658)
			(xy 422.735965 -292.87435) (xy 422.68711 -292.880282) (xy 422.637935 -292.878301) (xy 422.589716 -292.868457)
			(xy 422.5437 -292.851005) (xy 422.501079 -292.826398) (xy 422.462958 -292.795273) (xy 422.430323 -292.758436)
			(xy 422.40402 -292.71684) (xy 422.384729 -292.671564) (xy 422.372952 -292.62378) (xy 422.368992 -292.574726)
			(xy 422.030144 -292.574726) (xy 422.029649 -292.599333) (xy 422.021754 -292.64791) (xy 422.00617 -292.694591)
			(xy 421.983299 -292.738168) (xy 421.953734 -292.777512) (xy 421.918241 -292.811604) (xy 421.877738 -292.83956)
			(xy 421.833276 -292.860658) (xy 421.786005 -292.87435) (xy 421.73715 -292.880282) (xy 421.687975 -292.878301)
			(xy 421.639756 -292.868457) (xy 421.59374 -292.851005) (xy 421.551119 -292.826398) (xy 421.512998 -292.795273)
			(xy 421.480363 -292.758436) (xy 421.45406 -292.71684) (xy 421.434769 -292.671564) (xy 421.422992 -292.62378)
			(xy 421.419032 -292.574726) (xy 421.080184 -292.574726) (xy 421.079689 -292.599333) (xy 421.071794 -292.64791)
			(xy 421.05621 -292.694591) (xy 421.033339 -292.738168) (xy 421.003774 -292.777512) (xy 420.968281 -292.811604)
			(xy 420.927778 -292.83956) (xy 420.883316 -292.860658) (xy 420.836045 -292.87435) (xy 420.78719 -292.880282)
			(xy 420.738015 -292.878301) (xy 420.689796 -292.868457) (xy 420.64378 -292.851005) (xy 420.601159 -292.826398)
			(xy 420.563038 -292.795273) (xy 420.530403 -292.758436) (xy 420.5041 -292.71684) (xy 420.484809 -292.671564)
			(xy 420.473032 -292.62378) (xy 420.469072 -292.574726) (xy 420.130224 -292.574726) (xy 420.129729 -292.599333)
			(xy 420.121834 -292.64791) (xy 420.10625 -292.694591) (xy 420.083379 -292.738168) (xy 420.053814 -292.777512)
			(xy 420.018321 -292.811604) (xy 419.977818 -292.83956) (xy 419.933356 -292.860658) (xy 419.886085 -292.87435)
			(xy 419.83723 -292.880282) (xy 419.788055 -292.878301) (xy 419.739836 -292.868457) (xy 419.69382 -292.851005)
			(xy 419.651199 -292.826398) (xy 419.613078 -292.795273) (xy 419.580443 -292.758436) (xy 419.55414 -292.71684)
			(xy 419.534849 -292.671564) (xy 419.523072 -292.62378) (xy 419.519112 -292.574726) (xy 419.180259 -292.574726)
			(xy 419.180264 -292.57498) (xy 419.179769 -292.599587) (xy 419.171874 -292.648164) (xy 419.15629 -292.694845)
			(xy 419.133419 -292.738422) (xy 419.103854 -292.777766) (xy 419.068361 -292.811858) (xy 419.027858 -292.839814)
			(xy 418.983396 -292.860912) (xy 418.936125 -292.874604) (xy 418.88727 -292.880536) (xy 418.838095 -292.878555)
			(xy 418.789876 -292.868711) (xy 418.74386 -292.851259) (xy 418.701239 -292.826652) (xy 418.663118 -292.795527)
			(xy 418.630483 -292.75869) (xy 418.60418 -292.717094) (xy 418.584889 -292.671818) (xy 418.573112 -292.624034)
			(xy 418.569152 -292.57498) (xy 418.256124 -292.57498) (xy 418.252398 -292.624368) (xy 418.241249 -292.672898)
			(xy 418.222949 -292.719207) (xy 418.197913 -292.76225) (xy 418.166705 -292.801051) (xy 418.130033 -292.834734)
			(xy 418.109654 -292.849046) (xy 418.099681 -292.856528) (xy 418.087971 -292.878505) (xy 418.087302 -292.890956)
			(xy 418.087302 -293.20871) (xy 418.087988 -293.221155) (xy 418.099695 -293.243127) (xy 418.109654 -293.25062)
			(xy 418.130054 -293.264898) (xy 418.166722 -293.298584) (xy 418.197924 -293.337387) (xy 418.222955 -293.380431)
			(xy 418.241249 -293.426741) (xy 418.252392 -293.475271) (xy 418.256132 -293.524922) (xy 418.256131 -293.52494)
			(xy 418.569152 -293.52494) (xy 418.573112 -293.475886) (xy 418.584889 -293.428102) (xy 418.60418 -293.382826)
			(xy 418.630483 -293.34123) (xy 418.663118 -293.304393) (xy 418.701239 -293.273268) (xy 418.74386 -293.248661)
			(xy 418.789876 -293.231209) (xy 418.838095 -293.221365) (xy 418.88727 -293.219384) (xy 418.936125 -293.225316)
			(xy 418.983396 -293.239008) (xy 419.027858 -293.260106) (xy 419.068361 -293.288062) (xy 419.103854 -293.322154)
			(xy 419.133419 -293.361498) (xy 419.15629 -293.405075) (xy 419.171874 -293.451756) (xy 419.179769 -293.500333)
			(xy 419.180264 -293.52494) (xy 419.519112 -293.52494) (xy 419.523072 -293.475886) (xy 419.534849 -293.428102)
			(xy 419.55414 -293.382826) (xy 419.580443 -293.34123) (xy 419.613078 -293.304393) (xy 419.651199 -293.273268)
			(xy 419.69382 -293.248661) (xy 419.739836 -293.231209) (xy 419.788055 -293.221365) (xy 419.83723 -293.219384)
			(xy 419.886085 -293.225316) (xy 419.933356 -293.239008) (xy 419.977818 -293.260106) (xy 420.018321 -293.288062)
			(xy 420.053814 -293.322154) (xy 420.083379 -293.361498) (xy 420.10625 -293.405075) (xy 420.121834 -293.451756)
			(xy 420.129729 -293.500333) (xy 420.130224 -293.52494) (xy 420.469072 -293.52494) (xy 420.473032 -293.475886)
			(xy 420.484809 -293.428102) (xy 420.5041 -293.382826) (xy 420.530403 -293.34123) (xy 420.563038 -293.304393)
			(xy 420.601159 -293.273268) (xy 420.64378 -293.248661) (xy 420.689796 -293.231209) (xy 420.738015 -293.221365)
			(xy 420.78719 -293.219384) (xy 420.836045 -293.225316) (xy 420.883316 -293.239008) (xy 420.927778 -293.260106)
			(xy 420.968281 -293.288062) (xy 421.003774 -293.322154) (xy 421.033339 -293.361498) (xy 421.05621 -293.405075)
			(xy 421.071794 -293.451756) (xy 421.079689 -293.500333) (xy 421.080184 -293.52494) (xy 421.419032 -293.52494)
			(xy 421.422992 -293.475886) (xy 421.434769 -293.428102) (xy 421.45406 -293.382826) (xy 421.480363 -293.34123)
			(xy 421.512998 -293.304393) (xy 421.551119 -293.273268) (xy 421.59374 -293.248661) (xy 421.639756 -293.231209)
			(xy 421.687975 -293.221365) (xy 421.73715 -293.219384) (xy 421.786005 -293.225316) (xy 421.833276 -293.239008)
			(xy 421.877738 -293.260106) (xy 421.918241 -293.288062) (xy 421.953734 -293.322154) (xy 421.983299 -293.361498)
			(xy 422.00617 -293.405075) (xy 422.021754 -293.451756) (xy 422.029649 -293.500333) (xy 422.030144 -293.52494)
			(xy 422.369246 -293.52494) (xy 422.373206 -293.475886) (xy 422.384983 -293.428102) (xy 422.404274 -293.382826)
			(xy 422.430577 -293.34123) (xy 422.463212 -293.304393) (xy 422.501333 -293.273268) (xy 422.543954 -293.248661)
			(xy 422.58997 -293.231209) (xy 422.638189 -293.221365) (xy 422.687364 -293.219384) (xy 422.736219 -293.225316)
			(xy 422.78349 -293.239008) (xy 422.827952 -293.260106) (xy 422.868455 -293.288062) (xy 422.903948 -293.322154)
			(xy 422.933513 -293.361498) (xy 422.956384 -293.405075) (xy 422.971968 -293.451756) (xy 422.979863 -293.500333)
			(xy 422.980358 -293.52494) (xy 423.319206 -293.52494) (xy 423.323166 -293.475886) (xy 423.334943 -293.428102)
			(xy 423.354234 -293.382826) (xy 423.380537 -293.34123) (xy 423.413172 -293.304393) (xy 423.451293 -293.273268)
			(xy 423.493914 -293.248661) (xy 423.53993 -293.231209) (xy 423.588149 -293.221365) (xy 423.637324 -293.219384)
			(xy 423.686179 -293.225316) (xy 423.73345 -293.239008) (xy 423.777912 -293.260106) (xy 423.818415 -293.288062)
			(xy 423.853908 -293.322154) (xy 423.883473 -293.361498) (xy 423.906344 -293.405075) (xy 423.921928 -293.451756)
			(xy 423.929823 -293.500333) (xy 423.930318 -293.52494) (xy 424.269166 -293.52494) (xy 424.273126 -293.475886)
			(xy 424.284903 -293.428102) (xy 424.304194 -293.382826) (xy 424.330497 -293.34123) (xy 424.363132 -293.304393)
			(xy 424.401253 -293.273268) (xy 424.443874 -293.248661) (xy 424.48989 -293.231209) (xy 424.538109 -293.221365)
			(xy 424.587284 -293.219384) (xy 424.636139 -293.225316) (xy 424.68341 -293.239008) (xy 424.727872 -293.260106)
			(xy 424.768375 -293.288062) (xy 424.803868 -293.322154) (xy 424.833433 -293.361498) (xy 424.856304 -293.405075)
			(xy 424.871888 -293.451756) (xy 424.879783 -293.500333) (xy 424.880278 -293.52494) (xy 425.219126 -293.52494)
			(xy 425.223086 -293.475886) (xy 425.234863 -293.428102) (xy 425.254154 -293.382826) (xy 425.280457 -293.34123)
			(xy 425.313092 -293.304393) (xy 425.351213 -293.273268) (xy 425.393834 -293.248661) (xy 425.43985 -293.231209)
			(xy 425.488069 -293.221365) (xy 425.537244 -293.219384) (xy 425.586099 -293.225316) (xy 425.63337 -293.239008)
			(xy 425.677832 -293.260106) (xy 425.718335 -293.288062) (xy 425.753828 -293.322154) (xy 425.783393 -293.361498)
			(xy 425.806264 -293.405075) (xy 425.821848 -293.451756) (xy 425.829743 -293.500333) (xy 425.830238 -293.52494)
			(xy 426.169086 -293.52494) (xy 426.173046 -293.475886) (xy 426.184823 -293.428102) (xy 426.204114 -293.382826)
			(xy 426.230417 -293.34123) (xy 426.263052 -293.304393) (xy 426.301173 -293.273268) (xy 426.343794 -293.248661)
			(xy 426.38981 -293.231209) (xy 426.438029 -293.221365) (xy 426.487204 -293.219384) (xy 426.536059 -293.225316)
			(xy 426.58333 -293.239008) (xy 426.627792 -293.260106) (xy 426.668295 -293.288062) (xy 426.703788 -293.322154)
			(xy 426.733353 -293.361498) (xy 426.756224 -293.405075) (xy 426.771808 -293.451756) (xy 426.779703 -293.500333)
			(xy 426.780198 -293.52494) (xy 427.119046 -293.52494) (xy 427.123006 -293.475886) (xy 427.134783 -293.428102)
			(xy 427.154074 -293.382826) (xy 427.180377 -293.34123) (xy 427.213012 -293.304393) (xy 427.251133 -293.273268)
			(xy 427.293754 -293.248661) (xy 427.33977 -293.231209) (xy 427.387989 -293.221365) (xy 427.437164 -293.219384)
			(xy 427.486019 -293.225316) (xy 427.53329 -293.239008) (xy 427.577752 -293.260106) (xy 427.618255 -293.288062)
			(xy 427.653748 -293.322154) (xy 427.683313 -293.361498) (xy 427.706184 -293.405075) (xy 427.721768 -293.451756)
			(xy 427.729663 -293.500333) (xy 427.730158 -293.52494) (xy 428.069006 -293.52494) (xy 428.072966 -293.475886)
			(xy 428.084743 -293.428102) (xy 428.104034 -293.382826) (xy 428.130337 -293.34123) (xy 428.162972 -293.304393)
			(xy 428.201093 -293.273268) (xy 428.243714 -293.248661) (xy 428.28973 -293.231209) (xy 428.337949 -293.221365)
			(xy 428.387124 -293.219384) (xy 428.435979 -293.225316) (xy 428.48325 -293.239008) (xy 428.527712 -293.260106)
			(xy 428.568215 -293.288062) (xy 428.603708 -293.322154) (xy 428.633273 -293.361498) (xy 428.656144 -293.405075)
			(xy 428.671728 -293.451756) (xy 428.679623 -293.500333) (xy 428.680118 -293.52494) (xy 429.01922 -293.52494)
			(xy 429.02318 -293.475886) (xy 429.034957 -293.428102) (xy 429.054248 -293.382826) (xy 429.080551 -293.34123)
			(xy 429.113186 -293.304393) (xy 429.151307 -293.273268) (xy 429.193928 -293.248661) (xy 429.239944 -293.231209)
			(xy 429.288163 -293.221365) (xy 429.337338 -293.219384) (xy 429.386193 -293.225316) (xy 429.433464 -293.239008)
			(xy 429.477926 -293.260106) (xy 429.518429 -293.288062) (xy 429.553922 -293.322154) (xy 429.583487 -293.361498)
			(xy 429.606358 -293.405075) (xy 429.621942 -293.451756) (xy 429.629837 -293.500333) (xy 429.630332 -293.52494)
			(xy 429.96918 -293.52494) (xy 429.97314 -293.475886) (xy 429.984917 -293.428102) (xy 430.004208 -293.382826)
			(xy 430.030511 -293.34123) (xy 430.063146 -293.304393) (xy 430.101267 -293.273268) (xy 430.143888 -293.248661)
			(xy 430.189904 -293.231209) (xy 430.238123 -293.221365) (xy 430.287298 -293.219384) (xy 430.336153 -293.225316)
			(xy 430.383424 -293.239008) (xy 430.427886 -293.260106) (xy 430.468389 -293.288062) (xy 430.503882 -293.322154)
			(xy 430.533447 -293.361498) (xy 430.556318 -293.405075) (xy 430.571902 -293.451756) (xy 430.579797 -293.500333)
			(xy 430.580292 -293.52494) (xy 430.91914 -293.52494) (xy 430.9231 -293.475886) (xy 430.934877 -293.428102)
			(xy 430.954168 -293.382826) (xy 430.980471 -293.34123) (xy 431.013106 -293.304393) (xy 431.051227 -293.273268)
			(xy 431.093848 -293.248661) (xy 431.139864 -293.231209) (xy 431.188083 -293.221365) (xy 431.237258 -293.219384)
			(xy 431.286113 -293.225316) (xy 431.333384 -293.239008) (xy 431.377846 -293.260106) (xy 431.418349 -293.288062)
			(xy 431.453842 -293.322154) (xy 431.483407 -293.361498) (xy 431.506278 -293.405075) (xy 431.521862 -293.451756)
			(xy 431.529757 -293.500333) (xy 431.530252 -293.52494) (xy 431.529757 -293.549547) (xy 431.521862 -293.598124)
			(xy 431.506278 -293.644805) (xy 431.483407 -293.688382) (xy 431.453842 -293.727726) (xy 431.418349 -293.761818)
			(xy 431.377846 -293.789774) (xy 431.333384 -293.810872) (xy 431.286113 -293.824564) (xy 431.237258 -293.830496)
			(xy 431.188083 -293.828515) (xy 431.139864 -293.818671) (xy 431.093848 -293.801219) (xy 431.051227 -293.776612)
			(xy 431.013106 -293.745487) (xy 430.980471 -293.70865) (xy 430.954168 -293.667054) (xy 430.934877 -293.621778)
			(xy 430.9231 -293.573994) (xy 430.91914 -293.52494) (xy 430.580292 -293.52494) (xy 430.579797 -293.549547)
			(xy 430.571902 -293.598124) (xy 430.556318 -293.644805) (xy 430.533447 -293.688382) (xy 430.503882 -293.727726)
			(xy 430.468389 -293.761818) (xy 430.427886 -293.789774) (xy 430.383424 -293.810872) (xy 430.336153 -293.824564)
			(xy 430.287298 -293.830496) (xy 430.238123 -293.828515) (xy 430.189904 -293.818671) (xy 430.143888 -293.801219)
			(xy 430.101267 -293.776612) (xy 430.063146 -293.745487) (xy 430.030511 -293.70865) (xy 430.004208 -293.667054)
			(xy 429.984917 -293.621778) (xy 429.97314 -293.573994) (xy 429.96918 -293.52494) (xy 429.630332 -293.52494)
			(xy 429.629837 -293.549547) (xy 429.621942 -293.598124) (xy 429.606358 -293.644805) (xy 429.583487 -293.688382)
			(xy 429.553922 -293.727726) (xy 429.518429 -293.761818) (xy 429.477926 -293.789774) (xy 429.433464 -293.810872)
			(xy 429.386193 -293.824564) (xy 429.337338 -293.830496) (xy 429.288163 -293.828515) (xy 429.239944 -293.818671)
			(xy 429.193928 -293.801219) (xy 429.151307 -293.776612) (xy 429.113186 -293.745487) (xy 429.080551 -293.70865)
			(xy 429.054248 -293.667054) (xy 429.034957 -293.621778) (xy 429.02318 -293.573994) (xy 429.01922 -293.52494)
			(xy 428.680118 -293.52494) (xy 428.679623 -293.549547) (xy 428.671728 -293.598124) (xy 428.656144 -293.644805)
			(xy 428.633273 -293.688382) (xy 428.603708 -293.727726) (xy 428.568215 -293.761818) (xy 428.527712 -293.789774)
			(xy 428.48325 -293.810872) (xy 428.435979 -293.824564) (xy 428.387124 -293.830496) (xy 428.337949 -293.828515)
			(xy 428.28973 -293.818671) (xy 428.243714 -293.801219) (xy 428.201093 -293.776612) (xy 428.162972 -293.745487)
			(xy 428.130337 -293.70865) (xy 428.104034 -293.667054) (xy 428.084743 -293.621778) (xy 428.072966 -293.573994)
			(xy 428.069006 -293.52494) (xy 427.730158 -293.52494) (xy 427.729663 -293.549547) (xy 427.721768 -293.598124)
			(xy 427.706184 -293.644805) (xy 427.683313 -293.688382) (xy 427.653748 -293.727726) (xy 427.618255 -293.761818)
			(xy 427.577752 -293.789774) (xy 427.53329 -293.810872) (xy 427.486019 -293.824564) (xy 427.437164 -293.830496)
			(xy 427.387989 -293.828515) (xy 427.33977 -293.818671) (xy 427.293754 -293.801219) (xy 427.251133 -293.776612)
			(xy 427.213012 -293.745487) (xy 427.180377 -293.70865) (xy 427.154074 -293.667054) (xy 427.134783 -293.621778)
			(xy 427.123006 -293.573994) (xy 427.119046 -293.52494) (xy 426.780198 -293.52494) (xy 426.779703 -293.549547)
			(xy 426.771808 -293.598124) (xy 426.756224 -293.644805) (xy 426.733353 -293.688382) (xy 426.703788 -293.727726)
			(xy 426.668295 -293.761818) (xy 426.627792 -293.789774) (xy 426.58333 -293.810872) (xy 426.536059 -293.824564)
			(xy 426.487204 -293.830496) (xy 426.438029 -293.828515) (xy 426.38981 -293.818671) (xy 426.343794 -293.801219)
			(xy 426.301173 -293.776612) (xy 426.263052 -293.745487) (xy 426.230417 -293.70865) (xy 426.204114 -293.667054)
			(xy 426.184823 -293.621778) (xy 426.173046 -293.573994) (xy 426.169086 -293.52494) (xy 425.830238 -293.52494)
			(xy 425.829743 -293.549547) (xy 425.821848 -293.598124) (xy 425.806264 -293.644805) (xy 425.783393 -293.688382)
			(xy 425.753828 -293.727726) (xy 425.718335 -293.761818) (xy 425.677832 -293.789774) (xy 425.63337 -293.810872)
			(xy 425.586099 -293.824564) (xy 425.537244 -293.830496) (xy 425.488069 -293.828515) (xy 425.43985 -293.818671)
			(xy 425.393834 -293.801219) (xy 425.351213 -293.776612) (xy 425.313092 -293.745487) (xy 425.280457 -293.70865)
			(xy 425.254154 -293.667054) (xy 425.234863 -293.621778) (xy 425.223086 -293.573994) (xy 425.219126 -293.52494)
			(xy 424.880278 -293.52494) (xy 424.879783 -293.549547) (xy 424.871888 -293.598124) (xy 424.856304 -293.644805)
			(xy 424.833433 -293.688382) (xy 424.803868 -293.727726) (xy 424.768375 -293.761818) (xy 424.727872 -293.789774)
			(xy 424.68341 -293.810872) (xy 424.636139 -293.824564) (xy 424.587284 -293.830496) (xy 424.538109 -293.828515)
			(xy 424.48989 -293.818671) (xy 424.443874 -293.801219) (xy 424.401253 -293.776612) (xy 424.363132 -293.745487)
			(xy 424.330497 -293.70865) (xy 424.304194 -293.667054) (xy 424.284903 -293.621778) (xy 424.273126 -293.573994)
			(xy 424.269166 -293.52494) (xy 423.930318 -293.52494) (xy 423.929823 -293.549547) (xy 423.921928 -293.598124)
			(xy 423.906344 -293.644805) (xy 423.883473 -293.688382) (xy 423.853908 -293.727726) (xy 423.818415 -293.761818)
			(xy 423.777912 -293.789774) (xy 423.73345 -293.810872) (xy 423.686179 -293.824564) (xy 423.637324 -293.830496)
			(xy 423.588149 -293.828515) (xy 423.53993 -293.818671) (xy 423.493914 -293.801219) (xy 423.451293 -293.776612)
			(xy 423.413172 -293.745487) (xy 423.380537 -293.70865) (xy 423.354234 -293.667054) (xy 423.334943 -293.621778)
			(xy 423.323166 -293.573994) (xy 423.319206 -293.52494) (xy 422.980358 -293.52494) (xy 422.979863 -293.549547)
			(xy 422.971968 -293.598124) (xy 422.956384 -293.644805) (xy 422.933513 -293.688382) (xy 422.903948 -293.727726)
			(xy 422.868455 -293.761818) (xy 422.827952 -293.789774) (xy 422.78349 -293.810872) (xy 422.736219 -293.824564)
			(xy 422.687364 -293.830496) (xy 422.638189 -293.828515) (xy 422.58997 -293.818671) (xy 422.543954 -293.801219)
			(xy 422.501333 -293.776612) (xy 422.463212 -293.745487) (xy 422.430577 -293.70865) (xy 422.404274 -293.667054)
			(xy 422.384983 -293.621778) (xy 422.373206 -293.573994) (xy 422.369246 -293.52494) (xy 422.030144 -293.52494)
			(xy 422.029649 -293.549547) (xy 422.021754 -293.598124) (xy 422.00617 -293.644805) (xy 421.983299 -293.688382)
			(xy 421.953734 -293.727726) (xy 421.918241 -293.761818) (xy 421.877738 -293.789774) (xy 421.833276 -293.810872)
			(xy 421.786005 -293.824564) (xy 421.73715 -293.830496) (xy 421.687975 -293.828515) (xy 421.639756 -293.818671)
			(xy 421.59374 -293.801219) (xy 421.551119 -293.776612) (xy 421.512998 -293.745487) (xy 421.480363 -293.70865)
			(xy 421.45406 -293.667054) (xy 421.434769 -293.621778) (xy 421.422992 -293.573994) (xy 421.419032 -293.52494)
			(xy 421.080184 -293.52494) (xy 421.079689 -293.549547) (xy 421.071794 -293.598124) (xy 421.05621 -293.644805)
			(xy 421.033339 -293.688382) (xy 421.003774 -293.727726) (xy 420.968281 -293.761818) (xy 420.927778 -293.789774)
			(xy 420.883316 -293.810872) (xy 420.836045 -293.824564) (xy 420.78719 -293.830496) (xy 420.738015 -293.828515)
			(xy 420.689796 -293.818671) (xy 420.64378 -293.801219) (xy 420.601159 -293.776612) (xy 420.563038 -293.745487)
			(xy 420.530403 -293.70865) (xy 420.5041 -293.667054) (xy 420.484809 -293.621778) (xy 420.473032 -293.573994)
			(xy 420.469072 -293.52494) (xy 420.130224 -293.52494) (xy 420.129729 -293.549547) (xy 420.121834 -293.598124)
			(xy 420.10625 -293.644805) (xy 420.083379 -293.688382) (xy 420.053814 -293.727726) (xy 420.018321 -293.761818)
			(xy 419.977818 -293.789774) (xy 419.933356 -293.810872) (xy 419.886085 -293.824564) (xy 419.83723 -293.830496)
			(xy 419.788055 -293.828515) (xy 419.739836 -293.818671) (xy 419.69382 -293.801219) (xy 419.651199 -293.776612)
			(xy 419.613078 -293.745487) (xy 419.580443 -293.70865) (xy 419.55414 -293.667054) (xy 419.534849 -293.621778)
			(xy 419.523072 -293.573994) (xy 419.519112 -293.52494) (xy 419.180264 -293.52494) (xy 419.179769 -293.549547)
			(xy 419.171874 -293.598124) (xy 419.15629 -293.644805) (xy 419.133419 -293.688382) (xy 419.103854 -293.727726)
			(xy 419.068361 -293.761818) (xy 419.027858 -293.789774) (xy 418.983396 -293.810872) (xy 418.936125 -293.824564)
			(xy 418.88727 -293.830496) (xy 418.838095 -293.828515) (xy 418.789876 -293.818671) (xy 418.74386 -293.801219)
			(xy 418.701239 -293.776612) (xy 418.663118 -293.745487) (xy 418.630483 -293.70865) (xy 418.60418 -293.667054)
			(xy 418.584889 -293.621778) (xy 418.573112 -293.573994) (xy 418.569152 -293.52494) (xy 418.256131 -293.52494)
			(xy 418.252385 -293.574574) (xy 418.241236 -293.623102) (xy 418.222936 -293.669409) (xy 418.197899 -293.712449)
			(xy 418.166692 -293.751249) (xy 418.130019 -293.78493) (xy 418.109654 -293.79926) (xy 418.099683 -293.806743)
			(xy 418.087979 -293.82872) (xy 418.087302 -293.84117) (xy 418.087302 -294.15867) (xy 418.088134 -294.171074)
			(xy 418.099824 -294.192967) (xy 418.109654 -294.20058) (xy 418.130057 -294.214858) (xy 418.166731 -294.248545)
			(xy 418.197939 -294.28735) (xy 418.222975 -294.330396) (xy 418.241274 -294.37671) (xy 418.252421 -294.425244)
			(xy 418.256165 -294.4749) (xy 418.569152 -294.4749) (xy 418.573112 -294.425846) (xy 418.584889 -294.378062)
			(xy 418.60418 -294.332786) (xy 418.630483 -294.29119) (xy 418.663118 -294.254353) (xy 418.701239 -294.223228)
			(xy 418.74386 -294.198621) (xy 418.789876 -294.181169) (xy 418.838095 -294.171325) (xy 418.88727 -294.169344)
			(xy 418.936125 -294.175276) (xy 418.983396 -294.188968) (xy 419.027858 -294.210066) (xy 419.068361 -294.238022)
			(xy 419.103854 -294.272114) (xy 419.133419 -294.311458) (xy 419.15629 -294.355035) (xy 419.171874 -294.401716)
			(xy 419.179769 -294.450293) (xy 419.180264 -294.4749) (xy 419.519112 -294.4749) (xy 419.523072 -294.425846)
			(xy 419.534849 -294.378062) (xy 419.55414 -294.332786) (xy 419.580443 -294.29119) (xy 419.613078 -294.254353)
			(xy 419.651199 -294.223228) (xy 419.69382 -294.198621) (xy 419.739836 -294.181169) (xy 419.788055 -294.171325)
			(xy 419.83723 -294.169344) (xy 419.886085 -294.175276) (xy 419.933356 -294.188968) (xy 419.977818 -294.210066)
			(xy 420.018321 -294.238022) (xy 420.053814 -294.272114) (xy 420.083379 -294.311458) (xy 420.10625 -294.355035)
			(xy 420.121834 -294.401716) (xy 420.129729 -294.450293) (xy 420.130224 -294.4749) (xy 420.469072 -294.4749)
			(xy 420.473032 -294.425846) (xy 420.484809 -294.378062) (xy 420.5041 -294.332786) (xy 420.530403 -294.29119)
			(xy 420.563038 -294.254353) (xy 420.601159 -294.223228) (xy 420.64378 -294.198621) (xy 420.689796 -294.181169)
			(xy 420.738015 -294.171325) (xy 420.78719 -294.169344) (xy 420.836045 -294.175276) (xy 420.883316 -294.188968)
			(xy 420.927778 -294.210066) (xy 420.968281 -294.238022) (xy 421.003774 -294.272114) (xy 421.033339 -294.311458)
			(xy 421.05621 -294.355035) (xy 421.071794 -294.401716) (xy 421.079689 -294.450293) (xy 421.080184 -294.4749)
			(xy 421.419032 -294.4749) (xy 421.422992 -294.425846) (xy 421.434769 -294.378062) (xy 421.45406 -294.332786)
			(xy 421.480363 -294.29119) (xy 421.512998 -294.254353) (xy 421.551119 -294.223228) (xy 421.59374 -294.198621)
			(xy 421.639756 -294.181169) (xy 421.687975 -294.171325) (xy 421.73715 -294.169344) (xy 421.786005 -294.175276)
			(xy 421.833276 -294.188968) (xy 421.877738 -294.210066) (xy 421.918241 -294.238022) (xy 421.953734 -294.272114)
			(xy 421.983299 -294.311458) (xy 422.00617 -294.355035) (xy 422.021754 -294.401716) (xy 422.029649 -294.450293)
			(xy 422.030144 -294.4749) (xy 422.368992 -294.4749) (xy 422.372952 -294.425846) (xy 422.384729 -294.378062)
			(xy 422.40402 -294.332786) (xy 422.430323 -294.29119) (xy 422.462958 -294.254353) (xy 422.501079 -294.223228)
			(xy 422.5437 -294.198621) (xy 422.589716 -294.181169) (xy 422.637935 -294.171325) (xy 422.68711 -294.169344)
			(xy 422.735965 -294.175276) (xy 422.783236 -294.188968) (xy 422.827698 -294.210066) (xy 422.868201 -294.238022)
			(xy 422.903694 -294.272114) (xy 422.933259 -294.311458) (xy 422.95613 -294.355035) (xy 422.971714 -294.401716)
			(xy 422.979609 -294.450293) (xy 422.980104 -294.4749) (xy 423.319206 -294.4749) (xy 423.323166 -294.425846)
			(xy 423.334943 -294.378062) (xy 423.354234 -294.332786) (xy 423.380537 -294.29119) (xy 423.413172 -294.254353)
			(xy 423.451293 -294.223228) (xy 423.493914 -294.198621) (xy 423.53993 -294.181169) (xy 423.588149 -294.171325)
			(xy 423.637324 -294.169344) (xy 423.686179 -294.175276) (xy 423.73345 -294.188968) (xy 423.777912 -294.210066)
			(xy 423.818415 -294.238022) (xy 423.853908 -294.272114) (xy 423.883473 -294.311458) (xy 423.906344 -294.355035)
			(xy 423.921928 -294.401716) (xy 423.929823 -294.450293) (xy 423.930318 -294.4749) (xy 424.269166 -294.4749)
			(xy 424.273126 -294.425846) (xy 424.284903 -294.378062) (xy 424.304194 -294.332786) (xy 424.330497 -294.29119)
			(xy 424.363132 -294.254353) (xy 424.401253 -294.223228) (xy 424.443874 -294.198621) (xy 424.48989 -294.181169)
			(xy 424.538109 -294.171325) (xy 424.587284 -294.169344) (xy 424.636139 -294.175276) (xy 424.68341 -294.188968)
			(xy 424.727872 -294.210066) (xy 424.768375 -294.238022) (xy 424.803868 -294.272114) (xy 424.833433 -294.311458)
			(xy 424.856304 -294.355035) (xy 424.871888 -294.401716) (xy 424.879783 -294.450293) (xy 424.880278 -294.4749)
			(xy 425.219126 -294.4749) (xy 425.223086 -294.425846) (xy 425.234863 -294.378062) (xy 425.254154 -294.332786)
			(xy 425.280457 -294.29119) (xy 425.313092 -294.254353) (xy 425.351213 -294.223228) (xy 425.393834 -294.198621)
			(xy 425.43985 -294.181169) (xy 425.488069 -294.171325) (xy 425.537244 -294.169344) (xy 425.586099 -294.175276)
			(xy 425.63337 -294.188968) (xy 425.677832 -294.210066) (xy 425.718335 -294.238022) (xy 425.753828 -294.272114)
			(xy 425.783393 -294.311458) (xy 425.806264 -294.355035) (xy 425.821848 -294.401716) (xy 425.829743 -294.450293)
			(xy 425.830238 -294.4749) (xy 426.169086 -294.4749) (xy 426.173046 -294.425846) (xy 426.184823 -294.378062)
			(xy 426.204114 -294.332786) (xy 426.230417 -294.29119) (xy 426.263052 -294.254353) (xy 426.301173 -294.223228)
			(xy 426.343794 -294.198621) (xy 426.38981 -294.181169) (xy 426.438029 -294.171325) (xy 426.487204 -294.169344)
			(xy 426.536059 -294.175276) (xy 426.58333 -294.188968) (xy 426.627792 -294.210066) (xy 426.668295 -294.238022)
			(xy 426.703788 -294.272114) (xy 426.733353 -294.311458) (xy 426.756224 -294.355035) (xy 426.771808 -294.401716)
			(xy 426.779703 -294.450293) (xy 426.780198 -294.4749) (xy 427.119046 -294.4749) (xy 427.123006 -294.425846)
			(xy 427.134783 -294.378062) (xy 427.154074 -294.332786) (xy 427.180377 -294.29119) (xy 427.213012 -294.254353)
			(xy 427.251133 -294.223228) (xy 427.293754 -294.198621) (xy 427.33977 -294.181169) (xy 427.387989 -294.171325)
			(xy 427.437164 -294.169344) (xy 427.486019 -294.175276) (xy 427.53329 -294.188968) (xy 427.577752 -294.210066)
			(xy 427.618255 -294.238022) (xy 427.653748 -294.272114) (xy 427.683313 -294.311458) (xy 427.706184 -294.355035)
			(xy 427.721768 -294.401716) (xy 427.729663 -294.450293) (xy 427.730158 -294.4749) (xy 428.069006 -294.4749)
			(xy 428.072966 -294.425846) (xy 428.084743 -294.378062) (xy 428.104034 -294.332786) (xy 428.130337 -294.29119)
			(xy 428.162972 -294.254353) (xy 428.201093 -294.223228) (xy 428.243714 -294.198621) (xy 428.28973 -294.181169)
			(xy 428.337949 -294.171325) (xy 428.387124 -294.169344) (xy 428.435979 -294.175276) (xy 428.48325 -294.188968)
			(xy 428.527712 -294.210066) (xy 428.568215 -294.238022) (xy 428.603708 -294.272114) (xy 428.633273 -294.311458)
			(xy 428.656144 -294.355035) (xy 428.671728 -294.401716) (xy 428.679623 -294.450293) (xy 428.680118 -294.4749)
			(xy 429.01922 -294.4749) (xy 429.02318 -294.425846) (xy 429.034957 -294.378062) (xy 429.054248 -294.332786)
			(xy 429.080551 -294.29119) (xy 429.113186 -294.254353) (xy 429.151307 -294.223228) (xy 429.193928 -294.198621)
			(xy 429.239944 -294.181169) (xy 429.288163 -294.171325) (xy 429.337338 -294.169344) (xy 429.386193 -294.175276)
			(xy 429.433464 -294.188968) (xy 429.477926 -294.210066) (xy 429.518429 -294.238022) (xy 429.553922 -294.272114)
			(xy 429.583487 -294.311458) (xy 429.606358 -294.355035) (xy 429.621942 -294.401716) (xy 429.629837 -294.450293)
			(xy 429.630332 -294.4749) (xy 429.96918 -294.4749) (xy 429.97314 -294.425846) (xy 429.984917 -294.378062)
			(xy 430.004208 -294.332786) (xy 430.030511 -294.29119) (xy 430.063146 -294.254353) (xy 430.101267 -294.223228)
			(xy 430.143888 -294.198621) (xy 430.189904 -294.181169) (xy 430.238123 -294.171325) (xy 430.287298 -294.169344)
			(xy 430.336153 -294.175276) (xy 430.383424 -294.188968) (xy 430.427886 -294.210066) (xy 430.468389 -294.238022)
			(xy 430.503882 -294.272114) (xy 430.533447 -294.311458) (xy 430.556318 -294.355035) (xy 430.571902 -294.401716)
			(xy 430.579797 -294.450293) (xy 430.580292 -294.4749) (xy 430.91914 -294.4749) (xy 430.9231 -294.425846)
			(xy 430.934877 -294.378062) (xy 430.954168 -294.332786) (xy 430.980471 -294.29119) (xy 431.013106 -294.254353)
			(xy 431.051227 -294.223228) (xy 431.093848 -294.198621) (xy 431.139864 -294.181169) (xy 431.188083 -294.171325)
			(xy 431.237258 -294.169344) (xy 431.286113 -294.175276) (xy 431.333384 -294.188968) (xy 431.377846 -294.210066)
			(xy 431.418349 -294.238022) (xy 431.453842 -294.272114) (xy 431.483407 -294.311458) (xy 431.506278 -294.355035)
			(xy 431.521862 -294.401716) (xy 431.529757 -294.450293) (xy 431.530252 -294.4749) (xy 431.529757 -294.499507)
			(xy 431.521862 -294.548084) (xy 431.506278 -294.594765) (xy 431.483407 -294.638342) (xy 431.47054 -294.655465)
			(xy 437.463125 -294.655465) (xy 437.47088 -294.601509) (xy 437.486235 -294.549206) (xy 437.508877 -294.499621)
			(xy 437.538345 -294.453763) (xy 437.57404 -294.412565) (xy 437.615234 -294.376867) (xy 437.661089 -294.347394)
			(xy 437.710673 -294.324748) (xy 437.762974 -294.309388) (xy 437.816929 -294.301628) (xy 437.844184 -294.301164)
			(xy 437.869584 -294.301926) (xy 437.884316 -294.302449) (xy 437.913046 -294.295896) (xy 437.938712 -294.281417)
			(xy 437.959178 -294.260214) (xy 437.97274 -294.234052) (xy 437.978272 -294.205107) (xy 437.975313 -294.175788)
			(xy 437.970168 -294.161972) (xy 437.961006 -294.13877) (xy 437.948116 -294.090579) (xy 437.941616 -294.041119)
			(xy 437.941212 -294.016176) (xy 437.941704 -293.988927) (xy 437.949463 -293.934985) (xy 437.96482 -293.882695)
			(xy 437.987461 -293.833124) (xy 438.016927 -293.787279) (xy 438.052618 -293.746094) (xy 438.093806 -293.710407)
			(xy 438.139653 -293.680945) (xy 438.189227 -293.658308) (xy 438.241517 -293.642956) (xy 438.29546 -293.635202)
			(xy 438.349958 -293.635203) (xy 438.403901 -293.64296) (xy 438.456191 -293.658314) (xy 438.505763 -293.680954)
			(xy 438.551609 -293.710418) (xy 438.592796 -293.746107) (xy 438.628484 -293.787294) (xy 438.657948 -293.83314)
			(xy 438.680587 -293.882713) (xy 438.695941 -293.935003) (xy 438.702499 -293.980616) (xy 439.58078 -293.980616)
			(xy 439.584851 -293.924994) (xy 439.596977 -293.870557) (xy 439.6169 -293.818466) (xy 439.644196 -293.769831)
			(xy 439.678282 -293.725688) (xy 439.718431 -293.686979) (xy 439.763789 -293.654528) (xy 439.813389 -293.629027)
			(xy 439.866173 -293.61102) (xy 439.921016 -293.60089) (xy 439.97675 -293.598853) (xy 440.032187 -293.604953)
			(xy 440.086144 -293.619059) (xy 440.137473 -293.640871) (xy 440.185079 -293.669925) (xy 440.227947 -293.7056)
			(xy 440.265164 -293.747137) (xy 440.295937 -293.79365) (xy 440.319609 -293.844147) (xy 440.335677 -293.897554)
			(xy 440.343797 -293.95273) (xy 440.344306 -293.980616) (xy 440.343797 -294.008502) (xy 440.335677 -294.063678)
			(xy 440.319609 -294.117085) (xy 440.295937 -294.167582) (xy 440.265164 -294.214095) (xy 440.227947 -294.255632)
			(xy 440.185079 -294.291307) (xy 440.137473 -294.320361) (xy 440.086144 -294.342173) (xy 440.032187 -294.356279)
			(xy 439.97675 -294.362379) (xy 439.921016 -294.360342) (xy 439.866173 -294.350212) (xy 439.813389 -294.332205)
			(xy 439.763789 -294.306704) (xy 439.718431 -294.274253) (xy 439.678282 -294.235544) (xy 439.644196 -294.191401)
			(xy 439.6169 -294.142766) (xy 439.596977 -294.090675) (xy 439.584851 -294.036238) (xy 439.58078 -293.980616)
			(xy 438.702499 -293.980616) (xy 438.703697 -293.988946) (xy 438.703698 -294.043444) (xy 438.695943 -294.097387)
			(xy 438.680591 -294.149677) (xy 438.657953 -294.19925) (xy 438.62849 -294.245098) (xy 438.592803 -294.286285)
			(xy 438.551618 -294.321975) (xy 438.505773 -294.351441) (xy 438.456201 -294.374082) (xy 438.403911 -294.389438)
			(xy 438.349969 -294.397196) (xy 438.32272 -294.397684) (xy 438.29732 -294.396922) (xy 438.28259 -294.396475)
			(xy 438.253872 -294.403022) (xy 438.228216 -294.417492) (xy 438.207756 -294.438681) (xy 438.194192 -294.464827)
			(xy 438.188653 -294.493757) (xy 438.189439 -294.50157) (xy 438.83656 -294.50157) (xy 438.840631 -294.445948)
			(xy 438.852757 -294.391511) (xy 438.87268 -294.33942) (xy 438.899976 -294.290785) (xy 438.934062 -294.246642)
			(xy 438.974211 -294.207933) (xy 439.019569 -294.175482) (xy 439.069169 -294.149981) (xy 439.121953 -294.131974)
			(xy 439.176796 -294.121844) (xy 439.23253 -294.119807) (xy 439.287967 -294.125907) (xy 439.341924 -294.140013)
			(xy 439.393253 -294.161825) (xy 439.440859 -294.190879) (xy 439.483727 -294.226554) (xy 439.520944 -294.268091)
			(xy 439.551717 -294.314604) (xy 439.575389 -294.365101) (xy 439.591457 -294.418508) (xy 439.599577 -294.473684)
			(xy 439.600086 -294.50157) (xy 439.599577 -294.529456) (xy 439.591457 -294.584632) (xy 439.575389 -294.638039)
			(xy 439.551717 -294.688536) (xy 439.520944 -294.735049) (xy 439.483727 -294.776586) (xy 439.440859 -294.812261)
			(xy 439.393253 -294.841315) (xy 439.341924 -294.863127) (xy 439.287967 -294.877233) (xy 439.23253 -294.883333)
			(xy 439.176796 -294.881296) (xy 439.121953 -294.871166) (xy 439.069169 -294.853159) (xy 439.019569 -294.827658)
			(xy 438.974211 -294.795207) (xy 438.934062 -294.756498) (xy 438.899976 -294.712355) (xy 438.87268 -294.66372)
			(xy 438.852757 -294.611629) (xy 438.840631 -294.557192) (xy 438.83656 -294.50157) (xy 438.189439 -294.50157)
			(xy 438.1916 -294.523064) (xy 438.196736 -294.536876) (xy 438.205882 -294.560084) (xy 438.218779 -294.608272)
			(xy 438.225284 -294.65773) (xy 438.225692 -294.682672) (xy 438.225275 -294.709927) (xy 438.217521 -294.763883)
			(xy 438.202168 -294.816186) (xy 438.179527 -294.865772) (xy 438.15006 -294.911631) (xy 438.114366 -294.952829)
			(xy 438.073172 -294.988529) (xy 438.027318 -295.018002) (xy 437.977735 -295.04065) (xy 437.925434 -295.05601)
			(xy 437.871479 -295.063771) (xy 437.816969 -295.063775) (xy 437.763013 -295.056021) (xy 437.71071 -295.040666)
			(xy 437.661125 -295.018025) (xy 437.615266 -294.988557) (xy 437.574068 -294.952863) (xy 437.538369 -294.911669)
			(xy 437.508896 -294.865814) (xy 437.486249 -294.816231) (xy 437.470889 -294.76393) (xy 437.463128 -294.709975)
			(xy 437.463125 -294.655465) (xy 431.47054 -294.655465) (xy 431.453842 -294.677686) (xy 431.418349 -294.711778)
			(xy 431.377846 -294.739734) (xy 431.333384 -294.760832) (xy 431.286113 -294.774524) (xy 431.237258 -294.780456)
			(xy 431.188083 -294.778475) (xy 431.139864 -294.768631) (xy 431.093848 -294.751179) (xy 431.051227 -294.726572)
			(xy 431.013106 -294.695447) (xy 430.980471 -294.65861) (xy 430.954168 -294.617014) (xy 430.934877 -294.571738)
			(xy 430.9231 -294.523954) (xy 430.91914 -294.4749) (xy 430.580292 -294.4749) (xy 430.579797 -294.499507)
			(xy 430.571902 -294.548084) (xy 430.556318 -294.594765) (xy 430.533447 -294.638342) (xy 430.503882 -294.677686)
			(xy 430.468389 -294.711778) (xy 430.427886 -294.739734) (xy 430.383424 -294.760832) (xy 430.336153 -294.774524)
			(xy 430.287298 -294.780456) (xy 430.238123 -294.778475) (xy 430.189904 -294.768631) (xy 430.143888 -294.751179)
			(xy 430.101267 -294.726572) (xy 430.063146 -294.695447) (xy 430.030511 -294.65861) (xy 430.004208 -294.617014)
			(xy 429.984917 -294.571738) (xy 429.97314 -294.523954) (xy 429.96918 -294.4749) (xy 429.630332 -294.4749)
			(xy 429.629837 -294.499507) (xy 429.621942 -294.548084) (xy 429.606358 -294.594765) (xy 429.583487 -294.638342)
			(xy 429.553922 -294.677686) (xy 429.518429 -294.711778) (xy 429.477926 -294.739734) (xy 429.433464 -294.760832)
			(xy 429.386193 -294.774524) (xy 429.337338 -294.780456) (xy 429.288163 -294.778475) (xy 429.239944 -294.768631)
			(xy 429.193928 -294.751179) (xy 429.151307 -294.726572) (xy 429.113186 -294.695447) (xy 429.080551 -294.65861)
			(xy 429.054248 -294.617014) (xy 429.034957 -294.571738) (xy 429.02318 -294.523954) (xy 429.01922 -294.4749)
			(xy 428.680118 -294.4749) (xy 428.679623 -294.499507) (xy 428.671728 -294.548084) (xy 428.656144 -294.594765)
			(xy 428.633273 -294.638342) (xy 428.603708 -294.677686) (xy 428.568215 -294.711778) (xy 428.527712 -294.739734)
			(xy 428.48325 -294.760832) (xy 428.435979 -294.774524) (xy 428.387124 -294.780456) (xy 428.337949 -294.778475)
			(xy 428.28973 -294.768631) (xy 428.243714 -294.751179) (xy 428.201093 -294.726572) (xy 428.162972 -294.695447)
			(xy 428.130337 -294.65861) (xy 428.104034 -294.617014) (xy 428.084743 -294.571738) (xy 428.072966 -294.523954)
			(xy 428.069006 -294.4749) (xy 427.730158 -294.4749) (xy 427.729663 -294.499507) (xy 427.721768 -294.548084)
			(xy 427.706184 -294.594765) (xy 427.683313 -294.638342) (xy 427.653748 -294.677686) (xy 427.618255 -294.711778)
			(xy 427.577752 -294.739734) (xy 427.53329 -294.760832) (xy 427.486019 -294.774524) (xy 427.437164 -294.780456)
			(xy 427.387989 -294.778475) (xy 427.33977 -294.768631) (xy 427.293754 -294.751179) (xy 427.251133 -294.726572)
			(xy 427.213012 -294.695447) (xy 427.180377 -294.65861) (xy 427.154074 -294.617014) (xy 427.134783 -294.571738)
			(xy 427.123006 -294.523954) (xy 427.119046 -294.4749) (xy 426.780198 -294.4749) (xy 426.779703 -294.499507)
			(xy 426.771808 -294.548084) (xy 426.756224 -294.594765) (xy 426.733353 -294.638342) (xy 426.703788 -294.677686)
			(xy 426.668295 -294.711778) (xy 426.627792 -294.739734) (xy 426.58333 -294.760832) (xy 426.536059 -294.774524)
			(xy 426.487204 -294.780456) (xy 426.438029 -294.778475) (xy 426.38981 -294.768631) (xy 426.343794 -294.751179)
			(xy 426.301173 -294.726572) (xy 426.263052 -294.695447) (xy 426.230417 -294.65861) (xy 426.204114 -294.617014)
			(xy 426.184823 -294.571738) (xy 426.173046 -294.523954) (xy 426.169086 -294.4749) (xy 425.830238 -294.4749)
			(xy 425.829743 -294.499507) (xy 425.821848 -294.548084) (xy 425.806264 -294.594765) (xy 425.783393 -294.638342)
			(xy 425.753828 -294.677686) (xy 425.718335 -294.711778) (xy 425.677832 -294.739734) (xy 425.63337 -294.760832)
			(xy 425.586099 -294.774524) (xy 425.537244 -294.780456) (xy 425.488069 -294.778475) (xy 425.43985 -294.768631)
			(xy 425.393834 -294.751179) (xy 425.351213 -294.726572) (xy 425.313092 -294.695447) (xy 425.280457 -294.65861)
			(xy 425.254154 -294.617014) (xy 425.234863 -294.571738) (xy 425.223086 -294.523954) (xy 425.219126 -294.4749)
			(xy 424.880278 -294.4749) (xy 424.879783 -294.499507) (xy 424.871888 -294.548084) (xy 424.856304 -294.594765)
			(xy 424.833433 -294.638342) (xy 424.803868 -294.677686) (xy 424.768375 -294.711778) (xy 424.727872 -294.739734)
			(xy 424.68341 -294.760832) (xy 424.636139 -294.774524) (xy 424.587284 -294.780456) (xy 424.538109 -294.778475)
			(xy 424.48989 -294.768631) (xy 424.443874 -294.751179) (xy 424.401253 -294.726572) (xy 424.363132 -294.695447)
			(xy 424.330497 -294.65861) (xy 424.304194 -294.617014) (xy 424.284903 -294.571738) (xy 424.273126 -294.523954)
			(xy 424.269166 -294.4749) (xy 423.930318 -294.4749) (xy 423.929823 -294.499507) (xy 423.921928 -294.548084)
			(xy 423.906344 -294.594765) (xy 423.883473 -294.638342) (xy 423.853908 -294.677686) (xy 423.818415 -294.711778)
			(xy 423.777912 -294.739734) (xy 423.73345 -294.760832) (xy 423.686179 -294.774524) (xy 423.637324 -294.780456)
			(xy 423.588149 -294.778475) (xy 423.53993 -294.768631) (xy 423.493914 -294.751179) (xy 423.451293 -294.726572)
			(xy 423.413172 -294.695447) (xy 423.380537 -294.65861) (xy 423.354234 -294.617014) (xy 423.334943 -294.571738)
			(xy 423.323166 -294.523954) (xy 423.319206 -294.4749) (xy 422.980104 -294.4749) (xy 422.979609 -294.499507)
			(xy 422.971714 -294.548084) (xy 422.95613 -294.594765) (xy 422.933259 -294.638342) (xy 422.903694 -294.677686)
			(xy 422.868201 -294.711778) (xy 422.827698 -294.739734) (xy 422.783236 -294.760832) (xy 422.735965 -294.774524)
			(xy 422.68711 -294.780456) (xy 422.637935 -294.778475) (xy 422.589716 -294.768631) (xy 422.5437 -294.751179)
			(xy 422.501079 -294.726572) (xy 422.462958 -294.695447) (xy 422.430323 -294.65861) (xy 422.40402 -294.617014)
			(xy 422.384729 -294.571738) (xy 422.372952 -294.523954) (xy 422.368992 -294.4749) (xy 422.030144 -294.4749)
			(xy 422.029649 -294.499507) (xy 422.021754 -294.548084) (xy 422.00617 -294.594765) (xy 421.983299 -294.638342)
			(xy 421.953734 -294.677686) (xy 421.918241 -294.711778) (xy 421.877738 -294.739734) (xy 421.833276 -294.760832)
			(xy 421.786005 -294.774524) (xy 421.73715 -294.780456) (xy 421.687975 -294.778475) (xy 421.639756 -294.768631)
			(xy 421.59374 -294.751179) (xy 421.551119 -294.726572) (xy 421.512998 -294.695447) (xy 421.480363 -294.65861)
			(xy 421.45406 -294.617014) (xy 421.434769 -294.571738) (xy 421.422992 -294.523954) (xy 421.419032 -294.4749)
			(xy 421.080184 -294.4749) (xy 421.079689 -294.499507) (xy 421.071794 -294.548084) (xy 421.05621 -294.594765)
			(xy 421.033339 -294.638342) (xy 421.003774 -294.677686) (xy 420.968281 -294.711778) (xy 420.927778 -294.739734)
			(xy 420.883316 -294.760832) (xy 420.836045 -294.774524) (xy 420.78719 -294.780456) (xy 420.738015 -294.778475)
			(xy 420.689796 -294.768631) (xy 420.64378 -294.751179) (xy 420.601159 -294.726572) (xy 420.563038 -294.695447)
			(xy 420.530403 -294.65861) (xy 420.5041 -294.617014) (xy 420.484809 -294.571738) (xy 420.473032 -294.523954)
			(xy 420.469072 -294.4749) (xy 420.130224 -294.4749) (xy 420.129729 -294.499507) (xy 420.121834 -294.548084)
			(xy 420.10625 -294.594765) (xy 420.083379 -294.638342) (xy 420.053814 -294.677686) (xy 420.018321 -294.711778)
			(xy 419.977818 -294.739734) (xy 419.933356 -294.760832) (xy 419.886085 -294.774524) (xy 419.83723 -294.780456)
			(xy 419.788055 -294.778475) (xy 419.739836 -294.768631) (xy 419.69382 -294.751179) (xy 419.651199 -294.726572)
			(xy 419.613078 -294.695447) (xy 419.580443 -294.65861) (xy 419.55414 -294.617014) (xy 419.534849 -294.571738)
			(xy 419.523072 -294.523954) (xy 419.519112 -294.4749) (xy 419.180264 -294.4749) (xy 419.179769 -294.499507)
			(xy 419.171874 -294.548084) (xy 419.15629 -294.594765) (xy 419.133419 -294.638342) (xy 419.103854 -294.677686)
			(xy 419.068361 -294.711778) (xy 419.027858 -294.739734) (xy 418.983396 -294.760832) (xy 418.936125 -294.774524)
			(xy 418.88727 -294.780456) (xy 418.838095 -294.778475) (xy 418.789876 -294.768631) (xy 418.74386 -294.751179)
			(xy 418.701239 -294.726572) (xy 418.663118 -294.695447) (xy 418.630483 -294.65861) (xy 418.60418 -294.617014)
			(xy 418.584889 -294.571738) (xy 418.573112 -294.523954) (xy 418.569152 -294.4749) (xy 418.256165 -294.4749)
			(xy 418.252421 -294.524556) (xy 418.241274 -294.57309) (xy 418.222975 -294.619404) (xy 418.197939 -294.66245)
			(xy 418.166731 -294.701255) (xy 418.130057 -294.734942) (xy 418.109654 -294.74922) (xy 418.099677 -294.7567)
			(xy 418.087956 -294.778677) (xy 418.087302 -294.79113) (xy 418.087302 -295.355518) (xy 440.915804 -295.355518)
			(xy 440.919875 -295.299896) (xy 440.932001 -295.245459) (xy 440.951924 -295.193368) (xy 440.97922 -295.144733)
			(xy 441.013306 -295.10059) (xy 441.053455 -295.061881) (xy 441.098813 -295.02943) (xy 441.148413 -295.003929)
			(xy 441.201197 -294.985922) (xy 441.25604 -294.975792) (xy 441.311774 -294.973755) (xy 441.367211 -294.979855)
			(xy 441.421168 -294.993961) (xy 441.472497 -295.015773) (xy 441.520103 -295.044827) (xy 441.562971 -295.080502)
			(xy 441.600188 -295.122039) (xy 441.630961 -295.168552) (xy 441.654633 -295.219049) (xy 441.670701 -295.272456)
			(xy 441.678821 -295.327632) (xy 441.67933 -295.355518) (xy 441.678821 -295.383404) (xy 441.670701 -295.43858)
			(xy 441.654633 -295.491987) (xy 441.630961 -295.542484) (xy 441.600188 -295.588997) (xy 441.562971 -295.630534)
			(xy 441.520103 -295.666209) (xy 441.472497 -295.695263) (xy 441.421168 -295.717075) (xy 441.367211 -295.731181)
			(xy 441.311774 -295.737281) (xy 441.25604 -295.735244) (xy 441.201197 -295.725114) (xy 441.148413 -295.707107)
			(xy 441.098813 -295.681606) (xy 441.053455 -295.649155) (xy 441.013306 -295.610446) (xy 440.97922 -295.566303)
			(xy 440.951924 -295.517668) (xy 440.932001 -295.465577) (xy 440.919875 -295.41114) (xy 440.915804 -295.355518)
			(xy 418.087302 -295.355518) (xy 418.087302 -296.05859) (xy 418.087984 -296.071037) (xy 418.099686 -296.093017)
			(xy 418.109654 -296.1005) (xy 418.131733 -296.116008) (xy 418.171003 -296.153003) (xy 418.203749 -296.195881)
			(xy 418.229104 -296.243504) (xy 418.246394 -296.29461) (xy 418.255162 -296.347844) (xy 418.255704 -296.37482)
			(xy 418.569152 -296.37482) (xy 418.573112 -296.325766) (xy 418.584889 -296.277982) (xy 418.60418 -296.232706)
			(xy 418.630483 -296.19111) (xy 418.663118 -296.154273) (xy 418.701239 -296.123148) (xy 418.74386 -296.098541)
			(xy 418.789876 -296.081089) (xy 418.838095 -296.071245) (xy 418.88727 -296.069264) (xy 418.936125 -296.075196)
			(xy 418.983396 -296.088888) (xy 419.027858 -296.109986) (xy 419.068361 -296.137942) (xy 419.103854 -296.172034)
			(xy 419.133419 -296.211378) (xy 419.15629 -296.254955) (xy 419.171874 -296.301636) (xy 419.179769 -296.350213)
			(xy 419.180264 -296.37482) (xy 419.519112 -296.37482) (xy 419.523072 -296.325766) (xy 419.534849 -296.277982)
			(xy 419.55414 -296.232706) (xy 419.580443 -296.19111) (xy 419.613078 -296.154273) (xy 419.651199 -296.123148)
			(xy 419.69382 -296.098541) (xy 419.739836 -296.081089) (xy 419.788055 -296.071245) (xy 419.83723 -296.069264)
			(xy 419.886085 -296.075196) (xy 419.933356 -296.088888) (xy 419.977818 -296.109986) (xy 420.018321 -296.137942)
			(xy 420.053814 -296.172034) (xy 420.083379 -296.211378) (xy 420.10625 -296.254955) (xy 420.121834 -296.301636)
			(xy 420.129729 -296.350213) (xy 420.130224 -296.37482) (xy 420.469072 -296.37482) (xy 420.473032 -296.325766)
			(xy 420.484809 -296.277982) (xy 420.5041 -296.232706) (xy 420.530403 -296.19111) (xy 420.563038 -296.154273)
			(xy 420.601159 -296.123148) (xy 420.64378 -296.098541) (xy 420.689796 -296.081089) (xy 420.738015 -296.071245)
			(xy 420.78719 -296.069264) (xy 420.836045 -296.075196) (xy 420.883316 -296.088888) (xy 420.927778 -296.109986)
			(xy 420.968281 -296.137942) (xy 421.003774 -296.172034) (xy 421.033339 -296.211378) (xy 421.05621 -296.254955)
			(xy 421.071794 -296.301636) (xy 421.079689 -296.350213) (xy 421.080184 -296.37482) (xy 421.419032 -296.37482)
			(xy 421.422992 -296.325766) (xy 421.434769 -296.277982) (xy 421.45406 -296.232706) (xy 421.480363 -296.19111)
			(xy 421.512998 -296.154273) (xy 421.551119 -296.123148) (xy 421.59374 -296.098541) (xy 421.639756 -296.081089)
			(xy 421.687975 -296.071245) (xy 421.73715 -296.069264) (xy 421.786005 -296.075196) (xy 421.833276 -296.088888)
			(xy 421.877738 -296.109986) (xy 421.918241 -296.137942) (xy 421.953734 -296.172034) (xy 421.983299 -296.211378)
			(xy 422.00617 -296.254955) (xy 422.021754 -296.301636) (xy 422.029649 -296.350213) (xy 422.030144 -296.37482)
			(xy 422.368992 -296.37482) (xy 422.372952 -296.325766) (xy 422.384729 -296.277982) (xy 422.40402 -296.232706)
			(xy 422.430323 -296.19111) (xy 422.462958 -296.154273) (xy 422.501079 -296.123148) (xy 422.5437 -296.098541)
			(xy 422.589716 -296.081089) (xy 422.637935 -296.071245) (xy 422.68711 -296.069264) (xy 422.735965 -296.075196)
			(xy 422.783236 -296.088888) (xy 422.827698 -296.109986) (xy 422.868201 -296.137942) (xy 422.903694 -296.172034)
			(xy 422.933259 -296.211378) (xy 422.95613 -296.254955) (xy 422.971714 -296.301636) (xy 422.979609 -296.350213)
			(xy 422.980104 -296.37482) (xy 423.319206 -296.37482) (xy 423.323166 -296.325766) (xy 423.334943 -296.277982)
			(xy 423.354234 -296.232706) (xy 423.380537 -296.19111) (xy 423.413172 -296.154273) (xy 423.451293 -296.123148)
			(xy 423.493914 -296.098541) (xy 423.53993 -296.081089) (xy 423.588149 -296.071245) (xy 423.637324 -296.069264)
			(xy 423.686179 -296.075196) (xy 423.73345 -296.088888) (xy 423.777912 -296.109986) (xy 423.818415 -296.137942)
			(xy 423.853908 -296.172034) (xy 423.883473 -296.211378) (xy 423.906344 -296.254955) (xy 423.921928 -296.301636)
			(xy 423.929823 -296.350213) (xy 423.930318 -296.37482) (xy 424.269166 -296.37482) (xy 424.273126 -296.325766)
			(xy 424.284903 -296.277982) (xy 424.304194 -296.232706) (xy 424.330497 -296.19111) (xy 424.363132 -296.154273)
			(xy 424.401253 -296.123148) (xy 424.443874 -296.098541) (xy 424.48989 -296.081089) (xy 424.538109 -296.071245)
			(xy 424.587284 -296.069264) (xy 424.636139 -296.075196) (xy 424.68341 -296.088888) (xy 424.727872 -296.109986)
			(xy 424.768375 -296.137942) (xy 424.803868 -296.172034) (xy 424.833433 -296.211378) (xy 424.856304 -296.254955)
			(xy 424.871888 -296.301636) (xy 424.879783 -296.350213) (xy 424.880278 -296.37482) (xy 425.219126 -296.37482)
			(xy 425.223086 -296.325766) (xy 425.234863 -296.277982) (xy 425.254154 -296.232706) (xy 425.280457 -296.19111)
			(xy 425.313092 -296.154273) (xy 425.351213 -296.123148) (xy 425.393834 -296.098541) (xy 425.43985 -296.081089)
			(xy 425.488069 -296.071245) (xy 425.537244 -296.069264) (xy 425.586099 -296.075196) (xy 425.63337 -296.088888)
			(xy 425.677832 -296.109986) (xy 425.718335 -296.137942) (xy 425.753828 -296.172034) (xy 425.783393 -296.211378)
			(xy 425.806264 -296.254955) (xy 425.821848 -296.301636) (xy 425.829743 -296.350213) (xy 425.830238 -296.37482)
			(xy 426.169086 -296.37482) (xy 426.173046 -296.325766) (xy 426.184823 -296.277982) (xy 426.204114 -296.232706)
			(xy 426.230417 -296.19111) (xy 426.263052 -296.154273) (xy 426.301173 -296.123148) (xy 426.343794 -296.098541)
			(xy 426.38981 -296.081089) (xy 426.438029 -296.071245) (xy 426.487204 -296.069264) (xy 426.536059 -296.075196)
			(xy 426.58333 -296.088888) (xy 426.627792 -296.109986) (xy 426.668295 -296.137942) (xy 426.703788 -296.172034)
			(xy 426.733353 -296.211378) (xy 426.756224 -296.254955) (xy 426.771808 -296.301636) (xy 426.779703 -296.350213)
			(xy 426.780198 -296.37482) (xy 427.119046 -296.37482) (xy 427.123006 -296.325766) (xy 427.134783 -296.277982)
			(xy 427.154074 -296.232706) (xy 427.180377 -296.19111) (xy 427.213012 -296.154273) (xy 427.251133 -296.123148)
			(xy 427.293754 -296.098541) (xy 427.33977 -296.081089) (xy 427.387989 -296.071245) (xy 427.437164 -296.069264)
			(xy 427.486019 -296.075196) (xy 427.53329 -296.088888) (xy 427.577752 -296.109986) (xy 427.618255 -296.137942)
			(xy 427.653748 -296.172034) (xy 427.683313 -296.211378) (xy 427.706184 -296.254955) (xy 427.721768 -296.301636)
			(xy 427.729663 -296.350213) (xy 427.730158 -296.37482) (xy 428.069006 -296.37482) (xy 428.072966 -296.325766)
			(xy 428.084743 -296.277982) (xy 428.104034 -296.232706) (xy 428.130337 -296.19111) (xy 428.162972 -296.154273)
			(xy 428.201093 -296.123148) (xy 428.243714 -296.098541) (xy 428.28973 -296.081089) (xy 428.337949 -296.071245)
			(xy 428.387124 -296.069264) (xy 428.435979 -296.075196) (xy 428.48325 -296.088888) (xy 428.527712 -296.109986)
			(xy 428.568215 -296.137942) (xy 428.603708 -296.172034) (xy 428.633273 -296.211378) (xy 428.656144 -296.254955)
			(xy 428.671728 -296.301636) (xy 428.679623 -296.350213) (xy 428.680118 -296.37482) (xy 429.01922 -296.37482)
			(xy 429.02318 -296.325766) (xy 429.034957 -296.277982) (xy 429.054248 -296.232706) (xy 429.080551 -296.19111)
			(xy 429.113186 -296.154273) (xy 429.151307 -296.123148) (xy 429.193928 -296.098541) (xy 429.239944 -296.081089)
			(xy 429.288163 -296.071245) (xy 429.337338 -296.069264) (xy 429.386193 -296.075196) (xy 429.433464 -296.088888)
			(xy 429.477926 -296.109986) (xy 429.518429 -296.137942) (xy 429.553922 -296.172034) (xy 429.583487 -296.211378)
			(xy 429.606358 -296.254955) (xy 429.621942 -296.301636) (xy 429.629837 -296.350213) (xy 429.630332 -296.37482)
			(xy 429.96918 -296.37482) (xy 429.97314 -296.325766) (xy 429.984917 -296.277982) (xy 430.004208 -296.232706)
			(xy 430.030511 -296.19111) (xy 430.063146 -296.154273) (xy 430.101267 -296.123148) (xy 430.143888 -296.098541)
			(xy 430.189904 -296.081089) (xy 430.238123 -296.071245) (xy 430.287298 -296.069264) (xy 430.336153 -296.075196)
			(xy 430.383424 -296.088888) (xy 430.427886 -296.109986) (xy 430.468389 -296.137942) (xy 430.503882 -296.172034)
			(xy 430.533447 -296.211378) (xy 430.556318 -296.254955) (xy 430.571902 -296.301636) (xy 430.579797 -296.350213)
			(xy 430.580292 -296.37482) (xy 430.91914 -296.37482) (xy 430.9231 -296.325766) (xy 430.934877 -296.277982)
			(xy 430.954168 -296.232706) (xy 430.980471 -296.19111) (xy 431.013106 -296.154273) (xy 431.051227 -296.123148)
			(xy 431.093848 -296.098541) (xy 431.139864 -296.081089) (xy 431.188083 -296.071245) (xy 431.237258 -296.069264)
			(xy 431.286113 -296.075196) (xy 431.333384 -296.088888) (xy 431.377846 -296.109986) (xy 431.418349 -296.137942)
			(xy 431.453842 -296.172034) (xy 431.483407 -296.211378) (xy 431.506278 -296.254955) (xy 431.521862 -296.301636)
			(xy 431.529757 -296.350213) (xy 431.530252 -296.37482) (xy 431.529757 -296.399427) (xy 431.521862 -296.448004)
			(xy 431.506278 -296.494685) (xy 431.483407 -296.538262) (xy 431.453842 -296.577606) (xy 431.418349 -296.611698)
			(xy 431.416358 -296.613072) (xy 437.562496 -296.613072) (xy 437.566567 -296.55745) (xy 437.578693 -296.503013)
			(xy 437.598616 -296.450922) (xy 437.625912 -296.402287) (xy 437.659998 -296.358144) (xy 437.700147 -296.319435)
			(xy 437.745505 -296.286984) (xy 437.795105 -296.261483) (xy 437.847889 -296.243476) (xy 437.902732 -296.233346)
			(xy 437.958466 -296.231309) (xy 438.013903 -296.237409) (xy 438.06786 -296.251515) (xy 438.119189 -296.273327)
			(xy 438.166795 -296.302381) (xy 438.209663 -296.338056) (xy 438.24688 -296.379593) (xy 438.277653 -296.426106)
			(xy 438.301325 -296.476603) (xy 438.317393 -296.53001) (xy 438.325513 -296.585186) (xy 438.326022 -296.613072)
			(xy 438.837322 -296.613072) (xy 438.841393 -296.55745) (xy 438.853519 -296.503013) (xy 438.873442 -296.450922)
			(xy 438.900738 -296.402287) (xy 438.934824 -296.358144) (xy 438.974973 -296.319435) (xy 439.020331 -296.286984)
			(xy 439.069931 -296.261483) (xy 439.122715 -296.243476) (xy 439.177558 -296.233346) (xy 439.233292 -296.231309)
			(xy 439.288729 -296.237409) (xy 439.342686 -296.251515) (xy 439.394015 -296.273327) (xy 439.441621 -296.302381)
			(xy 439.484489 -296.338056) (xy 439.521706 -296.379593) (xy 439.552479 -296.426106) (xy 439.576151 -296.476603)
			(xy 439.592219 -296.53001) (xy 439.600339 -296.585186) (xy 439.600848 -296.613072) (xy 439.600339 -296.640958)
			(xy 439.592219 -296.696134) (xy 439.576151 -296.749541) (xy 439.552479 -296.800038) (xy 439.521706 -296.846551)
			(xy 439.484489 -296.888088) (xy 439.441621 -296.923763) (xy 439.394015 -296.952817) (xy 439.342686 -296.974629)
			(xy 439.288729 -296.988735) (xy 439.233292 -296.994835) (xy 439.177558 -296.992798) (xy 439.122715 -296.982668)
			(xy 439.069931 -296.964661) (xy 439.020331 -296.93916) (xy 438.974973 -296.906709) (xy 438.934824 -296.868)
			(xy 438.900738 -296.823857) (xy 438.873442 -296.775222) (xy 438.853519 -296.723131) (xy 438.841393 -296.668694)
			(xy 438.837322 -296.613072) (xy 438.326022 -296.613072) (xy 438.325513 -296.640958) (xy 438.317393 -296.696134)
			(xy 438.301325 -296.749541) (xy 438.277653 -296.800038) (xy 438.24688 -296.846551) (xy 438.209663 -296.888088)
			(xy 438.166795 -296.923763) (xy 438.119189 -296.952817) (xy 438.06786 -296.974629) (xy 438.013903 -296.988735)
			(xy 437.958466 -296.994835) (xy 437.902732 -296.992798) (xy 437.847889 -296.982668) (xy 437.795105 -296.964661)
			(xy 437.745505 -296.93916) (xy 437.700147 -296.906709) (xy 437.659998 -296.868) (xy 437.625912 -296.823857)
			(xy 437.598616 -296.775222) (xy 437.578693 -296.723131) (xy 437.566567 -296.668694) (xy 437.562496 -296.613072)
			(xy 431.416358 -296.613072) (xy 431.377846 -296.639654) (xy 431.333384 -296.660752) (xy 431.286113 -296.674444)
			(xy 431.237258 -296.680376) (xy 431.188083 -296.678395) (xy 431.139864 -296.668551) (xy 431.093848 -296.651099)
			(xy 431.051227 -296.626492) (xy 431.013106 -296.595367) (xy 430.980471 -296.55853) (xy 430.954168 -296.516934)
			(xy 430.934877 -296.471658) (xy 430.9231 -296.423874) (xy 430.91914 -296.37482) (xy 430.580292 -296.37482)
			(xy 430.579797 -296.399427) (xy 430.571902 -296.448004) (xy 430.556318 -296.494685) (xy 430.533447 -296.538262)
			(xy 430.503882 -296.577606) (xy 430.468389 -296.611698) (xy 430.427886 -296.639654) (xy 430.383424 -296.660752)
			(xy 430.336153 -296.674444) (xy 430.287298 -296.680376) (xy 430.238123 -296.678395) (xy 430.189904 -296.668551)
			(xy 430.143888 -296.651099) (xy 430.101267 -296.626492) (xy 430.063146 -296.595367) (xy 430.030511 -296.55853)
			(xy 430.004208 -296.516934) (xy 429.984917 -296.471658) (xy 429.97314 -296.423874) (xy 429.96918 -296.37482)
			(xy 429.630332 -296.37482) (xy 429.629837 -296.399427) (xy 429.621942 -296.448004) (xy 429.606358 -296.494685)
			(xy 429.583487 -296.538262) (xy 429.553922 -296.577606) (xy 429.518429 -296.611698) (xy 429.477926 -296.639654)
			(xy 429.433464 -296.660752) (xy 429.386193 -296.674444) (xy 429.337338 -296.680376) (xy 429.288163 -296.678395)
			(xy 429.239944 -296.668551) (xy 429.193928 -296.651099) (xy 429.151307 -296.626492) (xy 429.113186 -296.595367)
			(xy 429.080551 -296.55853) (xy 429.054248 -296.516934) (xy 429.034957 -296.471658) (xy 429.02318 -296.423874)
			(xy 429.01922 -296.37482) (xy 428.680118 -296.37482) (xy 428.679623 -296.399427) (xy 428.671728 -296.448004)
			(xy 428.656144 -296.494685) (xy 428.633273 -296.538262) (xy 428.603708 -296.577606) (xy 428.568215 -296.611698)
			(xy 428.527712 -296.639654) (xy 428.48325 -296.660752) (xy 428.435979 -296.674444) (xy 428.387124 -296.680376)
			(xy 428.337949 -296.678395) (xy 428.28973 -296.668551) (xy 428.243714 -296.651099) (xy 428.201093 -296.626492)
			(xy 428.162972 -296.595367) (xy 428.130337 -296.55853) (xy 428.104034 -296.516934) (xy 428.084743 -296.471658)
			(xy 428.072966 -296.423874) (xy 428.069006 -296.37482) (xy 427.730158 -296.37482) (xy 427.729663 -296.399427)
			(xy 427.721768 -296.448004) (xy 427.706184 -296.494685) (xy 427.683313 -296.538262) (xy 427.653748 -296.577606)
			(xy 427.618255 -296.611698) (xy 427.577752 -296.639654) (xy 427.53329 -296.660752) (xy 427.486019 -296.674444)
			(xy 427.437164 -296.680376) (xy 427.387989 -296.678395) (xy 427.33977 -296.668551) (xy 427.293754 -296.651099)
			(xy 427.251133 -296.626492) (xy 427.213012 -296.595367) (xy 427.180377 -296.55853) (xy 427.154074 -296.516934)
			(xy 427.134783 -296.471658) (xy 427.123006 -296.423874) (xy 427.119046 -296.37482) (xy 426.780198 -296.37482)
			(xy 426.779703 -296.399427) (xy 426.771808 -296.448004) (xy 426.756224 -296.494685) (xy 426.733353 -296.538262)
			(xy 426.703788 -296.577606) (xy 426.668295 -296.611698) (xy 426.627792 -296.639654) (xy 426.58333 -296.660752)
			(xy 426.536059 -296.674444) (xy 426.487204 -296.680376) (xy 426.438029 -296.678395) (xy 426.38981 -296.668551)
			(xy 426.343794 -296.651099) (xy 426.301173 -296.626492) (xy 426.263052 -296.595367) (xy 426.230417 -296.55853)
			(xy 426.204114 -296.516934) (xy 426.184823 -296.471658) (xy 426.173046 -296.423874) (xy 426.169086 -296.37482)
			(xy 425.830238 -296.37482) (xy 425.829743 -296.399427) (xy 425.821848 -296.448004) (xy 425.806264 -296.494685)
			(xy 425.783393 -296.538262) (xy 425.753828 -296.577606) (xy 425.718335 -296.611698) (xy 425.677832 -296.639654)
			(xy 425.63337 -296.660752) (xy 425.586099 -296.674444) (xy 425.537244 -296.680376) (xy 425.488069 -296.678395)
			(xy 425.43985 -296.668551) (xy 425.393834 -296.651099) (xy 425.351213 -296.626492) (xy 425.313092 -296.595367)
			(xy 425.280457 -296.55853) (xy 425.254154 -296.516934) (xy 425.234863 -296.471658) (xy 425.223086 -296.423874)
			(xy 425.219126 -296.37482) (xy 424.880278 -296.37482) (xy 424.879783 -296.399427) (xy 424.871888 -296.448004)
			(xy 424.856304 -296.494685) (xy 424.833433 -296.538262) (xy 424.803868 -296.577606) (xy 424.768375 -296.611698)
			(xy 424.727872 -296.639654) (xy 424.68341 -296.660752) (xy 424.636139 -296.674444) (xy 424.587284 -296.680376)
			(xy 424.538109 -296.678395) (xy 424.48989 -296.668551) (xy 424.443874 -296.651099) (xy 424.401253 -296.626492)
			(xy 424.363132 -296.595367) (xy 424.330497 -296.55853) (xy 424.304194 -296.516934) (xy 424.284903 -296.471658)
			(xy 424.273126 -296.423874) (xy 424.269166 -296.37482) (xy 423.930318 -296.37482) (xy 423.929823 -296.399427)
			(xy 423.921928 -296.448004) (xy 423.906344 -296.494685) (xy 423.883473 -296.538262) (xy 423.853908 -296.577606)
			(xy 423.818415 -296.611698) (xy 423.777912 -296.639654) (xy 423.73345 -296.660752) (xy 423.686179 -296.674444)
			(xy 423.637324 -296.680376) (xy 423.588149 -296.678395) (xy 423.53993 -296.668551) (xy 423.493914 -296.651099)
			(xy 423.451293 -296.626492) (xy 423.413172 -296.595367) (xy 423.380537 -296.55853) (xy 423.354234 -296.516934)
			(xy 423.334943 -296.471658) (xy 423.323166 -296.423874) (xy 423.319206 -296.37482) (xy 422.980104 -296.37482)
			(xy 422.979609 -296.399427) (xy 422.971714 -296.448004) (xy 422.95613 -296.494685) (xy 422.933259 -296.538262)
			(xy 422.903694 -296.577606) (xy 422.868201 -296.611698) (xy 422.827698 -296.639654) (xy 422.783236 -296.660752)
			(xy 422.735965 -296.674444) (xy 422.68711 -296.680376) (xy 422.637935 -296.678395) (xy 422.589716 -296.668551)
			(xy 422.5437 -296.651099) (xy 422.501079 -296.626492) (xy 422.462958 -296.595367) (xy 422.430323 -296.55853)
			(xy 422.40402 -296.516934) (xy 422.384729 -296.471658) (xy 422.372952 -296.423874) (xy 422.368992 -296.37482)
			(xy 422.030144 -296.37482) (xy 422.029649 -296.399427) (xy 422.021754 -296.448004) (xy 422.00617 -296.494685)
			(xy 421.983299 -296.538262) (xy 421.953734 -296.577606) (xy 421.918241 -296.611698) (xy 421.877738 -296.639654)
			(xy 421.833276 -296.660752) (xy 421.786005 -296.674444) (xy 421.73715 -296.680376) (xy 421.687975 -296.678395)
			(xy 421.639756 -296.668551) (xy 421.59374 -296.651099) (xy 421.551119 -296.626492) (xy 421.512998 -296.595367)
			(xy 421.480363 -296.55853) (xy 421.45406 -296.516934) (xy 421.434769 -296.471658) (xy 421.422992 -296.423874)
			(xy 421.419032 -296.37482) (xy 421.080184 -296.37482) (xy 421.079689 -296.399427) (xy 421.071794 -296.448004)
			(xy 421.05621 -296.494685) (xy 421.033339 -296.538262) (xy 421.003774 -296.577606) (xy 420.968281 -296.611698)
			(xy 420.927778 -296.639654) (xy 420.883316 -296.660752) (xy 420.836045 -296.674444) (xy 420.78719 -296.680376)
			(xy 420.738015 -296.678395) (xy 420.689796 -296.668551) (xy 420.64378 -296.651099) (xy 420.601159 -296.626492)
			(xy 420.563038 -296.595367) (xy 420.530403 -296.55853) (xy 420.5041 -296.516934) (xy 420.484809 -296.471658)
			(xy 420.473032 -296.423874) (xy 420.469072 -296.37482) (xy 420.130224 -296.37482) (xy 420.129729 -296.399427)
			(xy 420.121834 -296.448004) (xy 420.10625 -296.494685) (xy 420.083379 -296.538262) (xy 420.053814 -296.577606)
			(xy 420.018321 -296.611698) (xy 419.977818 -296.639654) (xy 419.933356 -296.660752) (xy 419.886085 -296.674444)
			(xy 419.83723 -296.680376) (xy 419.788055 -296.678395) (xy 419.739836 -296.668551) (xy 419.69382 -296.651099)
			(xy 419.651199 -296.626492) (xy 419.613078 -296.595367) (xy 419.580443 -296.55853) (xy 419.55414 -296.516934)
			(xy 419.534849 -296.471658) (xy 419.523072 -296.423874) (xy 419.519112 -296.37482) (xy 419.180264 -296.37482)
			(xy 419.179769 -296.399427) (xy 419.171874 -296.448004) (xy 419.15629 -296.494685) (xy 419.133419 -296.538262)
			(xy 419.103854 -296.577606) (xy 419.068361 -296.611698) (xy 419.027858 -296.639654) (xy 418.983396 -296.660752)
			(xy 418.936125 -296.674444) (xy 418.88727 -296.680376) (xy 418.838095 -296.678395) (xy 418.789876 -296.668551)
			(xy 418.74386 -296.651099) (xy 418.701239 -296.626492) (xy 418.663118 -296.595367) (xy 418.630483 -296.55853)
			(xy 418.60418 -296.516934) (xy 418.584889 -296.471658) (xy 418.573112 -296.423874) (xy 418.569152 -296.37482)
			(xy 418.255704 -296.37482) (xy 418.255111 -296.403284) (xy 418.245375 -296.459374) (xy 418.226191 -296.512974)
			(xy 418.198126 -296.562504) (xy 418.18052 -296.584878) (xy 418.174424 -296.592244) (xy 418.17163 -296.600626)
			(xy 418.17025 -296.60513) (xy 418.168966 -296.61446) (xy 418.16909 -296.619168) (xy 418.169852 -296.635678)
			(xy 418.172392 -296.690542) (xy 418.173633 -296.699084) (xy 418.18103 -296.714667) (xy 418.18687 -296.721022)
			(xy 418.528754 -297.062906) (xy 418.535108 -297.068752) (xy 418.550687 -297.076172) (xy 418.559234 -297.077384)
			(xy 418.614098 -297.079924) (xy 418.630608 -297.080686) (xy 418.635318 -297.080823) (xy 418.644652 -297.079548)
			(xy 418.64915 -297.078146) (xy 418.657532 -297.075352) (xy 418.664898 -297.069256) (xy 418.68727 -297.051645)
			(xy 418.736796 -297.023568) (xy 418.790397 -297.004381) (xy 418.84649 -296.994648) (xy 418.874956 -296.994072)
			(xy 418.900043 -296.994534) (xy 418.949642 -297.002106) (xy 418.997529 -297.017083) (xy 419.042603 -297.039122)
			(xy 419.083832 -297.067716) (xy 419.120268 -297.10221) (xy 419.151076 -297.141811) (xy 419.175549 -297.185612)
			(xy 419.193125 -297.232607) (xy 419.203401 -297.281718) (xy 419.205156 -297.306746) (xy 419.205664 -297.316144)
			(xy 419.209474 -297.324526) (xy 419.211447 -297.328731) (xy 419.216685 -297.336402) (xy 419.219888 -297.339766)
			(xy 419.241986 -297.361864) (xy 419.247737 -297.367059) (xy 419.26157 -297.374029) (xy 419.269164 -297.37558)
			(xy 419.277546 -297.376342) (xy 419.422326 -297.376342) (xy 419.430708 -297.37558) (xy 419.438312 -297.374064)
			(xy 419.452142 -297.367073) (xy 419.457886 -297.361864) (xy 419.479984 -297.339766) (xy 419.48318 -297.336396)
			(xy 419.488414 -297.328726) (xy 419.490398 -297.324526) (xy 419.494208 -297.316144) (xy 419.494716 -297.306746)
			(xy 419.496671 -297.280409) (xy 419.507895 -297.228806) (xy 419.527177 -297.179642) (xy 419.554028 -297.134168)
			(xy 419.587764 -297.093539) (xy 419.627528 -297.058789) (xy 419.67231 -297.030799) (xy 419.720971 -297.010282)
			(xy 419.772275 -296.99776) (xy 419.824916 -296.99355) (xy 419.877557 -296.99776) (xy 419.928861 -297.010282)
			(xy 419.977522 -297.030799) (xy 420.022304 -297.058789) (xy 420.062068 -297.093539) (xy 420.095804 -297.134168)
			(xy 420.122655 -297.179642) (xy 420.141937 -297.228806) (xy 420.153161 -297.280409) (xy 420.155116 -297.306746)
			(xy 420.155624 -297.316144) (xy 420.159434 -297.324526) (xy 420.161409 -297.32873) (xy 420.166651 -297.336396)
			(xy 420.169848 -297.339766) (xy 420.191946 -297.361864) (xy 420.197694 -297.367064) (xy 420.211526 -297.374045)
			(xy 420.219124 -297.37558) (xy 420.227506 -297.376342) (xy 420.263574 -297.376342) (xy 420.268121 -297.376218)
			(xy 420.277064 -297.374555) (xy 420.281354 -297.37304) (xy 420.289736 -297.369992) (xy 420.296848 -297.363896)
			(xy 420.324477 -297.340729) (xy 420.38447 -297.300732) (xy 420.416482 -297.28414) (xy 420.426388 -297.279314)
			(xy 420.453566 -297.24604) (xy 420.45636 -297.23588) (xy 420.464085 -297.210153) (xy 420.486698 -297.161432)
			(xy 420.516886 -297.117006) (xy 420.553857 -297.078042) (xy 420.596639 -297.045564) (xy 420.644107 -297.020427)
			(xy 420.695013 -297.003292) (xy 420.74802 -296.994608) (xy 420.774876 -296.994072) (xy 420.802355 -296.994614)
			(xy 420.856559 -297.003695) (xy 420.908516 -297.021611) (xy 420.956796 -297.047869) (xy 421.000071 -297.081747)
			(xy 421.037151 -297.122312) (xy 421.067015 -297.168449) (xy 421.078406 -297.193462) (xy 421.078406 -297.193716)
			(xy 421.08156 -297.200444) (xy 421.091107 -297.21182) (xy 421.097202 -297.216068) (xy 421.103298 -297.220132)
			(xy 421.117268 -297.224196) (xy 421.376348 -297.224196) (xy 421.380666 -297.223942) (xy 421.393121 -297.22177)
			(xy 421.413774 -297.207241) (xy 421.420036 -297.196256) (xy 421.430434 -297.172824) (xy 421.457392 -297.129224)
			(xy 421.490755 -297.090306) (xy 421.529723 -297.057001) (xy 421.573363 -297.030108) (xy 421.62063 -297.01027)
			(xy 421.670392 -296.997963) (xy 421.721457 -296.99348) (xy 421.772602 -296.996931) (xy 421.822602 -297.008231)
			(xy 421.870259 -297.027111) (xy 421.914433 -297.053118) (xy 421.954066 -297.085629) (xy 421.988207 -297.123866)
			(xy 422.01604 -297.166913) (xy 422.026842 -297.19016) (xy 422.02735 -297.191176) (xy 422.032176 -297.20159)
			(xy 422.041066 -297.212004) (xy 422.044368 -297.214036) (xy 422.347898 -297.214036) (xy 422.361868 -297.209718)
			(xy 422.364662 -297.20794) (xy 422.372536 -297.191176) (xy 422.373044 -297.19016) (xy 422.383808 -297.167152)
			(xy 422.41134 -297.124467) (xy 422.445075 -297.086495) (xy 422.484221 -297.054128) (xy 422.527856 -297.028128)
			(xy 422.574953 -297.009108) (xy 422.624406 -296.997513) (xy 422.67505 -296.993618) (xy 422.725694 -296.997513)
			(xy 422.775147 -297.009108) (xy 422.822244 -297.028128) (xy 422.865879 -297.054128) (xy 422.905025 -297.086495)
			(xy 422.93876 -297.124467) (xy 422.966292 -297.167152) (xy 422.977056 -297.19016) (xy 422.977564 -297.191176)
			(xy 422.98239 -297.20159) (xy 422.99128 -297.212004) (xy 422.994582 -297.214036) (xy 423.297858 -297.214036)
			(xy 423.311828 -297.209718) (xy 423.314622 -297.20794) (xy 423.322496 -297.191176) (xy 423.323004 -297.19016)
			(xy 423.333768 -297.167152) (xy 423.3613 -297.124467) (xy 423.395035 -297.086495) (xy 423.434181 -297.054128)
			(xy 423.477816 -297.028128) (xy 423.524913 -297.009108) (xy 423.574366 -296.997513) (xy 423.62501 -296.993618)
			(xy 423.675654 -296.997513) (xy 423.725107 -297.009108) (xy 423.772204 -297.028128) (xy 423.815839 -297.054128)
			(xy 423.854985 -297.086495) (xy 423.88872 -297.124467) (xy 423.916252 -297.167152) (xy 423.927016 -297.19016)
			(xy 423.927524 -297.191176) (xy 423.93235 -297.20159) (xy 423.94124 -297.212004) (xy 423.944542 -297.214036)
			(xy 424.247818 -297.214036) (xy 424.261788 -297.209718) (xy 424.264582 -297.20794) (xy 424.272456 -297.191176)
			(xy 424.272964 -297.19016) (xy 424.283728 -297.167152) (xy 424.31126 -297.124467) (xy 424.344995 -297.086495)
			(xy 424.384141 -297.054128) (xy 424.427776 -297.028128) (xy 424.474873 -297.009108) (xy 424.524326 -296.997513)
			(xy 424.57497 -296.993618) (xy 424.625614 -296.997513) (xy 424.675067 -297.009108) (xy 424.722164 -297.028128)
			(xy 424.765799 -297.054128) (xy 424.804945 -297.086495) (xy 424.83868 -297.124467) (xy 424.866212 -297.167152)
			(xy 424.876976 -297.19016) (xy 424.877484 -297.191176) (xy 424.88231 -297.20159) (xy 424.8912 -297.212004)
			(xy 424.894502 -297.214036) (xy 425.197778 -297.214036) (xy 425.211748 -297.209718) (xy 425.214542 -297.20794)
			(xy 425.222416 -297.191176) (xy 425.222924 -297.19016) (xy 425.233688 -297.167152) (xy 425.26122 -297.124467)
			(xy 425.294955 -297.086495) (xy 425.334101 -297.054128) (xy 425.377736 -297.028128) (xy 425.424833 -297.009108)
			(xy 425.474286 -296.997513) (xy 425.52493 -296.993618) (xy 425.575574 -296.997513) (xy 425.625027 -297.009108)
			(xy 425.672124 -297.028128) (xy 425.715759 -297.054128) (xy 425.754905 -297.086495) (xy 425.78864 -297.124467)
			(xy 425.816172 -297.167152) (xy 425.826936 -297.19016) (xy 425.827444 -297.191176) (xy 425.83227 -297.20159)
			(xy 425.84116 -297.212004) (xy 425.844462 -297.214036) (xy 426.147738 -297.214036) (xy 426.161708 -297.209718)
			(xy 426.164502 -297.20794) (xy 426.172376 -297.191176) (xy 426.172884 -297.19016) (xy 426.183648 -297.167152)
			(xy 426.21118 -297.124467) (xy 426.244915 -297.086495) (xy 426.284061 -297.054128) (xy 426.327696 -297.028128)
			(xy 426.374793 -297.009108) (xy 426.424246 -296.997513) (xy 426.47489 -296.993618) (xy 426.525534 -296.997513)
			(xy 426.574987 -297.009108) (xy 426.622084 -297.028128) (xy 426.665719 -297.054128) (xy 426.704865 -297.086495)
			(xy 426.7386 -297.124467) (xy 426.766132 -297.167152) (xy 426.776896 -297.19016) (xy 426.777404 -297.191176)
			(xy 426.78223 -297.20159) (xy 426.79112 -297.212004) (xy 426.794422 -297.214036) (xy 427.097698 -297.214036)
			(xy 427.111668 -297.209718) (xy 427.114462 -297.20794) (xy 427.122336 -297.191176) (xy 427.122844 -297.19016)
			(xy 427.133608 -297.167152) (xy 427.16114 -297.124467) (xy 427.194875 -297.086495) (xy 427.234021 -297.054128)
			(xy 427.277656 -297.028128) (xy 427.324753 -297.009108) (xy 427.374206 -296.997513) (xy 427.42485 -296.993618)
			(xy 427.475494 -296.997513) (xy 427.524947 -297.009108) (xy 427.572044 -297.028128) (xy 427.615679 -297.054128)
			(xy 427.654825 -297.086495) (xy 427.68856 -297.124467) (xy 427.716092 -297.167152) (xy 427.726856 -297.19016)
			(xy 427.727364 -297.191176) (xy 427.73219 -297.20159) (xy 427.74108 -297.212004) (xy 427.744382 -297.214036)
			(xy 428.047658 -297.214036) (xy 428.061628 -297.209718) (xy 428.064422 -297.20794) (xy 428.072296 -297.191176)
			(xy 428.072804 -297.19016) (xy 428.083568 -297.167152) (xy 428.1111 -297.124467) (xy 428.144835 -297.086495)
			(xy 428.183981 -297.054128) (xy 428.227616 -297.028128) (xy 428.274713 -297.009108) (xy 428.324166 -296.997513)
			(xy 428.37481 -296.993618) (xy 428.425454 -296.997513) (xy 428.474907 -297.009108) (xy 428.522004 -297.028128)
			(xy 428.565639 -297.054128) (xy 428.604785 -297.086495) (xy 428.63852 -297.124467) (xy 428.666052 -297.167152)
			(xy 428.676816 -297.19016) (xy 428.677324 -297.191176) (xy 428.68215 -297.20159) (xy 428.69104 -297.212004)
			(xy 428.694342 -297.214036) (xy 428.997872 -297.214036) (xy 429.011842 -297.209718) (xy 429.014636 -297.20794)
			(xy 429.02251 -297.191176) (xy 429.023018 -297.19016) (xy 429.033782 -297.167152) (xy 429.061314 -297.124467)
			(xy 429.095049 -297.086495) (xy 429.134195 -297.054128) (xy 429.17783 -297.028128) (xy 429.224927 -297.009108)
			(xy 429.27438 -296.997513) (xy 429.325024 -296.993618) (xy 429.375668 -296.997513) (xy 429.425121 -297.009108)
			(xy 429.472218 -297.028128) (xy 429.515853 -297.054128) (xy 429.554999 -297.086495) (xy 429.588734 -297.124467)
			(xy 429.616266 -297.167152) (xy 429.62703 -297.19016) (xy 429.627538 -297.191176) (xy 429.632364 -297.20159)
			(xy 429.641254 -297.212004) (xy 429.644556 -297.214036) (xy 429.947832 -297.214036) (xy 429.961802 -297.209718)
			(xy 429.964596 -297.20794) (xy 429.97247 -297.191176) (xy 429.972978 -297.19016) (xy 429.983742 -297.167152)
			(xy 430.011274 -297.124467) (xy 430.045009 -297.086495) (xy 430.084155 -297.054128) (xy 430.12779 -297.028128)
			(xy 430.174887 -297.009108) (xy 430.22434 -296.997513) (xy 430.274984 -296.993618) (xy 430.325628 -296.997513)
			(xy 430.375081 -297.009108) (xy 430.422178 -297.028128) (xy 430.465813 -297.054128) (xy 430.504959 -297.086495)
			(xy 430.538694 -297.124467) (xy 430.566226 -297.167152) (xy 430.57699 -297.19016) (xy 430.577498 -297.191176)
			(xy 430.582324 -297.20159) (xy 430.591214 -297.212004) (xy 430.594516 -297.214036) (xy 430.897792 -297.214036)
			(xy 430.911762 -297.209718) (xy 430.914556 -297.20794) (xy 430.92243 -297.191176) (xy 430.922938 -297.19016)
			(xy 430.933702 -297.167152) (xy 430.961234 -297.124467) (xy 430.994969 -297.086495) (xy 431.034115 -297.054128)
			(xy 431.07775 -297.028128) (xy 431.124847 -297.009108) (xy 431.1743 -296.997513) (xy 431.224944 -296.993618)
			(xy 431.275588 -296.997513) (xy 431.325041 -297.009108) (xy 431.372138 -297.028128) (xy 431.415773 -297.054128)
			(xy 431.454919 -297.086495) (xy 431.488654 -297.124467) (xy 431.516186 -297.167152) (xy 431.52695 -297.19016)
			(xy 431.527458 -297.191176) (xy 431.532284 -297.20159) (xy 431.541174 -297.212004) (xy 431.544476 -297.214036)
			(xy 433.004214 -297.214036) (xy 433.039433 -297.214559) (xy 433.109364 -297.223) (xy 433.17778 -297.239761)
			(xy 433.243694 -297.264598) (xy 433.306157 -297.297154) (xy 433.36427 -297.33696) (xy 433.391056 -297.359832)
			(xy 433.391564 -297.36034) (xy 433.398422 -297.366182) (xy 433.41544 -297.372532) (xy 433.4383 -297.372532)
			(xy 433.454081 -297.372679) (xy 433.485594 -297.374459) (xy 433.501292 -297.376088) (xy 433.503832 -297.376342)
			(xy 433.636928 -297.376342) (xy 433.646995 -297.376772) (xy 433.665588 -297.384498) (xy 433.672996 -297.391328)
			(xy 433.734972 -297.453304) (xy 433.740306 -297.456606) (xy 433.770622 -297.475468) (xy 433.826874 -297.519447)
			(xy 433.877362 -297.569936) (xy 433.921339 -297.626189) (xy 433.940204 -297.656504) (xy 433.943506 -297.661838)
			(xy 434.25745 -297.975782) (xy 434.263199 -297.98098) (xy 434.277032 -297.987957) (xy 434.284628 -297.989498)
			(xy 434.29301 -297.99026) (xy 434.54828 -297.99026) (xy 434.556888 -297.989917) (xy 434.573135 -297.984223)
			(xy 434.586602 -297.973497) (xy 434.59146 -297.966384) (xy 434.644038 -297.881802) (xy 434.645308 -297.85564)
			(xy 434.639212 -297.843702) (xy 434.626882 -297.817405) (xy 434.609455 -297.762002) (xy 434.60065 -297.704594)
			(xy 434.600096 -297.675554) (xy 434.600096 -297.6753) (xy 434.600582 -297.648049) (xy 434.608338 -297.594101)
			(xy 434.623693 -297.541806) (xy 434.646335 -297.492229) (xy 434.675801 -297.446379) (xy 434.711492 -297.405188)
			(xy 434.752683 -297.369497) (xy 434.798533 -297.340031) (xy 434.84811 -297.317389) (xy 434.900405 -297.302034)
			(xy 434.954353 -297.294278) (xy 435.008855 -297.294278) (xy 435.062803 -297.302034) (xy 435.115098 -297.317389)
			(xy 435.164675 -297.340031) (xy 435.210525 -297.369497) (xy 435.251716 -297.405188) (xy 435.287407 -297.446379)
			(xy 435.316873 -297.492229) (xy 435.339515 -297.541806) (xy 435.35487 -297.594101) (xy 435.362626 -297.648049)
			(xy 435.363112 -297.6753) (xy 435.363112 -297.675554) (xy 435.362628 -297.702467) (xy 435.355029 -297.755753)
			(xy 435.340031 -297.807447) (xy 435.31793 -297.856527) (xy 435.30393 -297.879516) (xy 435.29758 -297.889422)
			(xy 435.294786 -297.911774) (xy 435.32298 -297.997118) (xy 435.327124 -298.007685) (xy 435.342817 -298.024042)
			(xy 435.353206 -298.028614) (xy 435.383688 -298.040858) (xy 435.441901 -298.071298) (xy 435.496269 -298.108169)
			(xy 435.546086 -298.15099) (xy 435.590703 -298.199205) (xy 435.629541 -298.252186) (xy 435.662094 -298.309244)
			(xy 435.687938 -298.369638) (xy 435.706739 -298.432581) (xy 435.718251 -298.497256) (xy 435.720744 -298.53001)
			(xy 435.722776 -298.541948) (xy 435.729115 -298.563378) (xy 435.738903 -298.606987) (xy 435.742334 -298.62907)
			(xy 435.745128 -298.647866) (xy 435.773576 -298.672504) (xy 436.172356 -298.672504) (xy 436.180634 -298.672178)
			(xy 436.19631 -298.666853) (xy 436.20309 -298.66209) (xy 436.228582 -298.643291) (xy 436.282884 -298.61068)
			(xy 436.340385 -298.584112) (xy 436.400415 -298.563896) (xy 436.462274 -298.550269) (xy 436.525241 -298.543389)
			(xy 436.556912 -298.542964) (xy 436.87873 -298.542964) (xy 436.911585 -298.54342) (xy 436.976884 -298.550769)
			(xy 437.040949 -298.565383) (xy 437.102975 -298.587077) (xy 437.162182 -298.615579) (xy 437.217826 -298.650531)
			(xy 437.269207 -298.691493) (xy 437.29275 -298.714414) (xy 437.370474 -298.792138) (xy 437.377873 -298.79898)
			(xy 437.396472 -298.806697) (xy 437.406542 -298.807124) (xy 437.785002 -298.807124) (xy 437.810202 -298.807659)
			(xy 437.859975 -298.815604) (xy 437.907903 -298.831204) (xy 437.952815 -298.85408) (xy 437.993615 -298.883674)
			(xy 438.011824 -298.901104) (xy 438.501028 -299.390562) (xy 438.508426 -299.397408) (xy 438.527025 -299.405139)
			(xy 438.537096 -299.405548) (xy 439.700162 -299.405548) (xy 439.735665 -299.406088) (xy 439.806147 -299.414704)
			(xy 439.875072 -299.431768) (xy 439.908442 -299.443902) (xy 439.917078 -299.447204) (xy 440.040776 -299.447204)
			(xy 440.066064 -299.447705) (xy 440.116018 -299.455622) (xy 440.16412 -299.471249) (xy 440.209189 -299.494203)
			(xy 440.250116 -299.523919) (xy 440.26836 -299.541438) (xy 440.43219 -299.705268) (xy 440.437936 -299.710474)
			(xy 440.451765 -299.717469) (xy 440.459368 -299.718984) (xy 440.46775 -299.719746) (xy 440.91987 -299.719746)
			(xy 440.947302 -299.698664) (xy 440.95162 -299.6819) (xy 440.959232 -299.655143) (xy 440.981143 -299.60401)
			(xy 441.010249 -299.556603) (xy 441.045933 -299.513927) (xy 441.087438 -299.476887) (xy 441.133884 -299.44627)
			(xy 441.184285 -299.422725) (xy 441.237571 -299.406752) (xy 441.292613 -299.398689) (xy 441.320428 -299.398182)
			(xy 441.347678 -299.39867) (xy 441.401623 -299.406429) (xy 441.453915 -299.421787) (xy 441.50349 -299.444429)
			(xy 441.549337 -299.473896) (xy 441.590525 -299.509588) (xy 441.626214 -299.550777) (xy 441.655679 -299.596626)
			(xy 441.678319 -299.646201) (xy 441.693674 -299.698494) (xy 441.701432 -299.75244) (xy 441.701936 -299.77969)
			(xy 441.701936 -299.780198) (xy 441.701575 -299.802703) (xy 441.696224 -299.847396) (xy 441.691268 -299.869352)
			(xy 441.690019 -299.875257) (xy 441.690016 -299.887324) (xy 441.691268 -299.893228) (xy 441.69624 -299.915181)
			(xy 441.701591 -299.959876) (xy 441.701936 -299.982382) (xy 441.701936 -299.98289) (xy 441.701472 -300.009519)
			(xy 441.694063 -300.062259) (xy 441.679387 -300.113455) (xy 441.657729 -300.16211) (xy 441.629512 -300.207279)
			(xy 441.595284 -300.248082) (xy 441.555711 -300.283724) (xy 441.511563 -300.313514) (xy 441.4637 -300.33687)
			(xy 441.438538 -300.345602) (xy 441.438284 -300.345602) (xy 441.437776 -300.345856) (xy 441.430506 -300.348613)
			(xy 441.417965 -300.357794) (xy 441.413138 -300.36389) (xy 441.408579 -300.37053) (xy 441.403524 -300.385813)
			(xy 441.403232 -300.393862) (xy 441.403232 -300.438312) (xy 441.428378 -300.46676) (xy 441.447682 -300.4693)
			(xy 441.481177 -300.474088) (xy 441.54685 -300.490385) (xy 441.610209 -300.514137) (xy 441.67041 -300.54503)
			(xy 441.726652 -300.58265) (xy 441.778186 -300.626499) (xy 441.824327 -300.675991) (xy 441.86446 -300.730469)
			(xy 441.898051 -300.789207) (xy 441.924653 -300.851423) (xy 441.943912 -300.916289) (xy 441.955571 -300.982942)
			(xy 441.959475 -301.050494) (xy 441.955572 -301.118046) (xy 441.943915 -301.184699) (xy 441.924658 -301.249565)
			(xy 441.898057 -301.311782) (xy 441.864467 -301.37052) (xy 441.824335 -301.424999) (xy 441.778195 -301.474493)
			(xy 441.726662 -301.518342) (xy 441.67042 -301.555964) (xy 441.61022 -301.586858) (xy 441.546862 -301.610612)
			(xy 441.481189 -301.62691) (xy 441.447682 -301.631604) (xy 441.428378 -301.634144) (xy 441.403232 -301.662592)
			(xy 441.403232 -302.603662) (xy 441.403572 -302.612356) (xy 441.409406 -302.628734) (xy 441.414662 -302.635666)
			(xy 441.420321 -302.642197) (xy 441.434994 -302.651303) (xy 441.443364 -302.653446) (xy 441.443618 -302.653446)
			(xy 441.470352 -302.659518) (xy 441.521857 -302.678299) (xy 441.570143 -302.704261) (xy 441.614213 -302.736868)
			(xy 441.653162 -302.775449) (xy 441.686186 -302.819209) (xy 441.712604 -302.867246) (xy 441.731873 -302.91857)
			(xy 441.743595 -302.972124) (xy 441.747528 -303.026805) (xy 441.743593 -303.081486) (xy 441.73187 -303.13504)
			(xy 441.712599 -303.186364) (xy 441.68618 -303.2344) (xy 441.653155 -303.278159) (xy 441.614205 -303.316739)
			(xy 441.570134 -303.349345) (xy 441.521848 -303.375305) (xy 441.470342 -303.394085) (xy 441.443618 -303.400206)
			(xy 441.443364 -303.400206) (xy 441.435016 -303.402404) (xy 441.420354 -303.411495) (xy 441.414662 -303.417986)
			(xy 441.409453 -303.424947) (xy 441.403597 -303.441305) (xy 441.403232 -303.44999) (xy 441.403232 -304.465228)
			(xy 441.402771 -304.475105) (xy 441.395329 -304.493404) (xy 441.388754 -304.500788) (xy 441.388246 -304.501296)
			(xy 441.382456 -304.507914) (xy 441.37534 -304.523981) (xy 441.374039 -304.541506) (xy 441.376054 -304.550064)
			(xy 441.381642 -304.56886) (xy 441.402216 -304.636932) (xy 441.405249 -304.645578) (xy 441.416393 -304.660106)
			(xy 441.431926 -304.669799) (xy 441.440824 -304.671984) (xy 441.469288 -304.678223) (xy 441.524032 -304.698179)
			(xy 441.575106 -304.726227) (xy 441.62132 -304.761716) (xy 441.6616 -304.803821) (xy 441.695008 -304.851561)
			(xy 441.720768 -304.903826) (xy 441.73828 -304.9594) (xy 441.747137 -305.016992) (xy 441.747656 -305.046126)
			(xy 441.747168 -305.073377) (xy 441.739409 -305.127325) (xy 441.724052 -305.179619) (xy 441.70141 -305.229196)
			(xy 441.671944 -305.275047) (xy 441.636253 -305.316238) (xy 441.595064 -305.351931) (xy 441.549215 -305.3814)
			(xy 441.49964 -305.404045) (xy 441.447346 -305.419405) (xy 441.393399 -305.427167) (xy 441.366148 -305.427634)
			(xy 441.337018 -305.427079) (xy 441.279436 -305.418214) (xy 441.223871 -305.400698) (xy 441.171615 -305.374937)
			(xy 441.123884 -305.341531) (xy 441.081785 -305.301257) (xy 441.046299 -305.255051) (xy 441.018251 -305.203987)
			(xy 440.998292 -305.149252) (xy 440.992006 -305.120802) (xy 440.990449 -305.114027) (xy 440.984141 -305.101645)
			(xy 440.97956 -305.096418) (xy 440.975242 -305.091592) (xy 440.963558 -305.084226) (xy 440.939174 -305.07686)
			(xy 440.871102 -305.056286) (xy 440.862231 -305.053996) (xy 440.843965 -305.055202) (xy 440.827305 -305.062788)
			(xy 440.820556 -305.068986) (xy 440.724036 -305.165506) (xy 440.720014 -305.169791) (xy 440.713853 -305.179795)
			(xy 440.711844 -305.185318) (xy 440.701988 -305.212986) (xy 440.674989 -305.265144) (xy 440.640316 -305.312549)
			(xy 440.598789 -305.354081) (xy 440.551389 -305.388761) (xy 440.499235 -305.415767) (xy 440.47156 -305.425602)
			(xy 440.466033 -305.427604) (xy 440.45602 -305.433757) (xy 440.451748 -305.437794) (xy 440.305698 -305.583844)
			(xy 440.302996 -305.586697) (xy 440.298411 -305.59308) (xy 440.296554 -305.596544) (xy 440.293968 -305.60197)
			(xy 440.291142 -305.61365) (xy 440.290966 -305.619658) (xy 440.290966 -307.40731) (xy 440.291 -307.411446)
			(xy 440.292279 -307.419616) (xy 440.293506 -307.423566) (xy 440.294896 -307.427435) (xy 440.29872 -307.434711)
			(xy 440.301126 -307.438044) (xy 440.304428 -307.441854) (xy 440.335416 -307.475382) (xy 440.351926 -307.493162)
			(xy 440.355249 -307.496566) (xy 440.362923 -307.502186) (xy 440.367166 -307.504338) (xy 440.375548 -307.508402)
			(xy 440.385454 -307.509164) (xy 440.413975 -307.511697) (xy 440.469845 -307.52423) (xy 440.523216 -307.54497)
			(xy 440.572888 -307.573451) (xy 440.617748 -307.609034) (xy 440.656787 -307.65092) (xy 440.68913 -307.698168)
			(xy 440.714051 -307.749719) (xy 440.73099 -307.804415) (xy 440.739566 -307.861027) (xy 440.740038 -307.889656)
			(xy 440.739874 -307.906508) (xy 440.736947 -307.940085) (xy 440.734196 -307.956712) (xy 440.73191 -307.969158)
			(xy 440.735466 -307.980842) (xy 440.737475 -307.986678) (xy 440.743895 -307.997215) (xy 440.748166 -308.00167)
			(xy 440.793124 -308.046628) (xy 440.798624 -308.051614) (xy 440.811791 -308.058455) (xy 440.819032 -308.06009)
			(xy 440.828684 -308.061106)
		)
		(stroke
			(width 0)
			(type solid)
		)
		(fill yes)
		(layer "In5.Cu")
		(net "P1V8_PEX")
	)
	(gr_poly
		(pts
			(xy 16.235172 -216.432892) (xy 16.248607 -216.432485) (xy 16.274548 -216.42548) (xy 16.297762 -216.411949)
			(xy 16.31664 -216.392828) (xy 16.329874 -216.369444) (xy 16.336548 -216.343416) (xy 16.336198 -216.316548)
			(xy 16.328849 -216.290703) (xy 16.322294 -216.278968) (xy 16.309343 -216.256616) (xy 16.288926 -216.209163)
			(xy 16.275104 -216.159388) (xy 16.268132 -216.108201) (xy 16.267684 -216.082372) (xy 16.26817 -216.055103)
			(xy 16.275932 -216.001119) (xy 16.291297 -215.948789) (xy 16.313954 -215.899179) (xy 16.34344 -215.853298)
			(xy 16.379155 -215.812081) (xy 16.420372 -215.776366) (xy 16.466253 -215.74688) (xy 16.515863 -215.724223)
			(xy 16.568193 -215.708858) (xy 16.622177 -215.701096) (xy 16.676715 -215.701096) (xy 16.730699 -215.708858)
			(xy 16.783029 -215.724223) (xy 16.832639 -215.74688) (xy 16.87852 -215.776366) (xy 16.919737 -215.812081)
			(xy 16.955452 -215.853298) (xy 16.984938 -215.899179) (xy 17.007595 -215.948789) (xy 17.02296 -216.001119)
			(xy 17.030722 -216.055103) (xy 17.031208 -216.082372) (xy 17.030758 -216.108199) (xy 17.023754 -216.159378)
			(xy 17.009926 -216.209147) (xy 16.989523 -216.256603) (xy 16.976598 -216.278968) (xy 16.97003 -216.290698)
			(xy 16.96268 -216.316547) (xy 16.96233 -216.343419) (xy 16.969005 -216.369451) (xy 16.982241 -216.392839)
			(xy 17.001122 -216.411964) (xy 17.024339 -216.425498) (xy 17.050283 -216.432506) (xy 17.06372 -216.432892)
			(xy 30.360112 -216.432892) (xy 30.370181 -216.432466) (xy 30.388782 -216.424748) (xy 30.39618 -216.417906)
			(xy 30.682438 -216.131648) (xy 30.689283 -216.12425) (xy 30.697008 -216.105651) (xy 30.697424 -216.09558)
			(xy 30.697424 -205.484476) (xy 30.696997 -205.474407) (xy 30.689279 -205.455807) (xy 30.682438 -205.448408)
			(xy 28.01874 -202.78471) (xy 28.011791 -202.778325) (xy 27.994575 -202.770641) (xy 27.975746 -202.769685)
			(xy 27.96667 -202.772264) (xy 27.963876 -202.77328) (xy 27.963368 -202.773534) (xy 27.932551 -202.783742)
			(xy 27.868571 -202.794716) (xy 27.836114 -202.795378) (xy 27.809022 -202.794905) (xy 27.755382 -202.787242)
			(xy 27.703366 -202.772068) (xy 27.654019 -202.749688) (xy 27.608334 -202.720552) (xy 27.567231 -202.685247)
			(xy 27.531535 -202.644482) (xy 27.501965 -202.599078) (xy 27.479115 -202.549947) (xy 27.463446 -202.498077)
			(xy 27.455271 -202.444513) (xy 27.454606 -202.417426) (xy 27.454606 -202.413616) (xy 27.4553 -202.380617)
			(xy 27.466663 -202.315605) (xy 27.477212 -202.28433) (xy 27.482292 -202.27036) (xy 27.475942 -202.241912)
			(xy 27.109674 -201.875644) (xy 27.102828 -201.868246) (xy 27.095102 -201.849647) (xy 27.094688 -201.839576)
			(xy 27.094688 -196.71284) (xy 27.094254 -196.702775) (xy 27.086523 -196.684187) (xy 27.079702 -196.676772)
			(xy 23.795736 -193.392806) (xy 23.788885 -193.385409) (xy 23.781142 -193.366811) (xy 23.78075 -193.356738)
			(xy 23.78075 -168.75252) (xy 23.781189 -168.742457) (xy 23.78893 -168.723879) (xy 23.795736 -168.716452)
			(xy 23.939246 -168.572942) (xy 23.942548 -168.567608) (xy 23.958516 -168.542913) (xy 23.996823 -168.498296)
			(xy 24.041515 -168.460076) (xy 24.066246 -168.444164) (xy 24.071326 -168.440862) (xy 24.514302 -167.997886)
			(xy 24.51481 -167.997378) (xy 24.521402 -167.99) (xy 24.52887 -167.971701) (xy 24.529288 -167.961818)
			(xy 24.529288 -167.70604) (xy 24.528772 -167.69511) (xy 24.519693 -167.675224) (xy 24.511762 -167.667686)
			(xy 24.445976 -167.610282) (xy 24.425148 -167.603932) (xy 24.414226 -167.605456) (xy 24.401585 -167.607019)
			(xy 24.376163 -167.60867) (xy 24.363426 -167.608758) (xy 24.362918 -167.608758) (xy 24.333547 -167.608219)
			(xy 24.275497 -167.599219) (xy 24.219513 -167.581428) (xy 24.166918 -167.555267) (xy 24.118953 -167.521354)
			(xy 24.076752 -167.480491) (xy 24.058626 -167.457374) (xy 24.05126 -167.447722) (xy 24.030432 -167.437308)
			(xy 23.979632 -167.437054) (xy 23.942802 -167.4368) (xy 23.933658 -167.437562) (xy 23.918926 -167.440102)
			(xy 23.903178 -167.449754) (xy 23.897336 -167.45712) (xy 23.891141 -167.464908) (xy 23.878052 -167.4799)
			(xy 23.871174 -167.487092) (xy 23.853127 -167.505323) (xy 23.812992 -167.537275) (xy 23.768942 -167.563565)
			(xy 23.721767 -167.58372) (xy 23.672319 -167.597377) (xy 23.621487 -167.604291) (xy 23.595838 -167.604694)
			(xy 23.568584 -167.604233) (xy 23.514631 -167.596481) (xy 23.462331 -167.581129) (xy 23.412748 -167.558489)
			(xy 23.366892 -167.529023) (xy 23.325696 -167.493331) (xy 23.289999 -167.452139) (xy 23.260529 -167.406286)
			(xy 23.237884 -167.356705) (xy 23.222527 -167.304406) (xy 23.214769 -167.250454) (xy 23.214769 -167.195946)
			(xy 23.222527 -167.141994) (xy 23.237884 -167.089695) (xy 23.260529 -167.040114) (xy 23.289999 -166.994261)
			(xy 23.325696 -166.953069) (xy 23.366892 -166.917377) (xy 23.412748 -166.887911) (xy 23.462331 -166.865271)
			(xy 23.514631 -166.849919) (xy 23.568584 -166.842167) (xy 23.595838 -166.841678) (xy 23.624904 -166.842221)
			(xy 23.682363 -166.851039) (xy 23.737816 -166.868481) (xy 23.789977 -166.894142) (xy 23.837637 -166.927427)
			(xy 23.879689 -166.967563) (xy 23.897844 -166.990268) (xy 23.899876 -166.992808) (xy 23.90013 -166.993062)
			(xy 23.906988 -167.002206) (xy 23.92807 -167.012874) (xy 23.979124 -167.013128) (xy 24.03221 -167.013382)
			(xy 24.053038 -167.003222) (xy 24.060404 -166.993824) (xy 24.066538 -166.986041) (xy 24.0795 -166.971049)
			(xy 24.086312 -166.963852) (xy 24.086566 -166.963598) (xy 24.101552 -166.948866) (xy 24.108664 -166.942008)
			(xy 24.112982 -166.932864) (xy 24.115041 -166.928033) (xy 24.117345 -166.917791) (xy 24.117554 -166.912544)
			(xy 24.118062 -166.877238) (xy 24.118062 -166.87673) (xy 24.118824 -166.840916) (xy 24.118603 -166.830854)
			(xy 24.111273 -166.812127) (xy 24.1046 -166.804594) (xy 24.104346 -166.80434) (xy 24.084086 -166.782823)
			(xy 24.049783 -166.7347) (xy 24.02331 -166.681864) (xy 24.0053 -166.625578) (xy 23.996182 -166.567189)
			(xy 23.995634 -166.53764) (xy 23.996133 -166.509607) (xy 24.004344 -166.454145) (xy 24.020581 -166.400482)
			(xy 24.044493 -166.349771) (xy 24.075568 -166.303104) (xy 24.113135 -166.261485) (xy 24.156387 -166.22581)
			(xy 24.204393 -166.196847) (xy 24.256119 -166.175219) (xy 24.283162 -166.167816) (xy 24.283416 -166.167816)
			(xy 24.292074 -166.165134) (xy 24.306897 -166.154721) (xy 24.312372 -166.147496) (xy 24.355552 -166.085774)
			(xy 24.360124 -166.068756) (xy 24.359108 -166.059358) (xy 24.357584 -166.02583) (xy 24.357584 -152.357836)
			(xy 24.35711 -152.347935) (xy 24.349612 -152.329607) (xy 24.33575 -152.315464) (xy 24.32685 -152.3111)
			(xy 24.31733 -152.307496) (xy 24.296993 -152.307349) (xy 24.278197 -152.315118) (xy 24.270716 -152.322022)
			(xy 23.168102 -153.424636) (xy 23.149332 -153.442669) (xy 23.107216 -153.473251) (xy 23.06084 -153.496879)
			(xy 23.011342 -153.512972) (xy 22.959938 -153.521135) (xy 22.933914 -153.521664) (xy 22.676104 -153.521664)
			(xy 22.667157 -153.522025) (xy 22.65036 -153.528194) (xy 22.636697 -153.53975) (xy 22.631908 -153.547318)
			(xy 22.6187 -153.5684) (xy 22.61389 -153.576966) (xy 22.610494 -153.596299) (xy 22.612096 -153.605992)
			(xy 22.61362 -153.61285) (xy 22.61616 -153.618184) (xy 22.627843 -153.643899) (xy 22.644345 -153.697915)
			(xy 22.652701 -153.753774) (xy 22.653244 -153.782014) (xy 22.653244 -153.782522) (xy 22.652758 -153.809773)
			(xy 22.645002 -153.863721) (xy 22.629647 -153.916016) (xy 22.607005 -153.965593) (xy 22.577539 -154.011443)
			(xy 22.541848 -154.052634) (xy 22.500657 -154.088325) (xy 22.454807 -154.117791) (xy 22.40523 -154.140433)
			(xy 22.352935 -154.155788) (xy 22.298987 -154.163544) (xy 22.244485 -154.163544) (xy 22.190537 -154.155788)
			(xy 22.138242 -154.140433) (xy 22.088665 -154.117791) (xy 22.042815 -154.088325) (xy 22.001624 -154.052634)
			(xy 21.965933 -154.011443) (xy 21.936467 -153.965593) (xy 21.913825 -153.916016) (xy 21.89847 -153.863721)
			(xy 21.890714 -153.809773) (xy 21.890228 -153.782522) (xy 21.890784 -153.754231) (xy 21.899223 -153.698279)
			(xy 21.91583 -153.644187) (xy 21.927566 -153.618438) (xy 21.92782 -153.617676) (xy 21.930614 -153.611326)
			(xy 21.931884 -153.604976) (xy 21.933002 -153.597659) (xy 21.93145 -153.582945) (xy 21.928836 -153.57602)
			(xy 21.92655 -153.570432) (xy 21.910548 -153.545286) (xy 21.910294 -153.544778) (xy 21.902821 -153.534512)
			(xy 21.880554 -153.522382) (xy 21.867876 -153.521664) (xy 20.69592 -153.521664) (xy 20.695666 -153.521664)
			(xy 20.68444 -153.522304) (xy 20.664137 -153.531909) (xy 20.65655 -153.540206) (xy 20.654518 -153.543)
			(xy 20.5994 -153.620724) (xy 20.595844 -153.644854) (xy 20.599908 -153.656792) (xy 20.609834 -153.687208)
			(xy 20.620556 -153.75028) (xy 20.621244 -153.782268) (xy 20.621244 -153.782522) (xy 20.620758 -153.809773)
			(xy 20.613002 -153.863721) (xy 20.597647 -153.916016) (xy 20.575005 -153.965593) (xy 20.545539 -154.011443)
			(xy 20.509848 -154.052634) (xy 20.468657 -154.088325) (xy 20.422807 -154.117791) (xy 20.37323 -154.140433)
			(xy 20.320935 -154.155788) (xy 20.266987 -154.163544) (xy 20.212485 -154.163544) (xy 20.158537 -154.155788)
			(xy 20.106242 -154.140433) (xy 20.056665 -154.117791) (xy 20.010815 -154.088325) (xy 19.969624 -154.052634)
			(xy 19.933933 -154.011443) (xy 19.904467 -153.965593) (xy 19.881825 -153.916016) (xy 19.86647 -153.863721)
			(xy 19.858714 -153.809773) (xy 19.858228 -153.782522) (xy 19.858784 -153.754231) (xy 19.867223 -153.698279)
			(xy 19.88383 -153.644187) (xy 19.895566 -153.618438) (xy 19.89582 -153.617676) (xy 19.898614 -153.611326)
			(xy 19.899884 -153.604976) (xy 19.901002 -153.597659) (xy 19.89945 -153.582945) (xy 19.896836 -153.57602)
			(xy 19.89455 -153.570432) (xy 19.878548 -153.545286) (xy 19.878294 -153.544778) (xy 19.870821 -153.534512)
			(xy 19.848554 -153.522382) (xy 19.835876 -153.521664) (xy 17.99209 -153.521664) (xy 17.982022 -153.522091)
			(xy 17.963426 -153.529815) (xy 17.956022 -153.53665) (xy 17.564354 -153.928572) (xy 17.558004 -153.93924)
			(xy 17.556226 -153.945082) (xy 17.547776 -153.970648) (xy 17.524695 -154.019295) (xy 17.495008 -154.064216)
			(xy 17.459304 -154.104521) (xy 17.418292 -154.13941) (xy 17.372785 -154.168191) (xy 17.323686 -154.190293)
			(xy 17.271968 -154.205277) (xy 17.218658 -154.212847) (xy 17.191736 -154.213306) (xy 17.177004 -154.213052)
			(xy 17.140936 -154.210004) (xy 17.115756 -154.206214) (xy 17.06663 -154.192816) (xy 17.019725 -154.172998)
			(xy 16.975876 -154.147112) (xy 16.935862 -154.11562) (xy 16.900396 -154.079083) (xy 16.884904 -154.058874)
			(xy 16.884904 -154.05862) (xy 16.882618 -154.055572) (xy 16.876522 -154.049476) (xy 16.869833 -154.043313)
			(xy 16.853302 -154.035757) (xy 16.844264 -154.034744) (xy 16.781526 -154.030172) (xy 16.770559 -154.029879)
			(xy 16.750018 -154.037521) (xy 16.741902 -154.044904) (xy 16.59001 -154.196796) (xy 16.566455 -154.21974)
			(xy 16.515055 -154.260756) (xy 16.459383 -154.295756) (xy 16.40014 -154.324298) (xy 16.338073 -154.346023)
			(xy 16.273962 -154.360658) (xy 16.208616 -154.368018) (xy 16.175736 -154.3685) (xy 16.139708 -154.367945)
			(xy 16.068196 -154.359099) (xy 15.99831 -154.341548) (xy 15.931103 -154.315558) (xy 15.867593 -154.281521)
			(xy 15.808736 -154.239951) (xy 15.755423 -154.191475) (xy 15.73149 -154.164538) (xy 15.724168 -154.156822)
			(xy 15.705007 -154.147641) (xy 15.694406 -154.146758) (xy 15.647924 -154.145488) (xy 15.637555 -154.145664)
			(xy 15.618283 -154.153269) (xy 15.610586 -154.16022) (xy 15.57401 -154.196796) (xy 15.550455 -154.21974)
			(xy 15.499055 -154.260756) (xy 15.443383 -154.295756) (xy 15.38414 -154.324298) (xy 15.322073 -154.346023)
			(xy 15.257962 -154.360658) (xy 15.192616 -154.368018) (xy 15.159736 -154.3685) (xy 15.124336 -154.367989)
			(xy 15.054053 -154.359459) (xy 14.98531 -154.342519) (xy 14.919111 -154.317415) (xy 14.85642 -154.284515)
			(xy 14.798153 -154.244298) (xy 14.745158 -154.19735) (xy 14.698209 -154.144357) (xy 14.657991 -154.08609)
			(xy 14.62509 -154.0234) (xy 14.599985 -153.957201) (xy 14.583043 -153.888459) (xy 14.574512 -153.818176)
			(xy 14.574012 -153.782776) (xy 14.574012 -153.782268) (xy 14.574452 -153.749412) (xy 14.581802 -153.684113)
			(xy 14.596417 -153.620047) (xy 14.618113 -153.55802) (xy 14.646618 -153.498813) (xy 14.681573 -153.443169)
			(xy 14.722538 -153.391789) (xy 14.745462 -153.368248) (xy 15.98041 -152.1333) (xy 15.988032 -152.12487)
			(xy 15.995683 -152.103503) (xy 15.995142 -152.092152) (xy 15.990062 -152.042876) (xy 15.988792 -152.029922)
			(xy 15.98757 -152.021169) (xy 15.98003 -152.005198) (xy 15.97406 -151.99868) (xy 15.963646 -151.988266)
			(xy 15.959836 -151.985726) (xy 15.938299 -151.970391) (xy 15.899265 -151.934733) (xy 15.865526 -151.894028)
			(xy 15.837727 -151.849056) (xy 15.816402 -151.800678) (xy 15.801958 -151.74982) (xy 15.794672 -151.697455)
			(xy 15.794228 -151.67102) (xy 15.79469 -151.643767) (xy 15.802445 -151.589816) (xy 15.8178 -151.537518)
			(xy 15.840441 -151.487937) (xy 15.869909 -151.442084) (xy 15.905604 -151.400892) (xy 15.946797 -151.3652)
			(xy 15.992651 -151.335734) (xy 16.042233 -151.313094) (xy 16.094532 -151.297741) (xy 16.148483 -151.289989)
			(xy 16.175736 -151.289512) (xy 16.203216 -151.289987) (xy 16.257608 -151.297867) (xy 16.310306 -151.313473)
			(xy 16.360219 -151.336481) (xy 16.406311 -151.366416) (xy 16.44763 -151.402656) (xy 16.483319 -151.444453)
			(xy 16.512638 -151.490939) (xy 16.534982 -151.541152) (xy 16.549886 -151.594053) (xy 16.553942 -151.621236)
			(xy 16.554196 -151.62276) (xy 16.55445 -151.62403) (xy 16.555466 -151.631904) (xy 16.566642 -151.653494)
			(xy 16.569434 -151.659421) (xy 16.577536 -151.669711) (xy 16.582644 -151.673814) (xy 16.592042 -151.681942)
			(xy 16.611854 -151.688292) (xy 16.622522 -151.687276) (xy 16.636776 -151.686027) (xy 16.665364 -151.684755)
			(xy 16.679672 -151.684736) (xy 16.755364 -151.684736) (xy 16.764383 -151.684383) (xy 16.78131 -151.678149)
			(xy 16.788384 -151.672544) (xy 16.79194 -151.669496) (xy 16.798544 -151.663146) (xy 16.815308 -151.633682)
			(xy 16.816832 -151.625554) (xy 16.822227 -151.599721) (xy 16.839185 -151.549748) (xy 16.862862 -151.502586)
			(xy 16.892808 -151.459133) (xy 16.928452 -151.420217) (xy 16.969115 -151.386581) (xy 17.014023 -151.358864)
			(xy 17.062319 -151.337594) (xy 17.113084 -151.323178) (xy 17.16535 -151.315889) (xy 17.191736 -151.31542)
			(xy 17.218908 -151.315902) (xy 17.2727 -151.323617) (xy 17.324855 -151.338886) (xy 17.374315 -151.3614)
			(xy 17.420081 -151.390703) (xy 17.461226 -151.426203) (xy 17.496919 -151.467181) (xy 17.526437 -151.512808)
			(xy 17.549183 -151.562162) (xy 17.564697 -151.614244) (xy 17.56918 -151.641048) (xy 17.56918 -151.64181)
			(xy 17.57093 -151.650678) (xy 17.57974 -151.666447) (xy 17.593481 -151.678172) (xy 17.610439 -151.684391)
			(xy 17.619472 -151.684736) (xy 17.981168 -151.684736) (xy 17.993674 -151.684091) (xy 18.015772 -151.672368)
			(xy 18.023332 -151.662384) (xy 18.039588 -151.638254) (xy 18.039588 -151.637746) (xy 18.070068 -151.591772)
			(xy 18.072354 -151.56688) (xy 18.067274 -151.554942) (xy 18.057821 -151.531498) (xy 18.044493 -151.482738)
			(xy 18.037739 -151.432642) (xy 18.037302 -151.407368) (xy 18.037302 -151.403304) (xy 18.038012 -151.376207)
			(xy 18.046148 -151.322616) (xy 18.061787 -151.270717) (xy 18.084614 -151.221553) (xy 18.11417 -151.176115)
			(xy 18.14986 -151.135318) (xy 18.190964 -151.099983) (xy 18.236656 -151.070821) (xy 18.286016 -151.04842)
			(xy 18.338049 -151.033231) (xy 18.391708 -151.025559) (xy 18.445912 -151.025559) (xy 18.499571 -151.033231)
			(xy 18.551604 -151.04842) (xy 18.600964 -151.070821) (xy 18.646656 -151.099983) (xy 18.68776 -151.135318)
			(xy 18.72345 -151.176115) (xy 18.753006 -151.221553) (xy 18.775833 -151.270717) (xy 18.791472 -151.322616)
			(xy 18.799608 -151.376207) (xy 18.800318 -151.403304) (xy 18.800318 -151.40686) (xy 18.799882 -151.432217)
			(xy 18.793135 -151.48248) (xy 18.779807 -151.531412) (xy 18.770346 -151.554942) (xy 18.765266 -151.56688)
			(xy 18.767552 -151.591772) (xy 18.798032 -151.637746) (xy 18.798032 -151.638254) (xy 18.814288 -151.662384)
			(xy 18.821817 -151.672404) (xy 18.843933 -151.684134) (xy 18.856452 -151.684736) (xy 19.293078 -151.684736)
			(xy 19.297904 -151.680418) (xy 19.348704 -151.62784) (xy 19.355177 -151.620485) (xy 19.362478 -151.602323)
			(xy 19.362928 -151.592534) (xy 19.362928 -151.573484) (xy 19.363182 -151.566118) (xy 19.364883 -151.538395)
			(xy 19.375305 -151.48384) (xy 19.393525 -151.431372) (xy 19.419158 -151.3821) (xy 19.451664 -151.337064)
			(xy 19.490355 -151.297216) (xy 19.534413 -151.263398) (xy 19.582909 -151.236324) (xy 19.634817 -151.216567)
			(xy 19.689042 -151.204543) (xy 19.744436 -151.200506) (xy 19.79983 -151.204543) (xy 19.854055 -151.216567)
			(xy 19.905963 -151.236324) (xy 19.954459 -151.263398) (xy 19.998517 -151.297216) (xy 20.037208 -151.337064)
			(xy 20.069714 -151.3821) (xy 20.095347 -151.431372) (xy 20.113567 -151.48384) (xy 20.123989 -151.538395)
			(xy 20.12569 -151.566118) (xy 20.125944 -151.573484) (xy 20.125944 -151.592026) (xy 20.125944 -151.593042)
			(xy 20.126407 -151.602918) (xy 20.13385 -151.621216) (xy 20.140422 -151.628602) (xy 20.15109 -151.639524)
			(xy 20.1803 -151.669496) (xy 20.187726 -151.676443) (xy 20.206462 -151.684301) (xy 20.216622 -151.684736)
			(xy 20.8153 -151.684736) (xy 20.826495 -151.684147) (xy 20.846777 -151.674655) (xy 20.854416 -151.666448)
			(xy 20.862036 -151.657558) (xy 20.862036 -151.65705) (xy 20.865084 -151.653748) (xy 20.87102 -151.646192)
			(xy 20.877307 -151.628049) (xy 20.877276 -151.618442) (xy 20.877022 -151.616156) (xy 20.876768 -151.614378)
			(xy 20.875548 -151.603115) (xy 20.874279 -151.580494) (xy 20.874228 -151.569166) (xy 20.874694 -151.541916)
			(xy 20.882455 -151.48797) (xy 20.897814 -151.435679) (xy 20.920459 -151.386105) (xy 20.949929 -151.340259)
			(xy 20.985623 -151.299073) (xy 21.026815 -151.263387) (xy 21.072667 -151.233925) (xy 21.122244 -151.21129)
			(xy 21.174539 -151.19594) (xy 21.228486 -151.188189) (xy 21.255736 -151.187658) (xy 21.283474 -151.188158)
			(xy 21.338364 -151.196195) (xy 21.391513 -151.212095) (xy 21.441799 -151.235522) (xy 21.488164 -151.265983)
			(xy 21.52963 -151.302836) (xy 21.565323 -151.345305) (xy 21.594492 -151.392493) (xy 21.616521 -151.443408)
			(xy 21.630946 -151.496975) (xy 21.634704 -151.524462) (xy 21.637244 -151.546052) (xy 21.637498 -151.551132)
			(xy 21.637498 -151.56942) (xy 21.63699 -151.588724) (xy 21.636482 -151.59863) (xy 21.640038 -151.60879)
			(xy 21.643594 -151.619712) (xy 21.690838 -151.668988) (xy 21.698313 -151.67615) (xy 21.717326 -151.684282)
			(xy 21.727668 -151.684736) (xy 22.166326 -151.684736) (xy 22.176203 -151.684276) (xy 22.194503 -151.676834)
			(xy 22.201886 -151.670258) (xy 22.20214 -151.670004) (xy 22.810978 -151.061166) (xy 22.811486 -151.060658)
			(xy 22.818067 -151.053276) (xy 22.825516 -151.034977) (xy 22.825964 -151.025098) (xy 22.825964 -113.547652)
			(xy 22.80793 -113.521744) (xy 22.79269 -113.516156) (xy 22.767263 -113.506231) (xy 22.719312 -113.480154)
			(xy 22.675567 -113.447509) (xy 22.636922 -113.408961) (xy 22.604167 -113.365299) (xy 22.577969 -113.317414)
			(xy 22.558864 -113.266283) (xy 22.547242 -113.212952) (xy 22.543341 -113.158508) (xy 22.54724 -113.104065)
			(xy 22.558859 -113.050733) (xy 22.577962 -112.999601) (xy 22.604158 -112.951715) (xy 22.636911 -112.908051)
			(xy 22.675554 -112.869502) (xy 22.719298 -112.836855) (xy 22.767248 -112.810776) (xy 22.79269 -112.800892)
			(xy 22.800056 -112.798098) (xy 22.812248 -112.7887) (xy 22.81682 -112.78235) (xy 22.821026 -112.775792)
			(xy 22.82567 -112.760927) (xy 22.825964 -112.75314) (xy 22.825964 -95.98025) (xy 22.826421 -95.947395)
			(xy 22.833773 -95.882098) (xy 22.848388 -95.818034) (xy 22.870084 -95.75601) (xy 22.898587 -95.696804)
			(xy 22.93354 -95.641161) (xy 22.974502 -95.589782) (xy 22.997414 -95.56623) (xy 23.852378 -94.711266)
			(xy 23.875942 -94.688369) (xy 23.927326 -94.647417) (xy 23.982969 -94.612471) (xy 24.042173 -94.583971)
			(xy 24.104193 -94.562273) (xy 24.168252 -94.547651) (xy 24.233545 -94.540288) (xy 24.266398 -94.539816)
			(xy 24.957024 -94.539816) (xy 24.988227 -94.540203) (xy 25.050282 -94.546813) (xy 25.111281 -94.559989)
			(xy 25.170532 -94.579579) (xy 25.227362 -94.605362) (xy 25.254458 -94.620842) (xy 25.260368 -94.624099)
			(xy 25.273369 -94.627696) (xy 25.280112 -94.627954) (xy 26.145998 -94.627954) (xy 26.150824 -94.6277)
			(xy 26.159582 -94.626486) (xy 26.175565 -94.618959) (xy 26.182066 -94.612968) (xy 26.88971 -93.905324)
			(xy 26.896554 -93.897926) (xy 26.904275 -93.879326) (xy 26.904696 -93.869256) (xy 26.904696 -78.645766)
			(xy 26.904266 -78.635699) (xy 26.896543 -78.617104) (xy 26.88971 -78.609698) (xy 26.088594 -77.808582)
			(xy 26.081199 -77.801728) (xy 26.0626 -77.793982) (xy 26.052526 -77.793596) (xy 20.09775 -77.793596)
			(xy 20.090384 -77.789024) (xy 19.087846 -77.789024) (xy 19.061823 -77.788496) (xy 19.01042 -77.780328)
			(xy 18.960924 -77.764233) (xy 18.914549 -77.740605) (xy 18.872433 -77.710024) (xy 18.853658 -77.691996)
			(xy 12.467844 -71.306182) (xy 12.460732 -71.298816) (xy 12.441936 -71.291196) (xy 10.145268 -71.291196)
			(xy 10.134759 -71.291729) (xy 10.115493 -71.300135) (xy 10.10793 -71.307452) (xy 10.09142 -71.324978)
			(xy 10.09142 -71.325486) (xy 10.050272 -71.369936) (xy 10.043414 -71.389748) (xy 10.044176 -71.400416)
			(xy 10.0457 -71.443088) (xy 10.0457 -71.443596) (xy 10.045276 -71.475469) (xy 10.038238 -71.538824)
			(xy 10.024237 -71.601013) (xy 10.003445 -71.661272) (xy 9.976117 -71.718862) (xy 9.942587 -71.773077)
			(xy 9.923272 -71.798434) (xy 9.920478 -71.802244) (xy 9.903189 -71.828418) (xy 9.863863 -71.877293)
			(xy 9.841992 -71.89978) (xy 7.635748 -74.106024) (xy 8.468612 -74.106024) (xy 8.472683 -74.050402)
			(xy 8.484809 -73.995965) (xy 8.504732 -73.943874) (xy 8.532028 -73.895239) (xy 8.566114 -73.851096)
			(xy 8.606263 -73.812387) (xy 8.651621 -73.779936) (xy 8.701221 -73.754435) (xy 8.754005 -73.736428)
			(xy 8.808848 -73.726298) (xy 8.864582 -73.724261) (xy 8.920019 -73.730361) (xy 8.973976 -73.744467)
			(xy 9.025305 -73.766279) (xy 9.072911 -73.795333) (xy 9.115779 -73.831008) (xy 9.152996 -73.872545)
			(xy 9.183769 -73.919058) (xy 9.207441 -73.969555) (xy 9.223509 -74.022962) (xy 9.231629 -74.078138)
			(xy 9.232138 -74.106024) (xy 9.231629 -74.13391) (xy 9.223509 -74.189086) (xy 9.207441 -74.242493)
			(xy 9.183769 -74.29299) (xy 9.152996 -74.339503) (xy 9.115779 -74.38104) (xy 9.072911 -74.416715)
			(xy 9.025305 -74.445769) (xy 8.973976 -74.467581) (xy 8.920019 -74.481687) (xy 8.864582 -74.487787)
			(xy 8.808848 -74.48575) (xy 8.754005 -74.47562) (xy 8.701221 -74.457613) (xy 8.651621 -74.432112)
			(xy 8.606263 -74.399661) (xy 8.566114 -74.360952) (xy 8.532028 -74.316809) (xy 8.504732 -74.268174)
			(xy 8.484809 -74.216083) (xy 8.472683 -74.161646) (xy 8.468612 -74.106024) (xy 7.635748 -74.106024)
			(xy 7.413498 -74.328274) (xy 7.389933 -74.351168) (xy 7.338547 -74.392116) (xy 7.282903 -74.427057)
			(xy 7.2237 -74.455553) (xy 7.16168 -74.477247) (xy 7.097622 -74.491865) (xy 7.03233 -74.499225) (xy 6.999478 -74.499724)
			(xy 3.682492 -74.499724) (xy 3.649637 -74.499266) (xy 3.584341 -74.491914) (xy 3.520278 -74.477298)
			(xy 3.458254 -74.4556) (xy 3.39905 -74.427096) (xy 3.343409 -74.392142) (xy 3.292032 -74.351178)
			(xy 3.268472 -74.328274) (xy 1.685544 -72.745346) (xy 1.678432 -72.73798) (xy 1.659636 -72.73036)
			(xy 1.534922 -72.73036) (xy 1.524859 -72.730799) (xy 1.506281 -72.73854) (xy 1.498854 -72.745346)
			(xy 1.335786 -72.908414) (xy 1.32842 -72.915526) (xy 1.3208 -72.934322) (xy 1.3208 -75.087226) (xy 6.381748 -75.087226)
			(xy 6.385819 -75.031604) (xy 6.397945 -74.977167) (xy 6.417868 -74.925076) (xy 6.445164 -74.876441)
			(xy 6.47925 -74.832298) (xy 6.519399 -74.793589) (xy 6.564757 -74.761138) (xy 6.614357 -74.735637)
			(xy 6.667141 -74.71763) (xy 6.721984 -74.7075) (xy 6.777718 -74.705463) (xy 6.833155 -74.711563)
			(xy 6.887112 -74.725669) (xy 6.938441 -74.747481) (xy 6.986047 -74.776535) (xy 7.028915 -74.81221)
			(xy 7.066132 -74.853747) (xy 7.096905 -74.90026) (xy 7.120577 -74.950757) (xy 7.136645 -75.004164)
			(xy 7.144765 -75.05934) (xy 7.145274 -75.087226) (xy 7.144765 -75.115112) (xy 7.136645 -75.170288)
			(xy 7.120577 -75.223695) (xy 7.096905 -75.274192) (xy 7.066132 -75.320705) (xy 7.028915 -75.362242)
			(xy 6.986047 -75.397917) (xy 6.938441 -75.426971) (xy 6.887112 -75.448783) (xy 6.833155 -75.462889)
			(xy 6.777718 -75.468989) (xy 6.721984 -75.466952) (xy 6.667141 -75.456822) (xy 6.614357 -75.438815)
			(xy 6.564757 -75.413314) (xy 6.519399 -75.380863) (xy 6.47925 -75.342154) (xy 6.445164 -75.298011)
			(xy 6.417868 -75.249376) (xy 6.397945 -75.197285) (xy 6.385819 -75.142848) (xy 6.381748 -75.087226)
			(xy 1.3208 -75.087226) (xy 1.3208 -82.351118) (xy 1.32126 -82.360995) (xy 1.328703 -82.379294) (xy 1.335278 -82.386678)
			(xy 1.335532 -82.386932) (xy 5.583682 -86.635082) (xy 5.590517 -86.642484) (xy 5.598225 -86.661083)
			(xy 5.598668 -86.67115) (xy 5.598668 -112.501426) (xy 11.973304 -112.501426) (xy 11.977375 -112.445804)
			(xy 11.989501 -112.391367) (xy 12.009424 -112.339276) (xy 12.03672 -112.290641) (xy 12.070806 -112.246498)
			(xy 12.110955 -112.207789) (xy 12.156313 -112.175338) (xy 12.205913 -112.149837) (xy 12.258697 -112.13183)
			(xy 12.31354 -112.1217) (xy 12.369274 -112.119663) (xy 12.424711 -112.125763) (xy 12.478668 -112.139869)
			(xy 12.529997 -112.161681) (xy 12.577603 -112.190735) (xy 12.620471 -112.22641) (xy 12.657688 -112.267947)
			(xy 12.688461 -112.31446) (xy 12.712133 -112.364957) (xy 12.728201 -112.418364) (xy 12.736321 -112.47354)
			(xy 12.73683 -112.501426) (xy 12.736321 -112.529312) (xy 12.728201 -112.584488) (xy 12.712133 -112.637895)
			(xy 12.688461 -112.688392) (xy 12.657688 -112.734905) (xy 12.620471 -112.776442) (xy 12.577603 -112.812117)
			(xy 12.529997 -112.841171) (xy 12.478668 -112.862983) (xy 12.424711 -112.877089) (xy 12.369274 -112.883189)
			(xy 12.31354 -112.881152) (xy 12.258697 -112.871022) (xy 12.205913 -112.853015) (xy 12.156313 -112.827514)
			(xy 12.110955 -112.795063) (xy 12.070806 -112.756354) (xy 12.03672 -112.712211) (xy 12.009424 -112.663576)
			(xy 11.989501 -112.611485) (xy 11.977375 -112.557048) (xy 11.973304 -112.501426) (xy 5.598668 -112.501426)
			(xy 5.598668 -113.302034) (xy 14.31366 -113.302034) (xy 14.317731 -113.246412) (xy 14.329857 -113.191975)
			(xy 14.34978 -113.139884) (xy 14.377076 -113.091249) (xy 14.411162 -113.047106) (xy 14.451311 -113.008397)
			(xy 14.496669 -112.975946) (xy 14.546269 -112.950445) (xy 14.599053 -112.932438) (xy 14.653896 -112.922308)
			(xy 14.70963 -112.920271) (xy 14.765067 -112.926371) (xy 14.819024 -112.940477) (xy 14.870353 -112.962289)
			(xy 14.917959 -112.991343) (xy 14.960827 -113.027018) (xy 14.998044 -113.068555) (xy 15.028817 -113.115068)
			(xy 15.052489 -113.165565) (xy 15.057783 -113.183162) (xy 16.31518 -113.183162) (xy 16.319251 -113.12754)
			(xy 16.331377 -113.073103) (xy 16.3513 -113.021012) (xy 16.378596 -112.972377) (xy 16.412682 -112.928234)
			(xy 16.452831 -112.889525) (xy 16.498189 -112.857074) (xy 16.547789 -112.831573) (xy 16.600573 -112.813566)
			(xy 16.655416 -112.803436) (xy 16.71115 -112.801399) (xy 16.766587 -112.807499) (xy 16.820544 -112.821605)
			(xy 16.871873 -112.843417) (xy 16.919479 -112.872471) (xy 16.962347 -112.908146) (xy 16.999564 -112.949683)
			(xy 17.030337 -112.996196) (xy 17.054009 -113.046693) (xy 17.070077 -113.1001) (xy 17.078197 -113.155276)
			(xy 17.078706 -113.183162) (xy 17.078197 -113.211048) (xy 17.070077 -113.266224) (xy 17.054009 -113.319631)
			(xy 17.030337 -113.370128) (xy 16.999564 -113.416641) (xy 16.962347 -113.458178) (xy 16.919479 -113.493853)
			(xy 16.871873 -113.522907) (xy 16.820544 -113.544719) (xy 16.766587 -113.558825) (xy 16.71115 -113.564925)
			(xy 16.655416 -113.562888) (xy 16.600573 -113.552758) (xy 16.547789 -113.534751) (xy 16.498189 -113.50925)
			(xy 16.452831 -113.476799) (xy 16.412682 -113.43809) (xy 16.378596 -113.393947) (xy 16.3513 -113.345312)
			(xy 16.331377 -113.293221) (xy 16.319251 -113.238784) (xy 16.31518 -113.183162) (xy 15.057783 -113.183162)
			(xy 15.068557 -113.218972) (xy 15.076677 -113.274148) (xy 15.077186 -113.302034) (xy 15.076677 -113.32992)
			(xy 15.068557 -113.385096) (xy 15.052489 -113.438503) (xy 15.028817 -113.489) (xy 14.998044 -113.535513)
			(xy 14.960827 -113.57705) (xy 14.917959 -113.612725) (xy 14.870353 -113.641779) (xy 14.819024 -113.663591)
			(xy 14.765067 -113.677697) (xy 14.70963 -113.683797) (xy 14.653896 -113.68176) (xy 14.599053 -113.67163)
			(xy 14.546269 -113.653623) (xy 14.496669 -113.628122) (xy 14.451311 -113.595671) (xy 14.411162 -113.556962)
			(xy 14.377076 -113.512819) (xy 14.34978 -113.464184) (xy 14.329857 -113.412093) (xy 14.317731 -113.357656)
			(xy 14.31366 -113.302034) (xy 5.598668 -113.302034) (xy 5.598668 -114.660426) (xy 11.961366 -114.660426)
			(xy 11.965437 -114.604804) (xy 11.977563 -114.550367) (xy 11.997486 -114.498276) (xy 12.024782 -114.449641)
			(xy 12.058868 -114.405498) (xy 12.099017 -114.366789) (xy 12.144375 -114.334338) (xy 12.193975 -114.308837)
			(xy 12.246759 -114.29083) (xy 12.301602 -114.2807) (xy 12.357336 -114.278663) (xy 12.412773 -114.284763)
			(xy 12.46673 -114.298869) (xy 12.518059 -114.320681) (xy 12.565665 -114.349735) (xy 12.608533 -114.38541)
			(xy 12.64575 -114.426947) (xy 12.676523 -114.47346) (xy 12.700195 -114.523957) (xy 12.716263 -114.577364)
			(xy 12.724383 -114.63254) (xy 12.724892 -114.660426) (xy 12.724383 -114.688312) (xy 12.716263 -114.743488)
			(xy 12.700195 -114.796895) (xy 12.676523 -114.847392) (xy 12.64575 -114.893905) (xy 12.608533 -114.935442)
			(xy 12.565665 -114.971117) (xy 12.518059 -115.000171) (xy 12.46673 -115.021983) (xy 12.412773 -115.036089)
			(xy 12.357336 -115.042189) (xy 12.301602 -115.040152) (xy 12.246759 -115.030022) (xy 12.193975 -115.012015)
			(xy 12.144375 -114.986514) (xy 12.099017 -114.954063) (xy 12.058868 -114.915354) (xy 12.024782 -114.871211)
			(xy 11.997486 -114.822576) (xy 11.977563 -114.770485) (xy 11.965437 -114.716048) (xy 11.961366 -114.660426)
			(xy 5.598668 -114.660426) (xy 5.598668 -117.434106) (xy 13.37691 -117.434106) (xy 13.377377 -117.406736)
			(xy 13.385194 -117.352557) (xy 13.400683 -117.300053) (xy 13.423525 -117.250307) (xy 13.453249 -117.20434)
			(xy 13.47089 -117.183408) (xy 13.471144 -117.183154) (xy 13.476719 -117.17606) (xy 13.482972 -117.159149)
			(xy 13.483336 -117.150134) (xy 13.483336 -117.083078) (xy 13.482982 -117.074061) (xy 13.476732 -117.057144)
			(xy 13.471144 -117.050058) (xy 13.47089 -117.050058) (xy 13.47089 -117.049804) (xy 13.453257 -117.028866)
			(xy 13.423535 -116.982898) (xy 13.400691 -116.933152) (xy 13.385196 -116.880652) (xy 13.377368 -116.826474)
			(xy 13.377367 -116.771735) (xy 13.385194 -116.717557) (xy 13.400688 -116.665056) (xy 13.42353 -116.61531)
			(xy 13.453251 -116.569341) (xy 13.47089 -116.548408) (xy 13.471144 -116.548154) (xy 13.476719 -116.54106)
			(xy 13.482972 -116.524149) (xy 13.483336 -116.515134) (xy 13.483336 -116.448078) (xy 13.482982 -116.439061)
			(xy 13.476732 -116.422144) (xy 13.471144 -116.415058) (xy 13.47089 -116.415058) (xy 13.47089 -116.414804)
			(xy 13.453238 -116.393883) (xy 13.423528 -116.347907) (xy 13.400695 -116.298156) (xy 13.385207 -116.245653)
			(xy 13.377382 -116.191476) (xy 13.37691 -116.164106) (xy 13.377361 -116.136852) (xy 13.385118 -116.0829)
			(xy 13.400474 -116.030601) (xy 13.423117 -115.98102) (xy 13.452586 -115.935166) (xy 13.488281 -115.893972)
			(xy 13.529475 -115.858279) (xy 13.57533 -115.828811) (xy 13.624912 -115.80617) (xy 13.677212 -115.790815)
			(xy 13.731164 -115.78306) (xy 13.758418 -115.782598) (xy 13.785789 -115.783054) (xy 13.839968 -115.790874)
			(xy 13.892471 -115.806366) (xy 13.942218 -115.82921) (xy 13.988184 -115.858936) (xy 14.009116 -115.876578)
			(xy 14.00937 -115.876832) (xy 14.016458 -115.882416) (xy 14.033374 -115.888663) (xy 14.04239 -115.889024)
			(xy 14.109446 -115.889024) (xy 14.11846 -115.888636) (xy 14.135377 -115.882409) (xy 14.142466 -115.876832)
			(xy 14.142466 -115.876578) (xy 14.14272 -115.876578) (xy 14.163669 -115.85896) (xy 14.209637 -115.829245)
			(xy 14.259381 -115.806406) (xy 14.311877 -115.79091) (xy 14.36605 -115.783075) (xy 14.393418 -115.782598)
			(xy 14.42067 -115.783061) (xy 14.474619 -115.79082) (xy 14.526914 -115.806178) (xy 14.576492 -115.828822)
			(xy 14.622343 -115.85829) (xy 14.663533 -115.893984) (xy 14.699224 -115.935177) (xy 14.72869 -115.981029)
			(xy 14.75133 -116.030608) (xy 14.766685 -116.082905) (xy 14.774441 -116.136854) (xy 14.774926 -116.164106)
			(xy 14.774481 -116.191477) (xy 14.766661 -116.245658) (xy 14.751168 -116.298162) (xy 14.728321 -116.347909)
			(xy 14.69859 -116.393874) (xy 14.680946 -116.414804) (xy 14.680692 -116.415058) (xy 14.675116 -116.422152)
			(xy 14.668863 -116.439063) (xy 14.6685 -116.448078) (xy 14.6685 -116.515134) (xy 14.668841 -116.524152)
			(xy 14.6751 -116.541069) (xy 14.680692 -116.548154) (xy 14.680946 -116.548154) (xy 14.680946 -116.548408)
			(xy 14.698594 -116.569335) (xy 14.72832 -116.615303) (xy 14.751167 -116.66505) (xy 14.766664 -116.717554)
			(xy 14.774493 -116.771733) (xy 14.774492 -116.826476) (xy 14.766662 -116.880655) (xy 14.751164 -116.933158)
			(xy 14.728316 -116.982904) (xy 14.698588 -117.028872) (xy 14.680946 -117.049804) (xy 14.680692 -117.050058)
			(xy 14.675116 -117.057152) (xy 14.668863 -117.074063) (xy 14.6685 -117.083078) (xy 14.6685 -117.150134)
			(xy 14.668841 -117.159152) (xy 14.6751 -117.176069) (xy 14.680692 -117.183154) (xy 14.680946 -117.183154)
			(xy 14.680946 -117.183408) (xy 14.698594 -117.204333) (xy 14.728306 -117.250307) (xy 14.751141 -117.300056)
			(xy 14.76663 -117.352559) (xy 14.774454 -117.406736) (xy 14.774926 -117.434106) (xy 14.774786 -117.442234)
			(xy 15.659098 -117.442234) (xy 15.663169 -117.386612) (xy 15.675295 -117.332175) (xy 15.695218 -117.280084)
			(xy 15.722514 -117.231449) (xy 15.7566 -117.187306) (xy 15.796749 -117.148597) (xy 15.842107 -117.116146)
			(xy 15.891707 -117.090645) (xy 15.944491 -117.072638) (xy 15.999334 -117.062508) (xy 16.055068 -117.060471)
			(xy 16.110505 -117.066571) (xy 16.164462 -117.080677) (xy 16.215791 -117.102489) (xy 16.263397 -117.131543)
			(xy 16.306265 -117.167218) (xy 16.343482 -117.208755) (xy 16.374255 -117.255268) (xy 16.397927 -117.305765)
			(xy 16.413995 -117.359172) (xy 16.422115 -117.414348) (xy 16.422624 -117.442234) (xy 16.422115 -117.47012)
			(xy 16.413995 -117.525296) (xy 16.397927 -117.578703) (xy 16.374255 -117.6292) (xy 16.343482 -117.675713)
			(xy 16.306265 -117.71725) (xy 16.263397 -117.752925) (xy 16.215791 -117.781979) (xy 16.164462 -117.803791)
			(xy 16.110505 -117.817897) (xy 16.055068 -117.823997) (xy 15.999334 -117.82196) (xy 15.944491 -117.81183)
			(xy 15.891707 -117.793823) (xy 15.842107 -117.768322) (xy 15.796749 -117.735871) (xy 15.7566 -117.697162)
			(xy 15.722514 -117.653019) (xy 15.695218 -117.604384) (xy 15.675295 -117.552293) (xy 15.663169 -117.497856)
			(xy 15.659098 -117.442234) (xy 14.774786 -117.442234) (xy 14.774469 -117.460662) (xy 14.767101 -117.513262)
			(xy 14.752509 -117.564331) (xy 14.74216 -117.588792) (xy 14.737815 -117.600161) (xy 14.739162 -117.624433)
			(xy 14.7447 -117.635274) (xy 14.786102 -117.706394) (xy 14.792839 -117.716462) (xy 14.813244 -117.729453)
			(xy 14.825218 -117.731286) (xy 14.853196 -117.734495) (xy 14.90786 -117.748027) (xy 14.959939 -117.769449)
			(xy 15.008302 -117.798296) (xy 15.051898 -117.833941) (xy 15.089779 -117.875609) (xy 15.121122 -117.922394)
			(xy 15.145244 -117.973279) (xy 15.161622 -118.027158) (xy 15.167063 -118.063772) (xy 16.806162 -118.063772)
			(xy 16.810233 -118.00815) (xy 16.822359 -117.953713) (xy 16.842282 -117.901622) (xy 16.869578 -117.852987)
			(xy 16.903664 -117.808844) (xy 16.943813 -117.770135) (xy 16.989171 -117.737684) (xy 17.038771 -117.712183)
			(xy 17.091555 -117.694176) (xy 17.146398 -117.684046) (xy 17.202132 -117.682009) (xy 17.257569 -117.688109)
			(xy 17.311526 -117.702215) (xy 17.362855 -117.724027) (xy 17.410461 -117.753081) (xy 17.453329 -117.788756)
			(xy 17.490546 -117.830293) (xy 17.521319 -117.876806) (xy 17.544991 -117.927303) (xy 17.561059 -117.98071)
			(xy 17.567078 -118.021608) (xy 17.685512 -118.021608) (xy 17.68598 -117.994238) (xy 17.693797 -117.940059)
			(xy 17.709285 -117.887555) (xy 17.732127 -117.837809) (xy 17.761851 -117.791842) (xy 17.779492 -117.77091)
			(xy 17.779746 -117.770656) (xy 17.785321 -117.763562) (xy 17.791573 -117.746651) (xy 17.791938 -117.737636)
			(xy 17.791938 -117.67058) (xy 17.791582 -117.661563) (xy 17.785333 -117.644647) (xy 17.779746 -117.63756)
			(xy 17.779492 -117.63756) (xy 17.779492 -117.637306) (xy 17.761861 -117.616366) (xy 17.732138 -117.570399)
			(xy 17.709294 -117.520653) (xy 17.693799 -117.468153) (xy 17.68597 -117.413976) (xy 17.68597 -117.359236)
			(xy 17.693796 -117.305059) (xy 17.70929 -117.252558) (xy 17.732132 -117.202812) (xy 17.761853 -117.156843)
			(xy 17.779492 -117.13591) (xy 17.779746 -117.135656) (xy 17.785321 -117.128562) (xy 17.791573 -117.111651)
			(xy 17.791938 -117.102636) (xy 17.791938 -117.03558) (xy 17.791582 -117.026563) (xy 17.785333 -117.009647)
			(xy 17.779746 -117.00256) (xy 17.779492 -117.00256) (xy 17.779492 -117.002306) (xy 17.761841 -116.981384)
			(xy 17.732131 -116.935408) (xy 17.709298 -116.885658) (xy 17.693809 -116.833155) (xy 17.685984 -116.778978)
			(xy 17.685512 -116.751608) (xy 17.685963 -116.724354) (xy 17.693719 -116.670402) (xy 17.709075 -116.618103)
			(xy 17.731718 -116.568521) (xy 17.761187 -116.522667) (xy 17.796882 -116.481474) (xy 17.838077 -116.44578)
			(xy 17.883932 -116.416313) (xy 17.933514 -116.393671) (xy 17.985814 -116.378317) (xy 18.039766 -116.370562)
			(xy 18.06702 -116.3701) (xy 18.094391 -116.370554) (xy 18.14857 -116.378375) (xy 18.201073 -116.393867)
			(xy 18.25082 -116.416711) (xy 18.296787 -116.446438) (xy 18.317718 -116.46408) (xy 18.317972 -116.464334)
			(xy 18.32506 -116.469919) (xy 18.341976 -116.476165) (xy 18.350992 -116.476526) (xy 18.418048 -116.476526)
			(xy 18.427062 -116.476139) (xy 18.443979 -116.469912) (xy 18.451068 -116.464334) (xy 18.451068 -116.46408)
			(xy 18.451322 -116.46408) (xy 18.47227 -116.446461) (xy 18.518239 -116.416747) (xy 18.567982 -116.393907)
			(xy 18.620479 -116.378411) (xy 18.674652 -116.370577) (xy 18.70202 -116.3701) (xy 18.729272 -116.370559)
			(xy 18.783221 -116.378319) (xy 18.835517 -116.393677) (xy 18.885095 -116.416321) (xy 18.930945 -116.44579)
			(xy 18.972136 -116.481484) (xy 19.007827 -116.522677) (xy 19.037293 -116.56853) (xy 19.059933 -116.618109)
			(xy 19.075287 -116.670406) (xy 19.083043 -116.724356) (xy 19.083528 -116.751608) (xy 19.083084 -116.778979)
			(xy 19.075264 -116.83316) (xy 19.05977 -116.885664) (xy 19.036923 -116.935411) (xy 19.007192 -116.981376)
			(xy 18.989548 -117.002306) (xy 18.989294 -117.00256) (xy 18.983717 -117.009653) (xy 18.977465 -117.026565)
			(xy 18.977102 -117.03558) (xy 18.977102 -117.102636) (xy 18.977442 -117.111655) (xy 18.983701 -117.128571)
			(xy 18.989294 -117.135656) (xy 18.989548 -117.135656) (xy 18.989548 -117.13591) (xy 19.007198 -117.156836)
			(xy 19.036924 -117.202804) (xy 19.05977 -117.252551) (xy 19.075267 -117.305055) (xy 19.083095 -117.359235)
			(xy 19.083095 -117.413977) (xy 19.075265 -117.468157) (xy 19.059766 -117.52066) (xy 19.036918 -117.570406)
			(xy 19.00719 -117.616374) (xy 18.989548 -117.637306) (xy 18.989294 -117.63756) (xy 18.983717 -117.644653)
			(xy 18.977465 -117.661565) (xy 18.977102 -117.67058) (xy 18.977102 -117.737636) (xy 18.977442 -117.746655)
			(xy 18.983701 -117.763571) (xy 18.989294 -117.770656) (xy 18.989548 -117.770656) (xy 18.989548 -117.77091)
			(xy 19.007197 -117.791834) (xy 19.036909 -117.837808) (xy 19.059744 -117.887558) (xy 19.075233 -117.94006)
			(xy 19.083057 -117.994238) (xy 19.083528 -118.021608) (xy 19.08303 -118.048859) (xy 19.075273 -118.102805)
			(xy 19.059918 -118.155098) (xy 19.037277 -118.204674) (xy 19.007812 -118.250523) (xy 18.972122 -118.291713)
			(xy 18.930933 -118.327404) (xy 18.885085 -118.356871) (xy 18.835509 -118.379513) (xy 18.783217 -118.39487)
			(xy 18.729271 -118.402629) (xy 18.70202 -118.403116) (xy 18.674649 -118.402659) (xy 18.620469 -118.394842)
			(xy 18.567965 -118.379352) (xy 18.518218 -118.356508) (xy 18.472252 -118.326779) (xy 18.451322 -118.309136)
			(xy 18.451068 -118.308882) (xy 18.443968 -118.303316) (xy 18.427061 -118.297057) (xy 18.418048 -118.29669)
			(xy 18.350992 -118.29669) (xy 18.341975 -118.297045) (xy 18.325058 -118.303294) (xy 18.317972 -118.308882)
			(xy 18.317972 -118.309136) (xy 18.317718 -118.309136) (xy 18.296795 -118.326786) (xy 18.250819 -118.356495)
			(xy 18.201069 -118.379328) (xy 18.148567 -118.394817) (xy 18.09439 -118.402643) (xy 18.06702 -118.403116)
			(xy 18.039768 -118.402626) (xy 17.985818 -118.394872) (xy 17.933522 -118.379519) (xy 17.883942 -118.356879)
			(xy 17.838089 -118.327414) (xy 17.796897 -118.291723) (xy 17.761203 -118.250533) (xy 17.731734 -118.204683)
			(xy 17.709091 -118.155105) (xy 17.693734 -118.102809) (xy 17.685976 -118.04886) (xy 17.685512 -118.021608)
			(xy 17.567078 -118.021608) (xy 17.569179 -118.035886) (xy 17.569688 -118.063772) (xy 17.569179 -118.091658)
			(xy 17.561059 -118.146834) (xy 17.544991 -118.200241) (xy 17.521319 -118.250738) (xy 17.490546 -118.297251)
			(xy 17.453329 -118.338788) (xy 17.410461 -118.374463) (xy 17.362855 -118.403517) (xy 17.311526 -118.425329)
			(xy 17.257569 -118.439435) (xy 17.202132 -118.445535) (xy 17.146398 -118.443498) (xy 17.091555 -118.433368)
			(xy 17.038771 -118.415361) (xy 16.989171 -118.38986) (xy 16.943813 -118.357409) (xy 16.903664 -118.3187)
			(xy 16.869578 -118.274557) (xy 16.842282 -118.225922) (xy 16.822359 -118.173831) (xy 16.810233 -118.119394)
			(xy 16.806162 -118.063772) (xy 15.167063 -118.063772) (xy 15.1699 -118.082859) (xy 15.170404 -118.111016)
			(xy 15.169918 -118.138267) (xy 15.162162 -118.192215) (xy 15.146807 -118.24451) (xy 15.124165 -118.294087)
			(xy 15.094699 -118.339937) (xy 15.059008 -118.381128) (xy 15.017817 -118.416819) (xy 14.971967 -118.446285)
			(xy 14.92239 -118.468927) (xy 14.870095 -118.484282) (xy 14.816147 -118.492038) (xy 14.761645 -118.492038)
			(xy 14.707697 -118.484282) (xy 14.655402 -118.468927) (xy 14.605825 -118.446285) (xy 14.559975 -118.416819)
			(xy 14.518784 -118.381128) (xy 14.483093 -118.339937) (xy 14.453627 -118.294087) (xy 14.430985 -118.24451)
			(xy 14.41563 -118.192215) (xy 14.407874 -118.138267) (xy 14.407388 -118.111016) (xy 14.407851 -118.08446)
			(xy 14.415217 -118.031861) (xy 14.429807 -117.980792) (xy 14.440154 -117.95633) (xy 14.444483 -117.944956)
			(xy 14.443146 -117.920689) (xy 14.437614 -117.909848) (xy 14.396212 -117.838728) (xy 14.389488 -117.828651)
			(xy 14.369072 -117.815667) (xy 14.357096 -117.813836) (xy 14.32762 -117.810473) (xy 14.270151 -117.79575)
			(xy 14.215655 -117.772305) (xy 14.165446 -117.740706) (xy 14.14272 -117.721634) (xy 14.142466 -117.72138)
			(xy 14.135366 -117.715813) (xy 14.11846 -117.709555) (xy 14.109446 -117.709188) (xy 14.04239 -117.709188)
			(xy 14.033373 -117.709543) (xy 14.016456 -117.715792) (xy 14.00937 -117.72138) (xy 14.00937 -117.721634)
			(xy 14.009116 -117.721634) (xy 13.988193 -117.739284) (xy 13.942217 -117.768993) (xy 13.892467 -117.791827)
			(xy 13.839965 -117.807315) (xy 13.785788 -117.815141) (xy 13.758418 -117.815614) (xy 13.731166 -117.815128)
			(xy 13.677216 -117.807374) (xy 13.624919 -117.79202) (xy 13.575339 -117.76938) (xy 13.529486 -117.739915)
			(xy 13.488294 -117.704223) (xy 13.4526 -117.663033) (xy 13.423131 -117.617182) (xy 13.400488 -117.567604)
			(xy 13.385132 -117.515307) (xy 13.377374 -117.461358) (xy 13.37691 -117.434106) (xy 5.598668 -117.434106)
			(xy 5.598668 -118.089426) (xy 10.195304 -118.089426) (xy 10.199375 -118.033804) (xy 10.211501 -117.979367)
			(xy 10.231424 -117.927276) (xy 10.25872 -117.878641) (xy 10.292806 -117.834498) (xy 10.332955 -117.795789)
			(xy 10.378313 -117.763338) (xy 10.427913 -117.737837) (xy 10.480697 -117.71983) (xy 10.53554 -117.7097)
			(xy 10.591274 -117.707663) (xy 10.646711 -117.713763) (xy 10.700668 -117.727869) (xy 10.751997 -117.749681)
			(xy 10.799603 -117.778735) (xy 10.842471 -117.81441) (xy 10.879688 -117.855947) (xy 10.910461 -117.90246)
			(xy 10.934133 -117.952957) (xy 10.936982 -117.962426) (xy 12.227304 -117.962426) (xy 12.231375 -117.906804)
			(xy 12.243501 -117.852367) (xy 12.263424 -117.800276) (xy 12.29072 -117.751641) (xy 12.324806 -117.707498)
			(xy 12.364955 -117.668789) (xy 12.410313 -117.636338) (xy 12.459913 -117.610837) (xy 12.512697 -117.59283)
			(xy 12.56754 -117.5827) (xy 12.623274 -117.580663) (xy 12.678711 -117.586763) (xy 12.732668 -117.600869)
			(xy 12.783997 -117.622681) (xy 12.831603 -117.651735) (xy 12.874471 -117.68741) (xy 12.911688 -117.728947)
			(xy 12.942461 -117.77546) (xy 12.966133 -117.825957) (xy 12.982201 -117.879364) (xy 12.990321 -117.93454)
			(xy 12.99083 -117.962426) (xy 12.990321 -117.990312) (xy 12.982201 -118.045488) (xy 12.966133 -118.098895)
			(xy 12.942461 -118.149392) (xy 12.911688 -118.195905) (xy 12.874471 -118.237442) (xy 12.831603 -118.273117)
			(xy 12.783997 -118.302171) (xy 12.732668 -118.323983) (xy 12.678711 -118.338089) (xy 12.623274 -118.344189)
			(xy 12.56754 -118.342152) (xy 12.512697 -118.332022) (xy 12.459913 -118.314015) (xy 12.410313 -118.288514)
			(xy 12.364955 -118.256063) (xy 12.324806 -118.217354) (xy 12.29072 -118.173211) (xy 12.263424 -118.124576)
			(xy 12.243501 -118.072485) (xy 12.231375 -118.018048) (xy 12.227304 -117.962426) (xy 10.936982 -117.962426)
			(xy 10.950201 -118.006364) (xy 10.958321 -118.06154) (xy 10.95883 -118.089426) (xy 10.958321 -118.117312)
			(xy 10.950201 -118.172488) (xy 10.934133 -118.225895) (xy 10.910461 -118.276392) (xy 10.879688 -118.322905)
			(xy 10.842471 -118.364442) (xy 10.799603 -118.400117) (xy 10.751997 -118.429171) (xy 10.700668 -118.450983)
			(xy 10.646711 -118.465089) (xy 10.591274 -118.471189) (xy 10.53554 -118.469152) (xy 10.480697 -118.459022)
			(xy 10.427913 -118.441015) (xy 10.378313 -118.415514) (xy 10.332955 -118.383063) (xy 10.292806 -118.344354)
			(xy 10.25872 -118.300211) (xy 10.231424 -118.251576) (xy 10.211501 -118.199485) (xy 10.199375 -118.145048)
			(xy 10.195304 -118.089426) (xy 5.598668 -118.089426) (xy 5.598668 -125.442726) (xy 5.59918 -125.457352)
			(xy 5.607538 -125.485386) (xy 5.623501 -125.509901) (xy 5.645761 -125.528882) (xy 5.672489 -125.540773)
			(xy 5.701491 -125.544598) (xy 5.716016 -125.542802) (xy 5.723872 -125.541299) (xy 5.738117 -125.534045)
			(xy 5.743956 -125.528578) (xy 6.543548 -124.728732) (xy 6.562318 -124.710697) (xy 6.604433 -124.680112)
			(xy 6.650809 -124.65648) (xy 6.700307 -124.640381) (xy 6.751711 -124.632211) (xy 6.777736 -124.631704)
			(xy 8.860028 -124.631704) (xy 8.871966 -124.628656) (xy 8.8773 -124.625862) (xy 8.892873 -124.61792)
			(xy 8.925182 -124.604566) (xy 8.941816 -124.599192) (xy 8.947658 -124.59716) (xy 8.958326 -124.59081)
			(xy 9.218422 -124.330714) (xy 9.21893 -124.330206) (xy 9.225508 -124.322824) (xy 9.232948 -124.304524)
			(xy 9.233408 -124.294646) (xy 9.233408 -121.260362) (xy 9.233897 -121.234276) (xy 9.242068 -121.182747)
			(xy 9.258203 -121.133131) (xy 9.281905 -121.086653) (xy 9.312588 -121.044457) (xy 9.33069 -121.025666)
			(xy 10.204704 -120.151652) (xy 10.211054 -120.140984) (xy 10.212832 -120.135142) (xy 10.221281 -120.109577)
			(xy 10.244362 -120.060932) (xy 10.274049 -120.016012) (xy 10.309753 -119.97571) (xy 10.350766 -119.940825)
			(xy 10.396274 -119.912048) (xy 10.445374 -119.889952) (xy 10.497091 -119.874974) (xy 10.550401 -119.867411)
			(xy 10.577322 -119.866918) (xy 10.600933 -119.867222) (xy 10.647806 -119.872949) (xy 10.670794 -119.878348)
			(xy 10.682478 -119.881142) (xy 10.705084 -119.876316) (xy 10.748518 -119.842534) (xy 10.757347 -119.834944)
			(xy 10.767532 -119.814033) (xy 10.768076 -119.802402) (xy 10.768076 -119.58828) (xy 10.768601 -119.562256)
			(xy 10.776764 -119.51085) (xy 10.792856 -119.461351) (xy 10.816481 -119.414972) (xy 10.84706 -119.372852)
			(xy 10.865104 -119.354092) (xy 11.025632 -119.193564) (xy 11.044403 -119.175533) (xy 11.08652 -119.144956)
			(xy 11.132897 -119.121333) (xy 11.182394 -119.105245) (xy 11.233797 -119.097087) (xy 11.25982 -119.096536)
			(xy 15.080234 -119.096536) (xy 15.106258 -119.097062) (xy 15.157663 -119.105226) (xy 15.207162 -119.121318)
			(xy 15.253542 -119.144943) (xy 15.295662 -119.17552) (xy 15.314422 -119.193564) (xy 15.901416 -119.780812)
			(xy 15.91183 -119.787162) (xy 15.917926 -119.78894) (xy 15.943505 -119.79738) (xy 15.992178 -119.820445)
			(xy 16.037128 -119.850121) (xy 16.077462 -119.885818) (xy 16.11238 -119.926829) (xy 16.14119 -119.972339)
			(xy 16.163318 -120.021446) (xy 16.178328 -120.073175) (xy 16.18592 -120.126499) (xy 16.186404 -120.15343)
			(xy 16.185916 -120.18068) (xy 16.178156 -120.234624) (xy 16.162798 -120.286915) (xy 16.140155 -120.336488)
			(xy 16.110688 -120.382334) (xy 16.074997 -120.423521) (xy 16.033807 -120.459209) (xy 15.987958 -120.488672)
			(xy 15.938383 -120.51131) (xy 15.886091 -120.526663) (xy 15.832146 -120.534419) (xy 15.804896 -120.534938)
			(xy 15.777974 -120.534476) (xy 15.724664 -120.526909) (xy 15.672947 -120.511927) (xy 15.623848 -120.489825)
			(xy 15.578342 -120.461044) (xy 15.537332 -120.426153) (xy 15.501631 -120.385847) (xy 15.471949 -120.340923)
			(xy 15.448874 -120.292274) (xy 15.440406 -120.266714) (xy 15.438628 -120.260872) (xy 15.432278 -120.250204)
			(xy 14.957298 -119.77497) (xy 14.950186 -119.767604) (xy 14.93139 -119.759984) (xy 13.007086 -119.759984)
			(xy 12.997948 -119.760368) (xy 12.980836 -119.766784) (xy 12.967063 -119.778797) (xy 12.962382 -119.786654)
			(xy 12.925552 -119.855234) (xy 12.921686 -119.863152) (xy 12.91907 -119.880563) (xy 12.922548 -119.897822)
			(xy 12.926822 -119.905526) (xy 12.932156 -119.914416) (xy 12.93241 -119.914924) (xy 12.93368 -119.916702)
			(xy 12.947233 -119.939466) (xy 12.968613 -119.98794) (xy 12.983086 -120.038904) (xy 12.990373 -120.09138)
			(xy 12.99083 -120.11787) (xy 12.990369 -120.145125) (xy 12.982616 -120.19908) (xy 12.967263 -120.251383)
			(xy 12.944622 -120.300968) (xy 12.915155 -120.346827) (xy 12.879462 -120.388025) (xy 12.838269 -120.423724)
			(xy 12.792414 -120.453197) (xy 12.742832 -120.475844) (xy 12.690531 -120.491205) (xy 12.636577 -120.498966)
			(xy 12.609322 -120.499378) (xy 12.582715 -120.498918) (xy 12.530018 -120.491527) (xy 12.478859 -120.476886)
			(xy 12.43023 -120.455278) (xy 12.385076 -120.427124) (xy 12.344271 -120.392968) (xy 12.308608 -120.353474)
			(xy 12.278779 -120.309408) (xy 12.255362 -120.261624) (xy 12.238811 -120.21105) (xy 12.229448 -120.158667)
			(xy 12.228068 -120.132094) (xy 12.228068 -120.13184) (xy 12.22756 -120.120918) (xy 12.22756 -120.11787)
			(xy 12.228087 -120.090013) (xy 12.236217 -120.034895) (xy 12.252256 -119.981539) (xy 12.275866 -119.931075)
			(xy 12.290806 -119.907558) (xy 12.29106 -119.907304) (xy 12.295674 -119.899557) (xy 12.299647 -119.88198)
			(xy 12.29726 -119.864119) (xy 12.293346 -119.855996) (xy 12.293092 -119.855488) (xy 12.256262 -119.786908)
			(xy 12.251597 -119.779015) (xy 12.237836 -119.76692) (xy 12.220716 -119.760397) (xy 12.211558 -119.759984)
			(xy 11.991086 -119.759984) (xy 11.981948 -119.760368) (xy 11.964836 -119.766784) (xy 11.951063 -119.778797)
			(xy 11.946382 -119.786654) (xy 11.909552 -119.855234) (xy 11.905686 -119.863152) (xy 11.90307 -119.880563)
			(xy 11.906548 -119.897822) (xy 11.910822 -119.905526) (xy 11.916156 -119.914416) (xy 11.91641 -119.914924)
			(xy 11.91768 -119.916702) (xy 11.931233 -119.939466) (xy 11.952613 -119.98794) (xy 11.967086 -120.038904)
			(xy 11.974373 -120.09138) (xy 11.97483 -120.11787) (xy 11.974369 -120.145125) (xy 11.966616 -120.19908)
			(xy 11.951263 -120.251383) (xy 11.928622 -120.300968) (xy 11.899155 -120.346827) (xy 11.863462 -120.388025)
			(xy 11.822269 -120.423724) (xy 11.776414 -120.453197) (xy 11.726832 -120.475844) (xy 11.674531 -120.491205)
			(xy 11.620577 -120.498966) (xy 11.593322 -120.499378) (xy 11.583268 -120.499272) (xy 11.563191 -120.498126)
			(xy 11.55319 -120.497092) (xy 11.542268 -120.496076) (xy 11.521948 -120.502426) (xy 11.464544 -120.553734)
			(xy 11.463782 -120.554496) (xy 11.457686 -120.55983) (xy 11.449774 -120.567384) (xy 11.440685 -120.587258)
			(xy 11.44016 -120.598184) (xy 11.44016 -121.57075) (xy 13.619988 -121.57075) (xy 13.620426 -121.544435)
			(xy 13.627667 -121.492305) (xy 13.641992 -121.441662) (xy 13.66313 -121.393464) (xy 13.690682 -121.348621)
			(xy 13.724125 -121.307982) (xy 13.743178 -121.289826) (xy 13.750567 -121.282294) (xy 13.759099 -121.263022)
			(xy 13.759688 -121.252488) (xy 13.759688 -121.177812) (xy 13.759169 -121.167261) (xy 13.750627 -121.147966)
			(xy 13.743178 -121.140474) (xy 13.724113 -121.122328) (xy 13.690657 -121.081696) (xy 13.6631 -121.036854)
			(xy 13.641963 -120.988651) (xy 13.627648 -120.938002) (xy 13.620425 -120.885867) (xy 13.619988 -120.85955)
			(xy 13.620474 -120.832299) (xy 13.62823 -120.778351) (xy 13.643585 -120.726056) (xy 13.666227 -120.676479)
			(xy 13.695693 -120.630629) (xy 13.731384 -120.589438) (xy 13.772575 -120.553747) (xy 13.818425 -120.524281)
			(xy 13.868002 -120.501639) (xy 13.920297 -120.486284) (xy 13.974245 -120.478528) (xy 14.028747 -120.478528)
			(xy 14.082695 -120.486284) (xy 14.13499 -120.501639) (xy 14.184567 -120.524281) (xy 14.230417 -120.553747)
			(xy 14.271608 -120.589438) (xy 14.307299 -120.630629) (xy 14.336765 -120.676479) (xy 14.359407 -120.726056)
			(xy 14.374762 -120.778351) (xy 14.382518 -120.832299) (xy 14.383004 -120.85955) (xy 14.382569 -120.885865)
			(xy 14.375327 -120.937995) (xy 14.361002 -120.988638) (xy 14.339863 -121.036837) (xy 14.312311 -121.08168)
			(xy 14.278868 -121.122318) (xy 14.259814 -121.140474) (xy 14.252424 -121.148005) (xy 14.243892 -121.167278)
			(xy 14.243304 -121.177812) (xy 14.243304 -121.252488) (xy 14.243825 -121.263039) (xy 14.252366 -121.282334)
			(xy 14.259814 -121.289826) (xy 14.278878 -121.307973) (xy 14.312334 -121.348605) (xy 14.339891 -121.393447)
			(xy 14.361028 -121.44165) (xy 14.375344 -121.492298) (xy 14.382567 -121.544433) (xy 14.383004 -121.57075)
			(xy 14.382518 -121.598001) (xy 14.374762 -121.651949) (xy 14.359407 -121.704244) (xy 14.336765 -121.753821)
			(xy 14.307299 -121.799671) (xy 14.271608 -121.840862) (xy 14.230417 -121.876553) (xy 14.184567 -121.906019)
			(xy 14.13499 -121.928661) (xy 14.082695 -121.944016) (xy 14.028747 -121.951772) (xy 13.974245 -121.951772)
			(xy 13.920297 -121.944016) (xy 13.868002 -121.928661) (xy 13.818425 -121.906019) (xy 13.772575 -121.876553)
			(xy 13.731384 -121.840862) (xy 13.695693 -121.799671) (xy 13.666227 -121.753821) (xy 13.643585 -121.704244)
			(xy 13.62823 -121.651949) (xy 13.620474 -121.598001) (xy 13.619988 -121.57075) (xy 11.44016 -121.57075)
			(xy 11.44016 -122.088656) (xy 11.45667 -122.113802) (xy 11.47064 -122.119898) (xy 11.495875 -122.131373)
			(xy 11.543017 -122.160539) (xy 11.585443 -122.196218) (xy 11.622261 -122.23766) (xy 11.652697 -122.283992)
			(xy 11.676109 -122.334239) (xy 11.692006 -122.387346) (xy 11.700053 -122.442193) (xy 11.70051 -122.46991)
			(xy 11.700053 -122.496847) (xy 11.692489 -122.550187) (xy 11.677498 -122.601933) (xy 11.655378 -122.651056)
			(xy 11.626569 -122.69658) (xy 11.591643 -122.7376) (xy 11.551296 -122.773299) (xy 11.506329 -122.80297)
			(xy 11.457636 -122.826021) (xy 11.432032 -122.8344) (xy 11.425936 -122.836178) (xy 11.415522 -122.842528)
			(xy 11.008289 -123.249761) (xy 11.91004 -123.249761) (xy 11.91004 -123.195259) (xy 11.917796 -123.141311)
			(xy 11.933151 -123.089017) (xy 11.955792 -123.03944) (xy 11.985258 -122.99359) (xy 12.02095 -122.9524)
			(xy 12.06214 -122.916708) (xy 12.10799 -122.887242) (xy 12.157567 -122.864601) (xy 12.209861 -122.849246)
			(xy 12.263809 -122.84149) (xy 12.29106 -122.841004) (xy 12.318091 -122.841459) (xy 12.371611 -122.849105)
			(xy 12.423513 -122.864236) (xy 12.472757 -122.886548) (xy 12.518354 -122.915593) (xy 12.559391 -122.950789)
			(xy 12.577572 -122.970798) (xy 12.577826 -122.971052) (xy 12.585282 -122.978685) (xy 12.604757 -122.987361)
			(xy 12.615418 -122.987816) (xy 12.703048 -122.988324) (xy 12.722606 -122.979688) (xy 12.729972 -122.971306)
			(xy 12.748153 -122.951603) (xy 12.78905 -122.916937) (xy 12.834401 -122.888346) (xy 12.883312 -122.866393)
			(xy 12.934818 -122.851514) (xy 12.9879 -122.844) (xy 13.014706 -122.843544) (xy 13.042077 -122.843996)
			(xy 13.096257 -122.851815) (xy 13.148761 -122.867307) (xy 13.198507 -122.890152) (xy 13.244473 -122.919881)
			(xy 13.265404 -122.937524) (xy 13.265658 -122.937778) (xy 13.272746 -122.943362) (xy 13.289662 -122.949608)
			(xy 13.298678 -122.94997) (xy 13.365734 -122.94997) (xy 13.374753 -122.949636) (xy 13.39167 -122.943373)
			(xy 13.398754 -122.937778) (xy 13.398754 -122.937524) (xy 13.399008 -122.937524) (xy 13.419941 -122.919883)
			(xy 13.465909 -122.890159) (xy 13.515655 -122.867313) (xy 13.568157 -122.851817) (xy 13.622335 -122.843988)
			(xy 13.677077 -122.843988) (xy 13.731255 -122.851817) (xy 13.783757 -122.867313) (xy 13.833503 -122.890159)
			(xy 13.879471 -122.919883) (xy 13.900404 -122.937524) (xy 13.900658 -122.937778) (xy 13.907746 -122.943362)
			(xy 13.924662 -122.949608) (xy 13.933678 -122.94997) (xy 14.000734 -122.94997) (xy 14.009753 -122.949636)
			(xy 14.02667 -122.943373) (xy 14.033754 -122.937778) (xy 14.034262 -122.937524) (xy 14.046999 -122.926583)
			(xy 14.074088 -122.90674) (xy 14.088364 -122.8979) (xy 14.097254 -122.892566) (xy 14.109446 -122.875548)
			(xy 14.129766 -122.78233) (xy 14.125448 -122.761756) (xy 14.119606 -122.75312) (xy 14.103613 -122.729052)
			(xy 14.078269 -122.677122) (xy 14.061041 -122.621965) (xy 14.052324 -122.564842) (xy 14.051788 -122.53595)
			(xy 14.052274 -122.508699) (xy 14.06003 -122.454751) (xy 14.075385 -122.402456) (xy 14.098027 -122.352879)
			(xy 14.127493 -122.307029) (xy 14.163184 -122.265838) (xy 14.204375 -122.230147) (xy 14.250225 -122.200681)
			(xy 14.299802 -122.178039) (xy 14.352097 -122.162684) (xy 14.406045 -122.154928) (xy 14.460547 -122.154928)
			(xy 14.514495 -122.162684) (xy 14.56679 -122.178039) (xy 14.616367 -122.200681) (xy 14.662217 -122.230147)
			(xy 14.703408 -122.265838) (xy 14.739099 -122.307029) (xy 14.768565 -122.352879) (xy 14.791207 -122.402456)
			(xy 14.806562 -122.454751) (xy 14.814318 -122.508699) (xy 14.814804 -122.53595) (xy 14.814277 -122.56404)
			(xy 14.806056 -122.619616) (xy 14.789771 -122.673385) (xy 14.765774 -122.724183) (xy 14.734584 -122.77091)
			(xy 14.696876 -122.812556) (xy 14.653467 -122.848219) (xy 14.629638 -122.863102) (xy 14.620748 -122.868436)
			(xy 14.608556 -122.885454) (xy 14.588236 -122.978672) (xy 14.592554 -122.999246) (xy 14.598396 -123.007882)
			(xy 14.61439 -123.03195) (xy 14.639734 -123.08388) (xy 14.656962 -123.139036) (xy 14.665678 -123.19616)
			(xy 14.666214 -123.225052) (xy 14.6657 -123.252303) (xy 14.65795 -123.306252) (xy 14.6426 -123.358549)
			(xy 14.619964 -123.408128) (xy 14.590501 -123.453981) (xy 14.554813 -123.495174) (xy 14.513625 -123.530869)
			(xy 14.467776 -123.560338) (xy 14.418199 -123.582981) (xy 14.365905 -123.598338) (xy 14.311957 -123.606096)
			(xy 14.284706 -123.60656) (xy 14.257335 -123.6061) (xy 14.203156 -123.598282) (xy 14.150652 -123.582792)
			(xy 14.100905 -123.559949) (xy 14.054939 -123.530222) (xy 14.034008 -123.51258) (xy 14.033754 -123.512326)
			(xy 14.026662 -123.506747) (xy 14.009749 -123.500498) (xy 14.000734 -123.500134) (xy 13.933678 -123.500134)
			(xy 13.924659 -123.500473) (xy 13.907742 -123.506732) (xy 13.900658 -123.512326) (xy 13.900404 -123.51258)
			(xy 13.879471 -123.530221) (xy 13.833503 -123.559945) (xy 13.783757 -123.582791) (xy 13.731255 -123.598287)
			(xy 13.677077 -123.606116) (xy 13.622335 -123.606116) (xy 13.568157 -123.598287) (xy 13.515655 -123.582791)
			(xy 13.465909 -123.559945) (xy 13.419941 -123.530221) (xy 13.399008 -123.51258) (xy 13.398754 -123.512326)
			(xy 13.391662 -123.506747) (xy 13.374749 -123.500498) (xy 13.365734 -123.500134) (xy 13.298678 -123.500134)
			(xy 13.289659 -123.500473) (xy 13.272742 -123.506732) (xy 13.265658 -123.512326) (xy 13.265658 -123.51258)
			(xy 13.265404 -123.51258) (xy 13.244479 -123.530228) (xy 13.198504 -123.559939) (xy 13.148755 -123.582773)
			(xy 13.096253 -123.598262) (xy 13.042076 -123.606088) (xy 13.014706 -123.60656) (xy 12.987675 -123.606107)
			(xy 12.934156 -123.598457) (xy 12.882255 -123.583325) (xy 12.833012 -123.561012) (xy 12.787414 -123.531968)
			(xy 12.746376 -123.496774) (xy 12.728194 -123.476766) (xy 12.72794 -123.476512) (xy 12.720488 -123.468874)
			(xy 12.70101 -123.460199) (xy 12.690348 -123.459748) (xy 12.602718 -123.45924) (xy 12.58316 -123.467876)
			(xy 12.575794 -123.476258) (xy 12.557643 -123.495991) (xy 12.516739 -123.530651) (xy 12.471381 -123.559237)
			(xy 12.422464 -123.581184) (xy 12.370954 -123.596059) (xy 12.317867 -123.603567) (xy 12.29106 -123.60402)
			(xy 12.263809 -123.60353) (xy 12.209861 -123.595774) (xy 12.157567 -123.580419) (xy 12.10799 -123.557778)
			(xy 12.06214 -123.528312) (xy 12.02095 -123.49262) (xy 11.985258 -123.45143) (xy 11.955792 -123.40558)
			(xy 11.933151 -123.356003) (xy 11.917796 -123.303709) (xy 11.91004 -123.249761) (xy 11.008289 -123.249761)
			(xy 10.535158 -123.722892) (xy 10.527792 -123.730004) (xy 10.520172 -123.7488) (xy 10.520172 -124.995432)
			(xy 10.780774 -124.995432) (xy 10.784845 -124.93981) (xy 10.796971 -124.885373) (xy 10.816894 -124.833282)
			(xy 10.84419 -124.784647) (xy 10.878276 -124.740504) (xy 10.918425 -124.701795) (xy 10.963783 -124.669344)
			(xy 11.013383 -124.643843) (xy 11.066167 -124.625836) (xy 11.12101 -124.615706) (xy 11.176744 -124.613669)
			(xy 11.232181 -124.619769) (xy 11.286138 -124.633875) (xy 11.337467 -124.655687) (xy 11.385073 -124.684741)
			(xy 11.427941 -124.720416) (xy 11.465158 -124.761953) (xy 11.495931 -124.808466) (xy 11.519603 -124.858963)
			(xy 11.535671 -124.91237) (xy 11.543791 -124.967546) (xy 11.5443 -124.995432) (xy 11.543791 -125.023318)
			(xy 11.535671 -125.078494) (xy 11.519603 -125.131901) (xy 11.495931 -125.182398) (xy 11.465158 -125.228911)
			(xy 11.427941 -125.270448) (xy 11.385073 -125.306123) (xy 11.337467 -125.335177) (xy 11.286138 -125.356989)
			(xy 11.232181 -125.371095) (xy 11.176744 -125.377195) (xy 11.12101 -125.375158) (xy 11.066167 -125.365028)
			(xy 11.013383 -125.347021) (xy 10.963783 -125.32152) (xy 10.918425 -125.289069) (xy 10.878276 -125.25036)
			(xy 10.84419 -125.206217) (xy 10.816894 -125.157582) (xy 10.796971 -125.105491) (xy 10.784845 -125.051054)
			(xy 10.780774 -124.995432) (xy 10.520172 -124.995432) (xy 10.520172 -125.201172) (xy 10.519878 -125.220273)
			(xy 10.515426 -125.258216) (xy 10.511282 -125.276864) (xy 10.511282 -125.277372) (xy 10.510012 -125.283214)
			(xy 10.510012 -125.312932) (xy 10.509584 -125.323) (xy 10.501862 -125.341597) (xy 10.495026 -125.349)
			(xy 10.474198 -125.369828) (xy 10.470896 -125.374908) (xy 10.470642 -125.375416) (xy 10.46033 -125.391637)
			(xy 10.451086 -125.403356) (xy 15.544292 -125.403356) (xy 15.544793 -125.375987) (xy 15.552603 -125.32181)
			(xy 15.568084 -125.269307) (xy 15.590918 -125.219559) (xy 15.620634 -125.173591) (xy 15.638272 -125.152658)
			(xy 15.638526 -125.152404) (xy 15.64412 -125.145323) (xy 15.650361 -125.128402) (xy 15.650718 -125.119384)
			(xy 15.650718 -125.052328) (xy 15.650344 -125.043313) (xy 15.644108 -125.026396) (xy 15.638526 -125.019308)
			(xy 15.638272 -125.019308) (xy 15.638272 -125.019054) (xy 15.62064 -124.998116) (xy 15.590928 -124.952144)
			(xy 15.568091 -124.902398) (xy 15.552599 -124.849899) (xy 15.544768 -124.795725) (xy 15.544292 -124.768356)
			(xy 15.544778 -124.741105) (xy 15.552534 -124.687157) (xy 15.567889 -124.634862) (xy 15.590531 -124.585285)
			(xy 15.619997 -124.539435) (xy 15.655688 -124.498244) (xy 15.696879 -124.462553) (xy 15.742729 -124.433087)
			(xy 15.792306 -124.410445) (xy 15.844601 -124.39509) (xy 15.898549 -124.387334) (xy 15.953051 -124.387334)
			(xy 16.006999 -124.39509) (xy 16.059294 -124.410445) (xy 16.108871 -124.433087) (xy 16.154721 -124.462553)
			(xy 16.195912 -124.498244) (xy 16.231603 -124.539435) (xy 16.261069 -124.585285) (xy 16.283711 -124.634862)
			(xy 16.299066 -124.687157) (xy 16.306822 -124.741105) (xy 16.307308 -124.768356) (xy 16.306814 -124.795725)
			(xy 16.299003 -124.849903) (xy 16.28352 -124.902406) (xy 16.260685 -124.952153) (xy 16.230966 -124.998121)
			(xy 16.213328 -125.019054) (xy 16.213074 -125.019308) (xy 16.207475 -125.026386) (xy 16.201237 -125.043309)
			(xy 16.200882 -125.052328) (xy 16.200882 -125.119384) (xy 16.201251 -125.1284) (xy 16.207491 -125.145316)
			(xy 16.213074 -125.152404) (xy 16.213328 -125.152404) (xy 16.213328 -125.152658) (xy 16.230965 -125.173591)
			(xy 16.260676 -125.219564) (xy 16.283512 -125.269312) (xy 16.299004 -125.321812) (xy 16.306833 -125.375987)
			(xy 16.307308 -125.403356) (xy 16.306822 -125.430607) (xy 16.299066 -125.484555) (xy 16.283711 -125.53685)
			(xy 16.261069 -125.586427) (xy 16.231603 -125.632277) (xy 16.195912 -125.673468) (xy 16.154721 -125.709159)
			(xy 16.108871 -125.738625) (xy 16.059294 -125.761267) (xy 16.006999 -125.776622) (xy 15.953051 -125.784378)
			(xy 15.898549 -125.784378) (xy 15.844601 -125.776622) (xy 15.792306 -125.761267) (xy 15.742729 -125.738625)
			(xy 15.696879 -125.709159) (xy 15.655688 -125.673468) (xy 15.619997 -125.632277) (xy 15.590531 -125.586427)
			(xy 15.567889 -125.53685) (xy 15.552534 -125.484555) (xy 15.544778 -125.430607) (xy 15.544292 -125.403356)
			(xy 10.451086 -125.403356) (xy 10.436525 -125.421816) (xy 10.423144 -125.435614) (xy 10.145522 -125.713236)
			(xy 10.131774 -125.726596) (xy 10.101725 -125.750401) (xy 10.085578 -125.760734) (xy 10.080498 -125.763782)
			(xy 10.058908 -125.785372) (xy 10.0515 -125.792061) (xy 10.033064 -125.79965) (xy 10.023094 -125.800104)
			(xy 10.02284 -125.800104) (xy 9.993122 -125.800104) (xy 9.98728 -125.801374) (xy 9.968503 -125.805523)
			(xy 9.930307 -125.809984) (xy 9.91108 -125.810264) (xy 9.523476 -125.810264) (xy 9.512368 -125.810824)
			(xy 9.492215 -125.820177) (xy 9.484614 -125.828298) (xy 9.479534 -125.834394) (xy 9.442958 -125.877828)
			(xy 9.438894 -125.883416) (xy 9.434827 -125.890268) (xy 9.430805 -125.905677) (xy 9.43102 -125.913642)
			(xy 9.433665 -125.929959) (xy 9.436466 -125.962899) (xy 9.436608 -125.979428) (xy 9.436558 -125.982222)
			(xy 11.113006 -125.982222) (xy 11.117077 -125.9266) (xy 11.129203 -125.872163) (xy 11.149126 -125.820072)
			(xy 11.176422 -125.771437) (xy 11.210508 -125.727294) (xy 11.250657 -125.688585) (xy 11.296015 -125.656134)
			(xy 11.345615 -125.630633) (xy 11.398399 -125.612626) (xy 11.453242 -125.602496) (xy 11.508976 -125.600459)
			(xy 11.564413 -125.606559) (xy 11.61837 -125.620665) (xy 11.669699 -125.642477) (xy 11.717305 -125.671531)
			(xy 11.760173 -125.707206) (xy 11.79739 -125.748743) (xy 11.828163 -125.795256) (xy 11.851835 -125.845753)
			(xy 11.854225 -125.853698) (xy 16.484854 -125.853698) (xy 16.485306 -125.826327) (xy 16.493125 -125.772147)
			(xy 16.508617 -125.719643) (xy 16.531462 -125.669896) (xy 16.561191 -125.623931) (xy 16.578834 -125.603)
			(xy 16.579088 -125.602746) (xy 16.58466 -125.595649) (xy 16.590916 -125.57874) (xy 16.59128 -125.569726)
			(xy 16.59128 -125.50267) (xy 16.590942 -125.493651) (xy 16.584682 -125.476734) (xy 16.579088 -125.46965)
			(xy 16.578834 -125.46965) (xy 16.578834 -125.469396) (xy 16.561185 -125.448472) (xy 16.531473 -125.402497)
			(xy 16.508639 -125.352748) (xy 16.49315 -125.300245) (xy 16.485326 -125.246068) (xy 16.484854 -125.218698)
			(xy 16.48534 -125.191447) (xy 16.493096 -125.137499) (xy 16.508451 -125.085204) (xy 16.531093 -125.035627)
			(xy 16.560559 -124.989777) (xy 16.59625 -124.948586) (xy 16.637441 -124.912895) (xy 16.683291 -124.883429)
			(xy 16.732868 -124.860787) (xy 16.785163 -124.845432) (xy 16.839111 -124.837676) (xy 16.893613 -124.837676)
			(xy 16.947561 -124.845432) (xy 16.999856 -124.860787) (xy 17.049433 -124.883429) (xy 17.095283 -124.912895)
			(xy 17.136474 -124.948586) (xy 17.172165 -124.989777) (xy 17.201631 -125.035627) (xy 17.224273 -125.085204)
			(xy 17.239628 -125.137499) (xy 17.247384 -125.191447) (xy 17.24787 -125.218698) (xy 17.24741 -125.246069)
			(xy 17.239592 -125.300248) (xy 17.224102 -125.352752) (xy 17.201258 -125.402498) (xy 17.171532 -125.448465)
			(xy 17.15389 -125.469396) (xy 17.153636 -125.46965) (xy 17.148057 -125.476741) (xy 17.141807 -125.493655)
			(xy 17.141444 -125.50267) (xy 17.141444 -125.569726) (xy 17.141779 -125.578745) (xy 17.148041 -125.595663)
			(xy 17.153636 -125.602746) (xy 17.15389 -125.602746) (xy 17.15389 -125.603) (xy 17.171541 -125.623923)
			(xy 17.201251 -125.669898) (xy 17.224085 -125.719648) (xy 17.239573 -125.772151) (xy 17.247398 -125.826328)
			(xy 17.24787 -125.853698) (xy 17.247384 -125.880949) (xy 17.239628 -125.934897) (xy 17.224273 -125.987192)
			(xy 17.201631 -126.036769) (xy 17.172165 -126.082619) (xy 17.136474 -126.12381) (xy 17.095283 -126.159501)
			(xy 17.049433 -126.188967) (xy 16.999856 -126.211609) (xy 16.947561 -126.226964) (xy 16.893613 -126.23472)
			(xy 16.839111 -126.23472) (xy 16.785163 -126.226964) (xy 16.732868 -126.211609) (xy 16.683291 -126.188967)
			(xy 16.637441 -126.159501) (xy 16.59625 -126.12381) (xy 16.560559 -126.082619) (xy 16.531093 -126.036769)
			(xy 16.508451 -125.987192) (xy 16.493096 -125.934897) (xy 16.48534 -125.880949) (xy 16.484854 -125.853698)
			(xy 11.854225 -125.853698) (xy 11.867903 -125.89916) (xy 11.876023 -125.954336) (xy 11.876532 -125.982222)
			(xy 11.876023 -126.010108) (xy 11.867903 -126.065284) (xy 11.851835 -126.118691) (xy 11.828163 -126.169188)
			(xy 11.79739 -126.215701) (xy 11.760173 -126.257238) (xy 11.717305 -126.292913) (xy 11.669699 -126.321967)
			(xy 11.61837 -126.343779) (xy 11.564413 -126.357885) (xy 11.508976 -126.363985) (xy 11.453242 -126.361948)
			(xy 11.398399 -126.351818) (xy 11.345615 -126.333811) (xy 11.296015 -126.30831) (xy 11.250657 -126.275859)
			(xy 11.210508 -126.23715) (xy 11.176422 -126.193007) (xy 11.149126 -126.144372) (xy 11.129203 -126.092281)
			(xy 11.117077 -126.037844) (xy 11.113006 -125.982222) (xy 9.436558 -125.982222) (xy 9.436122 -126.006679)
			(xy 9.428366 -126.060627) (xy 9.413011 -126.112922) (xy 9.390369 -126.162499) (xy 9.360903 -126.208349)
			(xy 9.325212 -126.24954) (xy 9.284021 -126.285231) (xy 9.238171 -126.314697) (xy 9.188594 -126.337339)
			(xy 9.136299 -126.352694) (xy 9.082351 -126.36045) (xy 9.027849 -126.36045) (xy 8.973901 -126.352694)
			(xy 8.921606 -126.337339) (xy 8.872029 -126.314697) (xy 8.826179 -126.285231) (xy 8.784988 -126.24954)
			(xy 8.749297 -126.208349) (xy 8.719831 -126.162499) (xy 8.697189 -126.112922) (xy 8.681834 -126.060627)
			(xy 8.674078 -126.006679) (xy 8.673592 -125.979428) (xy 8.673733 -125.962898) (xy 8.676529 -125.929958)
			(xy 8.67918 -125.913642) (xy 8.679312 -125.905686) (xy 8.675306 -125.890294) (xy 8.671306 -125.883416)
			(xy 8.667242 -125.877828) (xy 8.630666 -125.834394) (xy 8.625586 -125.828298) (xy 8.618 -125.820154)
			(xy 8.59784 -125.810782) (xy 8.586724 -125.810264) (xy 7.402068 -125.810264) (xy 7.392002 -125.810695)
			(xy 7.373412 -125.818424) (xy 7.366 -125.82525) (xy 6.90499 -126.286514) (xy 6.897624 -126.293626)
			(xy 6.890004 -126.312422) (xy 6.890004 -126.530354) (xy 17.769586 -126.530354) (xy 17.770111 -126.501437)
			(xy 17.778834 -126.444265) (xy 17.796088 -126.389065) (xy 17.821479 -126.337102) (xy 17.854423 -126.289568)
			(xy 17.894166 -126.247553) (xy 17.916652 -126.229364) (xy 17.925474 -126.221772) (xy 17.935648 -126.200859)
			(xy 17.93621 -126.189232) (xy 17.93621 -126.109476) (xy 17.935667 -126.097845) (xy 17.92548 -126.076936)
			(xy 17.916652 -126.069344) (xy 17.89418 -126.05114) (xy 17.854446 -126.009122) (xy 17.821507 -125.961589)
			(xy 17.796117 -125.90963) (xy 17.778858 -125.854436) (xy 17.770124 -125.797269) (xy 17.769586 -125.768354)
			(xy 17.770035 -125.741102) (xy 17.777798 -125.687153) (xy 17.793158 -125.634858) (xy 17.815804 -125.585281)
			(xy 17.845275 -125.539431) (xy 17.88097 -125.498242) (xy 17.922163 -125.462551) (xy 17.968016 -125.433085)
			(xy 18.017596 -125.410444) (xy 18.069892 -125.395089) (xy 18.123842 -125.387332) (xy 18.151094 -125.386846)
			(xy 18.178465 -125.387304) (xy 18.232645 -125.395122) (xy 18.285148 -125.410613) (xy 18.334895 -125.433456)
			(xy 18.380861 -125.463183) (xy 18.401792 -125.480826) (xy 18.402046 -125.48108) (xy 18.409137 -125.486659)
			(xy 18.426051 -125.492908) (xy 18.435066 -125.493272) (xy 18.502122 -125.493272) (xy 18.511141 -125.492932)
			(xy 18.528058 -125.486673) (xy 18.535142 -125.48108) (xy 18.535142 -125.480826) (xy 18.535396 -125.480826)
			(xy 18.556322 -125.463179) (xy 18.602296 -125.433468) (xy 18.652045 -125.410633) (xy 18.704547 -125.395144)
			(xy 18.758724 -125.387318) (xy 18.786094 -125.386846) (xy 18.813343 -125.387383) (xy 18.867287 -125.395138)
			(xy 18.919577 -125.41049) (xy 18.969152 -125.433127) (xy 19.015 -125.462588) (xy 19.056189 -125.498274)
			(xy 19.091881 -125.539458) (xy 19.121348 -125.585303) (xy 19.143992 -125.634874) (xy 19.159351 -125.687163)
			(xy 19.167113 -125.741105) (xy 19.167602 -125.768354) (xy 19.16705 -125.79727) (xy 19.158328 -125.854439)
			(xy 19.141076 -125.909637) (xy 19.115691 -125.961599) (xy 19.082754 -126.009134) (xy 19.043019 -126.051153)
			(xy 19.020536 -126.069344) (xy 19.011708 -126.076931) (xy 19.001538 -126.097847) (xy 19.000978 -126.109476)
			(xy 19.000978 -126.189232) (xy 19.001521 -126.200863) (xy 19.011708 -126.221772) (xy 19.020536 -126.229364)
			(xy 19.04301 -126.247566) (xy 19.082744 -126.289585) (xy 19.115683 -126.337118) (xy 19.141073 -126.389077)
			(xy 19.158332 -126.444272) (xy 19.167065 -126.501439) (xy 19.167602 -126.530354) (xy 19.167102 -126.557606)
			(xy 19.159351 -126.611556) (xy 19.147251 -126.652782) (xy 19.438874 -126.652782) (xy 19.439311 -126.625411)
			(xy 19.447133 -126.571229) (xy 19.462628 -126.518725) (xy 19.485477 -126.468979) (xy 19.515209 -126.423014)
			(xy 19.532854 -126.402084) (xy 19.533108 -126.40183) (xy 19.538689 -126.39474) (xy 19.544939 -126.377826)
			(xy 19.5453 -126.36881) (xy 19.5453 -126.301754) (xy 19.544917 -126.29274) (xy 19.538687 -126.275823)
			(xy 19.533108 -126.268734) (xy 19.532854 -126.268734) (xy 19.532854 -126.26848) (xy 19.515195 -126.247562)
			(xy 19.485468 -126.201592) (xy 19.462622 -126.151844) (xy 19.447126 -126.099339) (xy 19.439299 -126.045158)
			(xy 19.439301 -125.990415) (xy 19.447132 -125.936234) (xy 19.462632 -125.883731) (xy 19.485481 -125.833984)
			(xy 19.515211 -125.788016) (xy 19.532854 -125.767084) (xy 19.533108 -125.76683) (xy 19.538689 -125.75974)
			(xy 19.544939 -125.742826) (xy 19.5453 -125.73381) (xy 19.5453 -125.666754) (xy 19.544917 -125.65774)
			(xy 19.538687 -125.640823) (xy 19.533108 -125.633734) (xy 19.532854 -125.633734) (xy 19.532854 -125.63348)
			(xy 19.515195 -125.612562) (xy 19.485468 -125.566592) (xy 19.462622 -125.516844) (xy 19.447126 -125.464339)
			(xy 19.439299 -125.410158) (xy 19.439301 -125.355415) (xy 19.447132 -125.301234) (xy 19.462632 -125.248731)
			(xy 19.485481 -125.198984) (xy 19.515211 -125.153016) (xy 19.532854 -125.132084) (xy 19.533108 -125.13183)
			(xy 19.538689 -125.12474) (xy 19.544939 -125.107826) (xy 19.5453 -125.09881) (xy 19.5453 -125.031754)
			(xy 19.544917 -125.02274) (xy 19.538687 -125.005823) (xy 19.533108 -124.998734) (xy 19.532854 -124.998734)
			(xy 19.532854 -124.99848) (xy 19.515247 -124.977522) (xy 19.485529 -124.931557) (xy 19.462686 -124.881816)
			(xy 19.447187 -124.829321) (xy 19.439352 -124.77515) (xy 19.438874 -124.747782) (xy 19.43936 -124.720531)
			(xy 19.447116 -124.666583) (xy 19.462471 -124.614288) (xy 19.485113 -124.564711) (xy 19.514579 -124.518861)
			(xy 19.55027 -124.47767) (xy 19.591461 -124.441979) (xy 19.637311 -124.412513) (xy 19.686888 -124.389871)
			(xy 19.739183 -124.374516) (xy 19.793131 -124.36676) (xy 19.847633 -124.36676) (xy 19.901581 -124.374516)
			(xy 19.953876 -124.389871) (xy 20.003453 -124.412513) (xy 20.049303 -124.441979) (xy 20.090494 -124.47767)
			(xy 20.126185 -124.518861) (xy 20.155651 -124.564711) (xy 20.178293 -124.614288) (xy 20.193648 -124.666583)
			(xy 20.201404 -124.720531) (xy 20.20189 -124.747782) (xy 20.201416 -124.775152) (xy 20.1936 -124.829331)
			(xy 20.178113 -124.881834) (xy 20.155273 -124.931581) (xy 20.12555 -124.977548) (xy 20.10791 -124.99848)
			(xy 20.107656 -124.998734) (xy 20.102086 -125.005831) (xy 20.09583 -125.02274) (xy 20.095464 -125.031754)
			(xy 20.095464 -125.09881) (xy 20.095824 -125.107826) (xy 20.10207 -125.124743) (xy 20.107656 -125.13183)
			(xy 20.10791 -125.13183) (xy 20.10791 -125.132084) (xy 20.125532 -125.153032) (xy 20.155254 -125.198998)
			(xy 20.178098 -125.248742) (xy 20.193594 -125.301241) (xy 20.201424 -125.355417) (xy 20.201426 -125.410156)
			(xy 20.1936 -125.464332) (xy 20.178108 -125.516833) (xy 20.155267 -125.566578) (xy 20.125548 -125.612547)
			(xy 20.10791 -125.63348) (xy 20.107656 -125.633734) (xy 20.102086 -125.640831) (xy 20.09583 -125.65774)
			(xy 20.095464 -125.666754) (xy 20.095464 -125.73381) (xy 20.095824 -125.742826) (xy 20.10207 -125.759743)
			(xy 20.107656 -125.76683) (xy 20.10791 -125.76683) (xy 20.10791 -125.767084) (xy 20.125532 -125.788032)
			(xy 20.155254 -125.833998) (xy 20.178098 -125.883742) (xy 20.193594 -125.936241) (xy 20.201424 -125.990417)
			(xy 20.201426 -126.045156) (xy 20.1936 -126.099332) (xy 20.178108 -126.151833) (xy 20.155267 -126.201578)
			(xy 20.125548 -126.247547) (xy 20.10791 -126.26848) (xy 20.107656 -126.268734) (xy 20.102086 -126.275831)
			(xy 20.09583 -126.29274) (xy 20.095464 -126.301754) (xy 20.095464 -126.36881) (xy 20.095824 -126.377826)
			(xy 20.10207 -126.394743) (xy 20.107656 -126.40183) (xy 20.10791 -126.40183) (xy 20.10791 -126.402084)
			(xy 20.125557 -126.42301) (xy 20.155267 -126.468985) (xy 20.178101 -126.518734) (xy 20.193591 -126.571236)
			(xy 20.201417 -126.625412) (xy 20.20189 -126.652782) (xy 20.201404 -126.680033) (xy 20.193648 -126.733981)
			(xy 20.178293 -126.786276) (xy 20.155651 -126.835853) (xy 20.126185 -126.881703) (xy 20.090494 -126.922894)
			(xy 20.049303 -126.958585) (xy 20.003453 -126.988051) (xy 19.953876 -127.010693) (xy 19.901581 -127.026048)
			(xy 19.847633 -127.033804) (xy 19.793131 -127.033804) (xy 19.739183 -127.026048) (xy 19.686888 -127.010693)
			(xy 19.637311 -126.988051) (xy 19.591461 -126.958585) (xy 19.55027 -126.922894) (xy 19.514579 -126.881703)
			(xy 19.485113 -126.835853) (xy 19.462471 -126.786276) (xy 19.447116 -126.733981) (xy 19.43936 -126.680033)
			(xy 19.438874 -126.652782) (xy 19.147251 -126.652782) (xy 19.144001 -126.663853) (xy 19.121363 -126.713434)
			(xy 19.091899 -126.759287) (xy 19.056209 -126.800481) (xy 19.01502 -126.836175) (xy 18.969169 -126.865644)
			(xy 18.919591 -126.888287) (xy 18.867295 -126.903643) (xy 18.813346 -126.911399) (xy 18.786094 -126.911862)
			(xy 18.758723 -126.911409) (xy 18.704543 -126.903589) (xy 18.65204 -126.888098) (xy 18.602293 -126.865253)
			(xy 18.556327 -126.835525) (xy 18.535396 -126.817882) (xy 18.535142 -126.817628) (xy 18.528054 -126.812044)
			(xy 18.511138 -126.805798) (xy 18.502122 -126.805436) (xy 18.435066 -126.805436) (xy 18.426047 -126.805769)
			(xy 18.409129 -126.812032) (xy 18.402046 -126.817628) (xy 18.402046 -126.817882) (xy 18.401792 -126.817882)
			(xy 18.380871 -126.835536) (xy 18.334896 -126.865246) (xy 18.285145 -126.888079) (xy 18.232642 -126.903567)
			(xy 18.178464 -126.911391) (xy 18.151094 -126.911862) (xy 18.123839 -126.91145) (xy 18.069884 -126.903691)
			(xy 18.017582 -126.888332) (xy 17.967999 -126.865685) (xy 17.922144 -126.836213) (xy 17.88095 -126.800513)
			(xy 17.845256 -126.759315) (xy 17.81579 -126.713455) (xy 17.79315 -126.663869) (xy 17.777798 -126.611565)
			(xy 17.770046 -126.557609) (xy 17.769586 -126.530354) (xy 6.890004 -126.530354) (xy 6.890004 -127.051308)
			(xy 10.744198 -127.051308) (xy 10.748269 -126.995686) (xy 10.760395 -126.941249) (xy 10.780318 -126.889158)
			(xy 10.807614 -126.840523) (xy 10.8417 -126.79638) (xy 10.881849 -126.757671) (xy 10.927207 -126.72522)
			(xy 10.976807 -126.699719) (xy 11.029591 -126.681712) (xy 11.084434 -126.671582) (xy 11.140168 -126.669545)
			(xy 11.195605 -126.675645) (xy 11.249562 -126.689751) (xy 11.300891 -126.711563) (xy 11.348497 -126.740617)
			(xy 11.391365 -126.776292) (xy 11.428582 -126.817829) (xy 11.459355 -126.864342) (xy 11.483027 -126.914839)
			(xy 11.499095 -126.968246) (xy 11.507215 -127.023422) (xy 11.507724 -127.051308) (xy 11.507215 -127.079194)
			(xy 11.499095 -127.13437) (xy 11.483027 -127.187777) (xy 11.459355 -127.238274) (xy 11.428582 -127.284787)
			(xy 11.391365 -127.326324) (xy 11.348497 -127.361999) (xy 11.300891 -127.391053) (xy 11.249562 -127.412865)
			(xy 11.195605 -127.426971) (xy 11.140168 -127.433071) (xy 11.084434 -127.431034) (xy 11.029591 -127.420904)
			(xy 10.976807 -127.402897) (xy 10.927207 -127.377396) (xy 10.881849 -127.344945) (xy 10.8417 -127.306236)
			(xy 10.807614 -127.262093) (xy 10.780318 -127.213458) (xy 10.760395 -127.161367) (xy 10.748269 -127.10693)
			(xy 10.744198 -127.051308) (xy 6.890004 -127.051308) (xy 6.890004 -128.252803) (xy 9.728405 -128.252803)
			(xy 9.728405 -128.198297) (xy 9.736162 -128.144346) (xy 9.751519 -128.092048) (xy 9.774161 -128.042467)
			(xy 9.80363 -127.996614) (xy 9.839324 -127.955421) (xy 9.880517 -127.919727) (xy 9.926371 -127.89026)
			(xy 9.975951 -127.867617) (xy 10.02825 -127.852262) (xy 10.082201 -127.844505) (xy 10.109454 -127.844042)
			(xy 10.136824 -127.844525) (xy 10.191003 -127.852337) (xy 10.243506 -127.867822) (xy 10.293253 -127.89066)
			(xy 10.33922 -127.920382) (xy 10.360152 -127.938022) (xy 10.360406 -127.938276) (xy 10.36748 -127.94388)
			(xy 10.384407 -127.950114) (xy 10.393426 -127.950468) (xy 10.460482 -127.950468) (xy 10.469499 -127.950109)
			(xy 10.486416 -127.943863) (xy 10.493502 -127.938276) (xy 10.493502 -127.938022) (xy 10.493756 -127.938022)
			(xy 10.514689 -127.920381) (xy 10.560657 -127.890657) (xy 10.610403 -127.867811) (xy 10.662905 -127.852315)
			(xy 10.717083 -127.844486) (xy 10.771825 -127.844486) (xy 10.826003 -127.852315) (xy 10.878505 -127.867811)
			(xy 10.928251 -127.890657) (xy 10.974219 -127.920381) (xy 10.995152 -127.938022) (xy 10.995406 -127.938276)
			(xy 11.00248 -127.94388) (xy 11.019407 -127.950114) (xy 11.028426 -127.950468) (xy 11.095482 -127.950468)
			(xy 11.104499 -127.950109) (xy 11.121416 -127.943863) (xy 11.128502 -127.938276) (xy 11.128502 -127.938022)
			(xy 11.128756 -127.938022) (xy 11.149697 -127.920393) (xy 11.195667 -127.890679) (xy 11.245412 -127.867841)
			(xy 11.297911 -127.852348) (xy 11.352085 -127.844517) (xy 11.379454 -127.844042) (xy 11.406705 -127.844528)
			(xy 11.460652 -127.852285) (xy 11.512947 -127.867641) (xy 11.562523 -127.890282) (xy 11.608373 -127.919748)
			(xy 11.649563 -127.95544) (xy 11.685254 -127.99663) (xy 11.71472 -128.04248) (xy 11.737361 -128.092057)
			(xy 11.752716 -128.144352) (xy 11.760472 -128.198299) (xy 11.760472 -128.252801) (xy 11.752716 -128.306748)
			(xy 11.737361 -128.359043) (xy 11.71472 -128.40862) (xy 11.685254 -128.45447) (xy 11.649563 -128.49566)
			(xy 11.608373 -128.531352) (xy 11.562523 -128.560818) (xy 11.512947 -128.583459) (xy 11.460652 -128.598815)
			(xy 11.406705 -128.606572) (xy 11.379454 -128.607058) (xy 11.352084 -128.606571) (xy 11.297906 -128.598759)
			(xy 11.245403 -128.583276) (xy 11.195655 -128.560439) (xy 11.149688 -128.530718) (xy 11.128756 -128.513078)
			(xy 11.128502 -128.512824) (xy 11.121425 -128.507223) (xy 11.104501 -128.500987) (xy 11.095482 -128.500632)
			(xy 11.028426 -128.500632) (xy 11.01941 -128.500995) (xy 11.002492 -128.507238) (xy 10.995406 -128.512824)
			(xy 10.995152 -128.513078) (xy 10.974219 -128.530719) (xy 10.928251 -128.560443) (xy 10.878505 -128.583289)
			(xy 10.826003 -128.598785) (xy 10.771825 -128.606614) (xy 10.717083 -128.606614) (xy 10.662905 -128.598785)
			(xy 10.610403 -128.583289) (xy 10.560657 -128.560443) (xy 10.514689 -128.530719) (xy 10.493756 -128.513078)
			(xy 10.493502 -128.512824) (xy 10.486425 -128.507223) (xy 10.469501 -128.500987) (xy 10.460482 -128.500632)
			(xy 10.393426 -128.500632) (xy 10.38441 -128.500995) (xy 10.367492 -128.507238) (xy 10.360406 -128.512824)
			(xy 10.360406 -128.513078) (xy 10.360152 -128.513078) (xy 10.339208 -128.530703) (xy 10.293239 -128.560418)
			(xy 10.243495 -128.583257) (xy 10.190996 -128.598751) (xy 10.136822 -128.606582) (xy 10.109454 -128.607058)
			(xy 10.082201 -128.606595) (xy 10.02825 -128.598838) (xy 9.975951 -128.583483) (xy 9.926371 -128.56084)
			(xy 9.880517 -128.531373) (xy 9.839324 -128.495679) (xy 9.80363 -128.454486) (xy 9.774161 -128.408633)
			(xy 9.751519 -128.359052) (xy 9.736162 -128.306754) (xy 9.728405 -128.252803) (xy 6.890004 -128.252803)
			(xy 6.890004 -131.447101) (xy 9.713452 -131.447101) (xy 9.713452 -131.392599) (xy 9.721208 -131.338652)
			(xy 9.736563 -131.286358) (xy 9.759204 -131.236782) (xy 9.78867 -131.190932) (xy 9.824361 -131.149742)
			(xy 9.86555 -131.114051) (xy 9.9114 -131.084585) (xy 9.960976 -131.061944) (xy 10.01327 -131.046589)
			(xy 10.067217 -131.038832) (xy 10.094468 -131.038346) (xy 10.121838 -131.03882) (xy 10.176017 -131.046634)
			(xy 10.228521 -131.062121) (xy 10.278268 -131.084961) (xy 10.324235 -131.114685) (xy 10.345166 -131.132326)
			(xy 10.34542 -131.13258) (xy 10.35249 -131.13819) (xy 10.36942 -131.144421) (xy 10.37844 -131.144772)
			(xy 10.445496 -131.144772) (xy 10.454513 -131.144419) (xy 10.471431 -131.13817) (xy 10.478516 -131.13258)
			(xy 10.478516 -131.132326) (xy 10.47877 -131.132326) (xy 10.499703 -131.114685) (xy 10.545671 -131.084961)
			(xy 10.595417 -131.062115) (xy 10.647919 -131.046619) (xy 10.702097 -131.03879) (xy 10.756839 -131.03879)
			(xy 10.811017 -131.046619) (xy 10.863519 -131.062115) (xy 10.913265 -131.084961) (xy 10.959233 -131.114685)
			(xy 10.980166 -131.132326) (xy 10.98042 -131.13258) (xy 10.98749 -131.13819) (xy 11.00442 -131.144421)
			(xy 11.01344 -131.144772) (xy 11.080496 -131.144772) (xy 11.089513 -131.144419) (xy 11.106431 -131.13817)
			(xy 11.113516 -131.13258) (xy 11.113516 -131.132326) (xy 11.11377 -131.132326) (xy 11.134706 -131.114692)
			(xy 11.180677 -131.084978) (xy 11.230424 -131.062141) (xy 11.282924 -131.046649) (xy 11.337099 -131.03882)
			(xy 11.364468 -131.038346) (xy 11.391721 -131.038801) (xy 11.445673 -131.046558) (xy 11.497972 -131.061914)
			(xy 11.547552 -131.084557) (xy 11.593406 -131.114025) (xy 11.6346 -131.149719) (xy 11.670294 -131.190912)
			(xy 11.699762 -131.236766) (xy 11.722405 -131.286347) (xy 11.737762 -131.338645) (xy 11.745519 -131.392597)
			(xy 11.745519 -131.447103) (xy 11.737762 -131.501055) (xy 11.722405 -131.553353) (xy 11.699762 -131.602934)
			(xy 11.670294 -131.648788) (xy 11.6346 -131.689981) (xy 11.593406 -131.725675) (xy 11.547552 -131.755143)
			(xy 11.497972 -131.777786) (xy 11.445673 -131.793142) (xy 11.391721 -131.800899) (xy 11.364468 -131.801362)
			(xy 11.337097 -131.800924) (xy 11.282916 -131.793101) (xy 11.230412 -131.777606) (xy 11.180666 -131.754757)
			(xy 11.1347 -131.725026) (xy 11.11377 -131.707382) (xy 11.113516 -131.707128) (xy 11.106435 -131.701534)
			(xy 11.089514 -131.695294) (xy 11.080496 -131.694936) (xy 11.01344 -131.694936) (xy 11.004424 -131.695304)
			(xy 10.987507 -131.701543) (xy 10.98042 -131.707128) (xy 10.980166 -131.707382) (xy 10.959233 -131.725023)
			(xy 10.913265 -131.754747) (xy 10.863519 -131.777593) (xy 10.811017 -131.793089) (xy 10.756839 -131.800918)
			(xy 10.702097 -131.800918) (xy 10.647919 -131.793089) (xy 10.595417 -131.777593) (xy 10.545671 -131.754747)
			(xy 10.499703 -131.725023) (xy 10.47877 -131.707382) (xy 10.478516 -131.707128) (xy 10.471435 -131.701534)
			(xy 10.454514 -131.695294) (xy 10.445496 -131.694936) (xy 10.37844 -131.694936) (xy 10.369424 -131.695304)
			(xy 10.352507 -131.701543) (xy 10.34542 -131.707128) (xy 10.34542 -131.707382) (xy 10.345166 -131.707382)
			(xy 10.324218 -131.725001) (xy 10.27825 -131.754716) (xy 10.228506 -131.777556) (xy 10.176009 -131.793052)
			(xy 10.121836 -131.800885) (xy 10.094468 -131.801362) (xy 10.067217 -131.800868) (xy 10.01327 -131.793111)
			(xy 9.960976 -131.777756) (xy 9.9114 -131.755115) (xy 9.86555 -131.725649) (xy 9.824361 -131.689958)
			(xy 9.78867 -131.648768) (xy 9.759204 -131.602918) (xy 9.736563 -131.553342) (xy 9.721208 -131.501048)
			(xy 9.713452 -131.447101) (xy 6.890004 -131.447101) (xy 6.890004 -133.443726) (xy 11.122914 -133.443726)
			(xy 11.123394 -133.417412) (xy 11.130626 -133.365284) (xy 11.144942 -133.314642) (xy 11.166072 -133.266442)
			(xy 11.193616 -133.221599) (xy 11.227053 -133.180959) (xy 11.246104 -133.162802) (xy 11.253507 -133.155282)
			(xy 11.26203 -133.136001) (xy 11.262614 -133.125464) (xy 11.262614 -133.050788) (xy 11.262101 -133.040237)
			(xy 11.253554 -133.020942) (xy 11.246104 -133.01345) (xy 11.227032 -132.995311) (xy 11.193576 -132.954678)
			(xy 11.166019 -132.909834) (xy 11.144884 -132.86163) (xy 11.13057 -132.81098) (xy 11.12335 -132.758843)
			(xy 11.122914 -132.732526) (xy 11.1234 -132.705275) (xy 11.131156 -132.651327) (xy 11.146511 -132.599032)
			(xy 11.169153 -132.549455) (xy 11.198619 -132.503605) (xy 11.23431 -132.462414) (xy 11.275501 -132.426723)
			(xy 11.321351 -132.397257) (xy 11.370928 -132.374615) (xy 11.423223 -132.35926) (xy 11.477171 -132.351504)
			(xy 11.531673 -132.351504) (xy 11.585621 -132.35926) (xy 11.637916 -132.374615) (xy 11.687493 -132.397257)
			(xy 11.733343 -132.426723) (xy 11.774534 -132.462414) (xy 11.810225 -132.503605) (xy 11.839691 -132.549455)
			(xy 11.862333 -132.599032) (xy 11.877688 -132.651327) (xy 11.885444 -132.705275) (xy 11.88593 -132.732526)
			(xy 11.88547 -132.75884) (xy 11.878233 -132.810969) (xy 11.863911 -132.861611) (xy 11.842777 -132.90981)
			(xy 11.81523 -132.954653) (xy 11.781791 -132.995293) (xy 11.76274 -133.01345) (xy 11.75532 -133.020957)
			(xy 11.746805 -133.040248) (xy 11.74623 -133.050788) (xy 11.74623 -133.125464) (xy 11.746756 -133.136014)
			(xy 11.755293 -133.15531) (xy 11.76274 -133.162802) (xy 11.781797 -133.180956) (xy 11.815253 -133.221587)
			(xy 11.84281 -133.266428) (xy 11.863948 -133.314629) (xy 11.878266 -133.365276) (xy 11.885491 -133.41741)
			(xy 11.88593 -133.443726) (xy 11.885444 -133.470977) (xy 11.877688 -133.524925) (xy 11.862333 -133.57722)
			(xy 11.839691 -133.626797) (xy 11.810225 -133.672647) (xy 11.774534 -133.713838) (xy 11.733343 -133.749529)
			(xy 11.687493 -133.778995) (xy 11.637916 -133.801637) (xy 11.585621 -133.816992) (xy 11.531673 -133.824748)
			(xy 11.477171 -133.824748) (xy 11.423223 -133.816992) (xy 11.370928 -133.801637) (xy 11.321351 -133.778995)
			(xy 11.275501 -133.749529) (xy 11.23431 -133.713838) (xy 11.198619 -133.672647) (xy 11.169153 -133.626797)
			(xy 11.146511 -133.57722) (xy 11.131156 -133.524925) (xy 11.1234 -133.470977) (xy 11.122914 -133.443726)
			(xy 6.890004 -133.443726) (xy 6.890004 -133.846824) (xy 6.893052 -133.858762) (xy 6.895846 -133.86435)
			(xy 6.909688 -133.891921) (xy 6.929269 -133.95042) (xy 6.939192 -134.011305) (xy 6.939788 -134.04215)
			(xy 6.939788 -134.044944) (xy 6.93928 -134.056882) (xy 6.937809 -134.083437) (xy 6.928427 -134.135786)
			(xy 6.911864 -134.186325) (xy 6.888441 -134.234072) (xy 6.858612 -134.278103) (xy 6.822956 -134.317563)
			(xy 6.782164 -134.351687) (xy 6.737027 -134.379814) (xy 6.68842 -134.401398) (xy 6.637287 -134.416021)
			(xy 6.584618 -134.423399) (xy 6.558026 -134.423912) (xy 6.557772 -134.423912) (xy 6.532416 -134.423479)
			(xy 6.482156 -134.41672) (xy 6.433238 -134.403352) (xy 6.386525 -134.383611) (xy 6.364478 -134.37108)
			(xy 6.359398 -134.36854) (xy 6.357366 -134.367524) (xy 6.345936 -134.361682) (xy 6.32079 -134.362444)
			(xy 6.243066 -134.40664) (xy 6.235453 -134.41137) (xy 6.223888 -134.425049) (xy 6.217753 -134.441879)
			(xy 6.217412 -134.450836) (xy 6.217412 -135.142043) (xy 9.361887 -135.142043) (xy 9.361887 -135.087537)
			(xy 9.369644 -135.033586) (xy 9.385 -134.981289) (xy 9.407643 -134.931709) (xy 9.437111 -134.885856)
			(xy 9.472805 -134.844663) (xy 9.513997 -134.80897) (xy 9.55985 -134.779502) (xy 9.609431 -134.75686)
			(xy 9.661728 -134.741504) (xy 9.715679 -134.733747) (xy 9.742932 -134.733284) (xy 9.771849 -134.733819)
			(xy 9.82902 -134.74254) (xy 9.88422 -134.759793) (xy 9.936183 -134.785181) (xy 9.983717 -134.818123)
			(xy 10.025733 -134.857864) (xy 10.043922 -134.88035) (xy 10.051733 -134.889318) (xy 10.073184 -134.899517)
			(xy 10.08507 -134.899908) (xy 10.178542 -134.897876) (xy 10.199878 -134.8867) (xy 10.206736 -134.876794)
			(xy 10.22216 -134.855904) (xy 10.257734 -134.818076) (xy 10.298108 -134.785422) (xy 10.342538 -134.758545)
			(xy 10.390203 -134.737942) (xy 10.440221 -134.723993) (xy 10.491669 -134.716955) (xy 10.517632 -134.71652)
			(xy 10.545003 -134.716962) (xy 10.599183 -134.724785) (xy 10.651687 -134.74028) (xy 10.701433 -134.763127)
			(xy 10.747399 -134.792856) (xy 10.76833 -134.8105) (xy 10.768584 -134.810754) (xy 10.775666 -134.816346)
			(xy 10.792587 -134.822588) (xy 10.801604 -134.822946) (xy 10.86866 -134.822946) (xy 10.877676 -134.822582)
			(xy 10.894594 -134.81634) (xy 10.90168 -134.810754) (xy 10.90168 -134.8105) (xy 10.901934 -134.8105)
			(xy 10.922867 -134.792859) (xy 10.968835 -134.763135) (xy 11.018581 -134.740289) (xy 11.071083 -134.724793)
			(xy 11.125261 -134.716964) (xy 11.180003 -134.716964) (xy 11.234181 -134.724793) (xy 11.286683 -134.740289)
			(xy 11.336429 -134.763135) (xy 11.382397 -134.792859) (xy 11.40333 -134.8105) (xy 11.403584 -134.810754)
			(xy 11.410666 -134.816346) (xy 11.427587 -134.822588) (xy 11.436604 -134.822946) (xy 11.50366 -134.822946)
			(xy 11.512676 -134.822582) (xy 11.529594 -134.81634) (xy 11.53668 -134.810754) (xy 11.537188 -134.8105)
			(xy 11.549922 -134.799555) (xy 11.577013 -134.779714) (xy 11.59129 -134.770876) (xy 11.60018 -134.765542)
			(xy 11.612372 -134.748524) (xy 11.632692 -134.655306) (xy 11.628374 -134.634732) (xy 11.622532 -134.626096)
			(xy 11.606532 -134.602032) (xy 11.581188 -134.550101) (xy 11.563962 -134.494943) (xy 11.555248 -134.437819)
			(xy 11.554714 -134.408926) (xy 11.5552 -134.381675) (xy 11.562956 -134.327727) (xy 11.578311 -134.275432)
			(xy 11.600953 -134.225855) (xy 11.630419 -134.180005) (xy 11.66611 -134.138814) (xy 11.707301 -134.103123)
			(xy 11.753151 -134.073657) (xy 11.802728 -134.051015) (xy 11.855023 -134.03566) (xy 11.908971 -134.027904)
			(xy 11.963473 -134.027904) (xy 12.017421 -134.03566) (xy 12.069716 -134.051015) (xy 12.119293 -134.073657)
			(xy 12.165143 -134.103123) (xy 12.206334 -134.138814) (xy 12.242025 -134.180005) (xy 12.271491 -134.225855)
			(xy 12.294133 -134.275432) (xy 12.309488 -134.327727) (xy 12.317244 -134.381675) (xy 12.31773 -134.408926)
			(xy 12.31725 -134.437018) (xy 12.309019 -134.492596) (xy 12.292725 -134.546365) (xy 12.26872 -134.597162)
			(xy 12.237523 -134.643889) (xy 12.19981 -134.685533) (xy 12.156395 -134.721196) (xy 12.132564 -134.736078)
			(xy 12.123674 -134.741412) (xy 12.111482 -134.75843) (xy 12.091162 -134.851648) (xy 12.09548 -134.872222)
			(xy 12.101322 -134.880858) (xy 12.117309 -134.90493) (xy 12.142654 -134.956859) (xy 12.159883 -135.012014)
			(xy 12.168603 -135.069136) (xy 12.16914 -135.098028) (xy 12.168648 -135.125278) (xy 12.160889 -135.179224)
			(xy 12.145532 -135.231517) (xy 12.12289 -135.281092) (xy 12.093423 -135.326941) (xy 12.057733 -135.36813)
			(xy 12.016544 -135.403821) (xy 11.970696 -135.433288) (xy 11.921121 -135.45593) (xy 11.868828 -135.471288)
			(xy 11.814882 -135.479048) (xy 11.787632 -135.479536) (xy 11.760262 -135.479067) (xy 11.706082 -135.471252)
			(xy 11.653578 -135.455765) (xy 11.603831 -135.432923) (xy 11.557865 -135.403198) (xy 11.536934 -135.385556)
			(xy 11.53668 -135.385302) (xy 11.529603 -135.379701) (xy 11.512679 -135.373463) (xy 11.50366 -135.37311)
			(xy 11.436604 -135.37311) (xy 11.427587 -135.373467) (xy 11.41067 -135.379714) (xy 11.403584 -135.385302)
			(xy 11.403584 -135.385556) (xy 11.40333 -135.385556) (xy 11.382397 -135.403197) (xy 11.336429 -135.432921)
			(xy 11.286683 -135.455767) (xy 11.234181 -135.471263) (xy 11.180003 -135.479092) (xy 11.125261 -135.479092)
			(xy 11.071083 -135.471263) (xy 11.018581 -135.455767) (xy 10.968835 -135.432921) (xy 10.922867 -135.403197)
			(xy 10.901934 -135.385556) (xy 10.90168 -135.385302) (xy 10.894603 -135.379701) (xy 10.877679 -135.373463)
			(xy 10.86866 -135.37311) (xy 10.801604 -135.37311) (xy 10.792587 -135.373467) (xy 10.77567 -135.379714)
			(xy 10.768584 -135.385302) (xy 10.768584 -135.385556) (xy 10.76833 -135.385556) (xy 10.747392 -135.403188)
			(xy 10.701421 -135.432902) (xy 10.651676 -135.45574) (xy 10.599176 -135.471233) (xy 10.545001 -135.479062)
			(xy 10.517632 -135.479536) (xy 10.488715 -135.479019) (xy 10.431542 -135.470293) (xy 10.376342 -135.453037)
			(xy 10.32438 -135.427645) (xy 10.276847 -135.3947) (xy 10.234831 -135.354957) (xy 10.216642 -135.33247)
			(xy 10.208844 -135.323489) (xy 10.187383 -135.313296) (xy 10.175494 -135.312912) (xy 10.082022 -135.314944)
			(xy 10.060686 -135.32612) (xy 10.053828 -135.336026) (xy 10.038432 -135.356938) (xy 10.002853 -135.394764)
			(xy 9.962473 -135.427415) (xy 9.918038 -135.454289) (xy 9.87037 -135.474889) (xy 9.820348 -135.488834)
			(xy 9.768897 -135.495867) (xy 9.742932 -135.4963) (xy 9.715679 -135.495833) (xy 9.661728 -135.488076)
			(xy 9.609431 -135.47272) (xy 9.55985 -135.450078) (xy 9.513997 -135.42061) (xy 9.472805 -135.384917)
			(xy 9.437111 -135.343724) (xy 9.407643 -135.297871) (xy 9.385 -135.248291) (xy 9.369644 -135.195994)
			(xy 9.361887 -135.142043) (xy 6.217412 -135.142043) (xy 6.217412 -135.689594) (xy 7.28294 -135.689594)
			(xy 7.287011 -135.633972) (xy 7.299137 -135.579535) (xy 7.31906 -135.527444) (xy 7.346356 -135.478809)
			(xy 7.380442 -135.434666) (xy 7.420591 -135.395957) (xy 7.465949 -135.363506) (xy 7.515549 -135.338005)
			(xy 7.568333 -135.319998) (xy 7.623176 -135.309868) (xy 7.67891 -135.307831) (xy 7.734347 -135.313931)
			(xy 7.788304 -135.328037) (xy 7.839633 -135.349849) (xy 7.887239 -135.378903) (xy 7.930107 -135.414578)
			(xy 7.967324 -135.456115) (xy 7.998097 -135.502628) (xy 8.021769 -135.553125) (xy 8.037837 -135.606532)
			(xy 8.045957 -135.661708) (xy 8.046466 -135.689594) (xy 8.045957 -135.71748) (xy 8.037837 -135.772656)
			(xy 8.021769 -135.826063) (xy 8.002632 -135.866886) (xy 8.43991 -135.866886) (xy 8.443981 -135.811264)
			(xy 8.456107 -135.756827) (xy 8.47603 -135.704736) (xy 8.503326 -135.656101) (xy 8.537412 -135.611958)
			(xy 8.577561 -135.573249) (xy 8.622919 -135.540798) (xy 8.672519 -135.515297) (xy 8.725303 -135.49729)
			(xy 8.780146 -135.48716) (xy 8.83588 -135.485123) (xy 8.891317 -135.491223) (xy 8.945274 -135.505329)
			(xy 8.996603 -135.527141) (xy 9.044209 -135.556195) (xy 9.087077 -135.59187) (xy 9.124294 -135.633407)
			(xy 9.155067 -135.67992) (xy 9.178739 -135.730417) (xy 9.194807 -135.783824) (xy 9.202927 -135.839)
			(xy 9.203436 -135.866886) (xy 9.202927 -135.894772) (xy 9.194807 -135.949948) (xy 9.178739 -136.003355)
			(xy 9.155067 -136.053852) (xy 9.124294 -136.100365) (xy 9.087077 -136.141902) (xy 9.044209 -136.177577)
			(xy 8.996603 -136.206631) (xy 8.945274 -136.228443) (xy 8.891317 -136.242549) (xy 8.83588 -136.248649)
			(xy 8.780146 -136.246612) (xy 8.725303 -136.236482) (xy 8.672519 -136.218475) (xy 8.622919 -136.192974)
			(xy 8.577561 -136.160523) (xy 8.537412 -136.121814) (xy 8.503326 -136.077671) (xy 8.47603 -136.029036)
			(xy 8.456107 -135.976945) (xy 8.443981 -135.922508) (xy 8.43991 -135.866886) (xy 8.002632 -135.866886)
			(xy 7.998097 -135.87656) (xy 7.967324 -135.923073) (xy 7.930107 -135.96461) (xy 7.887239 -136.000285)
			(xy 7.839633 -136.029339) (xy 7.788304 -136.051151) (xy 7.734347 -136.065257) (xy 7.67891 -136.071357)
			(xy 7.623176 -136.06932) (xy 7.568333 -136.05919) (xy 7.515549 -136.041183) (xy 7.465949 -136.015682)
			(xy 7.420591 -135.983231) (xy 7.380442 -135.944522) (xy 7.346356 -135.900379) (xy 7.31906 -135.851744)
			(xy 7.299137 -135.799653) (xy 7.287011 -135.745216) (xy 7.28294 -135.689594) (xy 6.217412 -135.689594)
			(xy 6.217412 -137.44829) (xy 8.345168 -137.44829) (xy 8.349239 -137.392668) (xy 8.361365 -137.338231)
			(xy 8.381288 -137.28614) (xy 8.408584 -137.237505) (xy 8.44267 -137.193362) (xy 8.482819 -137.154653)
			(xy 8.528177 -137.122202) (xy 8.577777 -137.096701) (xy 8.630561 -137.078694) (xy 8.685404 -137.068564)
			(xy 8.741138 -137.066527) (xy 8.796575 -137.072627) (xy 8.850532 -137.086733) (xy 8.901861 -137.108545)
			(xy 8.949467 -137.137599) (xy 8.992335 -137.173274) (xy 9.029552 -137.214811) (xy 9.060325 -137.261324)
			(xy 9.06736 -137.276332) (xy 13.047218 -137.276332) (xy 13.047698 -137.248962) (xy 13.055512 -137.194784)
			(xy 13.070998 -137.14228) (xy 13.093836 -137.092533) (xy 13.123558 -137.046566) (xy 13.141198 -137.025634)
			(xy 13.141452 -137.02538) (xy 13.147059 -137.018308) (xy 13.153292 -137.00138) (xy 13.153644 -136.99236)
			(xy 13.153644 -136.925304) (xy 13.153297 -136.916286) (xy 13.147044 -136.899368) (xy 13.141452 -136.892284)
			(xy 13.141198 -136.892284) (xy 13.141198 -136.89203) (xy 13.123559 -136.871098) (xy 13.093847 -136.825125)
			(xy 13.071011 -136.775377) (xy 13.05552 -136.722877) (xy 13.047692 -136.668701) (xy 13.047218 -136.641332)
			(xy 13.047704 -136.614081) (xy 13.05546 -136.560133) (xy 13.070815 -136.507838) (xy 13.093457 -136.458261)
			(xy 13.122923 -136.412411) (xy 13.158614 -136.37122) (xy 13.199805 -136.335529) (xy 13.245655 -136.306063)
			(xy 13.295232 -136.283421) (xy 13.347527 -136.268066) (xy 13.401475 -136.26031) (xy 13.455977 -136.26031)
			(xy 13.509925 -136.268066) (xy 13.56222 -136.283421) (xy 13.611797 -136.306063) (xy 13.657647 -136.335529)
			(xy 13.698838 -136.37122) (xy 13.734529 -136.412411) (xy 13.763995 -136.458261) (xy 13.786637 -136.507838)
			(xy 13.801992 -136.560133) (xy 13.809748 -136.614081) (xy 13.810234 -136.641332) (xy 13.809803 -136.668704)
			(xy 13.801979 -136.722885) (xy 13.786483 -136.775389) (xy 13.763633 -136.825135) (xy 13.7339 -136.8711)
			(xy 13.716254 -136.89203) (xy 13.716 -136.892284) (xy 13.710414 -136.899371) (xy 13.704167 -136.916287)
			(xy 13.703808 -136.925304) (xy 13.703808 -136.99236) (xy 13.704183 -137.001375) (xy 13.710418 -137.018292)
			(xy 13.716 -137.02538) (xy 13.716254 -137.02538) (xy 13.716254 -137.025634) (xy 13.733868 -137.046586)
			(xy 13.763586 -137.092553) (xy 13.786427 -137.142295) (xy 13.801924 -137.194792) (xy 13.809757 -137.248964)
			(xy 13.810234 -137.276332) (xy 13.809748 -137.303583) (xy 13.801992 -137.357531) (xy 13.786637 -137.409826)
			(xy 13.763995 -137.459403) (xy 13.734529 -137.505253) (xy 13.698838 -137.546444) (xy 13.657647 -137.582135)
			(xy 13.611797 -137.611601) (xy 13.56222 -137.634243) (xy 13.509925 -137.649598) (xy 13.455977 -137.657354)
			(xy 13.401475 -137.657354) (xy 13.347527 -137.649598) (xy 13.295232 -137.634243) (xy 13.245655 -137.611601)
			(xy 13.199805 -137.582135) (xy 13.158614 -137.546444) (xy 13.122923 -137.505253) (xy 13.093457 -137.459403)
			(xy 13.070815 -137.409826) (xy 13.05546 -137.357531) (xy 13.047704 -137.303583) (xy 13.047218 -137.276332)
			(xy 9.06736 -137.276332) (xy 9.083997 -137.311821) (xy 9.100065 -137.365228) (xy 9.108185 -137.420404)
			(xy 9.108694 -137.44829) (xy 9.108185 -137.476176) (xy 9.100065 -137.531352) (xy 9.083997 -137.584759)
			(xy 9.060325 -137.635256) (xy 9.029552 -137.681769) (xy 8.992335 -137.723306) (xy 8.988288 -137.726674)
			(xy 13.98778 -137.726674) (xy 13.988211 -137.699302) (xy 13.996035 -137.645121) (xy 14.011531 -137.592617)
			(xy 14.034381 -137.54287) (xy 14.064114 -137.496906) (xy 14.08176 -137.475976) (xy 14.082014 -137.475722)
			(xy 14.087599 -137.468634) (xy 14.093846 -137.451718) (xy 14.094206 -137.442702) (xy 14.094206 -137.375646)
			(xy 14.093826 -137.366631) (xy 14.087594 -137.349714) (xy 14.082014 -137.342626) (xy 14.08176 -137.342626)
			(xy 14.08176 -137.342372) (xy 14.064135 -137.321429) (xy 14.034422 -137.275459) (xy 14.011584 -137.225714)
			(xy 13.996089 -137.173216) (xy 13.988256 -137.119042) (xy 13.98778 -137.091674) (xy 13.988266 -137.064423)
			(xy 13.996022 -137.010475) (xy 14.011377 -136.95818) (xy 14.034019 -136.908603) (xy 14.063485 -136.862753)
			(xy 14.099176 -136.821562) (xy 14.140367 -136.785871) (xy 14.186217 -136.756405) (xy 14.235794 -136.733763)
			(xy 14.288089 -136.718408) (xy 14.342037 -136.710652) (xy 14.396539 -136.710652) (xy 14.450487 -136.718408)
			(xy 14.502782 -136.733763) (xy 14.552359 -136.756405) (xy 14.598209 -136.785871) (xy 14.6394 -136.821562)
			(xy 14.675091 -136.862753) (xy 14.704557 -136.908603) (xy 14.727199 -136.95818) (xy 14.742554 -137.010475)
			(xy 14.75031 -137.064423) (xy 14.750796 -137.091674) (xy 14.750316 -137.119044) (xy 14.742501 -137.173222)
			(xy 14.727016 -137.225725) (xy 14.704177 -137.275472) (xy 14.674456 -137.32144) (xy 14.656816 -137.342372)
			(xy 14.656562 -137.342626) (xy 14.650996 -137.349726) (xy 14.644738 -137.366633) (xy 14.64437 -137.375646)
			(xy 14.64437 -137.442702) (xy 14.644733 -137.451718) (xy 14.650977 -137.468635) (xy 14.656562 -137.475722)
			(xy 14.656816 -137.475722) (xy 14.656816 -137.475976) (xy 14.67446 -137.496904) (xy 14.70417 -137.542878)
			(xy 14.727005 -137.592627) (xy 14.742495 -137.645128) (xy 14.750322 -137.699305) (xy 14.750796 -137.726674)
			(xy 14.75031 -137.753925) (xy 14.742554 -137.807873) (xy 14.727199 -137.860168) (xy 14.704557 -137.909745)
			(xy 14.675091 -137.955595) (xy 14.6394 -137.996786) (xy 14.598209 -138.032477) (xy 14.552359 -138.061943)
			(xy 14.502782 -138.084585) (xy 14.450487 -138.09994) (xy 14.396539 -138.107696) (xy 14.342037 -138.107696)
			(xy 14.288089 -138.09994) (xy 14.235794 -138.084585) (xy 14.186217 -138.061943) (xy 14.140367 -138.032477)
			(xy 14.099176 -137.996786) (xy 14.063485 -137.955595) (xy 14.034019 -137.909745) (xy 14.011377 -137.860168)
			(xy 13.996022 -137.807873) (xy 13.988266 -137.753925) (xy 13.98778 -137.726674) (xy 8.988288 -137.726674)
			(xy 8.949467 -137.758981) (xy 8.901861 -137.788035) (xy 8.850532 -137.809847) (xy 8.796575 -137.823953)
			(xy 8.741138 -137.830053) (xy 8.685404 -137.828016) (xy 8.630561 -137.817886) (xy 8.577777 -137.799879)
			(xy 8.528177 -137.774378) (xy 8.482819 -137.741927) (xy 8.44267 -137.703218) (xy 8.408584 -137.659075)
			(xy 8.381288 -137.61044) (xy 8.361365 -137.558349) (xy 8.349239 -137.503912) (xy 8.345168 -137.44829)
			(xy 6.217412 -137.44829) (xy 6.217412 -137.951972) (xy 6.217767 -137.960952) (xy 6.223992 -137.977798)
			(xy 6.235678 -137.991435) (xy 6.24332 -137.996168) (xy 6.309868 -138.034014) (xy 6.315686 -138.037107)
			(xy 6.328427 -138.040444) (xy 6.335014 -138.040618) (xy 6.349238 -138.040618) (xy 6.36143 -138.033252)
			(xy 6.38376 -138.020341) (xy 6.431158 -137.999993) (xy 6.480868 -137.986225) (xy 6.531981 -137.979289)
			(xy 6.557772 -137.978896) (xy 6.566916 -137.978896) (xy 6.593751 -137.979975) (xy 6.646738 -137.988736)
			(xy 6.697971 -138.004843) (xy 6.746438 -138.027979) (xy 6.791181 -138.057685) (xy 6.831314 -138.093373)
			(xy 6.866043 -138.134339) (xy 6.894682 -138.179771) (xy 6.916665 -138.228772) (xy 6.931556 -138.280372)
			(xy 6.939062 -138.333551) (xy 6.939534 -138.360404) (xy 6.939048 -138.387656) (xy 6.936794 -138.40333)
			(xy 15.196312 -138.40333) (xy 15.196842 -138.375665) (xy 15.204838 -138.320917) (xy 15.220651 -138.267895)
			(xy 15.243951 -138.217711) (xy 15.274249 -138.171415) (xy 15.310912 -138.129977) (xy 15.353172 -138.094264)
			(xy 15.376398 -138.079226) (xy 15.386055 -138.072565) (xy 15.398512 -138.052722) (xy 15.400274 -138.041126)
			(xy 15.408148 -137.961116) (xy 15.408763 -137.949478) (xy 15.400695 -137.927642) (xy 15.392654 -137.919206)
			(xy 15.3924 -137.918952) (xy 15.373813 -137.900876) (xy 15.341235 -137.860543) (xy 15.314423 -137.816168)
			(xy 15.293871 -137.768568) (xy 15.279959 -137.718623) (xy 15.272943 -137.667253) (xy 15.272512 -137.64133)
			(xy 15.272983 -137.614077) (xy 15.280737 -137.560125) (xy 15.29609 -137.507826) (xy 15.31873 -137.458245)
			(xy 15.348197 -137.412391) (xy 15.38389 -137.371197) (xy 15.425083 -137.335503) (xy 15.470936 -137.306035)
			(xy 15.520517 -137.283393) (xy 15.572816 -137.268039) (xy 15.626767 -137.260284) (xy 15.65402 -137.259822)
			(xy 15.681391 -137.260271) (xy 15.735571 -137.268092) (xy 15.788074 -137.283585) (xy 15.837821 -137.306431)
			(xy 15.883787 -137.336159) (xy 15.904718 -137.353802) (xy 15.904972 -137.354056) (xy 15.912058 -137.359644)
			(xy 15.928975 -137.365888) (xy 15.937992 -137.366248) (xy 16.005048 -137.366248) (xy 16.014064 -137.365877)
			(xy 16.030981 -137.359641) (xy 16.038068 -137.354056) (xy 16.038068 -137.353802) (xy 16.038322 -137.353802)
			(xy 16.059273 -137.336186) (xy 16.105241 -137.306471) (xy 16.154983 -137.28363) (xy 16.20748 -137.268134)
			(xy 16.261652 -137.260299) (xy 16.28902 -137.259822) (xy 16.316275 -137.260236) (xy 16.370229 -137.267997)
			(xy 16.42253 -137.283357) (xy 16.472112 -137.306004) (xy 16.517966 -137.335477) (xy 16.55916 -137.371176)
			(xy 16.594853 -137.412374) (xy 16.62432 -137.458232) (xy 16.646961 -137.507817) (xy 16.662314 -137.56012)
			(xy 16.670067 -137.614075) (xy 16.670528 -137.64133) (xy 16.669987 -137.670246) (xy 16.661266 -137.727418)
			(xy 16.644015 -137.782617) (xy 16.618627 -137.83458) (xy 16.585686 -137.882114) (xy 16.545947 -137.92413)
			(xy 16.523462 -137.94232) (xy 16.514649 -137.949922) (xy 16.50447 -137.970827) (xy 16.503904 -137.982452)
			(xy 16.503904 -138.062208) (xy 16.504451 -138.073839) (xy 16.514634 -138.094749) (xy 16.523462 -138.10234)
			(xy 16.545957 -138.120518) (xy 16.585693 -138.162539) (xy 16.618632 -138.210077) (xy 16.644019 -138.262041)
			(xy 16.661272 -138.317241) (xy 16.669996 -138.374413) (xy 16.670528 -138.40333) (xy 16.67005 -138.430581)
			(xy 16.66229 -138.484528) (xy 16.646932 -138.536822) (xy 16.624289 -138.586398) (xy 16.594821 -138.632247)
			(xy 16.559129 -138.673436) (xy 16.517939 -138.709127) (xy 16.472089 -138.738594) (xy 16.422512 -138.761236)
			(xy 16.370218 -138.776592) (xy 16.316271 -138.784351) (xy 16.28902 -138.784838) (xy 16.262706 -138.784377)
			(xy 16.210576 -138.777144) (xy 16.159932 -138.762825) (xy 16.111733 -138.741691) (xy 16.06689 -138.714143)
			(xy 16.026251 -138.680701) (xy 16.008096 -138.661648) (xy 16.000571 -138.65425) (xy 15.981294 -138.645722)
			(xy 15.970758 -138.645138) (xy 15.896082 -138.645138) (xy 15.885534 -138.645687) (xy 15.866238 -138.654207)
			(xy 15.858744 -138.661648) (xy 15.840618 -138.680733) (xy 15.799981 -138.714185) (xy 15.755134 -138.741739)
			(xy 15.706928 -138.762872) (xy 15.656276 -138.777184) (xy 15.604138 -138.784403) (xy 15.57782 -138.784838)
			(xy 15.550571 -138.784303) (xy 15.496626 -138.77655) (xy 15.444334 -138.761199) (xy 15.394759 -138.738563)
			(xy 15.34891 -138.709101) (xy 15.307721 -138.673415) (xy 15.272029 -138.63223) (xy 15.242561 -138.586385)
			(xy 15.219918 -138.536813) (xy 15.20456 -138.484523) (xy 15.1968 -138.430579) (xy 15.196312 -138.40333)
			(xy 6.936794 -138.40333) (xy 6.931291 -138.441604) (xy 6.915936 -138.4939) (xy 6.893295 -138.543479)
			(xy 6.863829 -138.58933) (xy 6.828138 -138.630522) (xy 6.786948 -138.666216) (xy 6.741098 -138.695684)
			(xy 6.691521 -138.718328) (xy 6.639226 -138.733686) (xy 6.585278 -138.741446) (xy 6.558026 -138.741912)
			(xy 6.557772 -138.741912) (xy 6.532416 -138.741479) (xy 6.482156 -138.73472) (xy 6.433238 -138.721352)
			(xy 6.386525 -138.701611) (xy 6.364478 -138.68908) (xy 6.359398 -138.68654) (xy 6.357366 -138.685524)
			(xy 6.345936 -138.679682) (xy 6.32079 -138.680444) (xy 6.243066 -138.72464) (xy 6.235453 -138.72937)
			(xy 6.223888 -138.743049) (xy 6.217753 -138.759879) (xy 6.217412 -138.768836) (xy 6.217412 -138.824462)
			(xy 8.361932 -138.824462) (xy 8.366003 -138.76884) (xy 8.378129 -138.714403) (xy 8.398052 -138.662312)
			(xy 8.425348 -138.613677) (xy 8.459434 -138.569534) (xy 8.499583 -138.530825) (xy 8.544941 -138.498374)
			(xy 8.594541 -138.472873) (xy 8.647325 -138.454866) (xy 8.702168 -138.444736) (xy 8.757902 -138.442699)
			(xy 8.813339 -138.448799) (xy 8.867296 -138.462905) (xy 8.918625 -138.484717) (xy 8.966231 -138.513771)
			(xy 9.009099 -138.549446) (xy 9.046316 -138.590983) (xy 9.077089 -138.637496) (xy 9.100761 -138.687993)
			(xy 9.116829 -138.7414) (xy 9.124949 -138.796576) (xy 9.125458 -138.824462) (xy 9.124949 -138.852348)
			(xy 9.116829 -138.907524) (xy 9.100761 -138.960931) (xy 9.077089 -139.011428) (xy 9.046316 -139.057941)
			(xy 9.009099 -139.099478) (xy 8.966231 -139.135153) (xy 8.918625 -139.164207) (xy 8.867296 -139.186019)
			(xy 8.813339 -139.200125) (xy 8.757902 -139.206225) (xy 8.702168 -139.204188) (xy 8.647325 -139.194058)
			(xy 8.594541 -139.176051) (xy 8.544941 -139.15055) (xy 8.499583 -139.118099) (xy 8.459434 -139.07939)
			(xy 8.425348 -139.035247) (xy 8.398052 -138.986612) (xy 8.378129 -138.934521) (xy 8.366003 -138.880084)
			(xy 8.361932 -138.824462) (xy 6.217412 -138.824462) (xy 6.217412 -138.967972) (xy 6.217767 -138.976952)
			(xy 6.223992 -138.993798) (xy 6.235678 -139.007435) (xy 6.24332 -139.012168) (xy 6.309868 -139.050014)
			(xy 6.315686 -139.053107) (xy 6.328427 -139.056444) (xy 6.335014 -139.056618) (xy 6.349238 -139.056618)
			(xy 6.36143 -139.049252) (xy 6.38376 -139.036341) (xy 6.431158 -139.015993) (xy 6.480868 -139.002225)
			(xy 6.531981 -138.995289) (xy 6.557772 -138.994896) (xy 6.566916 -138.994896) (xy 6.593751 -138.995975)
			(xy 6.646738 -139.004736) (xy 6.697971 -139.020843) (xy 6.746438 -139.043979) (xy 6.791181 -139.073685)
			(xy 6.831314 -139.109373) (xy 6.866043 -139.150339) (xy 6.894682 -139.195771) (xy 6.916665 -139.244772)
			(xy 6.927677 -139.282932) (xy 16.938244 -139.282932) (xy 16.938754 -139.25414) (xy 16.947436 -139.197214)
			(xy 16.964578 -139.14224) (xy 16.989789 -139.090467) (xy 17.022498 -139.043074) (xy 17.061959 -139.001136)
			(xy 17.084294 -138.982958) (xy 17.092898 -138.975378) (xy 17.102912 -138.954782) (xy 17.103598 -138.943334)
			(xy 17.104106 -138.851894) (xy 17.093946 -138.830812) (xy 17.084802 -138.8237) (xy 17.062892 -138.805501)
			(xy 17.024216 -138.763691) (xy 16.992191 -138.716591) (xy 16.967531 -138.665251) (xy 16.950784 -138.610813)
			(xy 16.942323 -138.55449) (xy 16.9418 -138.526012) (xy 16.9418 -138.525758) (xy 16.9423 -138.498389)
			(xy 16.95011 -138.444211) (xy 16.965591 -138.391709) (xy 16.988425 -138.341961) (xy 17.018142 -138.295993)
			(xy 17.03578 -138.27506) (xy 17.036034 -138.274806) (xy 17.041628 -138.267725) (xy 17.047869 -138.250804)
			(xy 17.048226 -138.241786) (xy 17.048226 -138.17473) (xy 17.047849 -138.165715) (xy 17.041615 -138.148798)
			(xy 17.036034 -138.14171) (xy 17.03578 -138.14171) (xy 17.03578 -138.141456) (xy 17.018137 -138.120525)
			(xy 16.988412 -138.074557) (xy 16.965567 -138.02481) (xy 16.950071 -137.972308) (xy 16.942242 -137.918129)
			(xy 16.942242 -137.863388) (xy 16.950071 -137.809209) (xy 16.965568 -137.756707) (xy 16.988414 -137.70696)
			(xy 17.018139 -137.660993) (xy 17.03578 -137.64006) (xy 17.036034 -137.639806) (xy 17.041628 -137.632725)
			(xy 17.047869 -137.615804) (xy 17.048226 -137.606786) (xy 17.048226 -137.53973) (xy 17.047849 -137.530715)
			(xy 17.041615 -137.513798) (xy 17.036034 -137.50671) (xy 17.03578 -137.50671) (xy 17.03578 -137.506456)
			(xy 17.018137 -137.485525) (xy 16.988412 -137.439557) (xy 16.965567 -137.38981) (xy 16.950071 -137.337308)
			(xy 16.942242 -137.283129) (xy 16.942242 -137.228388) (xy 16.950071 -137.174209) (xy 16.965568 -137.121707)
			(xy 16.988414 -137.07196) (xy 17.018139 -137.025993) (xy 17.03578 -137.00506) (xy 17.036034 -137.004806)
			(xy 17.041628 -136.997725) (xy 17.047869 -136.980804) (xy 17.048226 -136.971786) (xy 17.048226 -136.90473)
			(xy 17.047849 -136.895715) (xy 17.041615 -136.878798) (xy 17.036034 -136.87171) (xy 17.03578 -136.87171)
			(xy 17.03578 -136.871456) (xy 17.018151 -136.850516) (xy 16.988438 -136.804545) (xy 16.9656 -136.7548)
			(xy 16.950107 -136.702301) (xy 16.942276 -136.648127) (xy 16.9418 -136.620758) (xy 16.942286 -136.593507)
			(xy 16.950042 -136.539559) (xy 16.965397 -136.487264) (xy 16.988039 -136.437687) (xy 17.017505 -136.391837)
			(xy 17.053196 -136.350646) (xy 17.094387 -136.314955) (xy 17.140237 -136.285489) (xy 17.189814 -136.262847)
			(xy 17.242109 -136.247492) (xy 17.296057 -136.239736) (xy 17.350559 -136.239736) (xy 17.404507 -136.247492)
			(xy 17.456802 -136.262847) (xy 17.506379 -136.285489) (xy 17.552229 -136.314955) (xy 17.59342 -136.350646)
			(xy 17.629111 -136.391837) (xy 17.658577 -136.437687) (xy 17.681219 -136.487264) (xy 17.696574 -136.539559)
			(xy 17.70433 -136.593507) (xy 17.704816 -136.620758) (xy 17.704346 -136.648128) (xy 17.696532 -136.702308)
			(xy 17.681045 -136.754812) (xy 17.658204 -136.804559) (xy 17.628478 -136.850525) (xy 17.610836 -136.871456)
			(xy 17.610582 -136.87171) (xy 17.604983 -136.878788) (xy 17.598744 -136.895711) (xy 17.59839 -136.90473)
			(xy 17.59839 -136.971786) (xy 17.598756 -136.980802) (xy 17.604998 -136.997719) (xy 17.610582 -137.004806)
			(xy 17.610836 -137.004806) (xy 17.610836 -137.00506) (xy 17.628475 -137.025994) (xy 17.658199 -137.071962)
			(xy 17.681045 -137.121708) (xy 17.696541 -137.17421) (xy 17.70437 -137.228388) (xy 17.70437 -137.283129)
			(xy 17.696541 -137.337307) (xy 17.681046 -137.389809) (xy 17.658201 -137.439555) (xy 17.628476 -137.485523)
			(xy 17.610836 -137.506456) (xy 17.610582 -137.50671) (xy 17.604983 -137.513788) (xy 17.598744 -137.530711)
			(xy 17.59839 -137.53973) (xy 17.59839 -137.606786) (xy 17.598756 -137.615802) (xy 17.604998 -137.632719)
			(xy 17.610582 -137.639806) (xy 17.610836 -137.639806) (xy 17.610836 -137.64006) (xy 17.628475 -137.660994)
			(xy 17.658199 -137.706962) (xy 17.681045 -137.756708) (xy 17.696541 -137.80921) (xy 17.70437 -137.863388)
			(xy 17.70437 -137.918129) (xy 17.696541 -137.972307) (xy 17.681046 -138.024809) (xy 17.658201 -138.074555)
			(xy 17.628476 -138.120523) (xy 17.610836 -138.141456) (xy 17.610582 -138.14171) (xy 17.604983 -138.148788)
			(xy 17.598744 -138.165711) (xy 17.59839 -138.17473) (xy 17.59839 -138.241786) (xy 17.598756 -138.250802)
			(xy 17.604998 -138.267719) (xy 17.610582 -138.274806) (xy 17.610836 -138.274806) (xy 17.610836 -138.27506)
			(xy 17.628475 -138.295992) (xy 17.658186 -138.341965) (xy 17.681021 -138.391713) (xy 17.696512 -138.444213)
			(xy 17.704341 -138.498389) (xy 17.704816 -138.525758) (xy 17.704314 -138.554551) (xy 17.695632 -138.611478)
			(xy 17.67849 -138.666453) (xy 17.653277 -138.718225) (xy 17.620567 -138.765619) (xy 17.581102 -138.807555)
			(xy 17.558766 -138.825732) (xy 17.550177 -138.833327) (xy 17.540152 -138.853911) (xy 17.539462 -138.865356)
			(xy 17.538954 -138.956796) (xy 17.549114 -138.977878) (xy 17.558258 -138.98499) (xy 17.57045 -138.995404)
			(xy 17.570704 -138.995658) (xy 17.57778 -139.001259) (xy 17.594705 -139.007496) (xy 17.603724 -139.00785)
			(xy 17.67078 -139.00785) (xy 17.679797 -139.007494) (xy 17.696715 -139.001247) (xy 17.7038 -138.995658)
			(xy 17.7038 -138.995404) (xy 17.704054 -138.995404) (xy 17.724987 -138.977763) (xy 17.770955 -138.948039)
			(xy 17.820701 -138.925193) (xy 17.873203 -138.909697) (xy 17.927381 -138.901868) (xy 17.982123 -138.901868)
			(xy 18.036301 -138.909697) (xy 18.088803 -138.925193) (xy 18.138549 -138.948039) (xy 18.184517 -138.977763)
			(xy 18.20545 -138.995404) (xy 18.205704 -138.995658) (xy 18.21278 -139.001259) (xy 18.229705 -139.007496)
			(xy 18.238724 -139.00785) (xy 18.30578 -139.00785) (xy 18.314797 -139.007494) (xy 18.331715 -139.001247)
			(xy 18.3388 -138.995658) (xy 18.3388 -138.995404) (xy 18.339054 -138.995404) (xy 18.359987 -138.977763)
			(xy 18.405955 -138.948039) (xy 18.455701 -138.925193) (xy 18.508203 -138.909697) (xy 18.562381 -138.901868)
			(xy 18.617123 -138.901868) (xy 18.671301 -138.909697) (xy 18.723803 -138.925193) (xy 18.773549 -138.948039)
			(xy 18.819517 -138.977763) (xy 18.84045 -138.995404) (xy 18.840704 -138.995658) (xy 18.84778 -139.001259)
			(xy 18.864705 -139.007496) (xy 18.873724 -139.00785) (xy 18.94078 -139.00785) (xy 18.949797 -139.007494)
			(xy 18.966715 -139.001247) (xy 18.9738 -138.995658) (xy 18.9738 -138.995404) (xy 18.974054 -138.995404)
			(xy 18.994993 -138.977774) (xy 19.040964 -138.94806) (xy 19.09071 -138.925223) (xy 19.143209 -138.90973)
			(xy 19.197383 -138.901899) (xy 19.224752 -138.901424) (xy 19.252003 -138.901906) (xy 19.305951 -138.909663)
			(xy 19.358246 -138.925018) (xy 19.407823 -138.947659) (xy 19.453674 -138.977126) (xy 19.494864 -139.012818)
			(xy 19.530555 -139.054008) (xy 19.560021 -139.099859) (xy 19.582663 -139.149436) (xy 19.598018 -139.201731)
			(xy 19.605774 -139.255679) (xy 19.605774 -139.310181) (xy 19.598018 -139.364129) (xy 19.582663 -139.416424)
			(xy 19.560021 -139.466001) (xy 19.530555 -139.511852) (xy 19.494864 -139.553042) (xy 19.453674 -139.588734)
			(xy 19.407823 -139.618201) (xy 19.358246 -139.640842) (xy 19.305951 -139.656197) (xy 19.252003 -139.663954)
			(xy 19.224752 -139.66444) (xy 19.197382 -139.663958) (xy 19.143203 -139.656146) (xy 19.0907 -139.640662)
			(xy 19.040952 -139.617823) (xy 18.994986 -139.588101) (xy 18.974054 -139.57046) (xy 18.9738 -139.570206)
			(xy 18.966717 -139.564614) (xy 18.949798 -139.55837) (xy 18.94078 -139.558014) (xy 18.873724 -139.558014)
			(xy 18.864708 -139.558379) (xy 18.847791 -139.564621) (xy 18.840704 -139.570206) (xy 18.84045 -139.57046)
			(xy 18.819517 -139.588101) (xy 18.773549 -139.617825) (xy 18.723803 -139.640671) (xy 18.671301 -139.656167)
			(xy 18.617123 -139.663996) (xy 18.562381 -139.663996) (xy 18.508203 -139.656167) (xy 18.455701 -139.640671)
			(xy 18.405955 -139.617825) (xy 18.359987 -139.588101) (xy 18.339054 -139.57046) (xy 18.3388 -139.570206)
			(xy 18.331717 -139.564614) (xy 18.314798 -139.55837) (xy 18.30578 -139.558014) (xy 18.238724 -139.558014)
			(xy 18.229708 -139.558379) (xy 18.212791 -139.564621) (xy 18.205704 -139.570206) (xy 18.205704 -139.57046)
			(xy 18.20545 -139.57046) (xy 18.184517 -139.588101) (xy 18.138549 -139.617825) (xy 18.088803 -139.640671)
			(xy 18.036301 -139.656167) (xy 17.982123 -139.663996) (xy 17.927381 -139.663996) (xy 17.873203 -139.656167)
			(xy 17.820701 -139.640671) (xy 17.770955 -139.617825) (xy 17.724987 -139.588101) (xy 17.704054 -139.57046)
			(xy 17.7038 -139.570206) (xy 17.696717 -139.564614) (xy 17.679798 -139.55837) (xy 17.67078 -139.558014)
			(xy 17.603724 -139.558014) (xy 17.594708 -139.558379) (xy 17.577791 -139.564621) (xy 17.570704 -139.570206)
			(xy 17.570704 -139.57046) (xy 17.57045 -139.57046) (xy 17.549505 -139.588083) (xy 17.503536 -139.617799)
			(xy 17.453792 -139.640638) (xy 17.401294 -139.656133) (xy 17.34712 -139.663964) (xy 17.319752 -139.66444)
			(xy 17.292501 -139.663967) (xy 17.238555 -139.656205) (xy 17.186262 -139.640845) (xy 17.136686 -139.618201)
			(xy 17.090838 -139.588732) (xy 17.049649 -139.55304) (xy 17.013958 -139.51185) (xy 16.984492 -139.466)
			(xy 16.961849 -139.416423) (xy 16.946492 -139.36413) (xy 16.938732 -139.310183) (xy 16.938244 -139.282932)
			(xy 6.927677 -139.282932) (xy 6.931556 -139.296372) (xy 6.939062 -139.349551) (xy 6.939534 -139.376404)
			(xy 6.939048 -139.403656) (xy 6.931291 -139.457604) (xy 6.915936 -139.5099) (xy 6.893295 -139.559479)
			(xy 6.863829 -139.60533) (xy 6.828138 -139.646522) (xy 6.786948 -139.682216) (xy 6.741098 -139.711684)
			(xy 6.691521 -139.734328) (xy 6.639226 -139.749686) (xy 6.585278 -139.757446) (xy 6.558026 -139.757912)
			(xy 6.557772 -139.757912) (xy 6.532416 -139.757479) (xy 6.482156 -139.75072) (xy 6.433238 -139.737352)
			(xy 6.386525 -139.717611) (xy 6.364478 -139.70508) (xy 6.359398 -139.70254) (xy 6.357366 -139.701524)
			(xy 6.345936 -139.695682) (xy 6.32079 -139.696444) (xy 6.243066 -139.74064) (xy 6.235453 -139.74537)
			(xy 6.223888 -139.759049) (xy 6.217753 -139.775879) (xy 6.217412 -139.784836) (xy 6.217412 -140.392404)
			(xy 8.367774 -140.392404) (xy 8.371845 -140.336782) (xy 8.383971 -140.282345) (xy 8.403894 -140.230254)
			(xy 8.43119 -140.181619) (xy 8.465276 -140.137476) (xy 8.505425 -140.098767) (xy 8.550783 -140.066316)
			(xy 8.600383 -140.040815) (xy 8.653167 -140.022808) (xy 8.70801 -140.012678) (xy 8.763744 -140.010641)
			(xy 8.819181 -140.016741) (xy 8.873138 -140.030847) (xy 8.924467 -140.052659) (xy 8.972073 -140.081713)
			(xy 9.014941 -140.117388) (xy 9.052158 -140.158925) (xy 9.082931 -140.205438) (xy 9.106603 -140.255935)
			(xy 9.122671 -140.309342) (xy 9.130791 -140.364518) (xy 9.1313 -140.392404) (xy 9.130791 -140.42029)
			(xy 9.122671 -140.475466) (xy 9.106603 -140.528873) (xy 9.082931 -140.57937) (xy 9.052158 -140.625883)
			(xy 9.014941 -140.66742) (xy 8.972073 -140.703095) (xy 8.924467 -140.732149) (xy 8.873138 -140.753961)
			(xy 8.819181 -140.768067) (xy 8.763744 -140.774167) (xy 8.70801 -140.77213) (xy 8.653167 -140.762)
			(xy 8.600383 -140.743993) (xy 8.550783 -140.718492) (xy 8.505425 -140.686041) (xy 8.465276 -140.647332)
			(xy 8.43119 -140.603189) (xy 8.403894 -140.554554) (xy 8.383971 -140.502463) (xy 8.371845 -140.448026)
			(xy 8.367774 -140.392404) (xy 6.217412 -140.392404) (xy 6.217412 -141.046533) (xy 10.755071 -141.046533)
			(xy 10.755071 -140.992027) (xy 10.762828 -140.938075) (xy 10.778185 -140.885777) (xy 10.800828 -140.836196)
			(xy 10.830296 -140.790342) (xy 10.86599 -140.749149) (xy 10.907184 -140.713455) (xy 10.953038 -140.683987)
			(xy 11.002618 -140.661344) (xy 11.054917 -140.645988) (xy 11.108869 -140.638231) (xy 11.136122 -140.637768)
			(xy 11.162436 -140.638231) (xy 11.214564 -140.645468) (xy 11.265207 -140.659789) (xy 11.313405 -140.680922)
			(xy 11.358249 -140.708469) (xy 11.398889 -140.741907) (xy 11.417046 -140.760958) (xy 11.424554 -140.768376)
			(xy 11.443844 -140.776892) (xy 11.454384 -140.777468) (xy 11.52906 -140.777468) (xy 11.53961 -140.77694)
			(xy 11.558906 -140.768405) (xy 11.566398 -140.760958) (xy 11.584553 -140.741902) (xy 11.625184 -140.708447)
			(xy 11.670025 -140.680889) (xy 11.718225 -140.659751) (xy 11.768872 -140.645433) (xy 11.821006 -140.638207)
			(xy 11.847322 -140.637768) (xy 11.874573 -140.638262) (xy 11.92852 -140.646019) (xy 11.980814 -140.661374)
			(xy 12.03039 -140.684015) (xy 12.07624 -140.713481) (xy 12.117429 -140.749172) (xy 12.15312 -140.790362)
			(xy 12.182586 -140.836212) (xy 12.205227 -140.885788) (xy 12.220582 -140.938082) (xy 12.228338 -140.992029)
			(xy 12.228338 -141.046531) (xy 12.220582 -141.100478) (xy 12.205227 -141.152772) (xy 12.182586 -141.202348)
			(xy 12.15312 -141.248198) (xy 12.117429 -141.289388) (xy 12.07624 -141.325079) (xy 12.03039 -141.354545)
			(xy 11.980814 -141.377186) (xy 11.92852 -141.392541) (xy 11.874573 -141.400298) (xy 11.847322 -141.400784)
			(xy 11.821008 -141.400307) (xy 11.76888 -141.393075) (xy 11.718237 -141.378758) (xy 11.670038 -141.357627)
			(xy 11.625194 -141.330083) (xy 11.584555 -141.296645) (xy 11.566398 -141.277594) (xy 11.55888 -141.270189)
			(xy 11.539597 -141.261667) (xy 11.52906 -141.261084) (xy 11.454384 -141.261084) (xy 11.443832 -141.261596)
			(xy 11.424538 -141.270144) (xy 11.417046 -141.277594) (xy 11.398909 -141.296668) (xy 11.358275 -141.330123)
			(xy 11.313431 -141.35768) (xy 11.265227 -141.378815) (xy 11.214576 -141.393129) (xy 11.162439 -141.400348)
			(xy 11.136122 -141.400784) (xy 11.108869 -141.400329) (xy 11.054917 -141.392572) (xy 11.002618 -141.377216)
			(xy 10.953038 -141.354573) (xy 10.907184 -141.325105) (xy 10.86599 -141.289411) (xy 10.830296 -141.248218)
			(xy 10.800828 -141.202364) (xy 10.778185 -141.152783) (xy 10.762828 -141.100485) (xy 10.755071 -141.046533)
			(xy 6.217412 -141.046533) (xy 6.217412 -143.078533) (xy 10.755071 -143.078533) (xy 10.755071 -143.024027)
			(xy 10.762828 -142.970075) (xy 10.778185 -142.917777) (xy 10.800828 -142.868196) (xy 10.830296 -142.822342)
			(xy 10.86599 -142.781149) (xy 10.907184 -142.745455) (xy 10.953038 -142.715987) (xy 11.002618 -142.693344)
			(xy 11.054917 -142.677988) (xy 11.108869 -142.670231) (xy 11.136122 -142.669768) (xy 11.162436 -142.670231)
			(xy 11.214564 -142.677468) (xy 11.265207 -142.691789) (xy 11.313405 -142.712922) (xy 11.358249 -142.740469)
			(xy 11.398889 -142.773907) (xy 11.417046 -142.792958) (xy 11.424554 -142.800376) (xy 11.443844 -142.808892)
			(xy 11.454384 -142.809468) (xy 11.52906 -142.809468) (xy 11.53961 -142.80894) (xy 11.558906 -142.800405)
			(xy 11.566398 -142.792958) (xy 11.584553 -142.773902) (xy 11.625184 -142.740447) (xy 11.670025 -142.712889)
			(xy 11.718225 -142.691751) (xy 11.768872 -142.677433) (xy 11.821006 -142.670207) (xy 11.847322 -142.669768)
			(xy 11.874573 -142.670262) (xy 11.92852 -142.678019) (xy 11.980814 -142.693374) (xy 12.03039 -142.716015)
			(xy 12.07624 -142.745481) (xy 12.117429 -142.781172) (xy 12.15312 -142.822362) (xy 12.182586 -142.868212)
			(xy 12.205227 -142.917788) (xy 12.220582 -142.970082) (xy 12.228338 -143.024029) (xy 12.228338 -143.078531)
			(xy 12.220582 -143.132478) (xy 12.205227 -143.184772) (xy 12.182586 -143.234348) (xy 12.15312 -143.280198)
			(xy 12.117429 -143.321388) (xy 12.07624 -143.357079) (xy 12.03039 -143.386545) (xy 11.980814 -143.409186)
			(xy 11.92852 -143.424541) (xy 11.874573 -143.432298) (xy 11.847322 -143.432784) (xy 11.821008 -143.432307)
			(xy 11.76888 -143.425075) (xy 11.718237 -143.410758) (xy 11.670038 -143.389627) (xy 11.625194 -143.362083)
			(xy 11.584555 -143.328645) (xy 11.566398 -143.309594) (xy 11.55888 -143.302189) (xy 11.539597 -143.293667)
			(xy 11.52906 -143.293084) (xy 11.454384 -143.293084) (xy 11.443832 -143.293596) (xy 11.424538 -143.302144)
			(xy 11.417046 -143.309594) (xy 11.398909 -143.328668) (xy 11.358275 -143.362123) (xy 11.313431 -143.38968)
			(xy 11.265227 -143.410815) (xy 11.214576 -143.425129) (xy 11.162439 -143.432348) (xy 11.136122 -143.432784)
			(xy 11.108869 -143.432329) (xy 11.054917 -143.424572) (xy 11.002618 -143.409216) (xy 10.953038 -143.386573)
			(xy 10.907184 -143.357105) (xy 10.86599 -143.321411) (xy 10.830296 -143.280218) (xy 10.800828 -143.234364)
			(xy 10.778185 -143.184783) (xy 10.762828 -143.132485) (xy 10.755071 -143.078533) (xy 6.217412 -143.078533)
			(xy 6.217412 -143.915638) (xy 19.464274 -143.915638) (xy 19.464775 -143.888065) (xy 19.472722 -143.833494)
			(xy 19.48844 -143.780635) (xy 19.511604 -143.730589) (xy 19.541729 -143.684399) (xy 19.57819 -143.643025)
			(xy 19.598894 -143.624808) (xy 19.606965 -143.617249) (xy 19.616322 -143.597241) (xy 19.616928 -143.5862)
			(xy 19.616928 -143.508476) (xy 19.616341 -143.497428) (xy 19.606991 -143.477406) (xy 19.598894 -143.469868)
			(xy 19.578163 -143.451679) (xy 19.541694 -143.410305) (xy 19.511565 -143.364111) (xy 19.488403 -143.314058)
			(xy 19.472691 -143.261192) (xy 19.464756 -143.206614) (xy 19.464274 -143.179038) (xy 19.464767 -143.150298)
			(xy 19.473398 -143.09347) (xy 19.490456 -143.038579) (xy 19.515554 -142.986868) (xy 19.548125 -142.939506)
			(xy 19.567398 -142.91818) (xy 19.574002 -142.911322) (xy 19.581114 -142.893288) (xy 19.581114 -142.804388)
			(xy 19.574002 -142.786354) (xy 19.567398 -142.779496) (xy 19.548166 -142.758136) (xy 19.515602 -142.710778)
			(xy 19.49051 -142.659072) (xy 19.473458 -142.604187) (xy 19.464833 -142.547364) (xy 19.464829 -142.489891)
			(xy 19.473446 -142.433068) (xy 19.490489 -142.37818) (xy 19.515574 -142.32647) (xy 19.548131 -142.279107)
			(xy 19.567398 -142.25778) (xy 19.574002 -142.250922) (xy 19.581114 -142.232888) (xy 19.581114 -142.143988)
			(xy 19.574002 -142.125954) (xy 19.567398 -142.119096) (xy 19.548166 -142.097736) (xy 19.515602 -142.050378)
			(xy 19.49051 -141.998672) (xy 19.473458 -141.943787) (xy 19.464833 -141.886964) (xy 19.464829 -141.829491)
			(xy 19.473446 -141.772668) (xy 19.490489 -141.71778) (xy 19.515574 -141.66607) (xy 19.548131 -141.618707)
			(xy 19.567398 -141.59738) (xy 19.574002 -141.590522) (xy 19.581114 -141.572488) (xy 19.581114 -141.483588)
			(xy 19.574002 -141.465554) (xy 19.567398 -141.458696) (xy 19.548166 -141.437336) (xy 19.515602 -141.389978)
			(xy 19.49051 -141.338272) (xy 19.473458 -141.283387) (xy 19.464833 -141.226564) (xy 19.464829 -141.169091)
			(xy 19.473446 -141.112268) (xy 19.490489 -141.05738) (xy 19.515574 -141.00567) (xy 19.548131 -140.958307)
			(xy 19.567398 -140.93698) (xy 19.574002 -140.930122) (xy 19.581114 -140.912088) (xy 19.581114 -140.823188)
			(xy 19.574002 -140.805154) (xy 19.567398 -140.798296) (xy 19.548156 -140.776944) (xy 19.515583 -140.72959)
			(xy 19.490484 -140.677885) (xy 19.473427 -140.622999) (xy 19.464798 -140.566175) (xy 19.464274 -140.537438)
			(xy 19.46476 -140.510187) (xy 19.472516 -140.456239) (xy 19.487871 -140.403944) (xy 19.510513 -140.354367)
			(xy 19.539979 -140.308517) (xy 19.57567 -140.267326) (xy 19.616861 -140.231635) (xy 19.662711 -140.202169)
			(xy 19.712288 -140.179527) (xy 19.764583 -140.164172) (xy 19.818531 -140.156416) (xy 19.873033 -140.156416)
			(xy 19.926981 -140.164172) (xy 19.979276 -140.179527) (xy 20.028853 -140.202169) (xy 20.074703 -140.231635)
			(xy 20.115894 -140.267326) (xy 20.151585 -140.308517) (xy 20.181051 -140.354367) (xy 20.203693 -140.403944)
			(xy 20.219048 -140.456239) (xy 20.226804 -140.510187) (xy 20.22729 -140.537438) (xy 20.226792 -140.566178)
			(xy 20.218164 -140.623007) (xy 20.201108 -140.677898) (xy 20.17601 -140.729609) (xy 20.143439 -140.77697)
			(xy 20.124166 -140.798296) (xy 20.117562 -140.805154) (xy 20.11045 -140.823188) (xy 20.11045 -140.912088)
			(xy 20.117562 -140.930122) (xy 20.124166 -140.93698) (xy 20.143475 -140.958274) (xy 20.17604 -141.005642)
			(xy 20.20113 -141.057359) (xy 20.218178 -141.112255) (xy 20.226797 -141.169087) (xy 20.226793 -141.226569)
			(xy 20.218165 -141.283399) (xy 20.20111 -141.338293) (xy 20.176012 -141.390006) (xy 20.14344 -141.437369)
			(xy 20.124166 -141.458696) (xy 20.117562 -141.465554) (xy 20.11045 -141.483588) (xy 20.11045 -141.572488)
			(xy 20.117562 -141.590522) (xy 20.124166 -141.59738) (xy 20.143475 -141.618674) (xy 20.17604 -141.666042)
			(xy 20.20113 -141.717759) (xy 20.218178 -141.772655) (xy 20.226797 -141.829487) (xy 20.226793 -141.886969)
			(xy 20.218165 -141.943799) (xy 20.20111 -141.998693) (xy 20.176012 -142.050406) (xy 20.14344 -142.097769)
			(xy 20.124166 -142.119096) (xy 20.117562 -142.125954) (xy 20.11045 -142.143988) (xy 20.11045 -142.232888)
			(xy 20.117562 -142.250922) (xy 20.124166 -142.25778) (xy 20.143475 -142.279074) (xy 20.17604 -142.326442)
			(xy 20.20113 -142.378159) (xy 20.218178 -142.433055) (xy 20.226797 -142.489887) (xy 20.226793 -142.547369)
			(xy 20.218165 -142.604199) (xy 20.20111 -142.659093) (xy 20.176012 -142.710806) (xy 20.14344 -142.758169)
			(xy 20.124166 -142.779496) (xy 20.117562 -142.786354) (xy 20.11045 -142.804388) (xy 20.11045 -142.893288)
			(xy 20.117562 -142.911322) (xy 20.124166 -142.91818) (xy 20.143455 -142.939491) (xy 20.176019 -142.986857)
			(xy 20.201108 -143.038573) (xy 20.218154 -143.093467) (xy 20.226772 -143.150298) (xy 20.22729 -143.179038)
			(xy 20.226785 -143.206611) (xy 20.218841 -143.261182) (xy 20.203124 -143.314042) (xy 20.179961 -143.364088)
			(xy 20.149836 -143.410279) (xy 20.113374 -143.451651) (xy 20.09267 -143.469868) (xy 20.084604 -143.477431)
			(xy 20.075246 -143.497437) (xy 20.074636 -143.508476) (xy 20.074636 -143.5862) (xy 20.075248 -143.597244)
			(xy 20.084581 -143.617266) (xy 20.09267 -143.624808) (xy 20.113382 -143.643018) (xy 20.149854 -143.684386)
			(xy 20.179987 -143.730576) (xy 20.203152 -143.780625) (xy 20.218868 -143.833488) (xy 20.226806 -143.888063)
			(xy 20.22729 -143.915638) (xy 20.226804 -143.942889) (xy 20.219048 -143.996837) (xy 20.203693 -144.049132)
			(xy 20.181051 -144.098709) (xy 20.151585 -144.144559) (xy 20.115894 -144.18575) (xy 20.074703 -144.221441)
			(xy 20.028853 -144.250907) (xy 19.979276 -144.273549) (xy 19.926981 -144.288904) (xy 19.873033 -144.29666)
			(xy 19.818531 -144.29666) (xy 19.764583 -144.288904) (xy 19.712288 -144.273549) (xy 19.662711 -144.250907)
			(xy 19.616861 -144.221441) (xy 19.57567 -144.18575) (xy 19.539979 -144.144559) (xy 19.510513 -144.098709)
			(xy 19.487871 -144.049132) (xy 19.472516 -143.996837) (xy 19.46476 -143.942889) (xy 19.464274 -143.915638)
			(xy 6.217412 -143.915638) (xy 6.217412 -145.110533) (xy 10.755071 -145.110533) (xy 10.755071 -145.056027)
			(xy 10.762828 -145.002075) (xy 10.778185 -144.949777) (xy 10.800828 -144.900196) (xy 10.830296 -144.854342)
			(xy 10.86599 -144.813149) (xy 10.907184 -144.777455) (xy 10.953038 -144.747987) (xy 11.002618 -144.725344)
			(xy 11.054917 -144.709988) (xy 11.108869 -144.702231) (xy 11.136122 -144.701768) (xy 11.162436 -144.702231)
			(xy 11.214564 -144.709468) (xy 11.265207 -144.723789) (xy 11.313405 -144.744922) (xy 11.358249 -144.772469)
			(xy 11.398889 -144.805907) (xy 11.417046 -144.824958) (xy 11.424554 -144.832376) (xy 11.443844 -144.840892)
			(xy 11.454384 -144.841468) (xy 11.52906 -144.841468) (xy 11.53961 -144.84094) (xy 11.558906 -144.832405)
			(xy 11.566398 -144.824958) (xy 11.584553 -144.805902) (xy 11.625184 -144.772447) (xy 11.670025 -144.744889)
			(xy 11.718225 -144.723751) (xy 11.768872 -144.709433) (xy 11.821006 -144.702207) (xy 11.847322 -144.701768)
			(xy 11.874573 -144.702262) (xy 11.92852 -144.710019) (xy 11.980814 -144.725374) (xy 12.03039 -144.748015)
			(xy 12.07624 -144.777481) (xy 12.117429 -144.813172) (xy 12.15312 -144.854362) (xy 12.182586 -144.900212)
			(xy 12.205227 -144.949788) (xy 12.206535 -144.954244) (xy 17.939004 -144.954244) (xy 17.939496 -144.926992)
			(xy 17.947248 -144.873041) (xy 17.962599 -144.820743) (xy 17.985237 -144.771162) (xy 18.014701 -144.725308)
			(xy 18.050392 -144.684115) (xy 18.091583 -144.648421) (xy 18.137434 -144.618952) (xy 18.187013 -144.59631)
			(xy 18.23931 -144.580954) (xy 18.29326 -144.573199) (xy 18.320512 -144.572736) (xy 18.349288 -144.573223)
			(xy 18.406184 -144.581882) (xy 18.461135 -144.598986) (xy 18.512895 -144.624148) (xy 18.560289 -144.656798)
			(xy 18.581624 -144.676114) (xy 18.589498 -144.68348) (xy 18.60931 -144.690592) (xy 18.705576 -144.683226)
			(xy 18.724372 -144.67332) (xy 18.730976 -144.664938) (xy 18.749179 -144.642735) (xy 18.791119 -144.603525)
			(xy 18.838459 -144.571041) (xy 18.890131 -144.546016) (xy 18.944969 -144.529014) (xy 19.001735 -144.520419)
			(xy 19.030442 -144.519904) (xy 19.057695 -144.520339) (xy 19.111645 -144.528101) (xy 19.163941 -144.543462)
			(xy 19.21352 -144.566109) (xy 19.25937 -144.595581) (xy 19.30056 -144.631278) (xy 19.336251 -144.672473)
			(xy 19.365717 -144.718328) (xy 19.388357 -144.767909) (xy 19.40371 -144.820208) (xy 19.411465 -144.874159)
			(xy 19.41195 -144.901412) (xy 19.411476 -144.928314) (xy 19.403904 -144.981583) (xy 19.388925 -145.03326)
			(xy 19.366836 -145.082321) (xy 19.338076 -145.127793) (xy 19.303214 -145.168775) (xy 19.262942 -145.204455)
			(xy 19.240754 -145.219674) (xy 19.229832 -145.226786) (xy 19.217894 -145.249646) (xy 19.219926 -145.361914)
			(xy 19.23288 -145.384266) (xy 19.244056 -145.391124) (xy 19.267647 -145.406062) (xy 19.310602 -145.441736)
			(xy 19.347897 -145.483291) (xy 19.378737 -145.529838) (xy 19.402462 -145.580383) (xy 19.418566 -145.633847)
			(xy 19.426704 -145.689088) (xy 19.42719 -145.717006) (xy 19.426721 -145.743999) (xy 19.419116 -145.797446)
			(xy 19.404057 -145.849289) (xy 19.381845 -145.898494) (xy 19.352923 -145.944079) (xy 19.33575 -145.96491)
			(xy 19.328638 -145.973038) (xy 19.322542 -145.993612) (xy 19.333464 -146.078956) (xy 19.335269 -146.089493)
			(xy 19.346303 -146.107777) (xy 19.3548 -146.114262) (xy 19.376018 -146.129632) (xy 19.414469 -146.165218)
			(xy 19.447687 -146.205732) (xy 19.475047 -146.250413) (xy 19.496032 -146.298418) (xy 19.510249 -146.348843)
			(xy 19.517429 -146.40074) (xy 19.517868 -146.426936) (xy 19.517382 -146.454187) (xy 19.509626 -146.508135)
			(xy 19.494271 -146.56043) (xy 19.471629 -146.610007) (xy 19.442163 -146.655857) (xy 19.406472 -146.697048)
			(xy 19.365281 -146.732739) (xy 19.319431 -146.762205) (xy 19.269854 -146.784847) (xy 19.217559 -146.800202)
			(xy 19.163611 -146.807958) (xy 19.109109 -146.807958) (xy 19.055161 -146.800202) (xy 19.002866 -146.784847)
			(xy 18.953289 -146.762205) (xy 18.907439 -146.732739) (xy 18.866248 -146.697048) (xy 18.830557 -146.655857)
			(xy 18.801091 -146.610007) (xy 18.778449 -146.56043) (xy 18.763094 -146.508135) (xy 18.755338 -146.454187)
			(xy 18.754852 -146.426936) (xy 18.755335 -146.399943) (xy 18.762936 -146.346496) (xy 18.777991 -146.294653)
			(xy 18.8002 -146.245448) (xy 18.82912 -146.199863) (xy 18.846292 -146.179032) (xy 18.853404 -146.170904)
			(xy 18.8595 -146.15033) (xy 18.848578 -146.064986) (xy 18.846822 -146.054437) (xy 18.835755 -146.036156)
			(xy 18.827242 -146.02968) (xy 18.802936 -146.012074) (xy 18.75968 -145.970474) (xy 18.741136 -145.946876)
			(xy 18.735294 -145.939002) (xy 18.717768 -145.928588) (xy 18.627344 -145.91538) (xy 18.60804 -145.920206)
			(xy 18.600166 -145.926048) (xy 18.599912 -145.926048) (xy 18.575181 -145.943571) (xy 18.521324 -145.97137)
			(xy 18.463748 -145.990301) (xy 18.403902 -145.999887) (xy 18.373598 -146.00047) (xy 18.346343 -146.000046)
			(xy 18.292389 -145.992288) (xy 18.240088 -145.97693) (xy 18.190505 -145.954284) (xy 18.144651 -145.924813)
			(xy 18.103457 -145.889115) (xy 18.067763 -145.847917) (xy 18.038296 -145.802059) (xy 18.015656 -145.752474)
			(xy 18.000303 -145.700172) (xy 17.992551 -145.646217) (xy 17.99209 -145.618962) (xy 17.992513 -145.592928)
			(xy 17.999606 -145.541344) (xy 18.01364 -145.491201) (xy 18.034357 -145.443431) (xy 18.061371 -145.398917)
			(xy 18.077434 -145.378424) (xy 18.08318 -145.37067) (xy 18.088917 -145.352257) (xy 18.08861 -145.34261)
			(xy 18.08226 -145.262854) (xy 18.073624 -145.245074) (xy 18.066258 -145.238724) (xy 18.046611 -145.220544)
			(xy 18.012087 -145.179638) (xy 17.983617 -145.134309) (xy 17.961759 -145.085447) (xy 17.946943 -145.03401)
			(xy 17.939458 -144.981008) (xy 17.939004 -144.954244) (xy 12.206535 -144.954244) (xy 12.220582 -145.002082)
			(xy 12.228338 -145.056029) (xy 12.228338 -145.110531) (xy 12.220582 -145.164478) (xy 12.205227 -145.216772)
			(xy 12.182586 -145.266348) (xy 12.15312 -145.312198) (xy 12.117429 -145.353388) (xy 12.07624 -145.389079)
			(xy 12.03039 -145.418545) (xy 11.980814 -145.441186) (xy 11.92852 -145.456541) (xy 11.874573 -145.464298)
			(xy 11.847322 -145.464784) (xy 11.821008 -145.464307) (xy 11.76888 -145.457075) (xy 11.718237 -145.442758)
			(xy 11.670038 -145.421627) (xy 11.625194 -145.394083) (xy 11.584555 -145.360645) (xy 11.566398 -145.341594)
			(xy 11.55888 -145.334189) (xy 11.539597 -145.325667) (xy 11.52906 -145.325084) (xy 11.454384 -145.325084)
			(xy 11.443832 -145.325596) (xy 11.424538 -145.334144) (xy 11.417046 -145.341594) (xy 11.398909 -145.360668)
			(xy 11.358275 -145.394123) (xy 11.313431 -145.42168) (xy 11.265227 -145.442815) (xy 11.214576 -145.457129)
			(xy 11.162439 -145.464348) (xy 11.136122 -145.464784) (xy 11.108869 -145.464329) (xy 11.054917 -145.456572)
			(xy 11.002618 -145.441216) (xy 10.953038 -145.418573) (xy 10.907184 -145.389105) (xy 10.86599 -145.353411)
			(xy 10.830296 -145.312218) (xy 10.800828 -145.266364) (xy 10.778185 -145.216783) (xy 10.762828 -145.164485)
			(xy 10.755071 -145.110533) (xy 6.217412 -145.110533) (xy 6.217412 -146.91487) (xy 19.616164 -146.91487)
			(xy 19.620235 -146.859248) (xy 19.632361 -146.804811) (xy 19.652284 -146.75272) (xy 19.67958 -146.704085)
			(xy 19.713666 -146.659942) (xy 19.753815 -146.621233) (xy 19.799173 -146.588782) (xy 19.848773 -146.563281)
			(xy 19.901557 -146.545274) (xy 19.9564 -146.535144) (xy 20.012134 -146.533107) (xy 20.067571 -146.539207)
			(xy 20.121528 -146.553313) (xy 20.172857 -146.575125) (xy 20.220463 -146.604179) (xy 20.263331 -146.639854)
			(xy 20.300548 -146.681391) (xy 20.331321 -146.727904) (xy 20.354993 -146.778401) (xy 20.371061 -146.831808)
			(xy 20.379181 -146.886984) (xy 20.37969 -146.91487) (xy 20.379181 -146.942756) (xy 20.371061 -146.997932)
			(xy 20.354993 -147.051339) (xy 20.349787 -147.062444) (xy 20.994368 -147.062444) (xy 20.998439 -147.006822)
			(xy 21.010565 -146.952385) (xy 21.030488 -146.900294) (xy 21.057784 -146.851659) (xy 21.09187 -146.807516)
			(xy 21.132019 -146.768807) (xy 21.177377 -146.736356) (xy 21.226977 -146.710855) (xy 21.279761 -146.692848)
			(xy 21.334604 -146.682718) (xy 21.390338 -146.680681) (xy 21.445775 -146.686781) (xy 21.499732 -146.700887)
			(xy 21.551061 -146.722699) (xy 21.598667 -146.751753) (xy 21.641535 -146.787428) (xy 21.678752 -146.828965)
			(xy 21.709525 -146.875478) (xy 21.733197 -146.925975) (xy 21.749265 -146.979382) (xy 21.757385 -147.034558)
			(xy 21.757894 -147.062444) (xy 21.757385 -147.09033) (xy 21.749265 -147.145506) (xy 21.733197 -147.198913)
			(xy 21.709525 -147.24941) (xy 21.678752 -147.295923) (xy 21.641535 -147.33746) (xy 21.598667 -147.373135)
			(xy 21.551061 -147.402189) (xy 21.499732 -147.424001) (xy 21.445775 -147.438107) (xy 21.390338 -147.444207)
			(xy 21.334604 -147.44217) (xy 21.279761 -147.43204) (xy 21.226977 -147.414033) (xy 21.177377 -147.388532)
			(xy 21.132019 -147.356081) (xy 21.09187 -147.317372) (xy 21.057784 -147.273229) (xy 21.030488 -147.224594)
			(xy 21.010565 -147.172503) (xy 20.998439 -147.118066) (xy 20.994368 -147.062444) (xy 20.349787 -147.062444)
			(xy 20.331321 -147.101836) (xy 20.300548 -147.148349) (xy 20.263331 -147.189886) (xy 20.220463 -147.225561)
			(xy 20.172857 -147.254615) (xy 20.121528 -147.276427) (xy 20.067571 -147.290533) (xy 20.012134 -147.296633)
			(xy 19.9564 -147.294596) (xy 19.901557 -147.284466) (xy 19.848773 -147.266459) (xy 19.799173 -147.240958)
			(xy 19.753815 -147.208507) (xy 19.713666 -147.169798) (xy 19.67958 -147.125655) (xy 19.652284 -147.07702)
			(xy 19.632361 -147.024929) (xy 19.620235 -146.970492) (xy 19.616164 -146.91487) (xy 6.217412 -146.91487)
			(xy 6.217412 -147.657652) (xy 11.150566 -147.657652) (xy 11.150566 -147.603148) (xy 11.158323 -147.549198)
			(xy 11.173678 -147.496902) (xy 11.19632 -147.447323) (xy 11.225787 -147.401471) (xy 11.26148 -147.36028)
			(xy 11.302671 -147.324587) (xy 11.348523 -147.29512) (xy 11.398102 -147.272478) (xy 11.450398 -147.257123)
			(xy 11.504348 -147.249366) (xy 11.5316 -147.24888) (xy 11.557914 -147.249354) (xy 11.610042 -147.256588)
			(xy 11.660684 -147.270907) (xy 11.708883 -147.292038) (xy 11.753727 -147.319582) (xy 11.794367 -147.353019)
			(xy 11.812524 -147.37207) (xy 11.820039 -147.37948) (xy 11.839324 -147.388001) (xy 11.849862 -147.38858)
			(xy 11.924538 -147.38858) (xy 11.935086 -147.388037) (xy 11.954382 -147.379512) (xy 11.961876 -147.37207)
			(xy 11.981696 -147.351282) (xy 12.026468 -147.315307) (xy 12.076126 -147.286447) (xy 12.129548 -147.265354)
			(xy 12.185527 -147.252505) (xy 12.2428 -147.24819) (xy 12.300073 -147.252505) (xy 12.356052 -147.265354)
			(xy 12.409474 -147.286447) (xy 12.459132 -147.315307) (xy 12.503904 -147.351282) (xy 12.523724 -147.37207)
			(xy 12.531239 -147.37948) (xy 12.550524 -147.388001) (xy 12.561062 -147.38858) (xy 12.635738 -147.38858)
			(xy 12.646286 -147.388037) (xy 12.665582 -147.379512) (xy 12.673076 -147.37207) (xy 12.691244 -147.353027)
			(xy 12.731872 -147.31957) (xy 12.77671 -147.29201) (xy 12.824908 -147.27087) (xy 12.875553 -147.256549)
			(xy 12.927685 -147.249321) (xy 12.954 -147.24888) (xy 12.98125 -147.24939) (xy 13.035196 -147.257147)
			(xy 13.087489 -147.272501) (xy 13.137065 -147.295142) (xy 13.182914 -147.324607) (xy 13.224103 -147.360297)
			(xy 13.259793 -147.401486) (xy 13.289258 -147.447335) (xy 13.311899 -147.496911) (xy 13.327253 -147.549204)
			(xy 13.33501 -147.60315) (xy 13.33501 -147.65765) (xy 13.327253 -147.711596) (xy 13.311899 -147.763889)
			(xy 13.289258 -147.813465) (xy 13.259793 -147.859314) (xy 13.224103 -147.900503) (xy 13.182914 -147.936193)
			(xy 13.137065 -147.965658) (xy 13.087489 -147.988299) (xy 13.035196 -148.003653) (xy 12.98125 -148.01141)
			(xy 12.954 -148.011896) (xy 12.927686 -148.01143) (xy 12.875557 -148.004195) (xy 12.824915 -147.989876)
			(xy 12.776716 -147.968743) (xy 12.731872 -147.941197) (xy 12.691233 -147.907758) (xy 12.673076 -147.888706)
			(xy 12.665564 -147.881293) (xy 12.646277 -147.872775) (xy 12.635738 -147.872196) (xy 12.561062 -147.872196)
			(xy 12.550515 -147.872746) (xy 12.531219 -147.881267) (xy 12.523724 -147.888706) (xy 12.503904 -147.909494)
			(xy 12.459132 -147.945469) (xy 12.409474 -147.974329) (xy 12.356052 -147.995422) (xy 12.300073 -148.008271)
			(xy 12.2428 -148.012586) (xy 12.185527 -148.008271) (xy 12.129548 -147.995422) (xy 12.076126 -147.974329)
			(xy 12.026468 -147.945469) (xy 11.981696 -147.909494) (xy 11.961876 -147.888706) (xy 11.954364 -147.881293)
			(xy 11.935077 -147.872775) (xy 11.924538 -147.872196) (xy 11.849862 -147.872196) (xy 11.839315 -147.872746)
			(xy 11.820019 -147.881267) (xy 11.812524 -147.888706) (xy 11.794351 -147.907744) (xy 11.753725 -147.941203)
			(xy 11.708888 -147.968764) (xy 11.660691 -147.989905) (xy 11.610047 -148.004226) (xy 11.557915 -148.011455)
			(xy 11.5316 -148.011896) (xy 11.504348 -148.011434) (xy 11.450398 -148.003677) (xy 11.398102 -147.988322)
			(xy 11.348523 -147.96568) (xy 11.302671 -147.936213) (xy 11.26148 -147.90052) (xy 11.225787 -147.859329)
			(xy 11.19632 -147.813477) (xy 11.173678 -147.763898) (xy 11.158323 -147.711602) (xy 11.150566 -147.657652)
			(xy 6.217412 -147.657652) (xy 6.217412 -148.017738) (xy 15.977614 -148.017738) (xy 15.981685 -147.962116)
			(xy 15.993811 -147.907679) (xy 16.013734 -147.855588) (xy 16.04103 -147.806953) (xy 16.075116 -147.76281)
			(xy 16.115265 -147.724101) (xy 16.160623 -147.69165) (xy 16.210223 -147.666149) (xy 16.263007 -147.648142)
			(xy 16.31785 -147.638012) (xy 16.373584 -147.635975) (xy 16.429021 -147.642075) (xy 16.482978 -147.656181)
			(xy 16.534307 -147.677993) (xy 16.581913 -147.707047) (xy 16.623176 -147.741386) (xy 21.662134 -147.741386)
			(xy 21.666205 -147.685764) (xy 21.678331 -147.631327) (xy 21.698254 -147.579236) (xy 21.72555 -147.530601)
			(xy 21.759636 -147.486458) (xy 21.799785 -147.447749) (xy 21.845143 -147.415298) (xy 21.894743 -147.389797)
			(xy 21.947527 -147.37179) (xy 22.00237 -147.36166) (xy 22.058104 -147.359623) (xy 22.113541 -147.365723)
			(xy 22.167498 -147.379829) (xy 22.218827 -147.401641) (xy 22.266433 -147.430695) (xy 22.309301 -147.46637)
			(xy 22.346518 -147.507907) (xy 22.377291 -147.55442) (xy 22.400963 -147.604917) (xy 22.417031 -147.658324)
			(xy 22.425151 -147.7135) (xy 22.42566 -147.741386) (xy 22.425151 -147.769272) (xy 22.417031 -147.824448)
			(xy 22.400963 -147.877855) (xy 22.377291 -147.928352) (xy 22.346518 -147.974865) (xy 22.309301 -148.016402)
			(xy 22.266433 -148.052077) (xy 22.218827 -148.081131) (xy 22.167498 -148.102943) (xy 22.113541 -148.117049)
			(xy 22.058104 -148.123149) (xy 22.00237 -148.121112) (xy 21.947527 -148.110982) (xy 21.894743 -148.092975)
			(xy 21.845143 -148.067474) (xy 21.799785 -148.035023) (xy 21.759636 -147.996314) (xy 21.72555 -147.952171)
			(xy 21.698254 -147.903536) (xy 21.678331 -147.851445) (xy 21.666205 -147.797008) (xy 21.662134 -147.741386)
			(xy 16.623176 -147.741386) (xy 16.624781 -147.742722) (xy 16.661998 -147.784259) (xy 16.692771 -147.830772)
			(xy 16.716443 -147.881269) (xy 16.732511 -147.934676) (xy 16.740631 -147.989852) (xy 16.74114 -148.017738)
			(xy 16.740631 -148.045624) (xy 16.732511 -148.1008) (xy 16.716443 -148.154207) (xy 16.692771 -148.204704)
			(xy 16.661998 -148.251217) (xy 16.624781 -148.292754) (xy 16.581913 -148.328429) (xy 16.534307 -148.357483)
			(xy 16.482978 -148.379295) (xy 16.429021 -148.393401) (xy 16.373584 -148.399501) (xy 16.31785 -148.397464)
			(xy 16.263007 -148.387334) (xy 16.210223 -148.369327) (xy 16.160623 -148.343826) (xy 16.115265 -148.311375)
			(xy 16.075116 -148.272666) (xy 16.04103 -148.228523) (xy 16.013734 -148.179888) (xy 15.993811 -148.127797)
			(xy 15.981685 -148.07336) (xy 15.977614 -148.017738) (xy 6.217412 -148.017738) (xy 6.217412 -150.19585)
			(xy 11.150588 -150.19585) (xy 11.150588 -150.14135) (xy 11.158345 -150.087403) (xy 11.173699 -150.03511)
			(xy 11.19634 -149.985534) (xy 11.225805 -149.939685) (xy 11.261496 -149.898496) (xy 11.302685 -149.862805)
			(xy 11.348534 -149.83334) (xy 11.39811 -149.810699) (xy 11.450403 -149.795345) (xy 11.50435 -149.787588)
			(xy 11.5316 -149.787102) (xy 11.557914 -149.787569) (xy 11.610043 -149.794804) (xy 11.660685 -149.809123)
			(xy 11.708884 -149.830255) (xy 11.753728 -149.857802) (xy 11.794367 -149.89124) (xy 11.812524 -149.910292)
			(xy 11.820036 -149.917705) (xy 11.839323 -149.926223) (xy 11.849862 -149.926802) (xy 11.924538 -149.926802)
			(xy 11.935085 -149.926252) (xy 11.954381 -149.917732) (xy 11.961876 -149.910292) (xy 11.981696 -149.889504)
			(xy 12.026468 -149.853529) (xy 12.076126 -149.824669) (xy 12.129548 -149.803576) (xy 12.185527 -149.790727)
			(xy 12.2428 -149.786412) (xy 12.300073 -149.790727) (xy 12.356052 -149.803576) (xy 12.409474 -149.824669)
			(xy 12.459132 -149.853529) (xy 12.503904 -149.889504) (xy 12.523724 -149.910292) (xy 12.531236 -149.917705)
			(xy 12.550523 -149.926223) (xy 12.561062 -149.926802) (xy 12.635738 -149.926802) (xy 12.646285 -149.926252)
			(xy 12.665581 -149.917732) (xy 12.673076 -149.910292) (xy 12.691249 -149.891254) (xy 12.731875 -149.857795)
			(xy 12.776712 -149.830234) (xy 12.824909 -149.809093) (xy 12.875553 -149.794772) (xy 12.927685 -149.787543)
			(xy 12.954 -149.787102) (xy 12.981252 -149.787568) (xy 13.035201 -149.795325) (xy 13.087497 -149.81068)
			(xy 13.137076 -149.833322) (xy 13.182927 -149.862789) (xy 13.224119 -149.898481) (xy 13.259811 -149.939673)
			(xy 13.289278 -149.985524) (xy 13.31192 -150.035103) (xy 13.320244 -150.063454) (xy 15.838168 -150.063454)
			(xy 15.842239 -150.007832) (xy 15.854365 -149.953395) (xy 15.874288 -149.901304) (xy 15.901584 -149.852669)
			(xy 15.93567 -149.808526) (xy 15.975819 -149.769817) (xy 16.021177 -149.737366) (xy 16.070777 -149.711865)
			(xy 16.123561 -149.693858) (xy 16.178404 -149.683728) (xy 16.234138 -149.681691) (xy 16.289575 -149.687791)
			(xy 16.343532 -149.701897) (xy 16.394861 -149.723709) (xy 16.442467 -149.752763) (xy 16.485335 -149.788438)
			(xy 16.522552 -149.829975) (xy 16.553325 -149.876488) (xy 16.576997 -149.926985) (xy 16.593065 -149.980392)
			(xy 16.601185 -150.035568) (xy 16.601694 -150.063454) (xy 16.601185 -150.09134) (xy 16.593065 -150.146516)
			(xy 16.576997 -150.199923) (xy 16.553325 -150.25042) (xy 16.522552 -150.296933) (xy 16.485335 -150.33847)
			(xy 16.442467 -150.374145) (xy 16.394861 -150.403199) (xy 16.343532 -150.425011) (xy 16.289575 -150.439117)
			(xy 16.234138 -150.445217) (xy 16.178404 -150.44318) (xy 16.123561 -150.43305) (xy 16.070777 -150.415043)
			(xy 16.021177 -150.389542) (xy 15.975819 -150.357091) (xy 15.93567 -150.318382) (xy 15.901584 -150.274239)
			(xy 15.874288 -150.225604) (xy 15.854365 -150.173513) (xy 15.842239 -150.119076) (xy 15.838168 -150.063454)
			(xy 13.320244 -150.063454) (xy 13.327275 -150.087399) (xy 13.335032 -150.141348) (xy 13.335032 -150.195852)
			(xy 13.327275 -150.249801) (xy 13.31192 -150.302097) (xy 13.289278 -150.351676) (xy 13.259811 -150.397527)
			(xy 13.224119 -150.438719) (xy 13.182927 -150.474411) (xy 13.137076 -150.503878) (xy 13.087497 -150.52652)
			(xy 13.035201 -150.541875) (xy 12.981252 -150.549632) (xy 12.954 -150.550118) (xy 12.927686 -150.549645)
			(xy 12.875558 -150.54241) (xy 12.824916 -150.528092) (xy 12.776717 -150.506961) (xy 12.731873 -150.479416)
			(xy 12.691233 -150.445979) (xy 12.673076 -150.426928) (xy 12.665562 -150.419518) (xy 12.646276 -150.410997)
			(xy 12.635738 -150.410418) (xy 12.561062 -150.410418) (xy 12.550514 -150.410962) (xy 12.531218 -150.419486)
			(xy 12.523724 -150.426928) (xy 12.503904 -150.447716) (xy 12.459132 -150.483691) (xy 12.409474 -150.512551)
			(xy 12.356052 -150.533644) (xy 12.300073 -150.546493) (xy 12.2428 -150.550808) (xy 12.185527 -150.546493)
			(xy 12.129548 -150.533644) (xy 12.076126 -150.512551) (xy 12.026468 -150.483691) (xy 11.981696 -150.447716)
			(xy 11.961876 -150.426928) (xy 11.954362 -150.419518) (xy 11.935076 -150.410997) (xy 11.924538 -150.410418)
			(xy 11.849862 -150.410418) (xy 11.839314 -150.410962) (xy 11.820018 -150.419486) (xy 11.812524 -150.426928)
			(xy 11.794355 -150.44597) (xy 11.753728 -150.479428) (xy 11.70889 -150.506988) (xy 11.660692 -150.528128)
			(xy 11.610047 -150.542449) (xy 11.557915 -150.549677) (xy 11.5316 -150.550118) (xy 11.50435 -150.549612)
			(xy 11.450403 -150.541855) (xy 11.39811 -150.526501) (xy 11.348534 -150.50386) (xy 11.302685 -150.474395)
			(xy 11.261496 -150.438704) (xy 11.225805 -150.397515) (xy 11.19634 -150.351666) (xy 11.173699 -150.30209)
			(xy 11.158345 -150.249797) (xy 11.150588 -150.19585) (xy 6.217412 -150.19585) (xy 6.217412 -155.212034)
			(xy 7.269224 -155.212034) (xy 7.273295 -155.156412) (xy 7.285421 -155.101975) (xy 7.305344 -155.049884)
			(xy 7.33264 -155.001249) (xy 7.366726 -154.957106) (xy 7.406875 -154.918397) (xy 7.452233 -154.885946)
			(xy 7.501833 -154.860445) (xy 7.554617 -154.842438) (xy 7.60946 -154.832308) (xy 7.665194 -154.830271)
			(xy 7.720631 -154.836371) (xy 7.774588 -154.850477) (xy 7.825917 -154.872289) (xy 7.873523 -154.901343)
			(xy 7.916391 -154.937018) (xy 7.953608 -154.978555) (xy 7.984381 -155.025068) (xy 8.008053 -155.075565)
			(xy 8.009144 -155.079192) (xy 9.86993 -155.079192) (xy 9.874001 -155.02357) (xy 9.886127 -154.969133)
			(xy 9.90605 -154.917042) (xy 9.933346 -154.868407) (xy 9.967432 -154.824264) (xy 10.007581 -154.785555)
			(xy 10.052939 -154.753104) (xy 10.102539 -154.727603) (xy 10.155323 -154.709596) (xy 10.210166 -154.699466)
			(xy 10.2659 -154.697429) (xy 10.321337 -154.703529) (xy 10.375294 -154.717635) (xy 10.426623 -154.739447)
			(xy 10.474229 -154.768501) (xy 10.517097 -154.804176) (xy 10.554314 -154.845713) (xy 10.585087 -154.892226)
			(xy 10.608759 -154.942723) (xy 10.624827 -154.99613) (xy 10.632947 -155.051306) (xy 10.633456 -155.079192)
			(xy 10.633391 -155.082748) (xy 11.19378 -155.082748) (xy 11.194219 -155.056433) (xy 11.201461 -155.004304)
			(xy 11.215786 -154.953661) (xy 11.236924 -154.905462) (xy 11.264474 -154.860619) (xy 11.297917 -154.81998)
			(xy 11.31697 -154.801824) (xy 11.324359 -154.794291) (xy 11.332892 -154.77502) (xy 11.33348 -154.764486)
			(xy 11.33348 -154.68981) (xy 11.332965 -154.679259) (xy 11.32442 -154.659963) (xy 11.31697 -154.652472)
			(xy 11.297902 -154.634329) (xy 11.264447 -154.593696) (xy 11.236891 -154.548853) (xy 11.215755 -154.50065)
			(xy 11.20144 -154.45) (xy 11.194217 -154.397865) (xy 11.19378 -154.371548) (xy 11.1943 -154.344297)
			(xy 11.20205 -154.290349) (xy 11.217399 -154.238053) (xy 11.240035 -154.188473) (xy 11.269497 -154.142621)
			(xy 11.305185 -154.101428) (xy 11.346372 -154.065733) (xy 11.392221 -154.036264) (xy 11.441796 -154.01362)
			(xy 11.49409 -153.998263) (xy 11.548037 -153.990504) (xy 11.575288 -153.99004) (xy 11.601602 -153.990503)
			(xy 11.653731 -153.997737) (xy 11.704375 -154.012056) (xy 11.752574 -154.033189) (xy 11.797417 -154.060737)
			(xy 11.838056 -154.094177) (xy 11.856212 -154.11323) (xy 11.863737 -154.120629) (xy 11.883014 -154.129157)
			(xy 11.89355 -154.12974) (xy 11.968226 -154.12974) (xy 11.978771 -154.129173) (xy 11.998066 -154.120663)
			(xy 12.005564 -154.11323) (xy 12.025384 -154.092442) (xy 12.070156 -154.056467) (xy 12.119814 -154.027607)
			(xy 12.173236 -154.006514) (xy 12.229215 -153.993665) (xy 12.286488 -153.98935) (xy 12.343761 -153.993665)
			(xy 12.39974 -154.006514) (xy 12.453162 -154.027607) (xy 12.50282 -154.056467) (xy 12.547592 -154.092442)
			(xy 12.567412 -154.11323) (xy 12.574937 -154.120629) (xy 12.594214 -154.129157) (xy 12.60475 -154.12974)
			(xy 12.679426 -154.12974) (xy 12.689971 -154.129173) (xy 12.709266 -154.120663) (xy 12.716764 -154.11323)
			(xy 12.736584 -154.092442) (xy 12.781356 -154.056467) (xy 12.831014 -154.027607) (xy 12.884436 -154.006514)
			(xy 12.940415 -153.993665) (xy 12.997688 -153.98935) (xy 13.054961 -153.993665) (xy 13.11094 -154.006514)
			(xy 13.164362 -154.027607) (xy 13.21402 -154.056467) (xy 13.258792 -154.092442) (xy 13.278612 -154.11323)
			(xy 13.286137 -154.120629) (xy 13.305414 -154.129157) (xy 13.31595 -154.12974) (xy 13.390626 -154.12974)
			(xy 13.401171 -154.129173) (xy 13.420466 -154.120663) (xy 13.427964 -154.11323) (xy 13.446101 -154.094156)
			(xy 13.486734 -154.060699) (xy 13.531578 -154.033142) (xy 13.579783 -154.012007) (xy 13.630434 -153.997694)
			(xy 13.682571 -153.990475) (xy 13.708888 -153.99004) (xy 13.736143 -153.990467) (xy 13.790097 -153.998223)
			(xy 13.842399 -154.01358) (xy 13.891982 -154.036225) (xy 13.937838 -154.065696) (xy 13.979032 -154.101394)
			(xy 14.014726 -154.142591) (xy 14.044193 -154.188449) (xy 14.066832 -154.238035) (xy 14.082184 -154.290338)
			(xy 14.089936 -154.344293) (xy 14.090396 -154.371548) (xy 14.089962 -154.397863) (xy 14.08272 -154.449993)
			(xy 14.068395 -154.500637) (xy 14.047256 -154.548835) (xy 14.019704 -154.593678) (xy 13.98626 -154.634316)
			(xy 13.967206 -154.652472) (xy 13.959816 -154.660003) (xy 13.951285 -154.679276) (xy 13.950696 -154.68981)
			(xy 13.950696 -154.764486) (xy 13.951221 -154.775036) (xy 13.959759 -154.794331) (xy 13.967206 -154.801824)
			(xy 13.986267 -154.819974) (xy 14.019724 -154.860605) (xy 14.047282 -154.905446) (xy 14.068419 -154.953648)
			(xy 14.082735 -155.004297) (xy 14.089958 -155.056432) (xy 14.090396 -155.082748) (xy 14.089967 -155.110001)
			(xy 14.082203 -155.163951) (xy 14.066842 -155.216248) (xy 14.044194 -155.265826) (xy 14.014722 -155.311677)
			(xy 13.979024 -155.352867) (xy 13.937829 -155.388558) (xy 13.891973 -155.418023) (xy 13.842392 -155.440663)
			(xy 13.790093 -155.456016) (xy 13.736141 -155.463771) (xy 13.708888 -155.464256) (xy 13.682573 -155.463811)
			(xy 13.630443 -155.456573) (xy 13.579799 -155.442251) (xy 13.5316 -155.421114) (xy 13.486757 -155.393564)
			(xy 13.446119 -155.36012) (xy 13.427964 -155.341066) (xy 13.420449 -155.333656) (xy 13.401164 -155.325134)
			(xy 13.390626 -155.324556) (xy 13.31595 -155.324556) (xy 13.305404 -155.325112) (xy 13.286109 -155.33363)
			(xy 13.278612 -155.341066) (xy 13.258792 -155.361854) (xy 13.21402 -155.397829) (xy 13.164362 -155.426689)
			(xy 13.11094 -155.447782) (xy 13.054961 -155.460631) (xy 12.997688 -155.464946) (xy 12.940415 -155.460631)
			(xy 12.884436 -155.447782) (xy 12.831014 -155.426689) (xy 12.781356 -155.397829) (xy 12.736584 -155.361854)
			(xy 12.716764 -155.341066) (xy 12.709249 -155.333656) (xy 12.689964 -155.325134) (xy 12.679426 -155.324556)
			(xy 12.60475 -155.324556) (xy 12.594204 -155.325112) (xy 12.574909 -155.33363) (xy 12.567412 -155.341066)
			(xy 12.547592 -155.361854) (xy 12.50282 -155.397829) (xy 12.453162 -155.426689) (xy 12.39974 -155.447782)
			(xy 12.343761 -155.460631) (xy 12.286488 -155.464946) (xy 12.229215 -155.460631) (xy 12.173236 -155.447782)
			(xy 12.119814 -155.426689) (xy 12.070156 -155.397829) (xy 12.025384 -155.361854) (xy 12.005564 -155.341066)
			(xy 11.998049 -155.333656) (xy 11.978764 -155.325134) (xy 11.968226 -155.324556) (xy 11.89355 -155.324556)
			(xy 11.883004 -155.325112) (xy 11.863709 -155.33363) (xy 11.856212 -155.341066) (xy 11.838057 -155.360121)
			(xy 11.797425 -155.393576) (xy 11.752585 -155.421133) (xy 11.704384 -155.442271) (xy 11.653737 -155.456589)
			(xy 11.601604 -155.463816) (xy 11.575288 -155.464256) (xy 11.548037 -155.463774) (xy 11.494089 -155.456017)
			(xy 11.441794 -155.440662) (xy 11.392216 -155.41802) (xy 11.346366 -155.388554) (xy 11.305176 -155.352862)
			(xy 11.269484 -155.311671) (xy 11.240018 -155.26582) (xy 11.217377 -155.216243) (xy 11.202022 -155.163947)
			(xy 11.194266 -155.109999) (xy 11.19378 -155.082748) (xy 10.633391 -155.082748) (xy 10.632947 -155.107078)
			(xy 10.624827 -155.162254) (xy 10.608759 -155.215661) (xy 10.585087 -155.266158) (xy 10.554314 -155.312671)
			(xy 10.517097 -155.354208) (xy 10.474229 -155.389883) (xy 10.426623 -155.418937) (xy 10.375294 -155.440749)
			(xy 10.321337 -155.454855) (xy 10.2659 -155.460955) (xy 10.210166 -155.458918) (xy 10.155323 -155.448788)
			(xy 10.102539 -155.430781) (xy 10.052939 -155.40528) (xy 10.007581 -155.372829) (xy 9.967432 -155.33412)
			(xy 9.933346 -155.289977) (xy 9.90605 -155.241342) (xy 9.886127 -155.189251) (xy 9.874001 -155.134814)
			(xy 9.86993 -155.079192) (xy 8.009144 -155.079192) (xy 8.024121 -155.128972) (xy 8.032241 -155.184148)
			(xy 8.03275 -155.212034) (xy 8.032241 -155.23992) (xy 8.024121 -155.295096) (xy 8.008053 -155.348503)
			(xy 7.984381 -155.399) (xy 7.953608 -155.445513) (xy 7.916391 -155.48705) (xy 7.873523 -155.522725)
			(xy 7.825917 -155.551779) (xy 7.774588 -155.573591) (xy 7.720631 -155.587697) (xy 7.665194 -155.593797)
			(xy 7.60946 -155.59176) (xy 7.554617 -155.58163) (xy 7.501833 -155.563623) (xy 7.452233 -155.538122)
			(xy 7.406875 -155.505671) (xy 7.366726 -155.466962) (xy 7.33264 -155.422819) (xy 7.305344 -155.374184)
			(xy 7.285421 -155.322093) (xy 7.273295 -155.267656) (xy 7.269224 -155.212034) (xy 6.217412 -155.212034)
			(xy 6.217412 -156.69387) (xy 8.887458 -156.69387) (xy 8.891529 -156.638248) (xy 8.903655 -156.583811)
			(xy 8.923578 -156.53172) (xy 8.950874 -156.483085) (xy 8.98496 -156.438942) (xy 9.025109 -156.400233)
			(xy 9.070467 -156.367782) (xy 9.120067 -156.342281) (xy 9.172851 -156.324274) (xy 9.227694 -156.314144)
			(xy 9.283428 -156.312107) (xy 9.338865 -156.318207) (xy 9.392822 -156.332313) (xy 9.444151 -156.354125)
			(xy 9.491757 -156.383179) (xy 9.534625 -156.418854) (xy 9.571842 -156.460391) (xy 9.602615 -156.506904)
			(xy 9.626287 -156.557401) (xy 9.642355 -156.610808) (xy 9.650475 -156.665984) (xy 9.650984 -156.69387)
			(xy 9.650475 -156.721756) (xy 9.642355 -156.776932) (xy 9.626287 -156.830339) (xy 9.602615 -156.880836)
			(xy 9.571842 -156.927349) (xy 9.534625 -156.968886) (xy 9.491757 -157.004561) (xy 9.444151 -157.033615)
			(xy 9.392822 -157.055427) (xy 9.338865 -157.069533) (xy 9.283428 -157.075633) (xy 9.227694 -157.073596)
			(xy 9.172851 -157.063466) (xy 9.120067 -157.045459) (xy 9.070467 -157.019958) (xy 9.025109 -156.987507)
			(xy 8.98496 -156.948798) (xy 8.950874 -156.904655) (xy 8.923578 -156.85602) (xy 8.903655 -156.803929)
			(xy 8.891529 -156.749492) (xy 8.887458 -156.69387) (xy 6.217412 -156.69387) (xy 6.217412 -157.812994)
			(xy 6.650226 -157.812994) (xy 6.654297 -157.757372) (xy 6.666423 -157.702935) (xy 6.686346 -157.650844)
			(xy 6.713642 -157.602209) (xy 6.747728 -157.558066) (xy 6.787877 -157.519357) (xy 6.833235 -157.486906)
			(xy 6.882835 -157.461405) (xy 6.935619 -157.443398) (xy 6.990462 -157.433268) (xy 7.046196 -157.431231)
			(xy 7.101633 -157.437331) (xy 7.15559 -157.451437) (xy 7.206919 -157.473249) (xy 7.254525 -157.502303)
			(xy 7.297393 -157.537978) (xy 7.33461 -157.579515) (xy 7.365383 -157.626028) (xy 7.375633 -157.647894)
			(xy 11.013948 -157.647894) (xy 11.014459 -157.62125) (xy 11.022984 -157.568649) (xy 11.039844 -157.518099)
			(xy 11.064602 -157.470913) (xy 11.096615 -157.428313) (xy 11.135053 -157.391407) (xy 11.156696 -157.37586)
			(xy 11.167989 -157.367504) (xy 11.185848 -157.34583) (xy 11.197132 -157.320114) (xy 11.20099 -157.292297)
			(xy 11.19713 -157.26448) (xy 11.185844 -157.238764) (xy 11.167984 -157.217092) (xy 11.156696 -157.208728)
			(xy 11.135107 -157.193114) (xy 11.096689 -157.156206) (xy 11.064685 -157.113615) (xy 11.039924 -157.066445)
			(xy 11.023047 -157.015914) (xy 11.014491 -156.963331) (xy 11.013948 -156.936694) (xy 11.014458 -156.910707)
			(xy 11.022588 -156.859372) (xy 11.038649 -156.809942) (xy 11.062245 -156.763632) (xy 11.092795 -156.721584)
			(xy 11.129546 -156.684833) (xy 11.171594 -156.654283) (xy 11.217904 -156.630687) (xy 11.267334 -156.614626)
			(xy 11.318669 -156.606496) (xy 11.370643 -156.606496) (xy 11.421978 -156.614626) (xy 11.471408 -156.630687)
			(xy 11.517718 -156.654283) (xy 11.559766 -156.684833) (xy 11.596517 -156.721584) (xy 11.627067 -156.763632)
			(xy 11.650663 -156.809942) (xy 11.666724 -156.859372) (xy 11.674854 -156.910707) (xy 11.675364 -156.936694)
			(xy 11.674839 -156.963337) (xy 11.666316 -157.015937) (xy 11.649459 -157.066487) (xy 11.624703 -157.113673)
			(xy 11.592693 -157.156273) (xy 11.554258 -157.193181) (xy 11.532616 -157.208728) (xy 11.521334 -157.217098)
			(xy 11.503473 -157.238768) (xy 11.492187 -157.264482) (xy 11.488327 -157.292297) (xy 11.492185 -157.320112)
			(xy 11.50347 -157.345826) (xy 11.521328 -157.367497) (xy 11.532616 -157.37586) (xy 11.554202 -157.391478)
			(xy 11.59262 -157.428386) (xy 11.624623 -157.470975) (xy 11.649384 -157.518145) (xy 11.666262 -157.568675)
			(xy 11.674821 -157.621257) (xy 11.675364 -157.647894) (xy 11.91387 -157.647894) (xy 11.914371 -157.62125)
			(xy 11.922897 -157.568648) (xy 11.939758 -157.518097) (xy 11.964518 -157.47091) (xy 11.996533 -157.428311)
			(xy 12.034973 -157.391406) (xy 12.056618 -157.37586) (xy 12.067909 -157.367503) (xy 12.085764 -157.345828)
			(xy 12.097046 -157.320112) (xy 12.100903 -157.292297) (xy 12.097044 -157.264481) (xy 12.08576 -157.238766)
			(xy 12.067904 -157.217092) (xy 12.056618 -157.208728) (xy 12.035012 -157.193137) (xy 11.996598 -157.156222)
			(xy 11.964599 -157.113625) (xy 11.939842 -157.066451) (xy 11.922968 -157.015917) (xy 11.914412 -156.963332)
			(xy 11.91387 -156.936694) (xy 11.91438 -156.910707) (xy 11.92251 -156.859372) (xy 11.938571 -156.809942)
			(xy 11.962167 -156.763632) (xy 11.992717 -156.721584) (xy 12.029468 -156.684833) (xy 12.071516 -156.654283)
			(xy 12.117826 -156.630687) (xy 12.167256 -156.614626) (xy 12.218591 -156.606496) (xy 12.270565 -156.606496)
			(xy 12.3219 -156.614626) (xy 12.37133 -156.630687) (xy 12.41764 -156.654283) (xy 12.459688 -156.684833)
			(xy 12.496439 -156.721584) (xy 12.526989 -156.763632) (xy 12.550585 -156.809942) (xy 12.566646 -156.859372)
			(xy 12.574776 -156.910707) (xy 12.575286 -156.936694) (xy 12.574752 -156.963337) (xy 12.56623 -157.015936)
			(xy 12.549373 -157.066485) (xy 12.52462 -157.113671) (xy 12.492611 -157.156271) (xy 12.454179 -157.19318)
			(xy 12.432538 -157.208728) (xy 12.421262 -157.217102) (xy 12.403416 -157.238776) (xy 12.392139 -157.264487)
			(xy 12.388282 -157.292297) (xy 12.392137 -157.320106) (xy 12.403412 -157.345818) (xy 12.421257 -157.367493)
			(xy 12.432538 -157.37586) (xy 12.454129 -157.391471) (xy 12.492545 -157.428381) (xy 12.524548 -157.470973)
			(xy 12.549308 -157.518144) (xy 12.566185 -157.568674) (xy 12.574743 -157.621257) (xy 12.575286 -157.647894)
			(xy 12.813792 -157.647894) (xy 12.814327 -157.621251) (xy 12.82285 -157.568653) (xy 12.839707 -157.518105)
			(xy 12.864461 -157.470918) (xy 12.896468 -157.428318) (xy 12.9349 -157.391409) (xy 12.95654 -157.37586)
			(xy 12.967829 -157.367502) (xy 12.98568 -157.345826) (xy 12.996959 -157.320111) (xy 13.000815 -157.292297)
			(xy 12.996957 -157.264483) (xy 12.985677 -157.238768) (xy 12.967824 -157.217094) (xy 12.95654 -157.208728)
			(xy 12.934939 -157.193131) (xy 12.896524 -157.156217) (xy 12.864523 -157.113623) (xy 12.839765 -157.066449)
			(xy 12.82289 -157.015916) (xy 12.814334 -156.963332) (xy 12.813792 -156.936694) (xy 12.814302 -156.910707)
			(xy 12.822432 -156.859372) (xy 12.838493 -156.809942) (xy 12.862089 -156.763632) (xy 12.892639 -156.721584)
			(xy 12.92939 -156.684833) (xy 12.971438 -156.654283) (xy 13.017748 -156.630687) (xy 13.067178 -156.614626)
			(xy 13.118513 -156.606496) (xy 13.170487 -156.606496) (xy 13.221822 -156.614626) (xy 13.271252 -156.630687)
			(xy 13.317562 -156.654283) (xy 13.35961 -156.684833) (xy 13.396361 -156.721584) (xy 13.426911 -156.763632)
			(xy 13.450507 -156.809942) (xy 13.466568 -156.859372) (xy 13.474698 -156.910707) (xy 13.475208 -156.936694)
			(xy 13.474664 -156.963336) (xy 13.466143 -157.015935) (xy 13.449288 -157.066482) (xy 13.424536 -157.113669)
			(xy 13.39253 -157.156269) (xy 13.3541 -157.193179) (xy 13.33246 -157.208728) (xy 13.321182 -157.217101)
			(xy 13.303332 -157.238773) (xy 13.292052 -157.264485) (xy 13.288195 -157.292297) (xy 13.29205 -157.320108)
			(xy 13.303328 -157.345821) (xy 13.321177 -157.367494) (xy 13.33246 -157.37586) (xy 13.354056 -157.391465)
			(xy 13.392471 -157.428377) (xy 13.424472 -157.47097) (xy 13.449231 -157.518142) (xy 13.466107 -157.568673)
			(xy 13.474665 -157.621257) (xy 13.475208 -157.647894) (xy 13.713968 -157.647894) (xy 13.71447 -157.62125)
			(xy 13.722996 -157.568648) (xy 13.739857 -157.518098) (xy 13.764617 -157.470911) (xy 13.796632 -157.428312)
			(xy 13.835071 -157.391406) (xy 13.856716 -157.37586) (xy 13.868008 -157.367503) (xy 13.885863 -157.345828)
			(xy 13.897145 -157.320112) (xy 13.901002 -157.292297) (xy 13.897143 -157.264481) (xy 13.885859 -157.238766)
			(xy 13.868002 -157.217092) (xy 13.856716 -157.208728) (xy 13.83511 -157.193138) (xy 13.796696 -157.156222)
			(xy 13.764697 -157.113626) (xy 13.73994 -157.066451) (xy 13.723066 -157.015917) (xy 13.71451 -156.963332)
			(xy 13.713968 -156.936694) (xy 13.714478 -156.910707) (xy 13.722608 -156.859372) (xy 13.738669 -156.809942)
			(xy 13.762265 -156.763632) (xy 13.792815 -156.721584) (xy 13.829566 -156.684833) (xy 13.871614 -156.654283)
			(xy 13.917924 -156.630687) (xy 13.967354 -156.614626) (xy 14.018689 -156.606496) (xy 14.070663 -156.606496)
			(xy 14.121998 -156.614626) (xy 14.171428 -156.630687) (xy 14.217738 -156.654283) (xy 14.259786 -156.684833)
			(xy 14.296537 -156.721584) (xy 14.327087 -156.763632) (xy 14.350683 -156.809942) (xy 14.366744 -156.859372)
			(xy 14.374874 -156.910707) (xy 14.375384 -156.936694) (xy 14.374851 -156.963337) (xy 14.366328 -157.015936)
			(xy 14.349472 -157.066485) (xy 14.324718 -157.113671) (xy 14.29271 -157.156271) (xy 14.254277 -157.19318)
			(xy 14.232636 -157.208728) (xy 14.221352 -157.217097) (xy 14.203488 -157.238766) (xy 14.192199 -157.26448)
			(xy 14.188338 -157.292297) (xy 14.192197 -157.320113) (xy 14.203484 -157.345828) (xy 14.221347 -157.367498)
			(xy 14.232636 -157.37586) (xy 14.254226 -157.391472) (xy 14.292643 -157.428382) (xy 14.324645 -157.470973)
			(xy 14.349405 -157.518144) (xy 14.366283 -157.568674) (xy 14.374841 -157.621257) (xy 14.375343 -157.645862)
			(xy 15.329408 -157.645862) (xy 15.329848 -157.619547) (xy 15.337088 -157.567417) (xy 15.351412 -157.516774)
			(xy 15.37255 -157.468575) (xy 15.400101 -157.423732) (xy 15.433544 -157.383094) (xy 15.452598 -157.364938)
			(xy 15.459984 -157.357404) (xy 15.468517 -157.338133) (xy 15.469108 -157.3276) (xy 15.469108 -157.252924)
			(xy 15.468577 -157.242375) (xy 15.460043 -157.223079) (xy 15.452598 -157.215586) (xy 15.433542 -157.197431)
			(xy 15.400085 -157.156801) (xy 15.372526 -157.111961) (xy 15.351388 -157.06376) (xy 15.337071 -157.013112)
			(xy 15.329846 -156.960978) (xy 15.329408 -156.934662) (xy 15.329894 -156.907411) (xy 15.33765 -156.853463)
			(xy 15.353005 -156.801168) (xy 15.375647 -156.751591) (xy 15.405113 -156.705741) (xy 15.440804 -156.66455)
			(xy 15.481995 -156.628859) (xy 15.527845 -156.599393) (xy 15.577422 -156.576751) (xy 15.629717 -156.561396)
			(xy 15.683665 -156.55364) (xy 15.738167 -156.55364) (xy 15.792115 -156.561396) (xy 15.84441 -156.576751)
			(xy 15.893987 -156.599393) (xy 15.939837 -156.628859) (xy 15.958582 -156.645101) (xy 17.31399 -156.645101)
			(xy 17.318305 -156.587829) (xy 17.331153 -156.531851) (xy 17.352244 -156.478429) (xy 17.381102 -156.428772)
			(xy 17.417075 -156.383999) (xy 17.437862 -156.364178) (xy 17.445269 -156.356661) (xy 17.453792 -156.337378)
			(xy 17.454372 -156.32684) (xy 17.454372 -156.252164) (xy 17.45383 -156.241616) (xy 17.445305 -156.22232)
			(xy 17.437862 -156.214826) (xy 17.418819 -156.196658) (xy 17.385362 -156.15603) (xy 17.357802 -156.111192)
			(xy 17.336662 -156.062994) (xy 17.322342 -156.012349) (xy 17.315113 -155.960217) (xy 17.314672 -155.933902)
			(xy 17.315158 -155.906651) (xy 17.322914 -155.852703) (xy 17.338269 -155.800408) (xy 17.360911 -155.750831)
			(xy 17.390377 -155.704981) (xy 17.426068 -155.66379) (xy 17.467259 -155.628099) (xy 17.513109 -155.598633)
			(xy 17.562686 -155.575991) (xy 17.614981 -155.560636) (xy 17.668929 -155.55288) (xy 17.723431 -155.55288)
			(xy 17.777379 -155.560636) (xy 17.829674 -155.575991) (xy 17.879251 -155.598633) (xy 17.925101 -155.628099)
			(xy 17.966292 -155.66379) (xy 18.001983 -155.704981) (xy 18.031449 -155.750831) (xy 18.054091 -155.800408)
			(xy 18.069446 -155.852703) (xy 18.077202 -155.906651) (xy 18.077688 -155.933902) (xy 18.077226 -155.960216)
			(xy 18.06999 -156.012345) (xy 18.055671 -156.062988) (xy 18.034537 -156.111187) (xy 18.00699 -156.15603)
			(xy 17.97355 -156.19667) (xy 17.954498 -156.214826) (xy 17.947083 -156.222336) (xy 17.938566 -156.241625)
			(xy 17.937988 -156.252164) (xy 17.937988 -156.32684) (xy 17.938539 -156.337387) (xy 17.947059 -156.356682)
			(xy 17.954498 -156.364178) (xy 17.975289 -156.383995) (xy 18.011266 -156.428768) (xy 18.040127 -156.478425)
			(xy 18.061221 -156.531848) (xy 18.07407 -156.587828) (xy 18.078386 -156.645101) (xy 18.07407 -156.702375)
			(xy 18.072934 -156.707322) (xy 20.379798 -156.707322) (xy 20.38411 -156.650054) (xy 20.396954 -156.594078)
			(xy 20.41804 -156.540659) (xy 20.446892 -156.491002) (xy 20.482858 -156.446229) (xy 20.503642 -156.426408)
			(xy 20.511034 -156.418878) (xy 20.519566 -156.399605) (xy 20.520152 -156.38907) (xy 20.520152 -156.314394)
			(xy 20.519654 -156.30384) (xy 20.511098 -156.284544) (xy 20.503642 -156.277056) (xy 20.484561 -156.258926)
			(xy 20.451108 -156.21829) (xy 20.423554 -156.173444) (xy 20.402421 -156.125238) (xy 20.388108 -156.074587)
			(xy 20.380888 -156.022449) (xy 20.380452 -155.996132) (xy 20.380938 -155.968881) (xy 20.388694 -155.914933)
			(xy 20.404049 -155.862638) (xy 20.426691 -155.813061) (xy 20.456157 -155.767211) (xy 20.491848 -155.72602)
			(xy 20.533039 -155.690329) (xy 20.578889 -155.660863) (xy 20.628466 -155.638221) (xy 20.680761 -155.622866)
			(xy 20.734709 -155.61511) (xy 20.789211 -155.61511) (xy 20.843159 -155.622866) (xy 20.895454 -155.638221)
			(xy 20.945031 -155.660863) (xy 20.990881 -155.690329) (xy 21.032072 -155.72602) (xy 21.067763 -155.767211)
			(xy 21.097229 -155.813061) (xy 21.119871 -155.862638) (xy 21.135226 -155.914933) (xy 21.142982 -155.968881)
			(xy 21.143468 -155.996132) (xy 21.143032 -156.022447) (xy 21.135792 -156.074577) (xy 21.121468 -156.125221)
			(xy 21.100329 -156.17342) (xy 21.072777 -156.218263) (xy 21.039333 -156.258901) (xy 21.020278 -156.277056)
			(xy 21.01289 -156.284589) (xy 21.004359 -156.303861) (xy 21.003768 -156.314394) (xy 21.003768 -156.38907)
			(xy 21.004309 -156.399618) (xy 21.012837 -156.418913) (xy 21.020278 -156.426408) (xy 21.0411 -156.446195)
			(xy 21.077078 -156.490971) (xy 21.10594 -156.540633) (xy 21.127033 -156.59406) (xy 21.139882 -156.650044)
			(xy 21.144195 -156.707322) (xy 21.139875 -156.764599) (xy 21.12702 -156.820582) (xy 21.105921 -156.874006)
			(xy 21.077054 -156.923665) (xy 21.04107 -156.968437) (xy 21.020278 -156.988256) (xy 21.01289 -156.995789)
			(xy 21.004359 -157.015061) (xy 21.003768 -157.025594) (xy 21.003768 -157.10027) (xy 21.004309 -157.110818)
			(xy 21.012837 -157.130113) (xy 21.020278 -157.137608) (xy 21.039326 -157.155771) (xy 21.072785 -157.196399)
			(xy 21.100345 -157.241237) (xy 21.121485 -157.289437) (xy 21.135804 -157.340083) (xy 21.143029 -157.392216)
			(xy 21.143468 -157.418532) (xy 21.142982 -157.445783) (xy 21.135226 -157.499731) (xy 21.119871 -157.552026)
			(xy 21.097229 -157.601603) (xy 21.067763 -157.647453) (xy 21.032072 -157.688644) (xy 20.990881 -157.724335)
			(xy 20.945031 -157.753801) (xy 20.895454 -157.776443) (xy 20.843159 -157.791798) (xy 20.789211 -157.799554)
			(xy 20.734709 -157.799554) (xy 20.680761 -157.791798) (xy 20.628466 -157.776443) (xy 20.578889 -157.753801)
			(xy 20.533039 -157.724335) (xy 20.491848 -157.688644) (xy 20.456157 -157.647453) (xy 20.426691 -157.601603)
			(xy 20.404049 -157.552026) (xy 20.388694 -157.499731) (xy 20.380938 -157.445783) (xy 20.380452 -157.418532)
			(xy 20.380857 -157.392216) (xy 20.388103 -157.340084) (xy 20.402433 -157.289439) (xy 20.423577 -157.24124)
			(xy 20.451135 -157.196398) (xy 20.484585 -157.155762) (xy 20.503642 -157.137608) (xy 20.511034 -157.130078)
			(xy 20.519566 -157.110805) (xy 20.520152 -157.10027) (xy 20.520152 -157.025594) (xy 20.519654 -157.01504)
			(xy 20.511098 -156.995744) (xy 20.503642 -156.988256) (xy 20.482888 -156.968403) (xy 20.446916 -156.923634)
			(xy 20.418059 -156.87398) (xy 20.396967 -156.820564) (xy 20.384116 -156.764589) (xy 20.379798 -156.707322)
			(xy 18.072934 -156.707322) (xy 18.06122 -156.758355) (xy 18.040126 -156.811777) (xy 18.011264 -156.861435)
			(xy 17.975287 -156.906207) (xy 17.954498 -156.926026) (xy 17.947083 -156.933536) (xy 17.938566 -156.952825)
			(xy 17.937988 -156.963364) (xy 17.937988 -157.03804) (xy 17.938539 -157.048587) (xy 17.947059 -157.067882)
			(xy 17.954498 -157.075378) (xy 17.973536 -157.093552) (xy 18.006994 -157.134177) (xy 18.034556 -157.179014)
			(xy 18.055697 -157.227211) (xy 18.070018 -157.277855) (xy 18.077247 -157.329987) (xy 18.077688 -157.356302)
			(xy 18.077202 -157.383553) (xy 18.069446 -157.437501) (xy 18.054091 -157.489796) (xy 18.031449 -157.539373)
			(xy 18.001983 -157.585223) (xy 17.966292 -157.626414) (xy 17.925101 -157.662105) (xy 17.879251 -157.691571)
			(xy 17.829674 -157.714213) (xy 17.777379 -157.729568) (xy 17.723431 -157.737324) (xy 17.668929 -157.737324)
			(xy 17.614981 -157.729568) (xy 17.562686 -157.714213) (xy 17.513109 -157.691571) (xy 17.467259 -157.662105)
			(xy 17.426068 -157.626414) (xy 17.390377 -157.585223) (xy 17.360911 -157.539373) (xy 17.338269 -157.489796)
			(xy 17.322914 -157.437501) (xy 17.315158 -157.383553) (xy 17.314672 -157.356302) (xy 17.31515 -157.329988)
			(xy 17.322384 -157.277861) (xy 17.336701 -157.227219) (xy 17.357832 -157.17902) (xy 17.385376 -157.134176)
			(xy 17.418812 -157.093535) (xy 17.437862 -157.075378) (xy 17.445269 -157.067861) (xy 17.453792 -157.048578)
			(xy 17.454372 -157.03804) (xy 17.454372 -156.963364) (xy 17.45383 -156.952816) (xy 17.445305 -156.93352)
			(xy 17.437862 -156.926026) (xy 17.417077 -156.906203) (xy 17.381104 -156.861431) (xy 17.352245 -156.811773)
			(xy 17.331154 -156.758352) (xy 17.318305 -156.702373) (xy 17.31399 -156.645101) (xy 15.958582 -156.645101)
			(xy 15.981028 -156.66455) (xy 16.016719 -156.705741) (xy 16.046185 -156.751591) (xy 16.068827 -156.801168)
			(xy 16.084182 -156.853463) (xy 16.091938 -156.907411) (xy 16.092424 -156.934662) (xy 16.09199 -156.960977)
			(xy 16.084747 -157.013107) (xy 16.070421 -157.06375) (xy 16.049282 -157.111948) (xy 16.021731 -157.156791)
			(xy 15.988288 -157.19743) (xy 15.969234 -157.215586) (xy 15.961841 -157.223115) (xy 15.953311 -157.242389)
			(xy 15.952724 -157.252924) (xy 15.952724 -157.3276) (xy 15.953233 -157.338152) (xy 15.961781 -157.357448)
			(xy 15.969234 -157.364938) (xy 15.988307 -157.383075) (xy 16.021762 -157.42371) (xy 16.049317 -157.468554)
			(xy 16.070453 -157.516758) (xy 16.084766 -157.567409) (xy 16.091987 -157.619545) (xy 16.092424 -157.645862)
			(xy 16.091938 -157.673113) (xy 16.084182 -157.727061) (xy 16.068827 -157.779356) (xy 16.046185 -157.828933)
			(xy 16.016719 -157.874783) (xy 15.981028 -157.915974) (xy 15.939837 -157.951665) (xy 15.893987 -157.981131)
			(xy 15.84441 -158.003773) (xy 15.792115 -158.019128) (xy 15.738167 -158.026884) (xy 15.683665 -158.026884)
			(xy 15.629717 -158.019128) (xy 15.577422 -158.003773) (xy 15.527845 -157.981131) (xy 15.481995 -157.951665)
			(xy 15.440804 -157.915974) (xy 15.405113 -157.874783) (xy 15.375647 -157.828933) (xy 15.353005 -157.779356)
			(xy 15.33765 -157.727061) (xy 15.329894 -157.673113) (xy 15.329408 -157.645862) (xy 14.375343 -157.645862)
			(xy 14.375384 -157.647894) (xy 14.374874 -157.673881) (xy 14.366744 -157.725216) (xy 14.350683 -157.774646)
			(xy 14.327087 -157.820956) (xy 14.296537 -157.863004) (xy 14.259786 -157.899755) (xy 14.217738 -157.930305)
			(xy 14.171428 -157.953901) (xy 14.121998 -157.969962) (xy 14.070663 -157.978092) (xy 14.018689 -157.978092)
			(xy 13.967354 -157.969962) (xy 13.917924 -157.953901) (xy 13.871614 -157.930305) (xy 13.829566 -157.899755)
			(xy 13.792815 -157.863004) (xy 13.762265 -157.820956) (xy 13.738669 -157.774646) (xy 13.722608 -157.725216)
			(xy 13.714478 -157.673881) (xy 13.713968 -157.647894) (xy 13.475208 -157.647894) (xy 13.474698 -157.673881)
			(xy 13.466568 -157.725216) (xy 13.450507 -157.774646) (xy 13.426911 -157.820956) (xy 13.396361 -157.863004)
			(xy 13.35961 -157.899755) (xy 13.317562 -157.930305) (xy 13.271252 -157.953901) (xy 13.221822 -157.969962)
			(xy 13.170487 -157.978092) (xy 13.118513 -157.978092) (xy 13.067178 -157.969962) (xy 13.017748 -157.953901)
			(xy 12.971438 -157.930305) (xy 12.92939 -157.899755) (xy 12.892639 -157.863004) (xy 12.862089 -157.820956)
			(xy 12.838493 -157.774646) (xy 12.822432 -157.725216) (xy 12.814302 -157.673881) (xy 12.813792 -157.647894)
			(xy 12.575286 -157.647894) (xy 12.574776 -157.673881) (xy 12.566646 -157.725216) (xy 12.550585 -157.774646)
			(xy 12.526989 -157.820956) (xy 12.496439 -157.863004) (xy 12.459688 -157.899755) (xy 12.41764 -157.930305)
			(xy 12.37133 -157.953901) (xy 12.3219 -157.969962) (xy 12.270565 -157.978092) (xy 12.218591 -157.978092)
			(xy 12.167256 -157.969962) (xy 12.117826 -157.953901) (xy 12.071516 -157.930305) (xy 12.029468 -157.899755)
			(xy 11.992717 -157.863004) (xy 11.962167 -157.820956) (xy 11.938571 -157.774646) (xy 11.92251 -157.725216)
			(xy 11.91438 -157.673881) (xy 11.91387 -157.647894) (xy 11.675364 -157.647894) (xy 11.674854 -157.673881)
			(xy 11.666724 -157.725216) (xy 11.650663 -157.774646) (xy 11.627067 -157.820956) (xy 11.596517 -157.863004)
			(xy 11.559766 -157.899755) (xy 11.517718 -157.930305) (xy 11.471408 -157.953901) (xy 11.421978 -157.969962)
			(xy 11.370643 -157.978092) (xy 11.318669 -157.978092) (xy 11.267334 -157.969962) (xy 11.217904 -157.953901)
			(xy 11.171594 -157.930305) (xy 11.129546 -157.899755) (xy 11.092795 -157.863004) (xy 11.062245 -157.820956)
			(xy 11.038649 -157.774646) (xy 11.022588 -157.725216) (xy 11.014458 -157.673881) (xy 11.013948 -157.647894)
			(xy 7.375633 -157.647894) (xy 7.389055 -157.676525) (xy 7.405123 -157.729932) (xy 7.413243 -157.785108)
			(xy 7.413752 -157.812994) (xy 7.413243 -157.84088) (xy 7.405123 -157.896056) (xy 7.389055 -157.949463)
			(xy 7.365383 -157.99996) (xy 7.33461 -158.046473) (xy 7.32214 -158.06039) (xy 8.839706 -158.06039)
			(xy 8.843777 -158.004768) (xy 8.855903 -157.950331) (xy 8.875826 -157.89824) (xy 8.903122 -157.849605)
			(xy 8.937208 -157.805462) (xy 8.977357 -157.766753) (xy 9.022715 -157.734302) (xy 9.072315 -157.708801)
			(xy 9.125099 -157.690794) (xy 9.179942 -157.680664) (xy 9.235676 -157.678627) (xy 9.291113 -157.684727)
			(xy 9.34507 -157.698833) (xy 9.396399 -157.720645) (xy 9.444005 -157.749699) (xy 9.486873 -157.785374)
			(xy 9.52409 -157.826911) (xy 9.554863 -157.873424) (xy 9.578535 -157.923921) (xy 9.594603 -157.977328)
			(xy 9.602723 -158.032504) (xy 9.603232 -158.06039) (xy 9.602723 -158.088276) (xy 9.594603 -158.143452)
			(xy 9.578535 -158.196859) (xy 9.554863 -158.247356) (xy 9.52409 -158.293869) (xy 9.486873 -158.335406)
			(xy 9.444005 -158.371081) (xy 9.396399 -158.400135) (xy 9.34507 -158.421947) (xy 9.291113 -158.436053)
			(xy 9.235676 -158.442153) (xy 9.179942 -158.440116) (xy 9.125099 -158.429986) (xy 9.072315 -158.411979)
			(xy 9.022715 -158.386478) (xy 8.977357 -158.354027) (xy 8.937208 -158.315318) (xy 8.903122 -158.271175)
			(xy 8.875826 -158.22254) (xy 8.855903 -158.170449) (xy 8.843777 -158.116012) (xy 8.839706 -158.06039)
			(xy 7.32214 -158.06039) (xy 7.297393 -158.08801) (xy 7.254525 -158.123685) (xy 7.206919 -158.152739)
			(xy 7.15559 -158.174551) (xy 7.101633 -158.188657) (xy 7.046196 -158.194757) (xy 6.990462 -158.19272)
			(xy 6.935619 -158.18259) (xy 6.882835 -158.164583) (xy 6.833235 -158.139082) (xy 6.787877 -158.106631)
			(xy 6.747728 -158.067922) (xy 6.713642 -158.023779) (xy 6.686346 -157.975144) (xy 6.666423 -157.923053)
			(xy 6.654297 -157.868616) (xy 6.650226 -157.812994) (xy 6.217412 -157.812994) (xy 6.217412 -158.828994)
			(xy 6.650226 -158.828994) (xy 6.654297 -158.773372) (xy 6.666423 -158.718935) (xy 6.686346 -158.666844)
			(xy 6.713642 -158.618209) (xy 6.747728 -158.574066) (xy 6.787877 -158.535357) (xy 6.833235 -158.502906)
			(xy 6.882835 -158.477405) (xy 6.935619 -158.459398) (xy 6.990462 -158.449268) (xy 7.046196 -158.447231)
			(xy 7.101633 -158.453331) (xy 7.15559 -158.467437) (xy 7.206919 -158.489249) (xy 7.254525 -158.518303)
			(xy 7.297393 -158.553978) (xy 7.33461 -158.595515) (xy 7.365383 -158.642028) (xy 7.389055 -158.692525)
			(xy 7.405123 -158.745932) (xy 7.406208 -158.753302) (xy 16.516602 -158.753302) (xy 16.520673 -158.69768)
			(xy 16.532799 -158.643243) (xy 16.552722 -158.591152) (xy 16.580018 -158.542517) (xy 16.614104 -158.498374)
			(xy 16.654253 -158.459665) (xy 16.699611 -158.427214) (xy 16.749211 -158.401713) (xy 16.801995 -158.383706)
			(xy 16.856838 -158.373576) (xy 16.912572 -158.371539) (xy 16.968009 -158.377639) (xy 17.021966 -158.391745)
			(xy 17.073295 -158.413557) (xy 17.120901 -158.442611) (xy 17.163769 -158.478286) (xy 17.200986 -158.519823)
			(xy 17.231759 -158.566336) (xy 17.255431 -158.616833) (xy 17.271499 -158.67024) (xy 17.279619 -158.725416)
			(xy 17.280128 -158.753302) (xy 17.279619 -158.781188) (xy 17.271499 -158.836364) (xy 17.255431 -158.889771)
			(xy 17.231759 -158.940268) (xy 17.200986 -158.986781) (xy 17.163769 -159.028318) (xy 17.120901 -159.063993)
			(xy 17.073295 -159.093047) (xy 17.021966 -159.114859) (xy 16.968009 -159.128965) (xy 16.912572 -159.135065)
			(xy 16.856838 -159.133028) (xy 16.801995 -159.122898) (xy 16.749211 -159.104891) (xy 16.699611 -159.07939)
			(xy 16.654253 -159.046939) (xy 16.614104 -159.00823) (xy 16.580018 -158.964087) (xy 16.552722 -158.915452)
			(xy 16.532799 -158.863361) (xy 16.520673 -158.808924) (xy 16.516602 -158.753302) (xy 7.406208 -158.753302)
			(xy 7.413243 -158.801108) (xy 7.413752 -158.828994) (xy 7.413243 -158.85688) (xy 7.405123 -158.912056)
			(xy 7.389055 -158.965463) (xy 7.365383 -159.01596) (xy 7.33461 -159.062473) (xy 7.297393 -159.10401)
			(xy 7.254525 -159.139685) (xy 7.206919 -159.168739) (xy 7.15559 -159.190551) (xy 7.101633 -159.204657)
			(xy 7.046196 -159.210757) (xy 6.990462 -159.20872) (xy 6.935619 -159.19859) (xy 6.882835 -159.180583)
			(xy 6.833235 -159.155082) (xy 6.787877 -159.122631) (xy 6.747728 -159.083922) (xy 6.713642 -159.039779)
			(xy 6.686346 -158.991144) (xy 6.666423 -158.939053) (xy 6.654297 -158.884616) (xy 6.650226 -158.828994)
			(xy 6.217412 -158.828994) (xy 6.217412 -159.439102) (xy 8.908032 -159.439102) (xy 8.912103 -159.38348)
			(xy 8.924229 -159.329043) (xy 8.944152 -159.276952) (xy 8.971448 -159.228317) (xy 9.005534 -159.184174)
			(xy 9.045683 -159.145465) (xy 9.091041 -159.113014) (xy 9.140641 -159.087513) (xy 9.193425 -159.069506)
			(xy 9.248268 -159.059376) (xy 9.304002 -159.057339) (xy 9.359439 -159.063439) (xy 9.413396 -159.077545)
			(xy 9.464725 -159.099357) (xy 9.512331 -159.128411) (xy 9.555199 -159.164086) (xy 9.592416 -159.205623)
			(xy 9.623189 -159.252136) (xy 9.646861 -159.302633) (xy 9.662929 -159.35604) (xy 9.671049 -159.411216)
			(xy 9.671558 -159.439102) (xy 9.671049 -159.466988) (xy 9.662929 -159.522164) (xy 9.660026 -159.531812)
			(xy 12.11275 -159.531812) (xy 12.116821 -159.47619) (xy 12.128947 -159.421753) (xy 12.14887 -159.369662)
			(xy 12.176166 -159.321027) (xy 12.210252 -159.276884) (xy 12.250401 -159.238175) (xy 12.295759 -159.205724)
			(xy 12.345359 -159.180223) (xy 12.398143 -159.162216) (xy 12.452986 -159.152086) (xy 12.50872 -159.150049)
			(xy 12.564157 -159.156149) (xy 12.618114 -159.170255) (xy 12.669443 -159.192067) (xy 12.717049 -159.221121)
			(xy 12.759917 -159.256796) (xy 12.797134 -159.298333) (xy 12.827907 -159.344846) (xy 12.851579 -159.395343)
			(xy 12.867647 -159.44875) (xy 12.873516 -159.488632) (xy 14.395956 -159.488632) (xy 14.400027 -159.43301)
			(xy 14.412153 -159.378573) (xy 14.432076 -159.326482) (xy 14.459372 -159.277847) (xy 14.493458 -159.233704)
			(xy 14.533607 -159.194995) (xy 14.578965 -159.162544) (xy 14.628565 -159.137043) (xy 14.681349 -159.119036)
			(xy 14.736192 -159.108906) (xy 14.791926 -159.106869) (xy 14.847363 -159.112969) (xy 14.90132 -159.127075)
			(xy 14.952649 -159.148887) (xy 15.000255 -159.177941) (xy 15.043123 -159.213616) (xy 15.08034 -159.255153)
			(xy 15.111113 -159.301666) (xy 15.134785 -159.352163) (xy 15.150853 -159.40557) (xy 15.158973 -159.460746)
			(xy 15.159482 -159.488632) (xy 15.158973 -159.516518) (xy 15.150853 -159.571694) (xy 15.134785 -159.625101)
			(xy 15.111113 -159.675598) (xy 15.08034 -159.722111) (xy 15.043123 -159.763648) (xy 15.000255 -159.799323)
			(xy 14.952649 -159.828377) (xy 14.90132 -159.850189) (xy 14.847363 -159.864295) (xy 14.791926 -159.870395)
			(xy 14.736192 -159.868358) (xy 14.681349 -159.858228) (xy 14.628565 -159.840221) (xy 14.578965 -159.81472)
			(xy 14.533607 -159.782269) (xy 14.493458 -159.74356) (xy 14.459372 -159.699417) (xy 14.432076 -159.650782)
			(xy 14.412153 -159.598691) (xy 14.400027 -159.544254) (xy 14.395956 -159.488632) (xy 12.873516 -159.488632)
			(xy 12.875767 -159.503926) (xy 12.876276 -159.531812) (xy 12.875767 -159.559698) (xy 12.867647 -159.614874)
			(xy 12.851579 -159.668281) (xy 12.827907 -159.718778) (xy 12.797134 -159.765291) (xy 12.759917 -159.806828)
			(xy 12.717049 -159.842503) (xy 12.669443 -159.871557) (xy 12.618114 -159.893369) (xy 12.564157 -159.907475)
			(xy 12.50872 -159.913575) (xy 12.452986 -159.911538) (xy 12.398143 -159.901408) (xy 12.345359 -159.883401)
			(xy 12.295759 -159.8579) (xy 12.250401 -159.825449) (xy 12.210252 -159.78674) (xy 12.176166 -159.742597)
			(xy 12.14887 -159.693962) (xy 12.128947 -159.641871) (xy 12.116821 -159.587434) (xy 12.11275 -159.531812)
			(xy 9.660026 -159.531812) (xy 9.646861 -159.575571) (xy 9.623189 -159.626068) (xy 9.592416 -159.672581)
			(xy 9.555199 -159.714118) (xy 9.512331 -159.749793) (xy 9.464725 -159.778847) (xy 9.413396 -159.800659)
			(xy 9.359439 -159.814765) (xy 9.304002 -159.820865) (xy 9.248268 -159.818828) (xy 9.193425 -159.808698)
			(xy 9.140641 -159.790691) (xy 9.091041 -159.76519) (xy 9.045683 -159.732739) (xy 9.005534 -159.69403)
			(xy 8.971448 -159.649887) (xy 8.944152 -159.601252) (xy 8.924229 -159.549161) (xy 8.912103 -159.494724)
			(xy 8.908032 -159.439102) (xy 6.217412 -159.439102) (xy 6.217412 -159.844994) (xy 6.650226 -159.844994)
			(xy 6.654297 -159.789372) (xy 6.666423 -159.734935) (xy 6.686346 -159.682844) (xy 6.713642 -159.634209)
			(xy 6.747728 -159.590066) (xy 6.787877 -159.551357) (xy 6.833235 -159.518906) (xy 6.882835 -159.493405)
			(xy 6.935619 -159.475398) (xy 6.990462 -159.465268) (xy 7.046196 -159.463231) (xy 7.101633 -159.469331)
			(xy 7.15559 -159.483437) (xy 7.206919 -159.505249) (xy 7.254525 -159.534303) (xy 7.297393 -159.569978)
			(xy 7.33461 -159.611515) (xy 7.365383 -159.658028) (xy 7.389055 -159.708525) (xy 7.405123 -159.761932)
			(xy 7.413243 -159.817108) (xy 7.413752 -159.844994) (xy 7.413243 -159.87288) (xy 7.405123 -159.928056)
			(xy 7.389055 -159.981463) (xy 7.365383 -160.03196) (xy 7.33461 -160.078473) (xy 7.297393 -160.12001)
			(xy 7.254525 -160.155685) (xy 7.206919 -160.184739) (xy 7.15559 -160.206551) (xy 7.101633 -160.220657)
			(xy 7.046196 -160.226757) (xy 6.990462 -160.22472) (xy 6.935619 -160.21459) (xy 6.882835 -160.196583)
			(xy 6.833235 -160.171082) (xy 6.787877 -160.138631) (xy 6.747728 -160.099922) (xy 6.713642 -160.055779)
			(xy 6.686346 -160.007144) (xy 6.666423 -159.955053) (xy 6.654297 -159.900616) (xy 6.650226 -159.844994)
			(xy 6.217412 -159.844994) (xy 6.217412 -160.965896) (xy 8.93775 -160.965896) (xy 8.941821 -160.910274)
			(xy 8.953947 -160.855837) (xy 8.97387 -160.803746) (xy 9.001166 -160.755111) (xy 9.035252 -160.710968)
			(xy 9.075401 -160.672259) (xy 9.120759 -160.639808) (xy 9.170359 -160.614307) (xy 9.223143 -160.5963)
			(xy 9.277986 -160.58617) (xy 9.33372 -160.584133) (xy 9.389157 -160.590233) (xy 9.443114 -160.604339)
			(xy 9.494443 -160.626151) (xy 9.542049 -160.655205) (xy 9.584917 -160.69088) (xy 9.622134 -160.732417)
			(xy 9.652907 -160.77893) (xy 9.676579 -160.829427) (xy 9.692647 -160.882834) (xy 9.700767 -160.93801)
			(xy 9.701239 -160.963864) (xy 10.32967 -160.963864) (xy 10.333741 -160.908242) (xy 10.345867 -160.853805)
			(xy 10.36579 -160.801714) (xy 10.393086 -160.753079) (xy 10.427172 -160.708936) (xy 10.467321 -160.670227)
			(xy 10.512679 -160.637776) (xy 10.562279 -160.612275) (xy 10.615063 -160.594268) (xy 10.669906 -160.584138)
			(xy 10.72564 -160.582101) (xy 10.781077 -160.588201) (xy 10.835034 -160.602307) (xy 10.886363 -160.624119)
			(xy 10.933969 -160.653173) (xy 10.976837 -160.688848) (xy 11.014054 -160.730385) (xy 11.044827 -160.776898)
			(xy 11.068499 -160.827395) (xy 11.084567 -160.880802) (xy 11.092687 -160.935978) (xy 11.093196 -160.963864)
			(xy 11.093103 -160.968944) (xy 11.601448 -160.968944) (xy 11.605519 -160.913322) (xy 11.617645 -160.858885)
			(xy 11.637568 -160.806794) (xy 11.664864 -160.758159) (xy 11.69895 -160.714016) (xy 11.739099 -160.675307)
			(xy 11.784457 -160.642856) (xy 11.834057 -160.617355) (xy 11.886841 -160.599348) (xy 11.941684 -160.589218)
			(xy 11.997418 -160.587181) (xy 12.052855 -160.593281) (xy 12.106812 -160.607387) (xy 12.158141 -160.629199)
			(xy 12.205747 -160.658253) (xy 12.248615 -160.693928) (xy 12.285832 -160.735465) (xy 12.316605 -160.781978)
			(xy 12.340277 -160.832475) (xy 12.356345 -160.885882) (xy 12.358738 -160.902142) (xy 13.38275 -160.902142)
			(xy 13.386821 -160.84652) (xy 13.398947 -160.792083) (xy 13.41887 -160.739992) (xy 13.446166 -160.691357)
			(xy 13.480252 -160.647214) (xy 13.520401 -160.608505) (xy 13.565759 -160.576054) (xy 13.615359 -160.550553)
			(xy 13.668143 -160.532546) (xy 13.722986 -160.522416) (xy 13.77872 -160.520379) (xy 13.834157 -160.526479)
			(xy 13.888114 -160.540585) (xy 13.939443 -160.562397) (xy 13.987049 -160.591451) (xy 14.029917 -160.627126)
			(xy 14.067134 -160.668663) (xy 14.097907 -160.715176) (xy 14.121579 -160.765673) (xy 14.137647 -160.81908)
			(xy 14.145767 -160.874256) (xy 14.146276 -160.902142) (xy 14.145767 -160.930028) (xy 14.137647 -160.985204)
			(xy 14.121579 -161.038611) (xy 14.097907 -161.089108) (xy 14.067134 -161.135621) (xy 14.029917 -161.177158)
			(xy 13.987049 -161.212833) (xy 13.939443 -161.241887) (xy 13.888114 -161.263699) (xy 13.834157 -161.277805)
			(xy 13.77872 -161.283905) (xy 13.722986 -161.281868) (xy 13.668143 -161.271738) (xy 13.615359 -161.253731)
			(xy 13.565759 -161.22823) (xy 13.520401 -161.195779) (xy 13.480252 -161.15707) (xy 13.446166 -161.112927)
			(xy 13.41887 -161.064292) (xy 13.398947 -161.012201) (xy 13.386821 -160.957764) (xy 13.38275 -160.902142)
			(xy 12.358738 -160.902142) (xy 12.364465 -160.941058) (xy 12.364974 -160.968944) (xy 12.364465 -160.99683)
			(xy 12.356345 -161.052006) (xy 12.340277 -161.105413) (xy 12.316605 -161.15591) (xy 12.285832 -161.202423)
			(xy 12.248615 -161.24396) (xy 12.205747 -161.279635) (xy 12.158141 -161.308689) (xy 12.106812 -161.330501)
			(xy 12.052855 -161.344607) (xy 11.997418 -161.350707) (xy 11.941684 -161.34867) (xy 11.886841 -161.33854)
			(xy 11.834057 -161.320533) (xy 11.784457 -161.295032) (xy 11.739099 -161.262581) (xy 11.69895 -161.223872)
			(xy 11.664864 -161.179729) (xy 11.637568 -161.131094) (xy 11.617645 -161.079003) (xy 11.605519 -161.024566)
			(xy 11.601448 -160.968944) (xy 11.093103 -160.968944) (xy 11.092687 -160.99175) (xy 11.084567 -161.046926)
			(xy 11.068499 -161.100333) (xy 11.044827 -161.15083) (xy 11.014054 -161.197343) (xy 10.976837 -161.23888)
			(xy 10.933969 -161.274555) (xy 10.886363 -161.303609) (xy 10.835034 -161.325421) (xy 10.781077 -161.339527)
			(xy 10.72564 -161.345627) (xy 10.669906 -161.34359) (xy 10.615063 -161.33346) (xy 10.562279 -161.315453)
			(xy 10.512679 -161.289952) (xy 10.467321 -161.257501) (xy 10.427172 -161.218792) (xy 10.393086 -161.174649)
			(xy 10.36579 -161.126014) (xy 10.345867 -161.073923) (xy 10.333741 -161.019486) (xy 10.32967 -160.963864)
			(xy 9.701239 -160.963864) (xy 9.701276 -160.965896) (xy 9.700767 -160.993782) (xy 9.692647 -161.048958)
			(xy 9.676579 -161.102365) (xy 9.652907 -161.152862) (xy 9.622134 -161.199375) (xy 9.584917 -161.240912)
			(xy 9.542049 -161.276587) (xy 9.494443 -161.305641) (xy 9.443114 -161.327453) (xy 9.389157 -161.341559)
			(xy 9.33372 -161.347659) (xy 9.277986 -161.345622) (xy 9.223143 -161.335492) (xy 9.170359 -161.317485)
			(xy 9.120759 -161.291984) (xy 9.075401 -161.259533) (xy 9.035252 -161.220824) (xy 9.001166 -161.176681)
			(xy 8.97387 -161.128046) (xy 8.953947 -161.075955) (xy 8.941821 -161.021518) (xy 8.93775 -160.965896)
			(xy 6.217412 -160.965896) (xy 6.217412 -163.114736) (xy 16.04975 -163.114736) (xy 16.053821 -163.059114)
			(xy 16.065947 -163.004677) (xy 16.08587 -162.952586) (xy 16.113166 -162.903951) (xy 16.147252 -162.859808)
			(xy 16.187401 -162.821099) (xy 16.232759 -162.788648) (xy 16.282359 -162.763147) (xy 16.335143 -162.74514)
			(xy 16.389986 -162.73501) (xy 16.44572 -162.732973) (xy 16.501157 -162.739073) (xy 16.555114 -162.753179)
			(xy 16.606443 -162.774991) (xy 16.654049 -162.804045) (xy 16.696917 -162.83972) (xy 16.734134 -162.881257)
			(xy 16.764907 -162.92777) (xy 16.788579 -162.978267) (xy 16.804647 -163.031674) (xy 16.812767 -163.08685)
			(xy 16.813276 -163.114736) (xy 16.812767 -163.142622) (xy 16.804647 -163.197798) (xy 16.788579 -163.251205)
			(xy 16.764907 -163.301702) (xy 16.734134 -163.348215) (xy 16.696917 -163.389752) (xy 16.654049 -163.425427)
			(xy 16.606443 -163.454481) (xy 16.555114 -163.476293) (xy 16.501157 -163.490399) (xy 16.44572 -163.496499)
			(xy 16.389986 -163.494462) (xy 16.335143 -163.484332) (xy 16.282359 -163.466325) (xy 16.232759 -163.440824)
			(xy 16.187401 -163.408373) (xy 16.147252 -163.369664) (xy 16.113166 -163.325521) (xy 16.08587 -163.276886)
			(xy 16.065947 -163.224795) (xy 16.053821 -163.170358) (xy 16.04975 -163.114736) (xy 6.217412 -163.114736)
			(xy 6.217412 -167.667178) (xy 18.392138 -167.667178) (xy 18.396209 -167.611556) (xy 18.408335 -167.557119)
			(xy 18.428258 -167.505028) (xy 18.455554 -167.456393) (xy 18.48964 -167.41225) (xy 18.529789 -167.373541)
			(xy 18.575147 -167.34109) (xy 18.624747 -167.315589) (xy 18.677531 -167.297582) (xy 18.732374 -167.287452)
			(xy 18.788108 -167.285415) (xy 18.843545 -167.291515) (xy 18.897502 -167.305621) (xy 18.948831 -167.327433)
			(xy 18.996437 -167.356487) (xy 19.039305 -167.392162) (xy 19.076522 -167.433699) (xy 19.107295 -167.480212)
			(xy 19.130967 -167.530709) (xy 19.147035 -167.584116) (xy 19.149914 -167.603678) (xy 21.168612 -167.603678)
			(xy 21.172683 -167.548056) (xy 21.184809 -167.493619) (xy 21.204732 -167.441528) (xy 21.232028 -167.392893)
			(xy 21.266114 -167.34875) (xy 21.306263 -167.310041) (xy 21.351621 -167.27759) (xy 21.401221 -167.252089)
			(xy 21.454005 -167.234082) (xy 21.508848 -167.223952) (xy 21.564582 -167.221915) (xy 21.620019 -167.228015)
			(xy 21.673976 -167.242121) (xy 21.725305 -167.263933) (xy 21.772911 -167.292987) (xy 21.815779 -167.328662)
			(xy 21.852996 -167.370199) (xy 21.883769 -167.416712) (xy 21.907441 -167.467209) (xy 21.923509 -167.520616)
			(xy 21.931629 -167.575792) (xy 21.932138 -167.603678) (xy 21.931629 -167.631564) (xy 21.923509 -167.68674)
			(xy 21.907441 -167.740147) (xy 21.883769 -167.790644) (xy 21.852996 -167.837157) (xy 21.815779 -167.878694)
			(xy 21.772911 -167.914369) (xy 21.725305 -167.943423) (xy 21.673976 -167.965235) (xy 21.620019 -167.979341)
			(xy 21.564582 -167.985441) (xy 21.508848 -167.983404) (xy 21.454005 -167.973274) (xy 21.401221 -167.955267)
			(xy 21.351621 -167.929766) (xy 21.306263 -167.897315) (xy 21.266114 -167.858606) (xy 21.232028 -167.814463)
			(xy 21.204732 -167.765828) (xy 21.184809 -167.713737) (xy 21.172683 -167.6593) (xy 21.168612 -167.603678)
			(xy 19.149914 -167.603678) (xy 19.155155 -167.639292) (xy 19.155664 -167.667178) (xy 19.155155 -167.695064)
			(xy 19.147035 -167.75024) (xy 19.130967 -167.803647) (xy 19.107295 -167.854144) (xy 19.076522 -167.900657)
			(xy 19.039305 -167.942194) (xy 18.996437 -167.977869) (xy 18.948831 -168.006923) (xy 18.897502 -168.028735)
			(xy 18.843545 -168.042841) (xy 18.788108 -168.048941) (xy 18.732374 -168.046904) (xy 18.677531 -168.036774)
			(xy 18.624747 -168.018767) (xy 18.575147 -167.993266) (xy 18.529789 -167.960815) (xy 18.48964 -167.922106)
			(xy 18.455554 -167.877963) (xy 18.428258 -167.829328) (xy 18.408335 -167.777237) (xy 18.396209 -167.7228)
			(xy 18.392138 -167.667178) (xy 6.217412 -167.667178) (xy 6.217412 -168.417063) (xy 8.583373 -168.417063)
			(xy 8.583373 -168.362557) (xy 8.59113 -168.308606) (xy 8.606487 -168.256307) (xy 8.629129 -168.206727)
			(xy 8.658598 -168.160873) (xy 8.694292 -168.11968) (xy 8.735485 -168.083987) (xy 8.781339 -168.054518)
			(xy 8.830919 -168.031876) (xy 8.883217 -168.01652) (xy 8.937169 -168.008763) (xy 8.964422 -168.0083)
			(xy 8.991897 -168.008773) (xy 9.046277 -168.016668) (xy 9.09896 -168.032292) (xy 9.148852 -168.055319)
			(xy 9.19492 -168.085273) (xy 9.215882 -168.103042) (xy 9.223155 -168.108845) (xy 9.240617 -168.115223)
			(xy 9.249918 -168.115488) (xy 9.32815 -168.114218) (xy 9.345422 -168.107106) (xy 9.35228 -168.100756)
			(xy 9.373594 -168.08147) (xy 9.420959 -168.048905) (xy 9.472674 -168.023815) (xy 9.527568 -168.006768)
			(xy 9.584398 -167.99815) (xy 9.613138 -167.997632) (xy 9.640391 -167.998095) (xy 9.694342 -168.005852)
			(xy 9.74664 -168.021208) (xy 9.796221 -168.04385) (xy 9.842074 -168.073318) (xy 9.883267 -168.109012)
			(xy 9.918961 -168.150204) (xy 9.948429 -168.196058) (xy 9.971072 -168.245638) (xy 9.986428 -168.297936)
			(xy 9.994185 -168.351887) (xy 9.994185 -168.406393) (xy 9.986428 -168.460344) (xy 9.971072 -168.512642)
			(xy 9.948429 -168.562222) (xy 9.918961 -168.608076) (xy 9.883267 -168.649268) (xy 9.842074 -168.684962)
			(xy 9.796221 -168.71443) (xy 9.74664 -168.737072) (xy 9.694342 -168.752428) (xy 9.640391 -168.760185)
			(xy 9.613138 -168.760648) (xy 9.585664 -168.760152) (xy 9.531284 -168.752264) (xy 9.478601 -168.736647)
			(xy 9.428708 -168.713624) (xy 9.38264 -168.683673) (xy 9.361678 -168.665906) (xy 9.354383 -168.660134)
			(xy 9.336938 -168.653736) (xy 9.327642 -168.65346) (xy 9.24941 -168.65473) (xy 9.232138 -168.661842)
			(xy 9.22528 -168.668192) (xy 9.203948 -168.687457) (xy 9.156587 -168.720023) (xy 9.104877 -168.745116)
			(xy 9.049987 -168.762168) (xy 8.993161 -168.770793) (xy 8.964422 -168.771316) (xy 8.937169 -168.770857)
			(xy 8.883217 -168.7631) (xy 8.830919 -168.747744) (xy 8.781339 -168.725102) (xy 8.735485 -168.695633)
			(xy 8.694292 -168.65994) (xy 8.658598 -168.618747) (xy 8.629129 -168.572893) (xy 8.606487 -168.523313)
			(xy 8.59113 -168.471014) (xy 8.583373 -168.417063) (xy 6.217412 -168.417063) (xy 6.217412 -169.517314)
			(xy 19.694904 -169.517314) (xy 19.698975 -169.461692) (xy 19.711101 -169.407255) (xy 19.731024 -169.355164)
			(xy 19.75832 -169.306529) (xy 19.792406 -169.262386) (xy 19.832555 -169.223677) (xy 19.877913 -169.191226)
			(xy 19.927513 -169.165725) (xy 19.980297 -169.147718) (xy 20.03514 -169.137588) (xy 20.090874 -169.135551)
			(xy 20.146311 -169.141651) (xy 20.200268 -169.155757) (xy 20.251597 -169.177569) (xy 20.299203 -169.206623)
			(xy 20.342071 -169.242298) (xy 20.379288 -169.283835) (xy 20.410061 -169.330348) (xy 20.433733 -169.380845)
			(xy 20.449801 -169.434252) (xy 20.457921 -169.489428) (xy 20.45843 -169.517314) (xy 20.457921 -169.5452)
			(xy 20.449801 -169.600376) (xy 20.433733 -169.653783) (xy 20.410061 -169.70428) (xy 20.379288 -169.750793)
			(xy 20.342071 -169.79233) (xy 20.299203 -169.828005) (xy 20.251597 -169.857059) (xy 20.200268 -169.878871)
			(xy 20.146311 -169.892977) (xy 20.090874 -169.899077) (xy 20.03514 -169.89704) (xy 19.980297 -169.88691)
			(xy 19.927513 -169.868903) (xy 19.877913 -169.843402) (xy 19.832555 -169.810951) (xy 19.792406 -169.772242)
			(xy 19.75832 -169.728099) (xy 19.731024 -169.679464) (xy 19.711101 -169.627373) (xy 19.698975 -169.572936)
			(xy 19.694904 -169.517314) (xy 6.217412 -169.517314) (xy 6.217412 -170.590281) (xy 8.57248 -170.590281)
			(xy 8.57248 -170.535779) (xy 8.580236 -170.481831) (xy 8.595591 -170.429537) (xy 8.618232 -170.37996)
			(xy 8.647698 -170.33411) (xy 8.68339 -170.29292) (xy 8.72458 -170.257228) (xy 8.77043 -170.227762)
			(xy 8.820007 -170.205121) (xy 8.872301 -170.189766) (xy 8.926249 -170.18201) (xy 8.9535 -170.181524)
			(xy 8.981589 -170.182012) (xy 9.037157 -170.190259) (xy 9.090913 -170.206574) (xy 9.141691 -170.230605)
			(xy 9.188391 -170.26183) (xy 9.209532 -170.28033) (xy 9.209786 -170.280584) (xy 9.216994 -170.286556)
			(xy 9.234468 -170.293221) (xy 9.243822 -170.293538) (xy 9.311894 -170.293538) (xy 9.32123 -170.293116)
			(xy 9.338682 -170.286482) (xy 9.34593 -170.280584) (xy 9.346184 -170.28033) (xy 9.367346 -170.26186)
			(xy 9.414058 -170.230668) (xy 9.464833 -170.206652) (xy 9.518577 -170.190328) (xy 9.574132 -170.182049)
			(xy 9.602216 -170.181524) (xy 9.629469 -170.181983) (xy 9.683421 -170.18974) (xy 9.735719 -170.205095)
			(xy 9.7853 -170.227738) (xy 9.831154 -170.257206) (xy 9.872348 -170.2929) (xy 9.908042 -170.334093)
			(xy 9.91985 -170.352466) (xy 20.610574 -170.352466) (xy 20.614645 -170.296844) (xy 20.626771 -170.242407)
			(xy 20.646694 -170.190316) (xy 20.67399 -170.141681) (xy 20.708076 -170.097538) (xy 20.748225 -170.058829)
			(xy 20.793583 -170.026378) (xy 20.843183 -170.000877) (xy 20.895967 -169.98287) (xy 20.95081 -169.97274)
			(xy 21.006544 -169.970703) (xy 21.061981 -169.976803) (xy 21.115938 -169.990909) (xy 21.167267 -170.012721)
			(xy 21.214873 -170.041775) (xy 21.257741 -170.07745) (xy 21.294958 -170.118987) (xy 21.325731 -170.1655)
			(xy 21.349403 -170.215997) (xy 21.365471 -170.269404) (xy 21.373591 -170.32458) (xy 21.3741 -170.352466)
			(xy 21.373591 -170.380352) (xy 21.365471 -170.435528) (xy 21.349403 -170.488935) (xy 21.325731 -170.539432)
			(xy 21.294958 -170.585945) (xy 21.257741 -170.627482) (xy 21.214873 -170.663157) (xy 21.167267 -170.692211)
			(xy 21.115938 -170.714023) (xy 21.061981 -170.728129) (xy 21.006544 -170.734229) (xy 20.95081 -170.732192)
			(xy 20.895967 -170.722062) (xy 20.843183 -170.704055) (xy 20.793583 -170.678554) (xy 20.748225 -170.646103)
			(xy 20.708076 -170.607394) (xy 20.67399 -170.563251) (xy 20.646694 -170.514616) (xy 20.626771 -170.462525)
			(xy 20.614645 -170.408088) (xy 20.610574 -170.352466) (xy 9.91985 -170.352466) (xy 9.93751 -170.379946)
			(xy 9.960153 -170.429527) (xy 9.97551 -170.481825) (xy 9.983267 -170.535777) (xy 9.983267 -170.590283)
			(xy 9.97551 -170.644235) (xy 9.960153 -170.696533) (xy 9.93751 -170.746114) (xy 9.908042 -170.791967)
			(xy 9.872348 -170.83316) (xy 9.831154 -170.868854) (xy 9.7853 -170.898322) (xy 9.735719 -170.920965)
			(xy 9.683421 -170.93632) (xy 9.629469 -170.944077) (xy 9.602216 -170.94454) (xy 9.574127 -170.944051)
			(xy 9.518559 -170.935806) (xy 9.464803 -170.919491) (xy 9.414025 -170.89546) (xy 9.367325 -170.864235)
			(xy 9.346184 -170.845734) (xy 9.34593 -170.84548) (xy 9.338721 -170.839511) (xy 9.321247 -170.832845)
			(xy 9.311894 -170.832526) (xy 9.243822 -170.832526) (xy 9.234488 -170.832963) (xy 9.217036 -170.839587)
			(xy 9.209786 -170.84548) (xy 9.209532 -170.845734) (xy 9.188359 -170.864191) (xy 9.141651 -170.895386)
			(xy 9.090878 -170.919405) (xy 9.037136 -170.935732) (xy 8.981583 -170.944014) (xy 8.9535 -170.94454)
			(xy 8.926249 -170.94405) (xy 8.872301 -170.936294) (xy 8.820007 -170.920939) (xy 8.77043 -170.898298)
			(xy 8.72458 -170.868832) (xy 8.68339 -170.83314) (xy 8.647698 -170.79195) (xy 8.618232 -170.7461)
			(xy 8.595591 -170.696523) (xy 8.580236 -170.644229) (xy 8.57248 -170.590281) (xy 6.217412 -170.590281)
			(xy 6.217412 -172.729398) (xy 20.58873 -172.729398) (xy 20.592801 -172.673776) (xy 20.604927 -172.619339)
			(xy 20.62485 -172.567248) (xy 20.652146 -172.518613) (xy 20.686232 -172.47447) (xy 20.726381 -172.435761)
			(xy 20.771739 -172.40331) (xy 20.821339 -172.377809) (xy 20.874123 -172.359802) (xy 20.928966 -172.349672)
			(xy 20.9847 -172.347635) (xy 21.040137 -172.353735) (xy 21.094094 -172.367841) (xy 21.145423 -172.389653)
			(xy 21.193029 -172.418707) (xy 21.235897 -172.454382) (xy 21.273114 -172.495919) (xy 21.303887 -172.542432)
			(xy 21.327559 -172.592929) (xy 21.343627 -172.646336) (xy 21.351747 -172.701512) (xy 21.352256 -172.729398)
			(xy 21.351747 -172.757284) (xy 21.343627 -172.81246) (xy 21.327559 -172.865867) (xy 21.303887 -172.916364)
			(xy 21.273114 -172.962877) (xy 21.235897 -173.004414) (xy 21.193029 -173.040089) (xy 21.145423 -173.069143)
			(xy 21.094094 -173.090955) (xy 21.040137 -173.105061) (xy 20.9847 -173.111161) (xy 20.928966 -173.109124)
			(xy 20.874123 -173.098994) (xy 20.821339 -173.080987) (xy 20.771739 -173.055486) (xy 20.726381 -173.023035)
			(xy 20.686232 -172.984326) (xy 20.652146 -172.940183) (xy 20.62485 -172.891548) (xy 20.604927 -172.839457)
			(xy 20.592801 -172.78502) (xy 20.58873 -172.729398) (xy 6.217412 -172.729398) (xy 6.217412 -173.282681)
			(xy 8.99412 -173.282681) (xy 8.99412 -173.228179) (xy 9.001876 -173.174231) (xy 9.017231 -173.121937)
			(xy 9.039872 -173.07236) (xy 9.069338 -173.02651) (xy 9.10503 -172.98532) (xy 9.14622 -172.949628)
			(xy 9.19207 -172.920162) (xy 9.241647 -172.897521) (xy 9.293941 -172.882166) (xy 9.347889 -172.87441)
			(xy 9.37514 -172.873924) (xy 9.404399 -172.874486) (xy 9.462231 -172.883433) (xy 9.518021 -172.901096)
			(xy 9.570464 -172.927062) (xy 9.618333 -172.960722) (xy 9.639808 -172.980604) (xy 9.647174 -172.987716)
			(xy 9.664954 -172.994828) (xy 9.755632 -172.994828) (xy 9.773412 -172.987716) (xy 9.780778 -172.980604)
			(xy 9.802223 -172.960685) (xy 9.850091 -172.92701) (xy 9.902541 -172.90104) (xy 9.958341 -172.883382)
			(xy 10.016182 -172.874453) (xy 10.045446 -172.873924) (xy 10.072699 -172.874383) (xy 10.126651 -172.88214)
			(xy 10.178949 -172.897495) (xy 10.22853 -172.920138) (xy 10.274384 -172.949606) (xy 10.315578 -172.9853)
			(xy 10.351272 -173.026493) (xy 10.38074 -173.072346) (xy 10.403383 -173.121927) (xy 10.41874 -173.174225)
			(xy 10.426497 -173.228177) (xy 10.426497 -173.282683) (xy 10.41874 -173.336635) (xy 10.403383 -173.388933)
			(xy 10.38074 -173.438514) (xy 10.351272 -173.484367) (xy 10.315578 -173.52556) (xy 10.274384 -173.561254)
			(xy 10.229336 -173.590204) (xy 19.616672 -173.590204) (xy 19.620743 -173.534582) (xy 19.632869 -173.480145)
			(xy 19.652792 -173.428054) (xy 19.680088 -173.379419) (xy 19.714174 -173.335276) (xy 19.754323 -173.296567)
			(xy 19.799681 -173.264116) (xy 19.849281 -173.238615) (xy 19.902065 -173.220608) (xy 19.956908 -173.210478)
			(xy 20.012642 -173.208441) (xy 20.068079 -173.214541) (xy 20.122036 -173.228647) (xy 20.173365 -173.250459)
			(xy 20.220971 -173.279513) (xy 20.263839 -173.315188) (xy 20.301056 -173.356725) (xy 20.331829 -173.403238)
			(xy 20.355501 -173.453735) (xy 20.371569 -173.507142) (xy 20.379689 -173.562318) (xy 20.380198 -173.590204)
			(xy 20.379689 -173.61809) (xy 20.371569 -173.673266) (xy 20.355501 -173.726673) (xy 20.331829 -173.77717)
			(xy 20.301056 -173.823683) (xy 20.263839 -173.86522) (xy 20.220971 -173.900895) (xy 20.173365 -173.929949)
			(xy 20.122036 -173.951761) (xy 20.068079 -173.965867) (xy 20.012642 -173.971967) (xy 19.956908 -173.96993)
			(xy 19.902065 -173.9598) (xy 19.849281 -173.941793) (xy 19.799681 -173.916292) (xy 19.754323 -173.883841)
			(xy 19.714174 -173.845132) (xy 19.680088 -173.800989) (xy 19.652792 -173.752354) (xy 19.632869 -173.700263)
			(xy 19.620743 -173.645826) (xy 19.616672 -173.590204) (xy 10.229336 -173.590204) (xy 10.22853 -173.590722)
			(xy 10.178949 -173.613365) (xy 10.126651 -173.62872) (xy 10.072699 -173.636477) (xy 10.045446 -173.63694)
			(xy 10.016186 -173.636396) (xy 9.958353 -173.627446) (xy 9.902562 -173.60978) (xy 9.85012 -173.58381)
			(xy 9.802252 -173.550144) (xy 9.780778 -173.53026) (xy 9.773412 -173.523148) (xy 9.755632 -173.516036)
			(xy 9.664954 -173.516036) (xy 9.647174 -173.523148) (xy 9.639808 -173.53026) (xy 9.618364 -173.550179)
			(xy 9.570496 -173.583855) (xy 9.518046 -173.609827) (xy 9.462246 -173.627484) (xy 9.404404 -173.636412)
			(xy 9.37514 -173.63694) (xy 9.347889 -173.63645) (xy 9.293941 -173.628694) (xy 9.241647 -173.613339)
			(xy 9.19207 -173.590698) (xy 9.14622 -173.561232) (xy 9.10503 -173.52554) (xy 9.069338 -173.48435)
			(xy 9.039872 -173.4385) (xy 9.017231 -173.388923) (xy 9.001876 -173.336629) (xy 8.99412 -173.282681)
			(xy 6.217412 -173.282681) (xy 6.217412 -174.271178) (xy 21.033738 -174.271178) (xy 21.037809 -174.215556)
			(xy 21.049935 -174.161119) (xy 21.069858 -174.109028) (xy 21.097154 -174.060393) (xy 21.13124 -174.01625)
			(xy 21.171389 -173.977541) (xy 21.216747 -173.94509) (xy 21.266347 -173.919589) (xy 21.319131 -173.901582)
			(xy 21.373974 -173.891452) (xy 21.429708 -173.889415) (xy 21.485145 -173.895515) (xy 21.539102 -173.909621)
			(xy 21.590431 -173.931433) (xy 21.638037 -173.960487) (xy 21.680905 -173.996162) (xy 21.718122 -174.037699)
			(xy 21.748895 -174.084212) (xy 21.772567 -174.134709) (xy 21.788635 -174.188116) (xy 21.796755 -174.243292)
			(xy 21.797264 -174.271178) (xy 21.796755 -174.299064) (xy 21.788635 -174.35424) (xy 21.772567 -174.407647)
			(xy 21.748895 -174.458144) (xy 21.718122 -174.504657) (xy 21.680905 -174.546194) (xy 21.638037 -174.581869)
			(xy 21.590431 -174.610923) (xy 21.539102 -174.632735) (xy 21.485145 -174.646841) (xy 21.429708 -174.652941)
			(xy 21.373974 -174.650904) (xy 21.319131 -174.640774) (xy 21.266347 -174.622767) (xy 21.216747 -174.597266)
			(xy 21.171389 -174.564815) (xy 21.13124 -174.526106) (xy 21.097154 -174.481963) (xy 21.069858 -174.433328)
			(xy 21.049935 -174.381237) (xy 21.037809 -174.3268) (xy 21.033738 -174.271178) (xy 6.217412 -174.271178)
			(xy 6.217412 -177.594081) (xy 8.398486 -177.594081) (xy 8.398486 -177.539579) (xy 8.406242 -177.485631)
			(xy 8.421598 -177.433336) (xy 8.444239 -177.383758) (xy 8.473705 -177.337907) (xy 8.509397 -177.296717)
			(xy 8.550587 -177.261025) (xy 8.596438 -177.231559) (xy 8.646016 -177.208918) (xy 8.698311 -177.193562)
			(xy 8.752259 -177.185806) (xy 8.77951 -177.18532) (xy 8.805824 -177.185774) (xy 8.857954 -177.193011)
			(xy 8.908597 -177.207332) (xy 8.956796 -177.228467) (xy 9.001639 -177.256016) (xy 9.042278 -177.289457)
			(xy 9.060434 -177.30851) (xy 9.06794 -177.31593) (xy 9.087232 -177.324444) (xy 9.097772 -177.32502)
			(xy 9.172448 -177.32502) (xy 9.182995 -177.32447) (xy 9.20229 -177.315949) (xy 9.209786 -177.30851)
			(xy 9.229606 -177.287722) (xy 9.274378 -177.251747) (xy 9.324036 -177.222887) (xy 9.377458 -177.201794)
			(xy 9.433437 -177.188945) (xy 9.49071 -177.18463) (xy 9.547983 -177.188945) (xy 9.603962 -177.201794)
			(xy 9.657384 -177.222887) (xy 9.707042 -177.251747) (xy 9.751814 -177.287722) (xy 9.771634 -177.30851)
			(xy 9.77914 -177.31593) (xy 9.798432 -177.324444) (xy 9.808972 -177.32502) (xy 9.883648 -177.32502)
			(xy 9.894195 -177.32447) (xy 9.91349 -177.315949) (xy 9.920986 -177.30851) (xy 9.939157 -177.28947)
			(xy 9.979783 -177.256011) (xy 10.02462 -177.22845) (xy 10.072818 -177.207309) (xy 10.123463 -177.192988)
			(xy 10.175595 -177.18576) (xy 10.20191 -177.18532) (xy 10.229161 -177.18581) (xy 10.283109 -177.193566)
			(xy 10.335403 -177.208921) (xy 10.38498 -177.231562) (xy 10.43083 -177.261028) (xy 10.47202 -177.29672)
			(xy 10.507712 -177.33791) (xy 10.537178 -177.38376) (xy 10.559819 -177.433337) (xy 10.575174 -177.485631)
			(xy 10.58293 -177.539579) (xy 10.58293 -177.594081) (xy 10.575174 -177.648029) (xy 10.559819 -177.700323)
			(xy 10.537178 -177.7499) (xy 10.507712 -177.79575) (xy 10.47202 -177.83694) (xy 10.43083 -177.872632)
			(xy 10.38498 -177.902098) (xy 10.335403 -177.924739) (xy 10.283109 -177.940094) (xy 10.229161 -177.94785)
			(xy 10.20191 -177.948336) (xy 10.175597 -177.94785) (xy 10.12347 -177.940618) (xy 10.072828 -177.926301)
			(xy 10.024629 -177.905172) (xy 9.979785 -177.87763) (xy 9.939144 -177.844195) (xy 9.920986 -177.825146)
			(xy 9.913465 -177.817743) (xy 9.894185 -177.809218) (xy 9.883648 -177.808636) (xy 9.808972 -177.808636)
			(xy 9.798424 -177.80918) (xy 9.779127 -177.817703) (xy 9.771634 -177.825146) (xy 9.751814 -177.845934)
			(xy 9.707042 -177.881909) (xy 9.657384 -177.910769) (xy 9.603962 -177.931862) (xy 9.547983 -177.944711)
			(xy 9.49071 -177.949026) (xy 9.433437 -177.944711) (xy 9.377458 -177.931862) (xy 9.324036 -177.910769)
			(xy 9.274378 -177.881909) (xy 9.229606 -177.845934) (xy 9.209786 -177.825146) (xy 9.202265 -177.817743)
			(xy 9.182985 -177.809218) (xy 9.172448 -177.808636) (xy 9.097772 -177.808636) (xy 9.087224 -177.80918)
			(xy 9.067927 -177.817703) (xy 9.060434 -177.825146) (xy 9.042313 -177.844235) (xy 9.001674 -177.877688)
			(xy 8.956827 -177.905241) (xy 8.908619 -177.926373) (xy 8.857966 -177.940684) (xy 8.805828 -177.947901)
			(xy 8.77951 -177.948336) (xy 8.752259 -177.947854) (xy 8.698311 -177.940098) (xy 8.646016 -177.924742)
			(xy 8.596438 -177.902101) (xy 8.550587 -177.872635) (xy 8.509397 -177.836943) (xy 8.473705 -177.795753)
			(xy 8.444239 -177.749902) (xy 8.421598 -177.700324) (xy 8.406242 -177.648029) (xy 8.398486 -177.594081)
			(xy 6.217412 -177.594081) (xy 6.217412 -209.478372) (xy 18.503138 -209.478372) (xy 18.503575 -209.452057)
			(xy 18.510814 -209.399927) (xy 18.525138 -209.349283) (xy 18.546277 -209.301084) (xy 18.573829 -209.256241)
			(xy 18.607273 -209.215603) (xy 18.626328 -209.197448) (xy 18.633744 -209.189938) (xy 18.642263 -209.17065)
			(xy 18.642838 -209.16011) (xy 18.642838 -209.085434) (xy 18.642293 -209.074886) (xy 18.633768 -209.055592)
			(xy 18.626328 -209.048096) (xy 18.607283 -209.02993) (xy 18.573824 -208.989303) (xy 18.546263 -208.944465)
			(xy 18.525122 -208.896266) (xy 18.510803 -208.84562) (xy 18.503577 -208.793488) (xy 18.503138 -208.767172)
			(xy 18.503624 -208.739921) (xy 18.51138 -208.685973) (xy 18.526735 -208.633678) (xy 18.549377 -208.584101)
			(xy 18.578843 -208.538251) (xy 18.614534 -208.49706) (xy 18.655725 -208.461369) (xy 18.701575 -208.431903)
			(xy 18.751152 -208.409261) (xy 18.803447 -208.393906) (xy 18.857395 -208.38615) (xy 18.911897 -208.38615)
			(xy 18.965845 -208.393906) (xy 19.01814 -208.409261) (xy 19.067717 -208.431903) (xy 19.113567 -208.461369)
			(xy 19.154758 -208.49706) (xy 19.190449 -208.538251) (xy 19.219915 -208.584101) (xy 19.242557 -208.633678)
			(xy 19.257912 -208.685973) (xy 19.265668 -208.739921) (xy 19.266154 -208.767172) (xy 19.265749 -208.793488)
			(xy 19.263405 -208.810352) (xy 21.535388 -208.810352) (xy 21.539459 -208.75473) (xy 21.551585 -208.700293)
			(xy 21.571508 -208.648202) (xy 21.598804 -208.599567) (xy 21.63289 -208.555424) (xy 21.673039 -208.516715)
			(xy 21.718397 -208.484264) (xy 21.767997 -208.458763) (xy 21.820781 -208.440756) (xy 21.875624 -208.430626)
			(xy 21.931358 -208.428589) (xy 21.986795 -208.434689) (xy 22.040752 -208.448795) (xy 22.092081 -208.470607)
			(xy 22.139687 -208.499661) (xy 22.182555 -208.535336) (xy 22.219772 -208.576873) (xy 22.250545 -208.623386)
			(xy 22.274217 -208.673883) (xy 22.290285 -208.72729) (xy 22.298405 -208.782466) (xy 22.298914 -208.810352)
			(xy 22.298405 -208.838238) (xy 22.290285 -208.893414) (xy 22.274217 -208.946821) (xy 22.250545 -208.997318)
			(xy 22.219772 -209.043831) (xy 22.182555 -209.085368) (xy 22.139687 -209.121043) (xy 22.092081 -209.150097)
			(xy 22.040752 -209.171909) (xy 21.986795 -209.186015) (xy 21.931358 -209.192115) (xy 21.875624 -209.190078)
			(xy 21.820781 -209.179948) (xy 21.767997 -209.161941) (xy 21.718397 -209.13644) (xy 21.673039 -209.103989)
			(xy 21.63289 -209.06528) (xy 21.598804 -209.021137) (xy 21.571508 -208.972502) (xy 21.551585 -208.920411)
			(xy 21.539459 -208.865974) (xy 21.535388 -208.810352) (xy 19.263405 -208.810352) (xy 19.258504 -208.84562)
			(xy 19.244173 -208.896265) (xy 19.223029 -208.944464) (xy 19.195471 -208.989305) (xy 19.162021 -209.029942)
			(xy 19.142964 -209.048096) (xy 19.135572 -209.055626) (xy 19.12704 -209.074899) (xy 19.126454 -209.085434)
			(xy 19.126454 -209.16011) (xy 19.126978 -209.17066) (xy 19.135518 -209.189954) (xy 19.142964 -209.197448)
			(xy 19.162048 -209.215575) (xy 19.1955 -209.256212) (xy 19.223054 -209.301059) (xy 19.244187 -209.349265)
			(xy 19.258499 -209.399917) (xy 19.265718 -209.452054) (xy 19.266154 -209.478372) (xy 19.265668 -209.505623)
			(xy 19.257912 -209.559571) (xy 19.242557 -209.611866) (xy 19.219915 -209.661443) (xy 19.190449 -209.707293)
			(xy 19.154758 -209.748484) (xy 19.113567 -209.784175) (xy 19.067717 -209.813641) (xy 19.01814 -209.836283)
			(xy 18.965845 -209.851638) (xy 18.911897 -209.859394) (xy 18.857395 -209.859394) (xy 18.803447 -209.851638)
			(xy 18.751152 -209.836283) (xy 18.701575 -209.813641) (xy 18.655725 -209.784175) (xy 18.614534 -209.748484)
			(xy 18.578843 -209.707293) (xy 18.549377 -209.661443) (xy 18.526735 -209.611866) (xy 18.51138 -209.559571)
			(xy 18.503624 -209.505623) (xy 18.503138 -209.478372) (xy 6.217412 -209.478372) (xy 6.217412 -210.113372)
			(xy 13.854428 -210.113372) (xy 13.858499 -210.05775) (xy 13.870625 -210.003313) (xy 13.890548 -209.951222)
			(xy 13.917844 -209.902587) (xy 13.95193 -209.858444) (xy 13.992079 -209.819735) (xy 14.037437 -209.787284)
			(xy 14.087037 -209.761783) (xy 14.139821 -209.743776) (xy 14.194664 -209.733646) (xy 14.250398 -209.731609)
			(xy 14.305835 -209.737709) (xy 14.359792 -209.751815) (xy 14.411121 -209.773627) (xy 14.458727 -209.802681)
			(xy 14.501595 -209.838356) (xy 14.538812 -209.879893) (xy 14.569585 -209.926406) (xy 14.593257 -209.976903)
			(xy 14.609325 -210.03031) (xy 14.617445 -210.085486) (xy 14.617954 -210.113372) (xy 17.054828 -210.113372)
			(xy 17.058899 -210.05775) (xy 17.071025 -210.003313) (xy 17.090948 -209.951222) (xy 17.118244 -209.902587)
			(xy 17.15233 -209.858444) (xy 17.192479 -209.819735) (xy 17.237837 -209.787284) (xy 17.287437 -209.761783)
			(xy 17.340221 -209.743776) (xy 17.395064 -209.733646) (xy 17.450798 -209.731609) (xy 17.506235 -209.737709)
			(xy 17.560192 -209.751815) (xy 17.611521 -209.773627) (xy 17.659127 -209.802681) (xy 17.701995 -209.838356)
			(xy 17.739212 -209.879893) (xy 17.769985 -209.926406) (xy 17.793657 -209.976903) (xy 17.809725 -210.03031)
			(xy 17.817845 -210.085486) (xy 17.818354 -210.113372) (xy 17.81789 -210.138772) (xy 17.943828 -210.138772)
			(xy 17.947899 -210.08315) (xy 17.960025 -210.028713) (xy 17.979948 -209.976622) (xy 18.007244 -209.927987)
			(xy 18.04133 -209.883844) (xy 18.081479 -209.845135) (xy 18.126837 -209.812684) (xy 18.176437 -209.787183)
			(xy 18.229221 -209.769176) (xy 18.284064 -209.759046) (xy 18.339798 -209.757009) (xy 18.395235 -209.763109)
			(xy 18.449192 -209.777215) (xy 18.500521 -209.799027) (xy 18.548127 -209.828081) (xy 18.590995 -209.863756)
			(xy 18.628212 -209.905293) (xy 18.658985 -209.951806) (xy 18.682657 -210.002303) (xy 18.698725 -210.05571)
			(xy 18.706845 -210.110886) (xy 18.707354 -210.138772) (xy 18.706845 -210.166658) (xy 18.698725 -210.221834)
			(xy 18.682657 -210.275241) (xy 18.658985 -210.325738) (xy 18.628212 -210.372251) (xy 18.590995 -210.413788)
			(xy 18.548127 -210.449463) (xy 18.500521 -210.478517) (xy 18.449192 -210.500329) (xy 18.395235 -210.514435)
			(xy 18.339798 -210.520535) (xy 18.284064 -210.518498) (xy 18.229221 -210.508368) (xy 18.176437 -210.490361)
			(xy 18.126837 -210.46486) (xy 18.081479 -210.432409) (xy 18.04133 -210.3937) (xy 18.007244 -210.349557)
			(xy 17.979948 -210.300922) (xy 17.960025 -210.248831) (xy 17.947899 -210.194394) (xy 17.943828 -210.138772)
			(xy 17.81789 -210.138772) (xy 17.817845 -210.141258) (xy 17.809725 -210.196434) (xy 17.793657 -210.249841)
			(xy 17.769985 -210.300338) (xy 17.739212 -210.346851) (xy 17.701995 -210.388388) (xy 17.659127 -210.424063)
			(xy 17.611521 -210.453117) (xy 17.560192 -210.474929) (xy 17.506235 -210.489035) (xy 17.450798 -210.495135)
			(xy 17.395064 -210.493098) (xy 17.340221 -210.482968) (xy 17.287437 -210.464961) (xy 17.237837 -210.43946)
			(xy 17.192479 -210.407009) (xy 17.15233 -210.3683) (xy 17.118244 -210.324157) (xy 17.090948 -210.275522)
			(xy 17.071025 -210.223431) (xy 17.058899 -210.168994) (xy 17.054828 -210.113372) (xy 14.617954 -210.113372)
			(xy 14.617445 -210.141258) (xy 14.609325 -210.196434) (xy 14.593257 -210.249841) (xy 14.569585 -210.300338)
			(xy 14.538812 -210.346851) (xy 14.501595 -210.388388) (xy 14.458727 -210.424063) (xy 14.411121 -210.453117)
			(xy 14.359792 -210.474929) (xy 14.305835 -210.489035) (xy 14.250398 -210.495135) (xy 14.194664 -210.493098)
			(xy 14.139821 -210.482968) (xy 14.087037 -210.464961) (xy 14.037437 -210.43946) (xy 13.992079 -210.407009)
			(xy 13.95193 -210.3683) (xy 13.917844 -210.324157) (xy 13.890548 -210.275522) (xy 13.870625 -210.223431)
			(xy 13.858499 -210.168994) (xy 13.854428 -210.113372) (xy 6.217412 -210.113372) (xy 6.217412 -212.658452)
			(xy 6.217845 -212.668518) (xy 6.225574 -212.687107) (xy 6.232398 -212.69452) (xy 6.345499 -212.807621)
			(xy 11.31543 -212.807621) (xy 11.31543 -212.753119) (xy 11.323186 -212.699172) (xy 11.338541 -212.646878)
			(xy 11.361182 -212.597301) (xy 11.390647 -212.551451) (xy 11.426338 -212.510261) (xy 11.467528 -212.47457)
			(xy 11.513378 -212.445104) (xy 11.562954 -212.422462) (xy 11.615248 -212.407107) (xy 11.669195 -212.39935)
			(xy 11.696446 -212.398864) (xy 11.723692 -212.399293) (xy 11.777628 -212.407058) (xy 11.82991 -212.422422)
			(xy 11.879471 -212.445072) (xy 11.925303 -212.474548) (xy 11.966472 -212.510248) (xy 12.002139 -212.551446)
			(xy 12.017248 -212.574124) (xy 12.022086 -212.581157) (xy 12.035497 -212.591704) (xy 12.051641 -212.597224)
			(xy 12.060174 -212.597492) (xy 12.145518 -212.597492) (xy 12.154038 -212.597173) (xy 12.17015 -212.591625)
			(xy 12.18356 -212.581112) (xy 12.188444 -212.574124) (xy 12.203523 -212.551427) (xy 12.239196 -212.510233)
			(xy 12.280371 -212.474539) (xy 12.326209 -212.445071) (xy 12.375776 -212.42243) (xy 12.428061 -212.407077)
			(xy 12.482 -212.399324) (xy 12.509246 -212.398864) (xy 12.535223 -212.399266) (xy 12.586696 -212.406315)
			(xy 12.636734 -212.42029) (xy 12.684411 -212.440933) (xy 12.728842 -212.467859) (xy 12.769204 -212.500572)
			(xy 12.804749 -212.538463) (xy 12.820142 -212.559392) (xy 12.827792 -212.568866) (xy 12.84939 -212.580023)
			(xy 12.861544 -212.580728) (xy 12.944348 -212.580728) (xy 12.956512 -212.580046) (xy 12.978134 -212.568901)
			(xy 12.98575 -212.559392) (xy 13.001177 -212.538491) (xy 13.036724 -212.500612) (xy 13.077084 -212.467909)
			(xy 13.121509 -212.440987) (xy 13.169179 -212.420345) (xy 13.219208 -212.406366) (xy 13.270673 -212.399307)
			(xy 13.296646 -212.398864) (xy 13.323899 -212.399323) (xy 13.377851 -212.40708) (xy 13.430149 -212.422435)
			(xy 13.47973 -212.445078) (xy 13.525584 -212.474546) (xy 13.566778 -212.51024) (xy 13.602472 -212.551433)
			(xy 13.63194 -212.597286) (xy 13.654583 -212.646867) (xy 13.66994 -212.699165) (xy 13.677697 -212.753117)
			(xy 13.677697 -212.807623) (xy 13.66994 -212.861575) (xy 13.654583 -212.913873) (xy 13.63194 -212.963454)
			(xy 13.602472 -213.009307) (xy 13.566778 -213.0505) (xy 13.525584 -213.086194) (xy 13.47973 -213.115662)
			(xy 13.430149 -213.138305) (xy 13.377851 -213.15366) (xy 13.323899 -213.161417) (xy 13.296646 -213.16188)
			(xy 13.27067 -213.161466) (xy 13.219198 -213.154416) (xy 13.169161 -213.140442) (xy 13.121485 -213.119801)
			(xy 13.077054 -213.092877) (xy 13.036691 -213.060167) (xy 13.001144 -213.02228) (xy 12.98575 -213.001352)
			(xy 12.978115 -212.991864) (xy 12.956505 -212.980717) (xy 12.944348 -212.980016) (xy 12.861544 -212.980016)
			(xy 12.849383 -212.980715) (xy 12.827762 -212.99185) (xy 12.820142 -213.001352) (xy 12.804733 -213.022266)
			(xy 12.769182 -213.060143) (xy 12.728818 -213.092844) (xy 12.684389 -213.119763) (xy 12.636718 -213.140403)
			(xy 12.586686 -213.154381) (xy 12.53522 -213.161438) (xy 12.509246 -213.16188) (xy 12.482001 -213.161437)
			(xy 12.428066 -213.153672) (xy 12.375786 -213.138309) (xy 12.326225 -213.115661) (xy 12.280393 -213.086187)
			(xy 12.239223 -213.05049) (xy 12.203555 -213.009296) (xy 12.188444 -212.98662) (xy 12.183567 -212.979618)
			(xy 12.170172 -212.96907) (xy 12.154045 -212.963533) (xy 12.145518 -212.963252) (xy 12.060174 -212.963252)
			(xy 12.051656 -212.96359) (xy 12.035548 -212.969134) (xy 12.022136 -212.979637) (xy 12.017248 -212.98662)
			(xy 12.002156 -213.009308) (xy 11.966487 -213.050504) (xy 11.925315 -213.086201) (xy 11.879479 -213.115671)
			(xy 11.829914 -213.138314) (xy 11.77763 -213.153668) (xy 11.723692 -213.16142) (xy 11.696446 -213.16188)
			(xy 11.669195 -213.16139) (xy 11.615248 -213.153633) (xy 11.562954 -213.138278) (xy 11.513378 -213.115636)
			(xy 11.467528 -213.08617) (xy 11.426338 -213.050479) (xy 11.390647 -213.009289) (xy 11.361182 -212.963439)
			(xy 11.338541 -212.913862) (xy 11.323186 -212.861568) (xy 11.31543 -212.807621) (xy 6.345499 -212.807621)
			(xy 7.68985 -214.151972) (xy 13.219428 -214.151972) (xy 13.223499 -214.09635) (xy 13.235625 -214.041913)
			(xy 13.255548 -213.989822) (xy 13.282844 -213.941187) (xy 13.31693 -213.897044) (xy 13.357079 -213.858335)
			(xy 13.402437 -213.825884) (xy 13.452037 -213.800383) (xy 13.504821 -213.782376) (xy 13.559664 -213.772246)
			(xy 13.615398 -213.770209) (xy 13.670835 -213.776309) (xy 13.724792 -213.790415) (xy 13.776121 -213.812227)
			(xy 13.823727 -213.841281) (xy 13.866595 -213.876956) (xy 13.903812 -213.918493) (xy 13.934585 -213.965006)
			(xy 13.958257 -214.015503) (xy 13.974325 -214.06891) (xy 13.978026 -214.09406) (xy 18.591782 -214.09406)
			(xy 18.595853 -214.038438) (xy 18.607979 -213.984001) (xy 18.627902 -213.93191) (xy 18.655198 -213.883275)
			(xy 18.689284 -213.839132) (xy 18.729433 -213.800423) (xy 18.774791 -213.767972) (xy 18.824391 -213.742471)
			(xy 18.877175 -213.724464) (xy 18.932018 -213.714334) (xy 18.987752 -213.712297) (xy 19.043189 -213.718397)
			(xy 19.097146 -213.732503) (xy 19.148475 -213.754315) (xy 19.196081 -213.783369) (xy 19.238949 -213.819044)
			(xy 19.276166 -213.860581) (xy 19.306939 -213.907094) (xy 19.330611 -213.957591) (xy 19.346679 -214.010998)
			(xy 19.354799 -214.066174) (xy 19.355308 -214.09406) (xy 19.354799 -214.121946) (xy 19.346679 -214.177122)
			(xy 19.330611 -214.230529) (xy 19.306939 -214.281026) (xy 19.276166 -214.327539) (xy 19.238949 -214.369076)
			(xy 19.196081 -214.404751) (xy 19.148475 -214.433805) (xy 19.097146 -214.455617) (xy 19.043189 -214.469723)
			(xy 18.987752 -214.475823) (xy 18.932018 -214.473786) (xy 18.877175 -214.463656) (xy 18.824391 -214.445649)
			(xy 18.774791 -214.420148) (xy 18.729433 -214.387697) (xy 18.689284 -214.348988) (xy 18.655198 -214.304845)
			(xy 18.627902 -214.25621) (xy 18.607979 -214.204119) (xy 18.595853 -214.149682) (xy 18.591782 -214.09406)
			(xy 13.978026 -214.09406) (xy 13.982445 -214.124086) (xy 13.982954 -214.151972) (xy 13.982445 -214.179858)
			(xy 13.974325 -214.235034) (xy 13.958257 -214.288441) (xy 13.934585 -214.338938) (xy 13.903812 -214.385451)
			(xy 13.866595 -214.426988) (xy 13.823727 -214.462663) (xy 13.776121 -214.491717) (xy 13.724792 -214.513529)
			(xy 13.670835 -214.527635) (xy 13.615398 -214.533735) (xy 13.559664 -214.531698) (xy 13.504821 -214.521568)
			(xy 13.452037 -214.503561) (xy 13.402437 -214.47806) (xy 13.357079 -214.445609) (xy 13.31693 -214.4069)
			(xy 13.282844 -214.362757) (xy 13.255548 -214.314122) (xy 13.235625 -214.262031) (xy 13.223499 -214.207594)
			(xy 13.219428 -214.151972) (xy 7.68985 -214.151972) (xy 8.85825 -215.320372) (xy 17.156428 -215.320372)
			(xy 17.160499 -215.26475) (xy 17.172625 -215.210313) (xy 17.192548 -215.158222) (xy 17.219844 -215.109587)
			(xy 17.25393 -215.065444) (xy 17.294079 -215.026735) (xy 17.339437 -214.994284) (xy 17.389037 -214.968783)
			(xy 17.441821 -214.950776) (xy 17.496664 -214.940646) (xy 17.552398 -214.938609) (xy 17.607835 -214.944709)
			(xy 17.661792 -214.958815) (xy 17.713121 -214.980627) (xy 17.760727 -215.009681) (xy 17.803595 -215.045356)
			(xy 17.840812 -215.086893) (xy 17.871585 -215.133406) (xy 17.895257 -215.183903) (xy 17.911325 -215.23731)
			(xy 17.919445 -215.292486) (xy 17.919954 -215.320372) (xy 17.919445 -215.348258) (xy 17.911325 -215.403434)
			(xy 17.908193 -215.413844) (xy 21.5552 -215.413844) (xy 21.559271 -215.358222) (xy 21.571397 -215.303785)
			(xy 21.59132 -215.251694) (xy 21.618616 -215.203059) (xy 21.652702 -215.158916) (xy 21.692851 -215.120207)
			(xy 21.738209 -215.087756) (xy 21.787809 -215.062255) (xy 21.840593 -215.044248) (xy 21.895436 -215.034118)
			(xy 21.95117 -215.032081) (xy 22.006607 -215.038181) (xy 22.060564 -215.052287) (xy 22.111893 -215.074099)
			(xy 22.159499 -215.103153) (xy 22.202367 -215.138828) (xy 22.239584 -215.180365) (xy 22.270357 -215.226878)
			(xy 22.294029 -215.277375) (xy 22.310097 -215.330782) (xy 22.318217 -215.385958) (xy 22.318726 -215.413844)
			(xy 22.318217 -215.44173) (xy 22.310097 -215.496906) (xy 22.294029 -215.550313) (xy 22.270357 -215.60081)
			(xy 22.239584 -215.647323) (xy 22.202367 -215.68886) (xy 22.159499 -215.724535) (xy 22.111893 -215.753589)
			(xy 22.060564 -215.775401) (xy 22.006607 -215.789507) (xy 21.95117 -215.795607) (xy 21.895436 -215.79357)
			(xy 21.840593 -215.78344) (xy 21.787809 -215.765433) (xy 21.738209 -215.739932) (xy 21.692851 -215.707481)
			(xy 21.652702 -215.668772) (xy 21.618616 -215.624629) (xy 21.59132 -215.575994) (xy 21.571397 -215.523903)
			(xy 21.559271 -215.469466) (xy 21.5552 -215.413844) (xy 17.908193 -215.413844) (xy 17.895257 -215.456841)
			(xy 17.871585 -215.507338) (xy 17.840812 -215.553851) (xy 17.803595 -215.595388) (xy 17.760727 -215.631063)
			(xy 17.713121 -215.660117) (xy 17.661792 -215.681929) (xy 17.607835 -215.696035) (xy 17.552398 -215.702135)
			(xy 17.496664 -215.700098) (xy 17.441821 -215.689968) (xy 17.389037 -215.671961) (xy 17.339437 -215.64646)
			(xy 17.294079 -215.614009) (xy 17.25393 -215.5753) (xy 17.219844 -215.531157) (xy 17.192548 -215.482522)
			(xy 17.172625 -215.430431) (xy 17.160499 -215.375994) (xy 17.156428 -215.320372) (xy 8.85825 -215.320372)
			(xy 9.955784 -216.417906) (xy 9.963187 -216.424738) (xy 9.981786 -216.432441) (xy 9.991852 -216.432892)
		)
		(stroke
			(width 0)
			(type solid)
		)
		(fill yes)
		(layer "In5.Cu")
		(net "GND")
	)
	(gr_poly
		(pts
			(xy 313.023504 -416.564064) (xy 313.032721 -416.563646) (xy 313.049945 -416.557068) (xy 313.063713 -416.544807)
			(xy 313.072234 -416.528458) (xy 313.073796 -416.51936) (xy 313.073796 -394.32992) (xy 313.073796 -394.27912)
			(xy 326.480424 -394.27912) (xy 326.485504 -394.280136) (xy 326.494211 -394.282363) (xy 326.509391 -394.291962)
			(xy 326.520314 -394.306219) (xy 326.52335 -394.31468) (xy 326.525636 -394.321792) (xy 326.525636 -405.622717)
			(xy 331.004946 -405.622717) (xy 331.004947 -405.557273) (xy 331.013741 -405.492423) (xy 331.031168 -405.429343)
			(xy 331.056914 -405.369176) (xy 331.073252 -405.34082) (xy 331.076556 -405.33479) (xy 331.080169 -405.32153)
			(xy 331.080364 -405.314658) (xy 331.080364 -404.565358) (xy 331.080154 -404.558486) (xy 331.076559 -404.545223)
			(xy 331.073252 -404.539196) (xy 331.056933 -404.51083) (xy 331.031187 -404.450665) (xy 331.013758 -404.387587)
			(xy 331.004962 -404.32274) (xy 331.00496 -404.257298) (xy 331.01375 -404.19245) (xy 331.031174 -404.12937)
			(xy 331.056916 -404.069204) (xy 331.073252 -404.040848) (xy 331.076581 -404.03483) (xy 331.080178 -404.021561)
			(xy 331.080364 -404.014686) (xy 331.080364 -403.728682) (xy 331.08075 -403.718506) (xy 331.088546 -403.699706)
			(xy 331.102943 -403.685321) (xy 331.12175 -403.677541) (xy 331.131926 -403.67712) (xy 331.848206 -403.67712)
			(xy 331.858362 -403.677628) (xy 331.877128 -403.685401) (xy 331.891492 -403.699762) (xy 331.899269 -403.718526)
			(xy 331.899768 -403.728682) (xy 331.899768 -404.014686) (xy 331.899969 -404.021558) (xy 331.903572 -404.034821)
			(xy 331.90688 -404.040848) (xy 331.923235 -404.069194) (xy 331.948977 -404.129363) (xy 331.9664 -404.192446)
			(xy 331.975191 -404.257297) (xy 331.975188 -404.322741) (xy 331.966393 -404.387591) (xy 331.948964 -404.450672)
			(xy 331.923218 -404.51084) (xy 331.90688 -404.539196) (xy 331.903565 -404.545221) (xy 331.89996 -404.558484)
			(xy 331.899768 -404.565358) (xy 331.899768 -405.314658) (xy 331.89998 -405.32153) (xy 331.903575 -405.334792)
			(xy 331.90688 -405.34082) (xy 331.923212 -405.369179) (xy 331.948955 -405.429345) (xy 331.966381 -405.492425)
			(xy 331.975175 -405.557274) (xy 331.975175 -405.622716) (xy 331.966383 -405.687565) (xy 331.948958 -405.750645)
			(xy 331.923216 -405.810812) (xy 331.90688 -405.839168) (xy 331.903575 -405.845197) (xy 331.899964 -405.858458)
			(xy 331.899768 -405.86533) (xy 331.899768 -406.151334) (xy 331.899295 -406.161493) (xy 331.89151 -406.180262)
			(xy 331.877138 -406.194626) (xy 331.858365 -406.2024) (xy 331.848206 -406.202896) (xy 331.131926 -406.202896)
			(xy 331.121774 -406.202346) (xy 331.103012 -406.194587) (xy 331.088647 -406.180238) (xy 331.080865 -406.161485)
			(xy 331.080364 -406.151334) (xy 331.080364 -405.86533) (xy 331.080165 -405.858457) (xy 331.076562 -405.845194)
			(xy 331.073252 -405.839168) (xy 331.056909 -405.810815) (xy 331.031165 -405.750648) (xy 331.013739 -405.687567)
			(xy 331.004946 -405.622717) (xy 326.525636 -405.622717) (xy 326.525636 -406.722795) (xy 333.204826 -406.722795)
			(xy 333.20483 -406.65735) (xy 333.213627 -406.592499) (xy 333.231058 -406.529417) (xy 333.256806 -406.46925)
			(xy 333.273146 -406.440894) (xy 333.276512 -406.43488) (xy 333.280246 -406.421619) (xy 333.280512 -406.414732)
			(xy 333.280512 -405.665432) (xy 333.2803 -405.658538) (xy 333.276558 -405.645265) (xy 333.273146 -405.63927)
			(xy 333.256805 -405.610916) (xy 333.231061 -405.550749) (xy 333.213635 -405.487668) (xy 333.204842 -405.422818)
			(xy 333.204843 -405.357375) (xy 333.213636 -405.292525) (xy 333.231063 -405.229445) (xy 333.256808 -405.169278)
			(xy 333.273146 -405.140922) (xy 333.276502 -405.134903) (xy 333.280243 -405.121646) (xy 333.280512 -405.11476)
			(xy 333.280512 -404.828756) (xy 333.280949 -404.818643) (xy 333.288704 -404.799961) (xy 333.303015 -404.785668)
			(xy 333.321706 -404.777937) (xy 333.33182 -404.777448) (xy 334.0481 -404.777448) (xy 334.058202 -404.777984)
			(xy 334.076871 -404.785712) (xy 334.091163 -404.799993) (xy 334.098907 -404.818654) (xy 334.099408 -404.828756)
			(xy 334.099408 -405.11476) (xy 334.099656 -405.12165) (xy 334.103388 -405.134916) (xy 334.106774 -405.140922)
			(xy 334.123108 -405.16928) (xy 334.148851 -405.229447) (xy 334.166277 -405.292526) (xy 334.175071 -405.357375)
			(xy 334.175071 -405.422818) (xy 334.166279 -405.487667) (xy 334.148853 -405.550747) (xy 334.123111 -405.610914)
			(xy 334.116311 -405.622716) (xy 335.404996 -405.622716) (xy 335.404997 -405.557273) (xy 335.41379 -405.492424)
			(xy 335.431215 -405.429344) (xy 335.456958 -405.369177) (xy 335.473294 -405.34082) (xy 335.476647 -405.334799)
			(xy 335.48039 -405.321543) (xy 335.48066 -405.314658) (xy 335.48066 -404.565358) (xy 335.480432 -404.558465)
			(xy 335.4767 -404.545193) (xy 335.473294 -404.539196) (xy 335.456977 -404.510829) (xy 335.431233 -404.450664)
			(xy 335.413807 -404.387587) (xy 335.405012 -404.322739) (xy 335.40501 -404.257298) (xy 335.413799 -404.192451)
			(xy 335.431221 -404.129371) (xy 335.45696 -404.069205) (xy 335.473294 -404.040848) (xy 335.476672 -404.03484)
			(xy 335.4804 -404.021574) (xy 335.48066 -404.014686) (xy 335.48066 -403.728682) (xy 335.481112 -403.718552)
			(xy 335.48885 -403.699826) (xy 335.503147 -403.68547) (xy 335.52184 -403.677655) (xy 335.531968 -403.67712)
			(xy 336.248248 -403.67712) (xy 336.258408 -403.677483) (xy 336.277165 -403.685298) (xy 336.291487 -403.699713)
			(xy 336.299182 -403.71852) (xy 336.299556 -403.728682) (xy 336.299556 -404.014686) (xy 336.299765 -404.021581)
			(xy 336.30351 -404.034853) (xy 336.306922 -404.040848) (xy 336.323279 -404.069193) (xy 336.349023 -404.129362)
			(xy 336.366449 -404.192445) (xy 336.375241 -404.257296) (xy 336.375238 -404.322741) (xy 336.366442 -404.387592)
			(xy 336.349011 -404.450673) (xy 336.323262 -404.51084) (xy 336.306922 -404.539196) (xy 336.303557 -404.545211)
			(xy 336.299822 -404.558471) (xy 336.299556 -404.565358) (xy 336.299556 -405.314658) (xy 336.299776 -405.321552)
			(xy 336.303513 -405.334824) (xy 336.306922 -405.34082) (xy 336.323255 -405.369179) (xy 336.349002 -405.429344)
			(xy 336.36643 -405.492424) (xy 336.375225 -405.557273) (xy 336.375225 -405.622716) (xy 336.366432 -405.687566)
			(xy 336.349005 -405.750646) (xy 336.32326 -405.810812) (xy 336.306922 -405.839168) (xy 336.303567 -405.845187)
			(xy 336.299826 -405.858444) (xy 336.299556 -405.86533) (xy 336.299556 -406.151334) (xy 336.299101 -406.161463)
			(xy 336.291362 -406.180186) (xy 336.277066 -406.194541) (xy 336.258375 -406.202359) (xy 336.248248 -406.202896)
			(xy 335.531968 -406.202896) (xy 335.521811 -406.202505) (xy 335.503057 -406.194698) (xy 335.488735 -406.180292)
			(xy 335.481037 -406.161493) (xy 335.48066 -406.151334) (xy 335.48066 -405.86533) (xy 335.480442 -405.858436)
			(xy 335.476703 -405.845164) (xy 335.473294 -405.839168) (xy 335.456953 -405.810814) (xy 335.431212 -405.750646)
			(xy 335.413788 -405.687566) (xy 335.404996 -405.622716) (xy 334.116311 -405.622716) (xy 334.106774 -405.63927)
			(xy 334.103422 -405.645291) (xy 334.099679 -405.658547) (xy 334.099408 -405.665432) (xy 334.099408 -406.414732)
			(xy 334.099666 -406.421621) (xy 334.103391 -406.434887) (xy 334.106774 -406.440894) (xy 334.123084 -406.469265)
			(xy 334.14883 -406.529429) (xy 334.166259 -406.592506) (xy 334.175055 -406.657352) (xy 334.175058 -406.722793)
			(xy 334.175058 -406.722795) (xy 337.604862 -406.722795) (xy 337.604866 -406.65735) (xy 337.613664 -406.592498)
			(xy 337.631096 -406.529417) (xy 337.656847 -406.46925) (xy 337.673188 -406.440894) (xy 337.676504 -406.43487)
			(xy 337.680109 -406.421606) (xy 337.6803 -406.414732) (xy 337.6803 -405.665432) (xy 337.680096 -405.65856)
			(xy 337.676496 -405.645297) (xy 337.673188 -405.63927) (xy 337.656846 -405.610916) (xy 337.6311 -405.55075)
			(xy 337.613672 -405.487669) (xy 337.604878 -405.422818) (xy 337.604879 -405.357375) (xy 337.613673 -405.292524)
			(xy 337.631102 -405.229444) (xy 337.656849 -405.169278) (xy 337.673188 -405.140922) (xy 337.676494 -405.134893)
			(xy 337.680105 -405.121633) (xy 337.6803 -405.11476) (xy 337.6803 -404.828756) (xy 337.680686 -404.818599)
			(xy 337.688496 -404.799846) (xy 337.702903 -404.785524) (xy 337.721703 -404.777826) (xy 337.731862 -404.777448)
			(xy 338.448142 -404.777448) (xy 338.458272 -404.777892) (xy 338.476996 -404.785635) (xy 338.491351 -404.799934)
			(xy 338.499167 -404.818628) (xy 338.499704 -404.828756) (xy 338.499704 -405.11476) (xy 338.499911 -405.121632)
			(xy 338.503509 -405.134895) (xy 338.506816 -405.140922) (xy 338.523151 -405.16928) (xy 338.548898 -405.229445)
			(xy 338.566326 -405.292525) (xy 338.575121 -405.357375) (xy 338.575121 -405.422818) (xy 338.566328 -405.487668)
			(xy 338.5489 -405.550748) (xy 338.523155 -405.610914) (xy 338.516354 -405.622717) (xy 339.805032 -405.622717)
			(xy 339.805033 -405.557273) (xy 339.813827 -405.492423) (xy 339.831254 -405.429343) (xy 339.856998 -405.369176)
			(xy 339.873336 -405.34082) (xy 339.876639 -405.334789) (xy 339.880253 -405.32153) (xy 339.880448 -405.314658)
			(xy 339.880448 -404.565358) (xy 339.880241 -404.558486) (xy 339.876644 -404.545223) (xy 339.873336 -404.539196)
			(xy 339.857017 -404.51083) (xy 339.831272 -404.450665) (xy 339.813844 -404.387587) (xy 339.805048 -404.32274)
			(xy 339.805046 -404.257298) (xy 339.813836 -404.19245) (xy 339.831259 -404.129371) (xy 339.857 -404.069204)
			(xy 339.873336 -404.040848) (xy 339.876664 -404.03483) (xy 339.880262 -404.021561) (xy 339.880448 -404.014686)
			(xy 339.880448 -403.728682) (xy 339.880919 -403.718522) (xy 339.888701 -403.69975) (xy 339.903074 -403.685385)
			(xy 339.92185 -403.677613) (xy 339.93201 -403.67712) (xy 340.64829 -403.67712) (xy 340.658445 -403.677641)
			(xy 340.67721 -403.685409) (xy 340.691575 -403.699766) (xy 340.699353 -403.718527) (xy 340.699852 -403.728682)
			(xy 340.699852 -404.014686) (xy 340.700043 -404.021559) (xy 340.703651 -404.034822) (xy 340.706964 -404.040848)
			(xy 340.72332 -404.069194) (xy 340.749062 -404.129363) (xy 340.766486 -404.192445) (xy 340.775277 -404.257297)
			(xy 340.775274 -404.322741) (xy 340.766479 -404.387592) (xy 340.749049 -404.450673) (xy 340.723303 -404.51084)
			(xy 340.706964 -404.539196) (xy 340.703656 -404.545224) (xy 340.700045 -404.558485) (xy 340.699852 -404.565358)
			(xy 340.699852 -405.314658) (xy 340.700053 -405.321531) (xy 340.703654 -405.334794) (xy 340.706964 -405.34082)
			(xy 340.723296 -405.369179) (xy 340.74904 -405.429345) (xy 340.766467 -405.492425) (xy 340.775261 -405.557274)
			(xy 340.775262 -405.622716) (xy 340.766469 -405.687565) (xy 340.749044 -405.750645) (xy 340.723301 -405.810812)
			(xy 340.706964 -405.839168) (xy 340.703666 -405.845201) (xy 340.700049 -405.858458) (xy 340.699852 -405.86533)
			(xy 340.699852 -406.151334) (xy 340.699394 -406.161495) (xy 340.691607 -406.180267) (xy 340.67723 -406.194631)
			(xy 340.658452 -406.202403) (xy 340.64829 -406.202896) (xy 339.93201 -406.202896) (xy 339.921857 -406.202359)
			(xy 339.903095 -406.194594) (xy 339.88873 -406.180242) (xy 339.880949 -406.161487) (xy 339.880448 -406.151334)
			(xy 339.880448 -405.86533) (xy 339.880251 -405.858457) (xy 339.876647 -405.845194) (xy 339.873336 -405.839168)
			(xy 339.856994 -405.810815) (xy 339.83125 -405.750647) (xy 339.813825 -405.687567) (xy 339.805032 -405.622717)
			(xy 338.516354 -405.622717) (xy 338.506816 -405.63927) (xy 338.503513 -405.6453) (xy 338.4999 -405.65856)
			(xy 338.499704 -405.665432) (xy 338.499704 -406.414732) (xy 338.499883 -406.421606) (xy 338.5035 -406.434869)
			(xy 338.506816 -406.440894) (xy 338.523128 -406.469265) (xy 338.548876 -406.529427) (xy 338.566308 -406.592505)
			(xy 338.575105 -406.657352) (xy 338.575108 -406.722793) (xy 338.575108 -406.722795) (xy 342.004912 -406.722795)
			(xy 342.004916 -406.65735) (xy 342.013713 -406.592499) (xy 342.031143 -406.529418) (xy 342.056891 -406.46925)
			(xy 342.07323 -406.440894) (xy 342.076595 -406.434879) (xy 342.08033 -406.421619) (xy 342.080596 -406.414732)
			(xy 342.080596 -405.665432) (xy 342.080351 -405.658542) (xy 342.076617 -405.645276) (xy 342.07323 -405.63927)
			(xy 342.05689 -405.610916) (xy 342.031146 -405.550748) (xy 342.013721 -405.487668) (xy 342.004928 -405.422818)
			(xy 342.004929 -405.357375) (xy 342.013722 -405.292525) (xy 342.031149 -405.229445) (xy 342.056893 -405.169278)
			(xy 342.07323 -405.140922) (xy 342.076585 -405.134902) (xy 342.080326 -405.121646) (xy 342.080596 -405.11476)
			(xy 342.080596 -404.828756) (xy 342.081049 -404.818645) (xy 342.0888 -404.799967) (xy 342.103107 -404.785673)
			(xy 342.121793 -404.77794) (xy 342.131904 -404.777448) (xy 342.848184 -404.777448) (xy 342.858285 -404.777997)
			(xy 342.876953 -404.78572) (xy 342.891247 -404.799996) (xy 342.898991 -404.818655) (xy 342.899492 -404.828756)
			(xy 342.899492 -405.11476) (xy 342.899742 -405.12165) (xy 342.903473 -405.134916) (xy 342.906858 -405.140922)
			(xy 342.923192 -405.16928) (xy 342.948936 -405.229446) (xy 342.966363 -405.292526) (xy 342.975157 -405.357375)
			(xy 342.975157 -405.422818) (xy 342.966365 -405.487667) (xy 342.948939 -405.550747) (xy 342.923195 -405.610914)
			(xy 342.916395 -405.622716) (xy 344.204822 -405.622716) (xy 344.204823 -405.557273) (xy 344.213616 -405.492424)
			(xy 344.231043 -405.429343) (xy 344.256787 -405.369176) (xy 344.273124 -405.34082) (xy 344.276433 -405.334793)
			(xy 344.280042 -405.321531) (xy 344.280236 -405.314658) (xy 344.280236 -404.565358) (xy 344.280018 -404.558487)
			(xy 344.276427 -404.545224) (xy 344.273124 -404.539196) (xy 344.256806 -404.510829) (xy 344.231061 -404.450665)
			(xy 344.213633 -404.387587) (xy 344.204838 -404.322739) (xy 344.204835 -404.257298) (xy 344.213625 -404.19245)
			(xy 344.231048 -404.129371) (xy 344.256789 -404.069204) (xy 344.273124 -404.040848) (xy 344.276459 -404.034833)
			(xy 344.280051 -404.021562) (xy 344.280236 -404.014686) (xy 344.280236 -403.728682) (xy 344.280718 -403.718523)
			(xy 344.288498 -403.699754) (xy 344.302867 -403.685389) (xy 344.321639 -403.677615) (xy 344.331798 -403.67712)
			(xy 345.048078 -403.67712) (xy 345.058246 -403.677582) (xy 345.077037 -403.685356) (xy 345.091422 -403.69973)
			(xy 345.09921 -403.718514) (xy 345.09964 -403.728682) (xy 345.09964 -404.014686) (xy 345.099832 -404.021559)
			(xy 345.10344 -404.034822) (xy 345.106752 -404.040848) (xy 345.123108 -404.069194) (xy 345.148851 -404.129363)
			(xy 345.166276 -404.192445) (xy 345.175066 -404.257297) (xy 345.175065 -404.290022) (xy 348.603832 -404.290022)
			(xy 348.607823 -404.227855) (xy 348.619732 -404.166708) (xy 348.639361 -404.107587) (xy 348.66639 -404.051461)
			(xy 348.700374 -403.999252) (xy 348.740756 -403.951817) (xy 348.786872 -403.909936) (xy 348.837964 -403.874296)
			(xy 348.893195 -403.845482) (xy 348.951657 -403.823968) (xy 349.012391 -403.810106) (xy 349.074398 -403.804124)
			(xy 349.136661 -403.80612) (xy 349.198158 -403.816063) (xy 349.257879 -403.833787) (xy 349.314842 -403.859004)
			(xy 349.368113 -403.891297) (xy 349.416818 -403.930137) (xy 349.460155 -403.974887) (xy 349.497415 -404.024811)
			(xy 349.527984 -404.07909) (xy 349.551362 -404.136833) (xy 349.567163 -404.197091) (xy 349.575129 -404.258874)
			(xy 349.575628 -404.290022) (xy 349.575129 -404.32117) (xy 349.567163 -404.382953) (xy 349.551362 -404.443211)
			(xy 349.527984 -404.500954) (xy 349.497415 -404.555233) (xy 349.460155 -404.605157) (xy 349.416818 -404.649907)
			(xy 349.368113 -404.688747) (xy 349.314842 -404.72104) (xy 349.257879 -404.746257) (xy 349.198158 -404.763981)
			(xy 349.136661 -404.773924) (xy 349.074398 -404.77592) (xy 349.012391 -404.769938) (xy 348.951657 -404.756076)
			(xy 348.893195 -404.734562) (xy 348.837964 -404.705748) (xy 348.786872 -404.670108) (xy 348.740756 -404.628227)
			(xy 348.700374 -404.580792) (xy 348.66639 -404.528583) (xy 348.639361 -404.472457) (xy 348.619732 -404.413336)
			(xy 348.607823 -404.352189) (xy 348.603832 -404.290022) (xy 345.175065 -404.290022) (xy 345.175064 -404.322741)
			(xy 345.166268 -404.387592) (xy 345.148838 -404.450673) (xy 345.123091 -404.51084) (xy 345.106752 -404.539196)
			(xy 345.103443 -404.545223) (xy 345.099833 -404.558485) (xy 345.09964 -404.565358) (xy 345.09964 -405.314658)
			(xy 345.099843 -405.32153) (xy 345.103443 -405.334793) (xy 345.106752 -405.34082) (xy 345.123085 -405.369179)
			(xy 345.148829 -405.429345) (xy 345.166257 -405.492424) (xy 345.17505 -405.557274) (xy 345.175051 -405.622716)
			(xy 345.166259 -405.687566) (xy 345.148833 -405.750645) (xy 345.123089 -405.810812) (xy 345.106752 -405.839168)
			(xy 345.103453 -405.8452) (xy 345.099837 -405.858458) (xy 345.09964 -405.86533) (xy 345.09964 -406.151334)
			(xy 345.099194 -406.161497) (xy 345.091404 -406.180271) (xy 345.077024 -406.194636) (xy 345.058241 -406.202405)
			(xy 345.048078 -406.202896) (xy 344.331798 -406.202896) (xy 344.321644 -406.202369) (xy 344.302882 -406.1946)
			(xy 344.288518 -406.180245) (xy 344.280737 -406.161487) (xy 344.280236 -406.151334) (xy 344.280236 -405.86533)
			(xy 344.280028 -405.858458) (xy 344.27643 -405.845195) (xy 344.273124 -405.839168) (xy 344.256782 -405.810814)
			(xy 344.231039 -405.750647) (xy 344.213614 -405.687566) (xy 344.204822 -405.622716) (xy 342.916395 -405.622716)
			(xy 342.906858 -405.63927) (xy 342.903505 -405.645291) (xy 342.899763 -405.658547) (xy 342.899492 -405.665432)
			(xy 342.899492 -406.414732) (xy 342.899752 -406.421621) (xy 342.903476 -406.434887) (xy 342.906858 -406.440894)
			(xy 342.923168 -406.469265) (xy 342.948915 -406.529428) (xy 342.966344 -406.592505) (xy 342.975141 -406.657352)
			(xy 342.975145 -406.722793) (xy 342.975145 -406.722795) (xy 346.404949 -406.722795) (xy 346.404952 -406.65735)
			(xy 346.41375 -406.592498) (xy 346.431182 -406.529417) (xy 346.456931 -406.46925) (xy 346.473272 -406.440894)
			(xy 346.476587 -406.434869) (xy 346.480193 -406.421606) (xy 346.480384 -406.414732) (xy 346.480384 -405.665432)
			(xy 346.480182 -405.65856) (xy 346.476581 -405.645297) (xy 346.473272 -405.63927) (xy 346.45693 -405.610916)
			(xy 346.431185 -405.550749) (xy 346.413758 -405.487669) (xy 346.404964 -405.422818) (xy 346.404965 -405.357375)
			(xy 346.413759 -405.292525) (xy 346.431187 -405.229444) (xy 346.456933 -405.169278) (xy 346.473272 -405.140922)
			(xy 346.476577 -405.134893) (xy 346.480189 -405.121633) (xy 346.480384 -405.11476) (xy 346.480384 -404.828756)
			(xy 346.480785 -404.818601) (xy 346.488592 -404.799851) (xy 346.502995 -404.78553) (xy 346.521789 -404.777829)
			(xy 346.531946 -404.777448) (xy 347.248226 -404.777448) (xy 347.258355 -404.777905) (xy 347.277079 -404.785643)
			(xy 347.291434 -404.799938) (xy 347.299251 -404.818629) (xy 347.299788 -404.828756) (xy 347.299788 -405.11476)
			(xy 347.299997 -405.121632) (xy 347.303594 -405.134895) (xy 347.3069 -405.140922) (xy 347.323233 -405.16928)
			(xy 347.348975 -405.229447) (xy 347.3664 -405.292527) (xy 347.375193 -405.357375) (xy 347.375193 -405.422818)
			(xy 347.366402 -405.487667) (xy 347.348977 -405.550746) (xy 347.332186 -405.589994) (xy 348.603832 -405.589994)
			(xy 348.607823 -405.527827) (xy 348.619732 -405.46668) (xy 348.639361 -405.407559) (xy 348.66639 -405.351433)
			(xy 348.700374 -405.299224) (xy 348.740756 -405.251789) (xy 348.786872 -405.209908) (xy 348.837964 -405.174268)
			(xy 348.893195 -405.145454) (xy 348.951657 -405.12394) (xy 349.012391 -405.110078) (xy 349.074398 -405.104096)
			(xy 349.136661 -405.106092) (xy 349.198158 -405.116035) (xy 349.257879 -405.133759) (xy 349.314842 -405.158976)
			(xy 349.368113 -405.191269) (xy 349.416818 -405.230109) (xy 349.460155 -405.274859) (xy 349.497415 -405.324783)
			(xy 349.527984 -405.379062) (xy 349.532451 -405.390096) (xy 350.80398 -405.390096) (xy 350.807971 -405.327929)
			(xy 350.81988 -405.266782) (xy 350.839509 -405.207661) (xy 350.866538 -405.151535) (xy 350.900522 -405.099326)
			(xy 350.940904 -405.051891) (xy 350.98702 -405.01001) (xy 351.038112 -404.97437) (xy 351.093343 -404.945556)
			(xy 351.151805 -404.924042) (xy 351.212539 -404.91018) (xy 351.274546 -404.904198) (xy 351.336809 -404.906194)
			(xy 351.398306 -404.916137) (xy 351.458027 -404.933861) (xy 351.51499 -404.959078) (xy 351.568261 -404.991371)
			(xy 351.616966 -405.030211) (xy 351.660303 -405.074961) (xy 351.697563 -405.124885) (xy 351.728132 -405.179164)
			(xy 351.75151 -405.236907) (xy 351.767311 -405.297165) (xy 351.775277 -405.358948) (xy 351.775776 -405.390096)
			(xy 351.775277 -405.421244) (xy 351.767311 -405.483027) (xy 351.75151 -405.543285) (xy 351.728132 -405.601028)
			(xy 351.715917 -405.622717) (xy 375.004856 -405.622717) (xy 375.004857 -405.557273) (xy 375.013651 -405.492423)
			(xy 375.031079 -405.429343) (xy 375.056825 -405.369176) (xy 375.073164 -405.34082) (xy 375.076469 -405.33479)
			(xy 375.080081 -405.321531) (xy 375.080276 -405.314658) (xy 375.080276 -404.565358) (xy 375.080065 -404.558486)
			(xy 375.07647 -404.545223) (xy 375.073164 -404.539196) (xy 375.056845 -404.51083) (xy 375.031098 -404.450666)
			(xy 375.013668 -404.387588) (xy 375.004872 -404.32274) (xy 375.00487 -404.257298) (xy 375.013661 -404.192449)
			(xy 375.031085 -404.12937) (xy 375.056827 -404.069204) (xy 375.073164 -404.040848) (xy 375.076494 -404.034831)
			(xy 375.08009 -404.021561) (xy 375.080276 -404.014686) (xy 375.080276 -403.728682) (xy 375.08065 -403.718505)
			(xy 375.088448 -403.699702) (xy 375.102849 -403.685317) (xy 375.12166 -403.677539) (xy 375.131838 -403.67712)
			(xy 375.848118 -403.67712) (xy 375.858275 -403.677618) (xy 375.877041 -403.685395) (xy 375.891405 -403.699759)
			(xy 375.899182 -403.718525) (xy 375.89968 -403.728682) (xy 375.89968 -404.014686) (xy 375.89988 -404.021559)
			(xy 375.903483 -404.034821) (xy 375.906792 -404.040848) (xy 375.923147 -404.069194) (xy 375.948888 -404.129364)
			(xy 375.966311 -404.192446) (xy 375.975101 -404.257297) (xy 375.975098 -404.322741) (xy 375.966303 -404.387591)
			(xy 375.948875 -404.450672) (xy 375.92313 -404.510839) (xy 375.906792 -404.539196) (xy 375.903478 -404.545221)
			(xy 375.899872 -404.558484) (xy 375.89968 -404.565358) (xy 375.89968 -405.314658) (xy 375.89989 -405.32153)
			(xy 375.903486 -405.334793) (xy 375.906792 -405.34082) (xy 375.923123 -405.369179) (xy 375.948866 -405.429346)
			(xy 375.966292 -405.492425) (xy 375.975085 -405.557274) (xy 375.975086 -405.622716) (xy 375.966294 -405.687565)
			(xy 375.948869 -405.750645) (xy 375.923128 -405.810812) (xy 375.906792 -405.839168) (xy 375.903488 -405.845198)
			(xy 375.899876 -405.858458) (xy 375.89968 -405.86533) (xy 375.89968 -406.151334) (xy 375.899195 -406.161492)
			(xy 375.891413 -406.180258) (xy 375.877045 -406.194622) (xy 375.858276 -406.202398) (xy 375.848118 -406.202896)
			(xy 375.131838 -406.202896) (xy 375.121673 -406.202406) (xy 375.102886 -406.19464) (xy 375.088501 -406.180275)
			(xy 375.080708 -406.161498) (xy 375.080276 -406.151334) (xy 375.080276 -405.86533) (xy 375.080075 -405.858457)
			(xy 375.076473 -405.845194) (xy 375.073164 -405.839168) (xy 375.056821 -405.810815) (xy 375.031076 -405.750648)
			(xy 375.013649 -405.687567) (xy 375.004856 -405.622717) (xy 351.715917 -405.622717) (xy 351.697563 -405.655307)
			(xy 351.660303 -405.705231) (xy 351.616966 -405.749981) (xy 351.568261 -405.788821) (xy 351.51499 -405.821114)
			(xy 351.458027 -405.846331) (xy 351.398306 -405.864055) (xy 351.336809 -405.873998) (xy 351.274546 -405.875994)
			(xy 351.212539 -405.870012) (xy 351.151805 -405.85615) (xy 351.093343 -405.834636) (xy 351.038112 -405.805822)
			(xy 350.98702 -405.770182) (xy 350.940904 -405.728301) (xy 350.900522 -405.680866) (xy 350.866538 -405.628657)
			(xy 350.839509 -405.572531) (xy 350.81988 -405.51341) (xy 350.807971 -405.452263) (xy 350.80398 -405.390096)
			(xy 349.532451 -405.390096) (xy 349.551362 -405.436805) (xy 349.567163 -405.497063) (xy 349.575129 -405.558846)
			(xy 349.575628 -405.589994) (xy 349.575129 -405.621142) (xy 349.567163 -405.682925) (xy 349.551362 -405.743183)
			(xy 349.527984 -405.800926) (xy 349.497415 -405.855205) (xy 349.460155 -405.905129) (xy 349.416818 -405.949879)
			(xy 349.368113 -405.988719) (xy 349.314842 -406.021012) (xy 349.257879 -406.046229) (xy 349.198158 -406.063953)
			(xy 349.136661 -406.073896) (xy 349.074398 -406.075892) (xy 349.012391 -406.06991) (xy 348.951657 -406.056048)
			(xy 348.893195 -406.034534) (xy 348.837964 -406.00572) (xy 348.786872 -405.97008) (xy 348.740756 -405.928199)
			(xy 348.700374 -405.880764) (xy 348.66639 -405.828555) (xy 348.639361 -405.772429) (xy 348.619732 -405.713308)
			(xy 348.607823 -405.652161) (xy 348.603832 -405.589994) (xy 347.332186 -405.589994) (xy 347.323236 -405.610913)
			(xy 347.3069 -405.63927) (xy 347.303596 -405.6453) (xy 347.299984 -405.65856) (xy 347.299788 -405.665432)
			(xy 347.299788 -406.414732) (xy 347.299969 -406.421606) (xy 347.303585 -406.434869) (xy 347.3069 -406.440894)
			(xy 347.323209 -406.469266) (xy 347.348953 -406.529429) (xy 347.366381 -406.592506) (xy 347.375177 -406.657352)
			(xy 347.375179 -406.690068) (xy 350.80398 -406.690068) (xy 350.807971 -406.627901) (xy 350.81988 -406.566754)
			(xy 350.839509 -406.507633) (xy 350.866538 -406.451507) (xy 350.900522 -406.399298) (xy 350.940904 -406.351863)
			(xy 350.98702 -406.309982) (xy 351.038112 -406.274342) (xy 351.093343 -406.245528) (xy 351.151805 -406.224014)
			(xy 351.212539 -406.210152) (xy 351.274546 -406.20417) (xy 351.336809 -406.206166) (xy 351.398306 -406.216109)
			(xy 351.458027 -406.233833) (xy 351.51499 -406.25905) (xy 351.568261 -406.291343) (xy 351.616966 -406.330183)
			(xy 351.660303 -406.374933) (xy 351.697563 -406.424857) (xy 351.728132 -406.479136) (xy 351.75151 -406.536879)
			(xy 351.767311 -406.597137) (xy 351.775277 -406.65892) (xy 351.775776 -406.690068) (xy 351.775277 -406.721216)
			(xy 351.775073 -406.722795) (xy 377.204736 -406.722795) (xy 377.20474 -406.65735) (xy 377.213537 -406.592498)
			(xy 377.230969 -406.529417) (xy 377.256718 -406.46925) (xy 377.273058 -406.440894) (xy 377.276425 -406.43488)
			(xy 377.280159 -406.421619) (xy 377.280424 -406.414732) (xy 377.280424 -405.665432) (xy 377.280211 -405.658538)
			(xy 377.276469 -405.645265) (xy 377.273058 -405.63927) (xy 377.256717 -405.610916) (xy 377.230972 -405.550749)
			(xy 377.213545 -405.487668) (xy 377.204752 -405.422818) (xy 377.204753 -405.357375) (xy 377.213547 -405.292525)
			(xy 377.230974 -405.229445) (xy 377.25672 -405.169278) (xy 377.273058 -405.140922) (xy 377.276415 -405.134904)
			(xy 377.280155 -405.121646) (xy 377.280424 -405.11476) (xy 377.280424 -404.828756) (xy 377.28085 -404.818641)
			(xy 377.288606 -404.799958) (xy 377.302922 -404.785664) (xy 377.321617 -404.777935) (xy 377.331732 -404.777448)
			(xy 378.048012 -404.777448) (xy 378.058115 -404.777974) (xy 378.076783 -404.785706) (xy 378.091076 -404.79999)
			(xy 378.098819 -404.818653) (xy 378.09932 -404.828756) (xy 378.09932 -405.11476) (xy 378.099566 -405.12165)
			(xy 378.103299 -405.134916) (xy 378.106686 -405.140922) (xy 378.123019 -405.16928) (xy 378.148762 -405.229447)
			(xy 378.166188 -405.292526) (xy 378.174981 -405.357375) (xy 378.174981 -405.422818) (xy 378.166189 -405.487667)
			(xy 378.148764 -405.550747) (xy 378.123022 -405.610914) (xy 378.116223 -405.622716) (xy 379.404907 -405.622716)
			(xy 379.404907 -405.557273) (xy 379.4137 -405.492424) (xy 379.431126 -405.429344) (xy 379.456869 -405.369177)
			(xy 379.473206 -405.34082) (xy 379.47656 -405.3348) (xy 379.480302 -405.321543) (xy 379.480572 -405.314658)
			(xy 379.480572 -404.565358) (xy 379.480342 -404.558465) (xy 379.476611 -404.545193) (xy 379.473206 -404.539196)
			(xy 379.456888 -404.510829) (xy 379.431144 -404.450665) (xy 379.413717 -404.387587) (xy 379.404922 -404.322739)
			(xy 379.40492 -404.257298) (xy 379.41371 -404.19245) (xy 379.431132 -404.129371) (xy 379.456871 -404.069204)
			(xy 379.473206 -404.040848) (xy 379.476585 -404.03484) (xy 379.480312 -404.021574) (xy 379.480572 -404.014686)
			(xy 379.480572 -403.728682) (xy 379.481013 -403.71855) (xy 379.488752 -403.699822) (xy 379.503053 -403.685466)
			(xy 379.52175 -403.677653) (xy 379.53188 -403.67712) (xy 380.24816 -403.67712) (xy 380.258314 -403.677555)
			(xy 380.277069 -403.685341) (xy 380.291395 -403.699734) (xy 380.299092 -403.718526) (xy 380.299468 -403.728682)
			(xy 380.299468 -404.014686) (xy 380.299676 -404.021581) (xy 380.303421 -404.034853) (xy 380.306834 -404.040848)
			(xy 380.323191 -404.069194) (xy 380.348934 -404.129362) (xy 380.36636 -404.192445) (xy 380.375151 -404.257296)
			(xy 380.375148 -404.322741) (xy 380.366352 -404.387592) (xy 380.348922 -404.450673) (xy 380.323174 -404.51084)
			(xy 380.306834 -404.539196) (xy 380.30347 -404.545211) (xy 380.299734 -404.558471) (xy 380.299468 -404.565358)
			(xy 380.299468 -405.314658) (xy 380.299686 -405.321552) (xy 380.303424 -405.334824) (xy 380.306834 -405.34082)
			(xy 380.323167 -405.369179) (xy 380.348913 -405.429345) (xy 380.366341 -405.492424) (xy 380.375135 -405.557273)
			(xy 380.375136 -405.622716) (xy 380.366343 -405.687566) (xy 380.348916 -405.750646) (xy 380.323172 -405.810812)
			(xy 380.306834 -405.839168) (xy 380.30348 -405.845188) (xy 380.299738 -405.858445) (xy 380.299468 -405.86533)
			(xy 380.299468 -406.151334) (xy 380.299002 -406.161462) (xy 380.291264 -406.180182) (xy 380.276972 -406.194537)
			(xy 380.258286 -406.202357) (xy 380.24816 -406.202896) (xy 379.53188 -406.202896) (xy 379.521724 -406.202495)
			(xy 379.50297 -406.194692) (xy 379.488648 -406.180289) (xy 379.480949 -406.161492) (xy 379.480572 -406.151334)
			(xy 379.480572 -405.86533) (xy 379.480331 -405.858439) (xy 379.476594 -405.845173) (xy 379.473206 -405.839168)
			(xy 379.456865 -405.810814) (xy 379.431123 -405.750647) (xy 379.413698 -405.687566) (xy 379.404907 -405.622716)
			(xy 378.116223 -405.622716) (xy 378.106686 -405.63927) (xy 378.103335 -405.645292) (xy 378.099591 -405.658547)
			(xy 378.09932 -405.665432) (xy 378.09932 -406.414732) (xy 378.099577 -406.421621) (xy 378.103303 -406.434887)
			(xy 378.106686 -406.440894) (xy 378.122995 -406.469265) (xy 378.148741 -406.529429) (xy 378.166169 -406.592506)
			(xy 378.174965 -406.657352) (xy 378.174969 -406.722793) (xy 378.174969 -406.722795) (xy 381.604787 -406.722795)
			(xy 381.60479 -406.65735) (xy 381.613586 -406.592499) (xy 381.631016 -406.529418) (xy 381.656762 -406.469251)
			(xy 381.6731 -406.440894) (xy 381.676417 -406.43487) (xy 381.680021 -406.421606) (xy 381.680212 -406.414732)
			(xy 381.680212 -405.665432) (xy 381.680007 -405.65856) (xy 381.676407 -405.645297) (xy 381.6731 -405.63927)
			(xy 381.65676 -405.610915) (xy 381.631019 -405.550748) (xy 381.613594 -405.487667) (xy 381.604803 -405.422818)
			(xy 381.604803 -405.357375) (xy 381.613596 -405.292526) (xy 381.631021 -405.229446) (xy 381.656764 -405.169279)
			(xy 381.6731 -405.140922) (xy 381.676407 -405.134894) (xy 381.680017 -405.121633) (xy 381.680212 -405.11476)
			(xy 381.680212 -404.828756) (xy 381.680586 -404.818598) (xy 381.688398 -404.799842) (xy 381.702809 -404.78552)
			(xy 381.721613 -404.777824) (xy 381.731774 -404.777448) (xy 382.448054 -404.777448) (xy 382.458179 -404.777965)
			(xy 382.4769 -404.785679) (xy 382.491258 -404.799956) (xy 382.499078 -404.818634) (xy 382.499616 -404.828756)
			(xy 382.499616 -405.11476) (xy 382.499821 -405.121632) (xy 382.50342 -405.134895) (xy 382.506728 -405.140922)
			(xy 382.523063 -405.16928) (xy 382.548809 -405.229446) (xy 382.566237 -405.292525) (xy 382.575031 -405.357375)
			(xy 382.575031 -405.422818) (xy 382.566238 -405.487668) (xy 382.548811 -405.550748) (xy 382.523066 -405.610914)
			(xy 382.516265 -405.622717) (xy 383.804943 -405.622717) (xy 383.804943 -405.557273) (xy 383.813737 -405.492423)
			(xy 383.831165 -405.429343) (xy 383.85691 -405.369176) (xy 383.873248 -405.34082) (xy 383.876551 -405.33479)
			(xy 383.880165 -405.32153) (xy 383.88036 -405.314658) (xy 383.88036 -404.565358) (xy 383.880151 -404.558486)
			(xy 383.876555 -404.545223) (xy 383.873248 -404.539196) (xy 383.856929 -404.51083) (xy 383.831183 -404.450665)
			(xy 383.813754 -404.387587) (xy 383.804959 -404.32274) (xy 383.804956 -404.257298) (xy 383.813746 -404.19245)
			(xy 383.83117 -404.12937) (xy 383.856912 -404.069204) (xy 383.873248 -404.040848) (xy 383.876577 -404.03483)
			(xy 383.880174 -404.021561) (xy 383.88036 -404.014686) (xy 383.88036 -403.728682) (xy 383.88075 -403.718507)
			(xy 383.888545 -403.699707) (xy 383.902941 -403.685322) (xy 383.921746 -403.677542) (xy 383.931922 -403.67712)
			(xy 384.648202 -403.67712) (xy 384.658358 -403.677631) (xy 384.677123 -403.685403) (xy 384.691488 -403.699763)
			(xy 384.699265 -403.718526) (xy 384.699764 -403.728682) (xy 384.699764 -404.014686) (xy 384.699966 -404.021558)
			(xy 384.703568 -404.034821) (xy 384.706876 -404.040848) (xy 384.723232 -404.069194) (xy 384.748973 -404.129363)
			(xy 384.766397 -404.192445) (xy 384.775187 -404.257297) (xy 384.775185 -404.322741) (xy 384.766389 -404.387592)
			(xy 384.74896 -404.450672) (xy 384.723214 -404.51084) (xy 384.706876 -404.539196) (xy 384.703561 -404.54522)
			(xy 384.699956 -404.558484) (xy 384.699764 -404.565358) (xy 384.699764 -405.314658) (xy 384.699976 -405.32153)
			(xy 384.703571 -405.334792) (xy 384.706876 -405.34082) (xy 384.723208 -405.369179) (xy 384.748951 -405.429345)
			(xy 384.766378 -405.492425) (xy 384.775171 -405.557274) (xy 384.775172 -405.622716) (xy 384.76638 -405.687565)
			(xy 384.748955 -405.750645) (xy 384.723213 -405.810812) (xy 384.706876 -405.839168) (xy 384.703571 -405.845197)
			(xy 384.69996 -405.858457) (xy 384.699764 -405.86533) (xy 384.699764 -406.151334) (xy 384.699295 -406.161494)
			(xy 384.691509 -406.180263) (xy 384.677136 -406.194627) (xy 384.658362 -406.202401) (xy 384.648202 -406.202896)
			(xy 383.931922 -406.202896) (xy 383.92177 -406.20235) (xy 383.903008 -406.194589) (xy 383.888643 -406.180239)
			(xy 383.880861 -406.161486) (xy 383.88036 -406.151334) (xy 383.88036 -405.86533) (xy 383.880162 -405.858457)
			(xy 383.876558 -405.845194) (xy 383.873248 -405.839168) (xy 383.856905 -405.810815) (xy 383.831161 -405.750647)
			(xy 383.813735 -405.687567) (xy 383.804943 -405.622717) (xy 382.516265 -405.622717) (xy 382.506728 -405.63927)
			(xy 382.503426 -405.645301) (xy 382.499812 -405.65856) (xy 382.499616 -405.665432) (xy 382.499616 -406.414732)
			(xy 382.499794 -406.421606) (xy 382.503411 -406.434869) (xy 382.506728 -406.440894) (xy 382.523039 -406.469265)
			(xy 382.548787 -406.529428) (xy 382.566218 -406.592505) (xy 382.575015 -406.657352) (xy 382.575019 -406.722793)
			(xy 382.575019 -406.722795) (xy 386.004823 -406.722795) (xy 386.004826 -406.65735) (xy 386.013623 -406.592499)
			(xy 386.031054 -406.529417) (xy 386.056802 -406.46925) (xy 386.073142 -406.440894) (xy 386.076507 -406.43488)
			(xy 386.080242 -406.421619) (xy 386.080508 -406.414732) (xy 386.080508 -405.665432) (xy 386.080261 -405.658542)
			(xy 386.076528 -405.645276) (xy 386.073142 -405.63927) (xy 386.056801 -405.610916) (xy 386.031057 -405.550749)
			(xy 386.013631 -405.487668) (xy 386.004839 -405.422818) (xy 386.004839 -405.357375) (xy 386.013633 -405.292525)
			(xy 386.03106 -405.229445) (xy 386.056804 -405.169278) (xy 386.073142 -405.140922) (xy 386.076498 -405.134903)
			(xy 386.080239 -405.121646) (xy 386.080508 -405.11476) (xy 386.080508 -404.828756) (xy 386.080949 -404.818643)
			(xy 386.088703 -404.799963) (xy 386.103013 -404.785669) (xy 386.121703 -404.777938) (xy 386.131816 -404.777448)
			(xy 386.848096 -404.777448) (xy 386.858198 -404.777987) (xy 386.876866 -404.785714) (xy 386.891159 -404.799993)
			(xy 386.898903 -404.818654) (xy 386.899404 -404.828756) (xy 386.899404 -405.11476) (xy 386.899652 -405.12165)
			(xy 386.903384 -405.134916) (xy 386.90677 -405.140922) (xy 386.923104 -405.16928) (xy 386.948847 -405.229446)
			(xy 386.966274 -405.292526) (xy 386.975067 -405.357375) (xy 386.975068 -405.422818) (xy 386.966275 -405.487667)
			(xy 386.94885 -405.550747) (xy 386.923107 -405.610914) (xy 386.916307 -405.622717) (xy 388.204732 -405.622717)
			(xy 388.204733 -405.557273) (xy 388.213527 -405.492423) (xy 388.230954 -405.429343) (xy 388.256698 -405.369176)
			(xy 388.273036 -405.34082) (xy 388.276339 -405.334789) (xy 388.279953 -405.32153) (xy 388.280148 -405.314658)
			(xy 388.280148 -404.565358) (xy 388.279941 -404.558486) (xy 388.276344 -404.545223) (xy 388.273036 -404.539196)
			(xy 388.256717 -404.51083) (xy 388.230972 -404.450665) (xy 388.213544 -404.387587) (xy 388.204748 -404.32274)
			(xy 388.204746 -404.257298) (xy 388.213536 -404.19245) (xy 388.230959 -404.129371) (xy 388.2567 -404.069204)
			(xy 388.273036 -404.040848) (xy 388.276364 -404.03483) (xy 388.279962 -404.021561) (xy 388.280148 -404.014686)
			(xy 388.280148 -403.728682) (xy 388.280619 -403.718522) (xy 388.288401 -403.69975) (xy 388.302774 -403.685385)
			(xy 388.32155 -403.677613) (xy 388.33171 -403.67712) (xy 389.04799 -403.67712) (xy 389.058145 -403.677641)
			(xy 389.07691 -403.685409) (xy 389.091275 -403.699766) (xy 389.099053 -403.718527) (xy 389.099552 -403.728682)
			(xy 389.099552 -404.014686) (xy 389.099743 -404.021559) (xy 389.103351 -404.034822) (xy 389.106664 -404.040848)
			(xy 389.12302 -404.069194) (xy 389.148762 -404.129363) (xy 389.166186 -404.192445) (xy 389.174977 -404.257297)
			(xy 389.174975 -404.290022) (xy 392.603744 -404.290022) (xy 392.607735 -404.227855) (xy 392.619644 -404.166708)
			(xy 392.639273 -404.107587) (xy 392.666302 -404.051461) (xy 392.700286 -403.999252) (xy 392.740668 -403.951817)
			(xy 392.786784 -403.909936) (xy 392.837876 -403.874296) (xy 392.893107 -403.845482) (xy 392.951569 -403.823968)
			(xy 393.012303 -403.810106) (xy 393.07431 -403.804124) (xy 393.136573 -403.80612) (xy 393.19807 -403.816063)
			(xy 393.257791 -403.833787) (xy 393.314754 -403.859004) (xy 393.368025 -403.891297) (xy 393.41673 -403.930137)
			(xy 393.460067 -403.974887) (xy 393.497327 -404.024811) (xy 393.527896 -404.07909) (xy 393.551274 -404.136833)
			(xy 393.567075 -404.197091) (xy 393.575041 -404.258874) (xy 393.57554 -404.290022) (xy 393.575041 -404.32117)
			(xy 393.567075 -404.382953) (xy 393.551274 -404.443211) (xy 393.527896 -404.500954) (xy 393.497327 -404.555233)
			(xy 393.460067 -404.605157) (xy 393.41673 -404.649907) (xy 393.368025 -404.688747) (xy 393.314754 -404.72104)
			(xy 393.257791 -404.746257) (xy 393.19807 -404.763981) (xy 393.136573 -404.773924) (xy 393.07431 -404.77592)
			(xy 393.012303 -404.769938) (xy 392.951569 -404.756076) (xy 392.893107 -404.734562) (xy 392.837876 -404.705748)
			(xy 392.786784 -404.670108) (xy 392.740668 -404.628227) (xy 392.700286 -404.580792) (xy 392.666302 -404.528583)
			(xy 392.639273 -404.472457) (xy 392.619644 -404.413336) (xy 392.607735 -404.352189) (xy 392.603744 -404.290022)
			(xy 389.174975 -404.290022) (xy 389.174974 -404.322741) (xy 389.166179 -404.387592) (xy 389.148749 -404.450673)
			(xy 389.123003 -404.51084) (xy 389.106664 -404.539196) (xy 389.103356 -404.545224) (xy 389.099745 -404.558485)
			(xy 389.099552 -404.565358) (xy 389.099552 -405.314658) (xy 389.099753 -405.321531) (xy 389.103354 -405.334794)
			(xy 389.106664 -405.34082) (xy 389.122996 -405.369179) (xy 389.14874 -405.429345) (xy 389.166167 -405.492425)
			(xy 389.174961 -405.557274) (xy 389.174962 -405.622716) (xy 389.166169 -405.687565) (xy 389.148744 -405.750645)
			(xy 389.123001 -405.810812) (xy 389.106664 -405.839168) (xy 389.103366 -405.845201) (xy 389.099749 -405.858458)
			(xy 389.099552 -405.86533) (xy 389.099552 -406.151334) (xy 389.099094 -406.161495) (xy 389.091307 -406.180267)
			(xy 389.07693 -406.194631) (xy 389.058152 -406.202403) (xy 389.04799 -406.202896) (xy 388.33171 -406.202896)
			(xy 388.321557 -406.202359) (xy 388.302795 -406.194594) (xy 388.28843 -406.180242) (xy 388.280649 -406.161487)
			(xy 388.280148 -406.151334) (xy 388.280148 -405.86533) (xy 388.279951 -405.858457) (xy 388.276347 -405.845194)
			(xy 388.273036 -405.839168) (xy 388.256694 -405.810815) (xy 388.23095 -405.750647) (xy 388.213525 -405.687567)
			(xy 388.204732 -405.622717) (xy 386.916307 -405.622717) (xy 386.90677 -405.63927) (xy 386.903418 -405.645291)
			(xy 386.899675 -405.658547) (xy 386.899404 -405.665432) (xy 386.899404 -406.414732) (xy 386.899663 -406.421621)
			(xy 386.903388 -406.434887) (xy 386.90677 -406.440894) (xy 386.92308 -406.469265) (xy 386.948826 -406.529429)
			(xy 386.966255 -406.592505) (xy 386.975051 -406.657352) (xy 386.975055 -406.722793) (xy 386.975055 -406.722795)
			(xy 390.404859 -406.722795) (xy 390.404863 -406.65735) (xy 390.41366 -406.592498) (xy 390.431093 -406.529417)
			(xy 390.456843 -406.46925) (xy 390.473184 -406.440894) (xy 390.4765 -406.43487) (xy 390.480105 -406.421606)
			(xy 390.480296 -406.414732) (xy 390.480296 -405.665432) (xy 390.480092 -405.65856) (xy 390.476492 -405.645297)
			(xy 390.473184 -405.63927) (xy 390.456842 -405.610916) (xy 390.431096 -405.550749) (xy 390.413668 -405.487669)
			(xy 390.404875 -405.422818) (xy 390.404875 -405.357375) (xy 390.41367 -405.292524) (xy 390.431098 -405.229444)
			(xy 390.456845 -405.169278) (xy 390.473184 -405.140922) (xy 390.47649 -405.134893) (xy 390.480101 -405.121633)
			(xy 390.480296 -405.11476) (xy 390.480296 -404.828756) (xy 390.480686 -404.8186) (xy 390.488495 -404.799847)
			(xy 390.502901 -404.785525) (xy 390.521699 -404.777826) (xy 390.531858 -404.777448) (xy 391.248138 -404.777448)
			(xy 391.258268 -404.777896) (xy 391.276992 -404.785637) (xy 391.291347 -404.799935) (xy 391.299163 -404.818628)
			(xy 391.2997 -404.828756) (xy 391.2997 -405.11476) (xy 391.299907 -405.121632) (xy 391.303505 -405.134895)
			(xy 391.306812 -405.140922) (xy 391.323148 -405.16928) (xy 391.348894 -405.229445) (xy 391.366323 -405.292525)
			(xy 391.375117 -405.357375) (xy 391.375118 -405.422818) (xy 391.366324 -405.487668) (xy 391.348897 -405.550748)
			(xy 391.332103 -405.589994) (xy 392.603744 -405.589994) (xy 392.607735 -405.527827) (xy 392.619644 -405.46668)
			(xy 392.639273 -405.407559) (xy 392.666302 -405.351433) (xy 392.700286 -405.299224) (xy 392.740668 -405.251789)
			(xy 392.786784 -405.209908) (xy 392.837876 -405.174268) (xy 392.893107 -405.145454) (xy 392.951569 -405.12394)
			(xy 393.012303 -405.110078) (xy 393.07431 -405.104096) (xy 393.136573 -405.106092) (xy 393.19807 -405.116035)
			(xy 393.257791 -405.133759) (xy 393.314754 -405.158976) (xy 393.368025 -405.191269) (xy 393.41673 -405.230109)
			(xy 393.460067 -405.274859) (xy 393.497327 -405.324783) (xy 393.527896 -405.379062) (xy 393.532363 -405.390096)
			(xy 394.803892 -405.390096) (xy 394.807883 -405.327929) (xy 394.819792 -405.266782) (xy 394.839421 -405.207661)
			(xy 394.86645 -405.151535) (xy 394.900434 -405.099326) (xy 394.940816 -405.051891) (xy 394.986932 -405.01001)
			(xy 395.038024 -404.97437) (xy 395.093255 -404.945556) (xy 395.151717 -404.924042) (xy 395.212451 -404.91018)
			(xy 395.274458 -404.904198) (xy 395.336721 -404.906194) (xy 395.398218 -404.916137) (xy 395.457939 -404.933861)
			(xy 395.514902 -404.959078) (xy 395.568173 -404.991371) (xy 395.616878 -405.030211) (xy 395.660215 -405.074961)
			(xy 395.697475 -405.124885) (xy 395.728044 -405.179164) (xy 395.751422 -405.236907) (xy 395.767223 -405.297165)
			(xy 395.775189 -405.358948) (xy 395.775688 -405.390096) (xy 395.775189 -405.421244) (xy 395.767223 -405.483027)
			(xy 395.751422 -405.543285) (xy 395.728044 -405.601028) (xy 395.697475 -405.655307) (xy 395.660215 -405.705231)
			(xy 395.616878 -405.749981) (xy 395.568173 -405.788821) (xy 395.514902 -405.821114) (xy 395.457939 -405.846331)
			(xy 395.398218 -405.864055) (xy 395.336721 -405.873998) (xy 395.274458 -405.875994) (xy 395.212451 -405.870012)
			(xy 395.151717 -405.85615) (xy 395.093255 -405.834636) (xy 395.038024 -405.805822) (xy 394.986932 -405.770182)
			(xy 394.940816 -405.728301) (xy 394.900434 -405.680866) (xy 394.86645 -405.628657) (xy 394.839421 -405.572531)
			(xy 394.819792 -405.51341) (xy 394.807883 -405.452263) (xy 394.803892 -405.390096) (xy 393.532363 -405.390096)
			(xy 393.551274 -405.436805) (xy 393.567075 -405.497063) (xy 393.575041 -405.558846) (xy 393.57554 -405.589994)
			(xy 393.575041 -405.621142) (xy 393.567075 -405.682925) (xy 393.551274 -405.743183) (xy 393.527896 -405.800926)
			(xy 393.497327 -405.855205) (xy 393.460067 -405.905129) (xy 393.41673 -405.949879) (xy 393.368025 -405.988719)
			(xy 393.314754 -406.021012) (xy 393.257791 -406.046229) (xy 393.19807 -406.063953) (xy 393.136573 -406.073896)
			(xy 393.07431 -406.075892) (xy 393.012303 -406.06991) (xy 392.951569 -406.056048) (xy 392.893107 -406.034534)
			(xy 392.837876 -406.00572) (xy 392.786784 -405.97008) (xy 392.740668 -405.928199) (xy 392.700286 -405.880764)
			(xy 392.666302 -405.828555) (xy 392.639273 -405.772429) (xy 392.619644 -405.713308) (xy 392.607735 -405.652161)
			(xy 392.603744 -405.589994) (xy 391.332103 -405.589994) (xy 391.323151 -405.610914) (xy 391.306812 -405.63927)
			(xy 391.303509 -405.6453) (xy 391.299896 -405.65856) (xy 391.2997 -405.665432) (xy 391.2997 -406.414732)
			(xy 391.29988 -406.421606) (xy 391.303496 -406.434869) (xy 391.306812 -406.440894) (xy 391.323124 -406.469265)
			(xy 391.348873 -406.529427) (xy 391.366304 -406.592505) (xy 391.375101 -406.657352) (xy 391.375103 -406.690068)
			(xy 394.803892 -406.690068) (xy 394.807883 -406.627901) (xy 394.819792 -406.566754) (xy 394.839421 -406.507633)
			(xy 394.86645 -406.451507) (xy 394.900434 -406.399298) (xy 394.940816 -406.351863) (xy 394.986932 -406.309982)
			(xy 395.038024 -406.274342) (xy 395.093255 -406.245528) (xy 395.151717 -406.224014) (xy 395.212451 -406.210152)
			(xy 395.274458 -406.20417) (xy 395.336721 -406.206166) (xy 395.398218 -406.216109) (xy 395.457939 -406.233833)
			(xy 395.514902 -406.25905) (xy 395.568173 -406.291343) (xy 395.616878 -406.330183) (xy 395.660215 -406.374933)
			(xy 395.697475 -406.424857) (xy 395.728044 -406.479136) (xy 395.751422 -406.536879) (xy 395.767223 -406.597137)
			(xy 395.775189 -406.65892) (xy 395.775688 -406.690068) (xy 395.775189 -406.721216) (xy 395.767223 -406.782999)
			(xy 395.751422 -406.843257) (xy 395.728044 -406.901) (xy 395.697475 -406.955279) (xy 395.660215 -407.005203)
			(xy 395.616878 -407.049953) (xy 395.568173 -407.088793) (xy 395.514902 -407.121086) (xy 395.457939 -407.146303)
			(xy 395.398218 -407.164027) (xy 395.336721 -407.17397) (xy 395.274458 -407.175966) (xy 395.212451 -407.169984)
			(xy 395.151717 -407.156122) (xy 395.093255 -407.134608) (xy 395.038024 -407.105794) (xy 394.986932 -407.070154)
			(xy 394.940816 -407.028273) (xy 394.900434 -406.980838) (xy 394.86645 -406.928629) (xy 394.839421 -406.872503)
			(xy 394.819792 -406.813382) (xy 394.807883 -406.752235) (xy 394.803892 -406.690068) (xy 391.375103 -406.690068)
			(xy 391.375105 -406.722793) (xy 391.366315 -406.787642) (xy 391.348891 -406.850721) (xy 391.323149 -406.910886)
			(xy 391.306812 -406.939242) (xy 391.303483 -406.94526) (xy 391.299886 -406.958529) (xy 391.2997 -406.965404)
			(xy 391.2997 -407.251408) (xy 391.299285 -407.261563) (xy 391.291487 -407.280315) (xy 391.277088 -407.294638)
			(xy 391.258295 -407.302338) (xy 391.248138 -407.302716) (xy 390.531858 -407.302716) (xy 390.521723 -407.302307)
			(xy 390.502993 -407.294557) (xy 390.488636 -407.280247) (xy 390.480826 -407.261541) (xy 390.480296 -407.251408)
			(xy 390.480296 -406.965404) (xy 390.480103 -406.958531) (xy 390.476496 -406.945268) (xy 390.473184 -406.939242)
			(xy 390.456818 -406.910901) (xy 390.431074 -406.850731) (xy 390.413649 -406.787648) (xy 390.404859 -406.722795)
			(xy 386.975055 -406.722795) (xy 386.966266 -406.787641) (xy 386.948844 -406.85072) (xy 386.923105 -406.910886)
			(xy 386.90677 -406.939242) (xy 386.903393 -406.945251) (xy 386.899665 -406.958516) (xy 386.899404 -406.965404)
			(xy 386.899404 -407.251408) (xy 386.898921 -407.261517) (xy 386.891182 -407.280194) (xy 386.876884 -407.294489)
			(xy 386.858205 -407.302224) (xy 386.848096 -407.302716) (xy 386.131816 -407.302716) (xy 386.121697 -407.302271)
			(xy 386.102996 -407.294531) (xy 386.088682 -407.280224) (xy 386.080933 -407.261527) (xy 386.080508 -407.251408)
			(xy 386.080508 -406.965404) (xy 386.080272 -406.958513) (xy 386.076531 -406.945247) (xy 386.073142 -406.939242)
			(xy 386.056777 -406.910901) (xy 386.031036 -406.850731) (xy 386.013612 -406.787647) (xy 386.004823 -406.722795)
			(xy 382.575019 -406.722795) (xy 382.566229 -406.787641) (xy 382.548806 -406.85072) (xy 382.523064 -406.910886)
			(xy 382.506728 -406.939242) (xy 382.5034 -406.94526) (xy 382.499802 -406.958529) (xy 382.499616 -406.965404)
			(xy 382.499616 -407.251408) (xy 382.499185 -407.261561) (xy 382.49139 -407.28031) (xy 382.476996 -407.294632)
			(xy 382.458209 -407.302335) (xy 382.448054 -407.302716) (xy 381.731774 -407.302716) (xy 381.72164 -407.302294)
			(xy 381.70291 -407.294549) (xy 381.688553 -407.280243) (xy 381.680743 -407.26154) (xy 381.680212 -407.251408)
			(xy 381.680212 -406.965404) (xy 381.680017 -406.958531) (xy 381.676411 -406.945268) (xy 381.6731 -406.939242)
			(xy 381.656737 -406.9109) (xy 381.630997 -406.85073) (xy 381.613575 -406.787647) (xy 381.604787 -406.722795)
			(xy 378.174969 -406.722795) (xy 378.16618 -406.78764) (xy 378.148759 -406.850719) (xy 378.12302 -406.910886)
			(xy 378.106686 -406.939242) (xy 378.10331 -406.945251) (xy 378.099581 -406.958516) (xy 378.09932 -406.965404)
			(xy 378.09932 -407.251408) (xy 378.098822 -407.261515) (xy 378.091085 -407.280189) (xy 378.076793 -407.294483)
			(xy 378.058119 -407.302221) (xy 378.048012 -407.302716) (xy 377.331732 -407.302716) (xy 377.321614 -407.302258)
			(xy 377.302914 -407.294524) (xy 377.288599 -407.28022) (xy 377.280849 -407.261526) (xy 377.280424 -407.251408)
			(xy 377.280424 -406.965404) (xy 377.280221 -406.958509) (xy 377.276473 -406.945237) (xy 377.273058 -406.939242)
			(xy 377.256693 -406.910901) (xy 377.230951 -406.850731) (xy 377.213526 -406.787648) (xy 377.204736 -406.722795)
			(xy 351.775073 -406.722795) (xy 351.767311 -406.782999) (xy 351.75151 -406.843257) (xy 351.728132 -406.901)
			(xy 351.697563 -406.955279) (xy 351.660303 -407.005203) (xy 351.616966 -407.049953) (xy 351.568261 -407.088793)
			(xy 351.51499 -407.121086) (xy 351.458027 -407.146303) (xy 351.398306 -407.164027) (xy 351.336809 -407.17397)
			(xy 351.274546 -407.175966) (xy 351.212539 -407.169984) (xy 351.151805 -407.156122) (xy 351.093343 -407.134608)
			(xy 351.038112 -407.105794) (xy 350.98702 -407.070154) (xy 350.940904 -407.028273) (xy 350.900522 -406.980838)
			(xy 350.866538 -406.928629) (xy 350.839509 -406.872503) (xy 350.81988 -406.813382) (xy 350.807971 -406.752235)
			(xy 350.80398 -406.690068) (xy 347.375179 -406.690068) (xy 347.375181 -406.722793) (xy 347.366392 -406.78764)
			(xy 347.348972 -406.850719) (xy 347.323234 -406.910885) (xy 347.3069 -406.939242) (xy 347.30357 -406.945259)
			(xy 347.299974 -406.958529) (xy 347.299788 -406.965404) (xy 347.299788 -407.251408) (xy 347.299385 -407.261564)
			(xy 347.291584 -407.280319) (xy 347.277182 -407.294642) (xy 347.258384 -407.30234) (xy 347.248226 -407.302716)
			(xy 346.531946 -407.302716) (xy 346.521817 -407.302234) (xy 346.503088 -407.294514) (xy 346.488729 -407.280225)
			(xy 346.480916 -407.261535) (xy 346.480384 -407.251408) (xy 346.480384 -406.965404) (xy 346.480192 -406.958531)
			(xy 346.476584 -406.945268) (xy 346.473272 -406.939242) (xy 346.456906 -406.910901) (xy 346.431163 -406.850731)
			(xy 346.413739 -406.787648) (xy 346.404949 -406.722795) (xy 342.975145 -406.722795) (xy 342.966355 -406.787641)
			(xy 342.948933 -406.85072) (xy 342.923193 -406.910886) (xy 342.906858 -406.939242) (xy 342.90348 -406.94525)
			(xy 342.899753 -406.958516) (xy 342.899492 -406.965404) (xy 342.899492 -407.251408) (xy 342.89909 -407.261532)
			(xy 342.891338 -407.280237) (xy 342.877017 -407.294551) (xy 342.858308 -407.302295) (xy 342.848184 -407.302716)
			(xy 342.131904 -407.302716) (xy 342.121798 -407.302212) (xy 342.103122 -407.294479) (xy 342.088828 -407.280188)
			(xy 342.08109 -407.261514) (xy 342.080596 -407.251408) (xy 342.080596 -406.965404) (xy 342.080362 -406.958513)
			(xy 342.07662 -406.945247) (xy 342.07323 -406.939242) (xy 342.056866 -406.910901) (xy 342.031125 -406.85073)
			(xy 342.013702 -406.787647) (xy 342.004912 -406.722795) (xy 338.575108 -406.722795) (xy 338.566319 -406.787642)
			(xy 338.548895 -406.850721) (xy 338.523153 -406.910886) (xy 338.506816 -406.939242) (xy 338.503487 -406.94526)
			(xy 338.49989 -406.958529) (xy 338.499704 -406.965404) (xy 338.499704 -407.251408) (xy 338.499285 -407.261562)
			(xy 338.491487 -407.280314) (xy 338.47709 -407.294637) (xy 338.458298 -407.302337) (xy 338.448142 -407.302716)
			(xy 337.731862 -407.302716) (xy 337.721727 -407.302303) (xy 337.702997 -407.294555) (xy 337.688641 -407.280246)
			(xy 337.68083 -407.261541) (xy 337.6803 -407.251408) (xy 337.6803 -406.965404) (xy 337.680107 -406.958531)
			(xy 337.6765 -406.945268) (xy 337.673188 -406.939242) (xy 337.656822 -406.910901) (xy 337.631078 -406.850732)
			(xy 337.613653 -406.787648) (xy 337.604862 -406.722795) (xy 334.175058 -406.722795) (xy 334.16627 -406.787641)
			(xy 334.148848 -406.850719) (xy 334.123109 -406.910886) (xy 334.106774 -406.939242) (xy 334.103397 -406.945251)
			(xy 334.099669 -406.958516) (xy 334.099408 -406.965404) (xy 334.099408 -407.251408) (xy 334.098921 -407.261516)
			(xy 334.091183 -407.280193) (xy 334.076886 -407.294487) (xy 334.058208 -407.302223) (xy 334.0481 -407.302716)
			(xy 333.33182 -407.302716) (xy 333.321701 -407.302268) (xy 333.303001 -407.29453) (xy 333.288686 -407.280223)
			(xy 333.280937 -407.261527) (xy 333.280512 -407.251408) (xy 333.280512 -406.965404) (xy 333.280311 -406.958509)
			(xy 333.276561 -406.945236) (xy 333.273146 -406.939242) (xy 333.256781 -406.910901) (xy 333.23104 -406.850731)
			(xy 333.213616 -406.787648) (xy 333.204826 -406.722795) (xy 326.525636 -406.722795) (xy 326.525636 -409.522892)
			(xy 331.004929 -409.522892) (xy 331.004933 -409.457446) (xy 331.013731 -409.392595) (xy 331.031162 -409.329513)
			(xy 331.056912 -409.269346) (xy 331.073252 -409.24099) (xy 331.076566 -409.234965) (xy 331.080173 -409.221702)
			(xy 331.080364 -409.214828) (xy 331.080364 -408.465528) (xy 331.080166 -408.458655) (xy 331.076562 -408.445392)
			(xy 331.073252 -408.439366) (xy 331.056907 -408.411014) (xy 331.031163 -408.350846) (xy 331.013737 -408.287765)
			(xy 331.004945 -408.222915) (xy 331.004946 -408.157471) (xy 331.01374 -408.092621) (xy 331.031168 -408.029541)
			(xy 331.056914 -407.969374) (xy 331.073252 -407.941018) (xy 331.076556 -407.934988) (xy 331.080169 -407.921729)
			(xy 331.080364 -407.914856) (xy 331.080364 -407.628852) (xy 331.080782 -407.618699) (xy 331.088586 -407.599953)
			(xy 331.102983 -407.585633) (xy 331.121771 -407.577928) (xy 331.131926 -407.577544) (xy 331.848206 -407.577544)
			(xy 331.858334 -407.578022) (xy 331.877056 -407.585752) (xy 331.891412 -407.600041) (xy 331.89923 -407.618727)
			(xy 331.899768 -407.628852) (xy 331.899768 -407.914856) (xy 331.899981 -407.921728) (xy 331.903575 -407.93499)
			(xy 331.90688 -407.941018) (xy 331.92321 -407.969378) (xy 331.948954 -408.029544) (xy 331.96638 -408.092623)
			(xy 331.975173 -408.157472) (xy 331.975174 -408.222914) (xy 331.966383 -408.287763) (xy 331.948958 -408.350843)
			(xy 331.923216 -408.41101) (xy 331.90688 -408.439366) (xy 331.903576 -408.445396) (xy 331.899964 -408.458656)
			(xy 331.899768 -408.465528) (xy 331.899768 -409.214828) (xy 331.899953 -409.221702) (xy 331.903567 -409.234964)
			(xy 331.90688 -409.24099) (xy 331.923186 -409.269363) (xy 331.948932 -409.329526) (xy 331.966361 -409.392603)
			(xy 331.975157 -409.457449) (xy 331.975162 -409.522889) (xy 331.966374 -409.587737) (xy 331.948952 -409.650815)
			(xy 331.923214 -409.710982) (xy 331.90688 -409.739338) (xy 331.90355 -409.745355) (xy 331.899954 -409.758625)
			(xy 331.899768 -409.7655) (xy 331.899768 -410.051504) (xy 331.899381 -410.061662) (xy 331.891578 -410.080421)
			(xy 331.87717 -410.094745) (xy 331.858367 -410.102439) (xy 331.848206 -410.102812) (xy 331.131926 -410.102812)
			(xy 331.121807 -410.102254) (xy 331.103097 -410.094544) (xy 331.088741 -410.08028) (xy 331.080912 -410.061619)
			(xy 331.080364 -410.051504) (xy 331.080364 -409.7655) (xy 331.080176 -409.758626) (xy 331.076566 -409.745363)
			(xy 331.073252 -409.739338) (xy 331.056884 -409.710999) (xy 331.031142 -409.650828) (xy 331.013718 -409.587745)
			(xy 331.004929 -409.522892) (xy 326.525636 -409.522892) (xy 326.525636 -410.622708) (xy 333.204835 -410.622708)
			(xy 333.204837 -410.557264) (xy 333.213632 -410.492414) (xy 333.231061 -410.429333) (xy 333.256807 -410.369166)
			(xy 333.273146 -410.34081) (xy 333.276506 -410.334793) (xy 333.280244 -410.321534) (xy 333.280512 -410.314648)
			(xy 333.280512 -409.565348) (xy 333.280294 -409.558454) (xy 333.276556 -409.545182) (xy 333.273146 -409.539186)
			(xy 333.256819 -409.510824) (xy 333.231073 -409.450659) (xy 333.213646 -409.38758) (xy 333.204851 -409.322731)
			(xy 333.20485 -409.257289) (xy 333.213641 -409.19244) (xy 333.231067 -409.129361) (xy 333.256809 -409.069194)
			(xy 333.273146 -409.040838) (xy 333.276531 -409.034834) (xy 333.280253 -409.021565) (xy 333.280512 -409.014676)
			(xy 333.280512 -408.728672) (xy 333.280962 -408.71856) (xy 333.288711 -408.699879) (xy 333.303019 -408.685585)
			(xy 333.321708 -408.677853) (xy 333.33182 -408.677364) (xy 334.0481 -408.677364) (xy 334.058204 -408.677884)
			(xy 334.076876 -408.685615) (xy 334.091169 -408.699901) (xy 334.09891 -408.718568) (xy 334.099408 -408.728672)
			(xy 334.099408 -409.014676) (xy 334.099649 -409.021567) (xy 334.103386 -409.034833) (xy 334.106774 -409.040838)
			(xy 334.123121 -409.069189) (xy 334.148863 -409.129357) (xy 334.166288 -409.192438) (xy 334.17508 -409.257288)
			(xy 334.175078 -409.322732) (xy 334.166284 -409.387582) (xy 334.148857 -409.450663) (xy 334.123112 -409.51083)
			(xy 334.116162 -409.522892) (xy 335.404979 -409.522892) (xy 335.404983 -409.457447) (xy 335.41378 -409.392596)
			(xy 335.431209 -409.329514) (xy 335.456956 -409.269347) (xy 335.473294 -409.24099) (xy 335.476657 -409.234974)
			(xy 335.480394 -409.221715) (xy 335.48066 -409.214828) (xy 335.48066 -408.465528) (xy 335.480443 -408.458634)
			(xy 335.476704 -408.445362) (xy 335.473294 -408.439366) (xy 335.456951 -408.411013) (xy 335.43121 -408.350845)
			(xy 335.413786 -408.287764) (xy 335.404995 -408.222915) (xy 335.404996 -408.157472) (xy 335.413789 -408.092622)
			(xy 335.431215 -408.029542) (xy 335.456957 -407.969375) (xy 335.473294 -407.941018) (xy 335.476648 -407.934998)
			(xy 335.480391 -407.921741) (xy 335.48066 -407.914856) (xy 335.48066 -407.628852) (xy 335.481145 -407.618745)
			(xy 335.488891 -407.600074) (xy 335.503187 -407.585782) (xy 335.521861 -407.578042) (xy 335.531968 -407.577544)
			(xy 336.248248 -407.577544) (xy 336.258353 -407.578045) (xy 336.277021 -407.585788) (xy 336.291312 -407.600079)
			(xy 336.299055 -407.618747) (xy 336.299556 -407.628852) (xy 336.299556 -407.914856) (xy 336.299777 -407.92175)
			(xy 336.303513 -407.935022) (xy 336.306922 -407.941018) (xy 336.323254 -407.969378) (xy 336.349 -408.029543)
			(xy 336.366429 -408.092622) (xy 336.375224 -408.157472) (xy 336.375224 -408.222915) (xy 336.366432 -408.287764)
			(xy 336.349005 -408.350844) (xy 336.32326 -408.41101) (xy 336.306922 -408.439366) (xy 336.303567 -408.445386)
			(xy 336.299826 -408.458643) (xy 336.299556 -408.465528) (xy 336.299556 -409.214828) (xy 336.299787 -409.221721)
			(xy 336.303517 -409.234993) (xy 336.306922 -409.24099) (xy 336.32323 -409.269363) (xy 336.348979 -409.329525)
			(xy 336.36641 -409.392602) (xy 336.375208 -409.457449) (xy 336.375212 -409.52289) (xy 336.366423 -409.587738)
			(xy 336.348999 -409.650817) (xy 336.323258 -409.710982) (xy 336.306922 -409.739338) (xy 336.303542 -409.745345)
			(xy 336.299817 -409.758612) (xy 336.299556 -409.7655) (xy 336.299556 -410.051504) (xy 336.299019 -410.061606)
			(xy 336.291291 -410.080274) (xy 336.277011 -410.094566) (xy 336.25835 -410.102311) (xy 336.248248 -410.102812)
			(xy 335.531968 -410.102812) (xy 335.521859 -410.102341) (xy 335.503182 -410.094595) (xy 335.488889 -410.080294)
			(xy 335.481153 -410.061614) (xy 335.48066 -410.051504) (xy 335.48066 -409.7655) (xy 335.480432 -409.758608)
			(xy 335.476687 -409.745342) (xy 335.473294 -409.739338) (xy 335.456928 -409.710998) (xy 335.431189 -409.650827)
			(xy 335.413767 -409.587744) (xy 335.404979 -409.522892) (xy 334.116162 -409.522892) (xy 334.106774 -409.539186)
			(xy 334.103417 -409.545205) (xy 334.099677 -409.558462) (xy 334.099408 -409.565348) (xy 334.099408 -410.314648)
			(xy 334.09966 -410.321538) (xy 334.103389 -410.334804) (xy 334.106774 -410.34081) (xy 334.123097 -410.369174)
			(xy 334.148842 -410.429339) (xy 334.166269 -410.492417) (xy 334.175064 -410.557265) (xy 334.175066 -410.622707)
			(xy 334.175066 -410.622709) (xy 337.604871 -410.622709) (xy 337.604873 -410.557264) (xy 337.613669 -410.492413)
			(xy 337.631099 -410.429332) (xy 337.656848 -410.369166) (xy 337.673188 -410.34081) (xy 337.676498 -410.334783)
			(xy 337.680107 -410.321521) (xy 337.6803 -410.314648) (xy 337.6803 -409.565348) (xy 337.68009 -409.558476)
			(xy 337.676494 -409.545213) (xy 337.673188 -409.539186) (xy 337.656859 -409.510825) (xy 337.631112 -409.45066)
			(xy 337.613682 -409.387581) (xy 337.604887 -409.322732) (xy 337.604886 -409.257289) (xy 337.613678 -409.19244)
			(xy 337.631105 -409.12936) (xy 337.65685 -409.069194) (xy 337.673188 -409.040838) (xy 337.676488 -409.034806)
			(xy 337.680103 -409.021548) (xy 337.6803 -409.014676) (xy 337.6803 -408.728672) (xy 337.680699 -408.718516)
			(xy 337.688503 -408.699763) (xy 337.702907 -408.685441) (xy 337.721704 -408.677742) (xy 337.731862 -408.677364)
			(xy 338.448142 -408.677364) (xy 338.458274 -408.677793) (xy 338.477001 -408.685539) (xy 338.491357 -408.699843)
			(xy 338.49917 -408.718542) (xy 338.499704 -408.728672) (xy 338.499704 -409.014676) (xy 338.499905 -409.021549)
			(xy 338.503507 -409.034811) (xy 338.506816 -409.040838) (xy 338.523165 -409.069188) (xy 338.54891 -409.129356)
			(xy 338.566337 -409.192437) (xy 338.57513 -409.257288) (xy 338.575128 -409.322732) (xy 338.566333 -409.387583)
			(xy 338.548903 -409.450664) (xy 338.523156 -409.51083) (xy 338.516205 -409.522892) (xy 339.805015 -409.522892)
			(xy 339.805019 -409.457446) (xy 339.813817 -409.392595) (xy 339.831248 -409.329514) (xy 339.856996 -409.269346)
			(xy 339.873336 -409.24099) (xy 339.876649 -409.234965) (xy 339.880257 -409.221702) (xy 339.880448 -409.214828)
			(xy 339.880448 -408.465528) (xy 339.880252 -408.458655) (xy 339.876647 -408.445392) (xy 339.873336 -408.439366)
			(xy 339.856992 -408.411014) (xy 339.831249 -408.350846) (xy 339.813823 -408.287765) (xy 339.805031 -408.222915)
			(xy 339.805032 -408.157471) (xy 339.813826 -408.092621) (xy 339.831253 -408.029541) (xy 339.856998 -407.969374)
			(xy 339.873336 -407.941018) (xy 339.876639 -407.934988) (xy 339.880253 -407.921728) (xy 339.880448 -407.914856)
			(xy 339.880448 -407.628852) (xy 339.880881 -407.618701) (xy 339.888683 -407.599958) (xy 339.903075 -407.585638)
			(xy 339.921857 -407.577931) (xy 339.93201 -407.577544) (xy 340.64829 -407.577544) (xy 340.658417 -407.578035)
			(xy 340.677138 -407.58576) (xy 340.691495 -407.600045) (xy 340.699314 -407.618728) (xy 340.699852 -407.628852)
			(xy 340.699852 -407.914856) (xy 340.700054 -407.921729) (xy 340.703655 -407.934992) (xy 340.706964 -407.941018)
			(xy 340.723294 -407.969378) (xy 340.749039 -408.029544) (xy 340.766466 -408.092623) (xy 340.77526 -408.157472)
			(xy 340.775261 -408.222914) (xy 340.766469 -408.287763) (xy 340.749043 -408.350843) (xy 340.723301 -408.41101)
			(xy 340.706964 -408.439366) (xy 340.703666 -408.445399) (xy 340.700049 -408.458656) (xy 340.699852 -408.465528)
			(xy 340.699852 -409.214828) (xy 340.700027 -409.221703) (xy 340.703646 -409.234966) (xy 340.706964 -409.24099)
			(xy 340.723271 -409.269363) (xy 340.749017 -409.329526) (xy 340.766447 -409.392602) (xy 340.775244 -409.457449)
			(xy 340.775248 -409.522889) (xy 340.766459 -409.587737) (xy 340.749038 -409.650816) (xy 340.723299 -409.710982)
			(xy 340.706964 -409.739338) (xy 340.703641 -409.745359) (xy 340.70004 -409.758625) (xy 340.699852 -409.7655)
			(xy 340.699852 -410.051504) (xy 340.699383 -410.061652) (xy 340.691595 -410.080394) (xy 340.677214 -410.094716)
			(xy 340.65844 -410.102424) (xy 340.64829 -410.102812) (xy 339.93201 -410.102812) (xy 339.92189 -410.102267)
			(xy 339.903179 -410.094552) (xy 339.888824 -410.080284) (xy 339.880996 -410.061621) (xy 339.880448 -410.051504)
			(xy 339.880448 -409.7655) (xy 339.880263 -409.758626) (xy 339.876651 -409.745363) (xy 339.873336 -409.739338)
			(xy 339.856968 -409.710999) (xy 339.831227 -409.650828) (xy 339.813804 -409.587744) (xy 339.805015 -409.522892)
			(xy 338.516205 -409.522892) (xy 338.506816 -409.539186) (xy 338.503507 -409.545214) (xy 338.499898 -409.558475)
			(xy 338.499704 -409.565348) (xy 338.499704 -410.314648) (xy 338.499915 -410.32152) (xy 338.50351 -410.334783)
			(xy 338.506816 -410.34081) (xy 338.523141 -410.369173) (xy 338.548889 -410.429338) (xy 338.566318 -410.492416)
			(xy 338.575114 -410.557265) (xy 338.575116 -410.622707) (xy 338.575116 -410.622708) (xy 342.004921 -410.622708)
			(xy 342.004923 -410.557264) (xy 342.013718 -410.492414) (xy 342.031146 -410.429333) (xy 342.056892 -410.369166)
			(xy 342.07323 -410.34081) (xy 342.076589 -410.334792) (xy 342.080328 -410.321534) (xy 342.080596 -410.314648)
			(xy 342.080596 -409.565348) (xy 342.080345 -409.558458) (xy 342.076615 -409.545192) (xy 342.07323 -409.539186)
			(xy 342.056903 -409.510824) (xy 342.031159 -409.450659) (xy 342.013731 -409.38758) (xy 342.004937 -409.322731)
			(xy 342.004936 -409.257289) (xy 342.013727 -409.19244) (xy 342.031152 -409.129361) (xy 342.056894 -409.069194)
			(xy 342.07323 -409.040838) (xy 342.076614 -409.034833) (xy 342.080337 -409.021565) (xy 342.080596 -409.014676)
			(xy 342.080596 -408.728672) (xy 342.081062 -408.718562) (xy 342.088808 -408.699884) (xy 342.103111 -408.68559)
			(xy 342.121794 -408.677856) (xy 342.131904 -408.677364) (xy 342.848184 -408.677364) (xy 342.858287 -408.677897)
			(xy 342.876958 -408.685623) (xy 342.891252 -408.699905) (xy 342.898994 -408.718569) (xy 342.899492 -408.728672)
			(xy 342.899492 -409.014676) (xy 342.899736 -409.021567) (xy 342.903471 -409.034832) (xy 342.906858 -409.040838)
			(xy 342.923206 -409.069189) (xy 342.948949 -409.129357) (xy 342.966374 -409.192438) (xy 342.975166 -409.257288)
			(xy 342.975165 -409.322732) (xy 342.96637 -409.387582) (xy 342.948942 -409.450663) (xy 342.923196 -409.51083)
			(xy 342.916246 -409.522892) (xy 344.204805 -409.522892) (xy 344.204809 -409.457447) (xy 344.213606 -409.392595)
			(xy 344.231037 -409.329514) (xy 344.256785 -409.269346) (xy 344.273124 -409.24099) (xy 344.276444 -409.234968)
			(xy 344.280046 -409.221702) (xy 344.280236 -409.214828) (xy 344.280236 -408.465528) (xy 344.280029 -408.458656)
			(xy 344.276431 -408.445393) (xy 344.273124 -408.439366) (xy 344.25678 -408.411013) (xy 344.231038 -408.350846)
			(xy 344.213613 -408.287765) (xy 344.204821 -408.222915) (xy 344.204822 -408.157471) (xy 344.213615 -408.092622)
			(xy 344.231042 -408.029541) (xy 344.256787 -407.969374) (xy 344.273124 -407.941018) (xy 344.276434 -407.934991)
			(xy 344.280042 -407.921729) (xy 344.280236 -407.914856) (xy 344.280236 -407.628852) (xy 344.280583 -407.61869)
			(xy 344.288401 -407.59993) (xy 344.302821 -407.585607) (xy 344.321634 -407.577916) (xy 344.331798 -407.577544)
			(xy 345.048078 -407.577544) (xy 345.058204 -407.578045) (xy 345.076925 -407.585766) (xy 345.091283 -407.600048)
			(xy 345.099102 -407.618729) (xy 345.09964 -407.628852) (xy 345.09964 -407.914856) (xy 345.099844 -407.921728)
			(xy 345.103443 -407.934991) (xy 345.106752 -407.941018) (xy 345.123083 -407.969378) (xy 345.148828 -408.029544)
			(xy 345.166255 -408.092623) (xy 345.175049 -408.157472) (xy 345.175049 -408.190192) (xy 348.603832 -408.190192)
			(xy 348.607823 -408.128025) (xy 348.619732 -408.066878) (xy 348.639361 -408.007757) (xy 348.66639 -407.951631)
			(xy 348.700374 -407.899422) (xy 348.740756 -407.851987) (xy 348.786872 -407.810106) (xy 348.837964 -407.774466)
			(xy 348.893195 -407.745652) (xy 348.951657 -407.724138) (xy 349.012391 -407.710276) (xy 349.074398 -407.704294)
			(xy 349.136661 -407.70629) (xy 349.198158 -407.716233) (xy 349.257879 -407.733957) (xy 349.314842 -407.759174)
			(xy 349.368113 -407.791467) (xy 349.416818 -407.830307) (xy 349.460155 -407.875057) (xy 349.497415 -407.924981)
			(xy 349.527984 -407.97926) (xy 349.551362 -408.037003) (xy 349.567163 -408.097261) (xy 349.575129 -408.159044)
			(xy 349.575628 -408.190192) (xy 349.575129 -408.22134) (xy 349.567163 -408.283123) (xy 349.551362 -408.343381)
			(xy 349.527984 -408.401124) (xy 349.497415 -408.455403) (xy 349.460155 -408.505327) (xy 349.416818 -408.550077)
			(xy 349.368113 -408.588917) (xy 349.314842 -408.62121) (xy 349.257879 -408.646427) (xy 349.198158 -408.664151)
			(xy 349.136661 -408.674094) (xy 349.074398 -408.67609) (xy 349.012391 -408.670108) (xy 348.951657 -408.656246)
			(xy 348.893195 -408.634732) (xy 348.837964 -408.605918) (xy 348.786872 -408.570278) (xy 348.740756 -408.528397)
			(xy 348.700374 -408.480962) (xy 348.66639 -408.428753) (xy 348.639361 -408.372627) (xy 348.619732 -408.313506)
			(xy 348.607823 -408.252359) (xy 348.603832 -408.190192) (xy 345.175049 -408.190192) (xy 345.17505 -408.222914)
			(xy 345.166258 -408.287764) (xy 345.148832 -408.350843) (xy 345.123089 -408.41101) (xy 345.106752 -408.439366)
			(xy 345.103453 -408.445399) (xy 345.099837 -408.458656) (xy 345.09964 -408.465528) (xy 345.09964 -409.214828)
			(xy 345.099816 -409.221702) (xy 345.103435 -409.234965) (xy 345.106752 -409.24099) (xy 345.123059 -409.269363)
			(xy 345.148806 -409.329526) (xy 345.166236 -409.392602) (xy 345.175033 -409.457449) (xy 345.175038 -409.522889)
			(xy 345.166249 -409.587737) (xy 345.148827 -409.650816) (xy 345.123087 -409.710982) (xy 345.106752 -409.739338)
			(xy 345.103428 -409.745358) (xy 345.099828 -409.758625) (xy 345.09964 -409.7655) (xy 345.09964 -410.051504)
			(xy 345.099182 -410.061653) (xy 345.091393 -410.080398) (xy 345.077008 -410.09472) (xy 345.058229 -410.102427)
			(xy 345.048078 -410.102812) (xy 344.331798 -410.102812) (xy 344.321678 -410.102277) (xy 344.302966 -410.094558)
			(xy 344.288612 -410.080287) (xy 344.280784 -410.061621) (xy 344.280236 -410.051504) (xy 344.280236 -409.7655)
			(xy 344.28004 -409.758627) (xy 344.276434 -409.745365) (xy 344.273124 -409.739338) (xy 344.256757 -409.710999)
			(xy 344.231016 -409.650828) (xy 344.213594 -409.587744) (xy 344.204805 -409.522892) (xy 342.916246 -409.522892)
			(xy 342.906858 -409.539186) (xy 342.9035 -409.545204) (xy 342.89976 -409.558462) (xy 342.899492 -409.565348)
			(xy 342.899492 -410.314648) (xy 342.899746 -410.321538) (xy 342.903474 -410.334804) (xy 342.906858 -410.34081)
			(xy 342.923182 -410.369174) (xy 342.948927 -410.429339) (xy 342.966355 -410.492417) (xy 342.97515 -410.557265)
			(xy 342.975152 -410.622707) (xy 342.975152 -410.622709) (xy 346.404958 -410.622709) (xy 346.404959 -410.557264)
			(xy 346.413755 -410.492413) (xy 346.431185 -410.429333) (xy 346.456933 -410.369166) (xy 346.473272 -410.34081)
			(xy 346.476581 -410.334783) (xy 346.480191 -410.321521) (xy 346.480384 -410.314648) (xy 346.480384 -409.565348)
			(xy 346.480176 -409.558476) (xy 346.476579 -409.545213) (xy 346.473272 -409.539186) (xy 346.456944 -409.510825)
			(xy 346.431197 -409.450659) (xy 346.413768 -409.38758) (xy 346.404974 -409.322732) (xy 346.404972 -409.257289)
			(xy 346.413764 -409.19244) (xy 346.43119 -409.12936) (xy 346.456934 -409.069194) (xy 346.473272 -409.040838)
			(xy 346.476571 -409.034806) (xy 346.480187 -409.021548) (xy 346.480384 -409.014676) (xy 346.480384 -408.728672)
			(xy 346.480798 -408.718518) (xy 346.4886 -408.699768) (xy 346.502999 -408.685446) (xy 346.52179 -408.677745)
			(xy 346.531946 -408.677364) (xy 347.248226 -408.677364) (xy 347.258357 -408.677806) (xy 347.277084 -408.685547)
			(xy 347.29144 -408.699847) (xy 347.299254 -408.718543) (xy 347.299788 -408.728672) (xy 347.299788 -409.014676)
			(xy 347.29999 -409.021548) (xy 347.303592 -409.034811) (xy 347.3069 -409.040838) (xy 347.323246 -409.069189)
			(xy 347.348987 -409.129357) (xy 347.366411 -409.192438) (xy 347.375202 -409.257289) (xy 347.375201 -409.322732)
			(xy 347.366407 -409.387582) (xy 347.34898 -409.450662) (xy 347.332079 -409.490164) (xy 348.603832 -409.490164)
			(xy 348.607823 -409.427997) (xy 348.619732 -409.36685) (xy 348.639361 -409.307729) (xy 348.66639 -409.251603)
			(xy 348.700374 -409.199394) (xy 348.740756 -409.151959) (xy 348.786872 -409.110078) (xy 348.837964 -409.074438)
			(xy 348.893195 -409.045624) (xy 348.951657 -409.02411) (xy 349.012391 -409.010248) (xy 349.074398 -409.004266)
			(xy 349.136661 -409.006262) (xy 349.198158 -409.016205) (xy 349.257879 -409.033929) (xy 349.314842 -409.059146)
			(xy 349.368113 -409.091439) (xy 349.416818 -409.130279) (xy 349.460155 -409.175029) (xy 349.497415 -409.224953)
			(xy 349.527984 -409.279232) (xy 349.532348 -409.290012) (xy 350.80398 -409.290012) (xy 350.807971 -409.227845)
			(xy 350.81988 -409.166698) (xy 350.839509 -409.107577) (xy 350.866538 -409.051451) (xy 350.900522 -408.999242)
			(xy 350.940904 -408.951807) (xy 350.98702 -408.909926) (xy 351.038112 -408.874286) (xy 351.093343 -408.845472)
			(xy 351.151805 -408.823958) (xy 351.212539 -408.810096) (xy 351.274546 -408.804114) (xy 351.336809 -408.80611)
			(xy 351.398306 -408.816053) (xy 351.458027 -408.833777) (xy 351.51499 -408.858994) (xy 351.568261 -408.891287)
			(xy 351.616966 -408.930127) (xy 351.660303 -408.974877) (xy 351.697563 -409.024801) (xy 351.728132 -409.07908)
			(xy 351.75151 -409.136823) (xy 351.767311 -409.197081) (xy 351.775277 -409.258864) (xy 351.775776 -409.290012)
			(xy 351.775277 -409.32116) (xy 351.767311 -409.382943) (xy 351.75151 -409.443201) (xy 351.728132 -409.500944)
			(xy 351.715771 -409.522892) (xy 375.004839 -409.522892) (xy 375.004844 -409.457446) (xy 375.013641 -409.392595)
			(xy 375.031073 -409.329513) (xy 375.056823 -409.269346) (xy 375.073164 -409.24099) (xy 375.076479 -409.234966)
			(xy 375.080085 -409.221702) (xy 375.080276 -409.214828) (xy 375.080276 -408.465528) (xy 375.080076 -408.458655)
			(xy 375.076474 -408.445392) (xy 375.073164 -408.439366) (xy 375.056819 -408.411014) (xy 375.031074 -408.350846)
			(xy 375.013648 -408.287766) (xy 375.004855 -408.222915) (xy 375.004856 -408.157471) (xy 375.013651 -408.092621)
			(xy 375.031079 -408.029541) (xy 375.056825 -407.969374) (xy 375.073164 -407.941018) (xy 375.076469 -407.934989)
			(xy 375.080081 -407.921729) (xy 375.080276 -407.914856) (xy 375.080276 -407.628852) (xy 375.080682 -407.618698)
			(xy 375.088489 -407.599949) (xy 375.10289 -407.585628) (xy 375.121682 -407.577926) (xy 375.131838 -407.577544)
			(xy 375.848118 -407.577544) (xy 375.858246 -407.578012) (xy 375.876969 -407.585746) (xy 375.891325 -407.600038)
			(xy 375.899143 -407.618726) (xy 375.89968 -407.628852) (xy 375.89968 -407.914856) (xy 375.899891 -407.921728)
			(xy 375.903486 -407.934991) (xy 375.906792 -407.941018) (xy 375.923122 -407.969378) (xy 375.948865 -408.029544)
			(xy 375.966291 -408.092624) (xy 375.975084 -408.157472) (xy 375.975085 -408.222914) (xy 375.966293 -408.287763)
			(xy 375.948869 -408.350843) (xy 375.923128 -408.41101) (xy 375.906792 -408.439366) (xy 375.903489 -408.445396)
			(xy 375.899876 -408.458656) (xy 375.89968 -408.465528) (xy 375.89968 -409.214828) (xy 375.899864 -409.221702)
			(xy 375.903478 -409.234964) (xy 375.906792 -409.24099) (xy 375.923098 -409.269363) (xy 375.948843 -409.329526)
			(xy 375.966272 -409.392603) (xy 375.975068 -409.457449) (xy 375.975072 -409.522889) (xy 375.966284 -409.587737)
			(xy 375.948863 -409.650815) (xy 375.923126 -409.710982) (xy 375.906792 -409.739338) (xy 375.903463 -409.745356)
			(xy 375.899867 -409.758625) (xy 375.89968 -409.7655) (xy 375.89968 -410.051504) (xy 375.899281 -410.061661)
			(xy 375.891481 -410.080417) (xy 375.877077 -410.094741) (xy 375.858277 -410.102437) (xy 375.848118 -410.102812)
			(xy 375.131838 -410.102812) (xy 375.12172 -410.102244) (xy 375.10301 -410.094538) (xy 375.088654 -410.080277)
			(xy 375.080824 -410.061618) (xy 375.080276 -410.051504) (xy 375.080276 -409.7655) (xy 375.080087 -409.758627)
			(xy 375.076477 -409.745364) (xy 375.073164 -409.739338) (xy 375.056795 -409.710999) (xy 375.031053 -409.650829)
			(xy 375.013629 -409.587745) (xy 375.004839 -409.522892) (xy 351.715771 -409.522892) (xy 351.697563 -409.555223)
			(xy 351.660303 -409.605147) (xy 351.616966 -409.649897) (xy 351.568261 -409.688737) (xy 351.51499 -409.72103)
			(xy 351.458027 -409.746247) (xy 351.398306 -409.763971) (xy 351.336809 -409.773914) (xy 351.274546 -409.77591)
			(xy 351.212539 -409.769928) (xy 351.151805 -409.756066) (xy 351.093343 -409.734552) (xy 351.038112 -409.705738)
			(xy 350.98702 -409.670098) (xy 350.940904 -409.628217) (xy 350.900522 -409.580782) (xy 350.866538 -409.528573)
			(xy 350.839509 -409.472447) (xy 350.81988 -409.413326) (xy 350.807971 -409.352179) (xy 350.80398 -409.290012)
			(xy 349.532348 -409.290012) (xy 349.551362 -409.336975) (xy 349.567163 -409.397233) (xy 349.575129 -409.459016)
			(xy 349.575628 -409.490164) (xy 349.575129 -409.521312) (xy 349.567163 -409.583095) (xy 349.551362 -409.643353)
			(xy 349.527984 -409.701096) (xy 349.497415 -409.755375) (xy 349.460155 -409.805299) (xy 349.416818 -409.850049)
			(xy 349.368113 -409.888889) (xy 349.314842 -409.921182) (xy 349.257879 -409.946399) (xy 349.198158 -409.964123)
			(xy 349.136661 -409.974066) (xy 349.074398 -409.976062) (xy 349.012391 -409.97008) (xy 348.951657 -409.956218)
			(xy 348.893195 -409.934704) (xy 348.837964 -409.90589) (xy 348.786872 -409.87025) (xy 348.740756 -409.828369)
			(xy 348.700374 -409.780934) (xy 348.66639 -409.728725) (xy 348.639361 -409.672599) (xy 348.619732 -409.613478)
			(xy 348.607823 -409.552331) (xy 348.603832 -409.490164) (xy 347.332079 -409.490164) (xy 347.323237 -409.510829)
			(xy 347.3069 -409.539186) (xy 347.30359 -409.545213) (xy 347.299981 -409.558475) (xy 347.299788 -409.565348)
			(xy 347.299788 -410.314648) (xy 347.300002 -410.32152) (xy 347.303595 -410.334782) (xy 347.3069 -410.34081)
			(xy 347.323223 -410.369174) (xy 347.348966 -410.429339) (xy 347.366392 -410.492418) (xy 347.375186 -410.557266)
			(xy 347.375187 -410.589984) (xy 350.80398 -410.589984) (xy 350.807971 -410.527817) (xy 350.81988 -410.46667)
			(xy 350.839509 -410.407549) (xy 350.866538 -410.351423) (xy 350.900522 -410.299214) (xy 350.940904 -410.251779)
			(xy 350.98702 -410.209898) (xy 351.038112 -410.174258) (xy 351.093343 -410.145444) (xy 351.151805 -410.12393)
			(xy 351.212539 -410.110068) (xy 351.274546 -410.104086) (xy 351.336809 -410.106082) (xy 351.398306 -410.116025)
			(xy 351.458027 -410.133749) (xy 351.51499 -410.158966) (xy 351.568261 -410.191259) (xy 351.616966 -410.230099)
			(xy 351.660303 -410.274849) (xy 351.697563 -410.324773) (xy 351.728132 -410.379052) (xy 351.75151 -410.436795)
			(xy 351.767311 -410.497053) (xy 351.775277 -410.558836) (xy 351.775776 -410.589984) (xy 351.775277 -410.621132)
			(xy 351.775074 -410.622708) (xy 377.204746 -410.622708) (xy 377.204747 -410.557264) (xy 377.213543 -410.492414)
			(xy 377.230972 -410.429333) (xy 377.256719 -410.369166) (xy 377.273058 -410.34081) (xy 377.276419 -410.334794)
			(xy 377.280157 -410.321534) (xy 377.280424 -410.314648) (xy 377.280424 -409.565348) (xy 377.280204 -409.558454)
			(xy 377.276467 -409.545182) (xy 377.273058 -409.539186) (xy 377.25673 -409.510824) (xy 377.230984 -409.450659)
			(xy 377.213556 -409.38758) (xy 377.204762 -409.322731) (xy 377.20476 -409.257289) (xy 377.213552 -409.19244)
			(xy 377.230978 -409.12936) (xy 377.256721 -409.069194) (xy 377.273058 -409.040838) (xy 377.276445 -409.034834)
			(xy 377.280166 -409.021565) (xy 377.280424 -409.014676) (xy 377.280424 -408.728672) (xy 377.280794 -408.718545)
			(xy 377.288555 -408.699836) (xy 377.302886 -408.685522) (xy 377.321604 -408.677782) (xy 377.331732 -408.677364)
			(xy 378.048012 -408.677364) (xy 378.058117 -408.677875) (xy 378.076789 -408.685609) (xy 378.091082 -408.699898)
			(xy 378.098822 -408.718567) (xy 378.09932 -408.728672) (xy 378.09932 -409.014676) (xy 378.09956 -409.021567)
			(xy 378.103297 -409.034833) (xy 378.106686 -409.040838) (xy 378.123033 -409.069189) (xy 378.148774 -409.129357)
			(xy 378.166199 -409.192438) (xy 378.17499 -409.257289) (xy 378.174989 -409.322732) (xy 378.166195 -409.387582)
			(xy 378.148768 -409.450662) (xy 378.123023 -409.51083) (xy 378.116074 -409.522892) (xy 379.404889 -409.522892)
			(xy 379.404894 -409.457447) (xy 379.41369 -409.392596) (xy 379.43112 -409.329514) (xy 379.456867 -409.269347)
			(xy 379.473206 -409.24099) (xy 379.47657 -409.234975) (xy 379.480306 -409.221715) (xy 379.480572 -409.214828)
			(xy 379.480572 -408.465528) (xy 379.480332 -408.458637) (xy 379.476595 -408.445371) (xy 379.473206 -408.439366)
			(xy 379.456863 -408.411013) (xy 379.431121 -408.350845) (xy 379.413697 -408.287765) (xy 379.404905 -408.222915)
			(xy 379.404906 -408.157472) (xy 379.4137 -408.092622) (xy 379.431126 -408.029542) (xy 379.456869 -407.969375)
			(xy 379.473206 -407.941018) (xy 379.47656 -407.934998) (xy 379.480303 -407.921742) (xy 379.480572 -407.914856)
			(xy 379.480572 -407.628852) (xy 379.481045 -407.618744) (xy 379.488793 -407.60007) (xy 379.503093 -407.585778)
			(xy 379.521771 -407.57804) (xy 379.53188 -407.577544) (xy 380.24816 -407.577544) (xy 380.258259 -407.578117)
			(xy 380.276926 -407.585831) (xy 380.29122 -407.6001) (xy 380.298966 -407.618754) (xy 380.299468 -407.628852)
			(xy 380.299468 -407.914856) (xy 380.299687 -407.92175) (xy 380.303425 -407.935022) (xy 380.306834 -407.941018)
			(xy 380.323165 -407.969378) (xy 380.348911 -408.029543) (xy 380.36634 -408.092623) (xy 380.375134 -408.157472)
			(xy 380.375135 -408.222915) (xy 380.366342 -408.287764) (xy 380.348916 -408.350844) (xy 380.323172 -408.41101)
			(xy 380.306834 -408.439366) (xy 380.30348 -408.445386) (xy 380.299738 -408.458643) (xy 380.299468 -408.465528)
			(xy 380.299468 -409.214828) (xy 380.299698 -409.221721) (xy 380.303429 -409.234993) (xy 380.306834 -409.24099)
			(xy 380.323142 -409.269363) (xy 380.34889 -409.329525) (xy 380.366321 -409.392602) (xy 380.375118 -409.457449)
			(xy 380.375122 -409.52289) (xy 380.366333 -409.587737) (xy 380.34891 -409.650816) (xy 380.32317 -409.710982)
			(xy 380.306834 -409.739338) (xy 380.303455 -409.745346) (xy 380.299729 -409.758612) (xy 380.299468 -409.7655)
			(xy 380.299468 -410.051504) (xy 380.299086 -410.061631) (xy 380.291331 -410.08034) (xy 380.277003 -410.094656)
			(xy 380.258287 -410.102395) (xy 380.24816 -410.102812) (xy 379.53188 -410.102812) (xy 379.521771 -410.102332)
			(xy 379.503095 -410.09459) (xy 379.488801 -410.080292) (xy 379.481065 -410.061613) (xy 379.480572 -410.051504)
			(xy 379.480572 -409.7655) (xy 379.480342 -409.758608) (xy 379.476598 -409.745342) (xy 379.473206 -409.739338)
			(xy 379.456839 -409.710998) (xy 379.4311 -409.650827) (xy 379.413678 -409.587744) (xy 379.404889 -409.522892)
			(xy 378.116074 -409.522892) (xy 378.106686 -409.539186) (xy 378.10333 -409.545205) (xy 378.099589 -409.558462)
			(xy 378.09932 -409.565348) (xy 378.09932 -410.314648) (xy 378.099571 -410.321538) (xy 378.103301 -410.334804)
			(xy 378.106686 -410.34081) (xy 378.123009 -410.369174) (xy 378.148753 -410.429339) (xy 378.16618 -410.492418)
			(xy 378.174974 -410.557266) (xy 378.174976 -410.622707) (xy 378.174976 -410.622708) (xy 381.604796 -410.622708)
			(xy 381.604798 -410.557265) (xy 381.613592 -410.492415) (xy 381.631019 -410.429334) (xy 381.656763 -410.369167)
			(xy 381.6731 -410.34081) (xy 381.676411 -410.334784) (xy 381.680019 -410.321521) (xy 381.680212 -410.314648)
			(xy 381.680212 -409.565348) (xy 381.68 -409.558476) (xy 381.676405 -409.545214) (xy 381.6731 -409.539186)
			(xy 381.656774 -409.510824) (xy 381.631031 -409.450658) (xy 381.613605 -409.387579) (xy 381.604812 -409.322731)
			(xy 381.60481 -409.257289) (xy 381.613601 -409.192441) (xy 381.631024 -409.129361) (xy 381.656765 -409.069195)
			(xy 381.6731 -409.040838) (xy 381.676401 -409.034807) (xy 381.680015 -409.021548) (xy 381.680212 -409.014676)
			(xy 381.680212 -408.728672) (xy 381.680599 -408.718515) (xy 381.688406 -408.699759) (xy 381.702813 -408.685436)
			(xy 381.721614 -408.67774) (xy 381.731774 -408.677364) (xy 382.448054 -408.677364) (xy 382.458181 -408.677865)
			(xy 382.476905 -408.685582) (xy 382.491264 -408.699865) (xy 382.499081 -408.718548) (xy 382.499616 -408.728672)
			(xy 382.499616 -409.014676) (xy 382.499815 -409.021549) (xy 382.503418 -409.034812) (xy 382.506728 -409.040838)
			(xy 382.523077 -409.069188) (xy 382.548821 -409.129356) (xy 382.566248 -409.192437) (xy 382.57504 -409.257288)
			(xy 382.575039 -409.322732) (xy 382.566244 -409.387583) (xy 382.548814 -409.450664) (xy 382.523067 -409.51083)
			(xy 382.516117 -409.522892) (xy 383.804926 -409.522892) (xy 383.80493 -409.457446) (xy 383.813727 -409.392595)
			(xy 383.831159 -409.329513) (xy 383.856908 -409.269346) (xy 383.873248 -409.24099) (xy 383.876562 -409.234965)
			(xy 383.880169 -409.221702) (xy 383.88036 -409.214828) (xy 383.88036 -408.465528) (xy 383.880162 -408.458655)
			(xy 383.876559 -408.445392) (xy 383.873248 -408.439366) (xy 383.856904 -408.411014) (xy 383.83116 -408.350846)
			(xy 383.813734 -408.287765) (xy 383.804942 -408.222915) (xy 383.804942 -408.157471) (xy 383.813737 -408.092621)
			(xy 383.831164 -408.029541) (xy 383.85691 -407.969374) (xy 383.873248 -407.941018) (xy 383.876552 -407.934988)
			(xy 383.880165 -407.921729) (xy 383.88036 -407.914856) (xy 383.88036 -407.628852) (xy 383.880782 -407.6187)
			(xy 383.888586 -407.599954) (xy 383.902981 -407.585634) (xy 383.921768 -407.577929) (xy 383.931922 -407.577544)
			(xy 384.648202 -407.577544) (xy 384.658329 -407.578025) (xy 384.677051 -407.585754) (xy 384.691408 -407.600042)
			(xy 384.699226 -407.618727) (xy 384.699764 -407.628852) (xy 384.699764 -407.914856) (xy 384.699977 -407.921728)
			(xy 384.703571 -407.93499) (xy 384.706876 -407.941018) (xy 384.723206 -407.969378) (xy 384.74895 -408.029544)
			(xy 384.766376 -408.092623) (xy 384.77517 -408.157472) (xy 384.775171 -408.222914) (xy 384.766379 -408.287763)
			(xy 384.748954 -408.350843) (xy 384.723212 -408.41101) (xy 384.706876 -408.439366) (xy 384.703572 -408.445396)
			(xy 384.69996 -408.458656) (xy 384.699764 -408.465528) (xy 384.699764 -409.214828) (xy 384.69995 -409.221702)
			(xy 384.703563 -409.234964) (xy 384.706876 -409.24099) (xy 384.723182 -409.269363) (xy 384.748928 -409.329526)
			(xy 384.766358 -409.392603) (xy 384.775154 -409.457449) (xy 384.775158 -409.522889) (xy 384.76637 -409.587737)
			(xy 384.748949 -409.650816) (xy 384.72321 -409.710982) (xy 384.706876 -409.739338) (xy 384.703546 -409.745355)
			(xy 384.69995 -409.758625) (xy 384.699764 -409.7655) (xy 384.699764 -410.051504) (xy 384.699381 -410.061663)
			(xy 384.691577 -410.080422) (xy 384.677168 -410.094747) (xy 384.658363 -410.10244) (xy 384.648202 -410.102812)
			(xy 383.931922 -410.102812) (xy 383.921803 -410.102257) (xy 383.903092 -410.094546) (xy 383.888737 -410.080281)
			(xy 383.880908 -410.06162) (xy 383.88036 -410.051504) (xy 383.88036 -409.7655) (xy 383.880173 -409.758626)
			(xy 383.876562 -409.745363) (xy 383.873248 -409.739338) (xy 383.85688 -409.710999) (xy 383.831138 -409.650828)
			(xy 383.813715 -409.587745) (xy 383.804926 -409.522892) (xy 382.516117 -409.522892) (xy 382.506728 -409.539186)
			(xy 382.50342 -409.545214) (xy 382.49981 -409.558475) (xy 382.499616 -409.565348) (xy 382.499616 -410.314648)
			(xy 382.499826 -410.32152) (xy 382.503422 -410.334783) (xy 382.506728 -410.34081) (xy 382.523053 -410.369173)
			(xy 382.5488 -410.429338) (xy 382.566229 -410.492417) (xy 382.575024 -410.557265) (xy 382.575026 -410.622707)
			(xy 382.575026 -410.622708) (xy 386.004832 -410.622708) (xy 386.004834 -410.557264) (xy 386.013629 -410.492414)
			(xy 386.031057 -410.429333) (xy 386.056803 -410.369166) (xy 386.073142 -410.34081) (xy 386.076502 -410.334793)
			(xy 386.08024 -410.321534) (xy 386.080508 -410.314648) (xy 386.080508 -409.565348) (xy 386.080255 -409.558458)
			(xy 386.076526 -409.545192) (xy 386.073142 -409.539186) (xy 386.056815 -409.510824) (xy 386.03107 -409.450659)
			(xy 386.013642 -409.38758) (xy 386.004848 -409.322731) (xy 386.004846 -409.257289) (xy 386.013638 -409.19244)
			(xy 386.031063 -409.129361) (xy 386.056805 -409.069194) (xy 386.073142 -409.040838) (xy 386.076527 -409.034833)
			(xy 386.080249 -409.021565) (xy 386.080508 -409.014676) (xy 386.080508 -408.728672) (xy 386.080962 -408.71856)
			(xy 386.088711 -408.69988) (xy 386.103017 -408.685586) (xy 386.121704 -408.677854) (xy 386.131816 -408.677364)
			(xy 386.848096 -408.677364) (xy 386.8582 -408.677888) (xy 386.876871 -408.685617) (xy 386.891165 -408.699902)
			(xy 386.898906 -408.718568) (xy 386.899404 -408.728672) (xy 386.899404 -409.014676) (xy 386.899646 -409.021567)
			(xy 386.903382 -409.034833) (xy 386.90677 -409.040838) (xy 386.923117 -409.069189) (xy 386.94886 -409.129357)
			(xy 386.966285 -409.192438) (xy 386.975076 -409.257288) (xy 386.975075 -409.322732) (xy 386.966281 -409.387582)
			(xy 386.948853 -409.450663) (xy 386.923108 -409.51083) (xy 386.916158 -409.522892) (xy 388.204715 -409.522892)
			(xy 388.204719 -409.457446) (xy 388.213517 -409.392595) (xy 388.230948 -409.329514) (xy 388.256696 -409.269346)
			(xy 388.273036 -409.24099) (xy 388.276349 -409.234965) (xy 388.279957 -409.221702) (xy 388.280148 -409.214828)
			(xy 388.280148 -408.465528) (xy 388.279952 -408.458655) (xy 388.276347 -408.445392) (xy 388.273036 -408.439366)
			(xy 388.256692 -408.411014) (xy 388.230949 -408.350846) (xy 388.213523 -408.287765) (xy 388.204731 -408.222915)
			(xy 388.204732 -408.157471) (xy 388.213526 -408.092621) (xy 388.230953 -408.029541) (xy 388.256698 -407.969374)
			(xy 388.273036 -407.941018) (xy 388.276339 -407.934988) (xy 388.279953 -407.921728) (xy 388.280148 -407.914856)
			(xy 388.280148 -407.628852) (xy 388.280581 -407.618701) (xy 388.288383 -407.599958) (xy 388.302775 -407.585638)
			(xy 388.321557 -407.577931) (xy 388.33171 -407.577544) (xy 389.04799 -407.577544) (xy 389.058117 -407.578035)
			(xy 389.076838 -407.58576) (xy 389.091195 -407.600045) (xy 389.099014 -407.618728) (xy 389.099552 -407.628852)
			(xy 389.099552 -407.914856) (xy 389.099754 -407.921729) (xy 389.103355 -407.934992) (xy 389.106664 -407.941018)
			(xy 389.122994 -407.969378) (xy 389.148739 -408.029544) (xy 389.166166 -408.092623) (xy 389.17496 -408.157472)
			(xy 389.17496 -408.190192) (xy 392.603744 -408.190192) (xy 392.607735 -408.128025) (xy 392.619644 -408.066878)
			(xy 392.639273 -408.007757) (xy 392.666302 -407.951631) (xy 392.700286 -407.899422) (xy 392.740668 -407.851987)
			(xy 392.786784 -407.810106) (xy 392.837876 -407.774466) (xy 392.893107 -407.745652) (xy 392.951569 -407.724138)
			(xy 393.012303 -407.710276) (xy 393.07431 -407.704294) (xy 393.136573 -407.70629) (xy 393.19807 -407.716233)
			(xy 393.257791 -407.733957) (xy 393.314754 -407.759174) (xy 393.368025 -407.791467) (xy 393.41673 -407.830307)
			(xy 393.460067 -407.875057) (xy 393.497327 -407.924981) (xy 393.527896 -407.97926) (xy 393.551274 -408.037003)
			(xy 393.567075 -408.097261) (xy 393.575041 -408.159044) (xy 393.57554 -408.190192) (xy 393.575041 -408.22134)
			(xy 393.567075 -408.283123) (xy 393.551274 -408.343381) (xy 393.527896 -408.401124) (xy 393.497327 -408.455403)
			(xy 393.460067 -408.505327) (xy 393.41673 -408.550077) (xy 393.368025 -408.588917) (xy 393.314754 -408.62121)
			(xy 393.257791 -408.646427) (xy 393.19807 -408.664151) (xy 393.136573 -408.674094) (xy 393.07431 -408.67609)
			(xy 393.012303 -408.670108) (xy 392.951569 -408.656246) (xy 392.893107 -408.634732) (xy 392.837876 -408.605918)
			(xy 392.786784 -408.570278) (xy 392.740668 -408.528397) (xy 392.700286 -408.480962) (xy 392.666302 -408.428753)
			(xy 392.639273 -408.372627) (xy 392.619644 -408.313506) (xy 392.607735 -408.252359) (xy 392.603744 -408.190192)
			(xy 389.17496 -408.190192) (xy 389.174961 -408.222914) (xy 389.166169 -408.287763) (xy 389.148743 -408.350843)
			(xy 389.123001 -408.41101) (xy 389.106664 -408.439366) (xy 389.103366 -408.445399) (xy 389.099749 -408.458656)
			(xy 389.099552 -408.465528) (xy 389.099552 -409.214828) (xy 389.099727 -409.221703) (xy 389.103346 -409.234966)
			(xy 389.106664 -409.24099) (xy 389.122971 -409.269363) (xy 389.148717 -409.329526) (xy 389.166147 -409.392602)
			(xy 389.174944 -409.457449) (xy 389.174948 -409.522889) (xy 389.166159 -409.587737) (xy 389.148738 -409.650816)
			(xy 389.122999 -409.710982) (xy 389.106664 -409.739338) (xy 389.103341 -409.745359) (xy 389.09974 -409.758625)
			(xy 389.099552 -409.7655) (xy 389.099552 -410.051504) (xy 389.099083 -410.061652) (xy 389.091295 -410.080394)
			(xy 389.076914 -410.094716) (xy 389.05814 -410.102424) (xy 389.04799 -410.102812) (xy 388.33171 -410.102812)
			(xy 388.32159 -410.102267) (xy 388.302879 -410.094552) (xy 388.288524 -410.080284) (xy 388.280696 -410.061621)
			(xy 388.280148 -410.051504) (xy 388.280148 -409.7655) (xy 388.279963 -409.758626) (xy 388.276351 -409.745363)
			(xy 388.273036 -409.739338) (xy 388.256668 -409.710999) (xy 388.230927 -409.650828) (xy 388.213504 -409.587744)
			(xy 388.204715 -409.522892) (xy 386.916158 -409.522892) (xy 386.90677 -409.539186) (xy 386.903412 -409.545204)
			(xy 386.899673 -409.558462) (xy 386.899404 -409.565348) (xy 386.899404 -410.314648) (xy 386.899657 -410.321538)
			(xy 386.903386 -410.334804) (xy 386.90677 -410.34081) (xy 386.923094 -410.369174) (xy 386.948838 -410.429339)
			(xy 386.966266 -410.492417) (xy 386.97506 -410.557265) (xy 386.975062 -410.622707) (xy 386.975062 -410.622709)
			(xy 390.404868 -410.622709) (xy 390.40487 -410.557264) (xy 390.413666 -410.492413) (xy 390.431096 -410.429332)
			(xy 390.456844 -410.369166) (xy 390.473184 -410.34081) (xy 390.476494 -410.334783) (xy 390.480103 -410.321521)
			(xy 390.480296 -410.314648) (xy 390.480296 -409.565348) (xy 390.480086 -409.558476) (xy 390.47649 -409.545213)
			(xy 390.473184 -409.539186) (xy 390.456855 -409.510825) (xy 390.431108 -409.45066) (xy 390.413679 -409.387581)
			(xy 390.404884 -409.322732) (xy 390.404883 -409.257289) (xy 390.413675 -409.19244) (xy 390.431101 -409.12936)
			(xy 390.456846 -409.069194) (xy 390.473184 -409.040838) (xy 390.476484 -409.034806) (xy 390.480099 -409.021548)
			(xy 390.480296 -409.014676) (xy 390.480296 -408.728672) (xy 390.480699 -408.718517) (xy 390.488503 -408.699764)
			(xy 390.502905 -408.685442) (xy 390.5217 -408.677743) (xy 390.531858 -408.677364) (xy 391.248138 -408.677364)
			(xy 391.25827 -408.677796) (xy 391.276997 -408.685541) (xy 391.291352 -408.699844) (xy 391.299166 -408.718542)
			(xy 391.2997 -408.728672) (xy 391.2997 -409.014676) (xy 391.299901 -409.021549) (xy 391.303503 -409.034811)
			(xy 391.306812 -409.040838) (xy 391.323161 -409.069188) (xy 391.348907 -409.129356) (xy 391.366334 -409.192437)
			(xy 391.375126 -409.257288) (xy 391.375125 -409.322732) (xy 391.36633 -409.387583) (xy 391.3489 -409.450664)
			(xy 391.331996 -409.490164) (xy 392.603744 -409.490164) (xy 392.607735 -409.427997) (xy 392.619644 -409.36685)
			(xy 392.639273 -409.307729) (xy 392.666302 -409.251603) (xy 392.700286 -409.199394) (xy 392.740668 -409.151959)
			(xy 392.786784 -409.110078) (xy 392.837876 -409.074438) (xy 392.893107 -409.045624) (xy 392.951569 -409.02411)
			(xy 393.012303 -409.010248) (xy 393.07431 -409.004266) (xy 393.136573 -409.006262) (xy 393.19807 -409.016205)
			(xy 393.257791 -409.033929) (xy 393.314754 -409.059146) (xy 393.368025 -409.091439) (xy 393.41673 -409.130279)
			(xy 393.460067 -409.175029) (xy 393.497327 -409.224953) (xy 393.527896 -409.279232) (xy 393.53226 -409.290012)
			(xy 394.803892 -409.290012) (xy 394.807883 -409.227845) (xy 394.819792 -409.166698) (xy 394.839421 -409.107577)
			(xy 394.86645 -409.051451) (xy 394.900434 -408.999242) (xy 394.940816 -408.951807) (xy 394.986932 -408.909926)
			(xy 395.038024 -408.874286) (xy 395.093255 -408.845472) (xy 395.151717 -408.823958) (xy 395.212451 -408.810096)
			(xy 395.274458 -408.804114) (xy 395.336721 -408.80611) (xy 395.398218 -408.816053) (xy 395.457939 -408.833777)
			(xy 395.514902 -408.858994) (xy 395.568173 -408.891287) (xy 395.616878 -408.930127) (xy 395.660215 -408.974877)
			(xy 395.697475 -409.024801) (xy 395.728044 -409.07908) (xy 395.751422 -409.136823) (xy 395.767223 -409.197081)
			(xy 395.775189 -409.258864) (xy 395.775688 -409.290012) (xy 395.775189 -409.32116) (xy 395.767223 -409.382943)
			(xy 395.751422 -409.443201) (xy 395.728044 -409.500944) (xy 395.697475 -409.555223) (xy 395.660215 -409.605147)
			(xy 395.616878 -409.649897) (xy 395.568173 -409.688737) (xy 395.514902 -409.72103) (xy 395.457939 -409.746247)
			(xy 395.398218 -409.763971) (xy 395.336721 -409.773914) (xy 395.274458 -409.77591) (xy 395.212451 -409.769928)
			(xy 395.151717 -409.756066) (xy 395.093255 -409.734552) (xy 395.038024 -409.705738) (xy 394.986932 -409.670098)
			(xy 394.940816 -409.628217) (xy 394.900434 -409.580782) (xy 394.86645 -409.528573) (xy 394.839421 -409.472447)
			(xy 394.819792 -409.413326) (xy 394.807883 -409.352179) (xy 394.803892 -409.290012) (xy 393.53226 -409.290012)
			(xy 393.551274 -409.336975) (xy 393.567075 -409.397233) (xy 393.575041 -409.459016) (xy 393.57554 -409.490164)
			(xy 393.575041 -409.521312) (xy 393.567075 -409.583095) (xy 393.551274 -409.643353) (xy 393.527896 -409.701096)
			(xy 393.497327 -409.755375) (xy 393.460067 -409.805299) (xy 393.41673 -409.850049) (xy 393.368025 -409.888889)
			(xy 393.314754 -409.921182) (xy 393.257791 -409.946399) (xy 393.19807 -409.964123) (xy 393.136573 -409.974066)
			(xy 393.07431 -409.976062) (xy 393.012303 -409.97008) (xy 392.951569 -409.956218) (xy 392.893107 -409.934704)
			(xy 392.837876 -409.90589) (xy 392.786784 -409.87025) (xy 392.740668 -409.828369) (xy 392.700286 -409.780934)
			(xy 392.666302 -409.728725) (xy 392.639273 -409.672599) (xy 392.619644 -409.613478) (xy 392.607735 -409.552331)
			(xy 392.603744 -409.490164) (xy 391.331996 -409.490164) (xy 391.323152 -409.51083) (xy 391.306812 -409.539186)
			(xy 391.303503 -409.545214) (xy 391.299894 -409.558475) (xy 391.2997 -409.565348) (xy 391.2997 -410.314648)
			(xy 391.299912 -410.32152) (xy 391.303507 -410.334782) (xy 391.306812 -410.34081) (xy 391.323137 -410.369173)
			(xy 391.348885 -410.429338) (xy 391.366315 -410.492416) (xy 391.37511 -410.557265) (xy 391.375111 -410.589984)
			(xy 394.803892 -410.589984) (xy 394.807883 -410.527817) (xy 394.819792 -410.46667) (xy 394.839421 -410.407549)
			(xy 394.86645 -410.351423) (xy 394.900434 -410.299214) (xy 394.940816 -410.251779) (xy 394.986932 -410.209898)
			(xy 395.038024 -410.174258) (xy 395.093255 -410.145444) (xy 395.151717 -410.12393) (xy 395.212451 -410.110068)
			(xy 395.274458 -410.104086) (xy 395.336721 -410.106082) (xy 395.398218 -410.116025) (xy 395.457939 -410.133749)
			(xy 395.514902 -410.158966) (xy 395.568173 -410.191259) (xy 395.616878 -410.230099) (xy 395.660215 -410.274849)
			(xy 395.697475 -410.324773) (xy 395.728044 -410.379052) (xy 395.751422 -410.436795) (xy 395.767223 -410.497053)
			(xy 395.775189 -410.558836) (xy 395.775688 -410.589984) (xy 395.775189 -410.621132) (xy 395.767223 -410.682915)
			(xy 395.751422 -410.743173) (xy 395.728044 -410.800916) (xy 395.697475 -410.855195) (xy 395.660215 -410.905119)
			(xy 395.616878 -410.949869) (xy 395.568173 -410.988709) (xy 395.514902 -411.021002) (xy 395.457939 -411.046219)
			(xy 395.398218 -411.063943) (xy 395.336721 -411.073886) (xy 395.274458 -411.075882) (xy 395.212451 -411.0699)
			(xy 395.151717 -411.056038) (xy 395.093255 -411.034524) (xy 395.038024 -411.00571) (xy 394.986932 -410.97007)
			(xy 394.940816 -410.928189) (xy 394.900434 -410.880754) (xy 394.86645 -410.828545) (xy 394.839421 -410.772419)
			(xy 394.819792 -410.713298) (xy 394.807883 -410.652151) (xy 394.803892 -410.589984) (xy 391.375111 -410.589984)
			(xy 391.375112 -410.622708) (xy 391.36632 -410.687557) (xy 391.348894 -410.750636) (xy 391.32315 -410.810802)
			(xy 391.306812 -410.839158) (xy 391.303513 -410.84519) (xy 391.299897 -410.858448) (xy 391.2997 -410.86532)
			(xy 391.2997 -411.151324) (xy 391.299298 -411.16148) (xy 391.291495 -411.180233) (xy 391.277092 -411.194555)
			(xy 391.258296 -411.202254) (xy 391.248138 -411.202632) (xy 390.531858 -411.202632) (xy 390.521725 -411.202207)
			(xy 390.502998 -411.19446) (xy 390.488642 -411.180155) (xy 390.480829 -411.161455) (xy 390.480296 -411.151324)
			(xy 390.480296 -410.86532) (xy 390.480097 -410.858447) (xy 390.476493 -410.845185) (xy 390.473184 -410.839158)
			(xy 390.456832 -410.81081) (xy 390.431087 -410.750642) (xy 390.41366 -410.68756) (xy 390.404868 -410.622709)
			(xy 386.975062 -410.622709) (xy 386.966271 -410.687556) (xy 386.948847 -410.750635) (xy 386.923106 -410.810802)
			(xy 386.90677 -410.839158) (xy 386.903387 -410.845164) (xy 386.899663 -410.858431) (xy 386.899404 -410.86532)
			(xy 386.899404 -411.151324) (xy 386.898935 -411.161434) (xy 386.89119 -411.180112) (xy 386.876888 -411.194406)
			(xy 386.858206 -411.20214) (xy 386.848096 -411.202632) (xy 386.131816 -411.202632) (xy 386.121712 -411.202103)
			(xy 386.10304 -411.194376) (xy 386.088746 -411.180093) (xy 386.081005 -411.161427) (xy 386.080508 -411.151324)
			(xy 386.080508 -410.86532) (xy 386.080266 -410.858429) (xy 386.076529 -410.845164) (xy 386.073142 -410.839158)
			(xy 386.056791 -410.810809) (xy 386.031048 -410.750641) (xy 386.013623 -410.687559) (xy 386.004832 -410.622708)
			(xy 382.575026 -410.622708) (xy 382.566234 -410.687556) (xy 382.548809 -410.750636) (xy 382.523065 -410.810802)
			(xy 382.506728 -410.839158) (xy 382.50343 -410.845191) (xy 382.499813 -410.858448) (xy 382.499616 -410.86532)
			(xy 382.499616 -411.151324) (xy 382.499198 -411.161478) (xy 382.491398 -411.180228) (xy 382.477 -411.19455)
			(xy 382.45821 -411.202251) (xy 382.448054 -411.202632) (xy 381.731774 -411.202632) (xy 381.721642 -411.202194)
			(xy 381.702915 -411.194453) (xy 381.688559 -411.180151) (xy 381.680745 -411.161454) (xy 381.680212 -411.151324)
			(xy 381.680212 -410.86532) (xy 381.680011 -410.858447) (xy 381.676409 -410.845185) (xy 381.6731 -410.839158)
			(xy 381.65675 -410.810809) (xy 381.63101 -410.75064) (xy 381.613586 -410.687559) (xy 381.604796 -410.622708)
			(xy 378.174976 -410.622708) (xy 378.166185 -410.687555) (xy 378.148762 -410.750635) (xy 378.123022 -410.810802)
			(xy 378.106686 -410.839158) (xy 378.103304 -410.845164) (xy 378.099579 -410.858431) (xy 378.09932 -410.86532)
			(xy 378.09932 -411.151324) (xy 378.098835 -411.161432) (xy 378.091093 -411.180107) (xy 378.076797 -411.1944)
			(xy 378.05812 -411.202138) (xy 378.048012 -411.202632) (xy 377.331732 -411.202632) (xy 377.321615 -411.202159)
			(xy 377.302919 -411.194427) (xy 377.288604 -411.180128) (xy 377.280852 -411.16144) (xy 377.280424 -411.151324)
			(xy 377.280424 -410.86532) (xy 377.280215 -410.858425) (xy 377.276471 -410.845153) (xy 377.273058 -410.839158)
			(xy 377.256706 -410.81081) (xy 377.230963 -410.750641) (xy 377.213537 -410.68756) (xy 377.204746 -410.622708)
			(xy 351.775074 -410.622708) (xy 351.767311 -410.682915) (xy 351.75151 -410.743173) (xy 351.728132 -410.800916)
			(xy 351.697563 -410.855195) (xy 351.660303 -410.905119) (xy 351.616966 -410.949869) (xy 351.568261 -410.988709)
			(xy 351.51499 -411.021002) (xy 351.458027 -411.046219) (xy 351.398306 -411.063943) (xy 351.336809 -411.073886)
			(xy 351.274546 -411.075882) (xy 351.212539 -411.0699) (xy 351.151805 -411.056038) (xy 351.093343 -411.034524)
			(xy 351.038112 -411.00571) (xy 350.98702 -410.97007) (xy 350.940904 -410.928189) (xy 350.900522 -410.880754)
			(xy 350.866538 -410.828545) (xy 350.839509 -410.772419) (xy 350.81988 -410.713298) (xy 350.807971 -410.652151)
			(xy 350.80398 -410.589984) (xy 347.375187 -410.589984) (xy 347.375188 -410.622707) (xy 347.366398 -410.687555)
			(xy 347.348975 -410.750635) (xy 347.323235 -410.810801) (xy 347.3069 -410.839158) (xy 347.3036 -410.84519)
			(xy 347.299985 -410.858448) (xy 347.299788 -410.86532) (xy 347.299788 -411.151324) (xy 347.299398 -411.161481)
			(xy 347.291592 -411.180236) (xy 347.277186 -411.194559) (xy 347.258386 -411.202256) (xy 347.248226 -411.202632)
			(xy 346.531946 -411.202632) (xy 346.521819 -411.202135) (xy 346.503093 -411.194417) (xy 346.488735 -411.180133)
			(xy 346.480919 -411.161449) (xy 346.480384 -411.151324) (xy 346.480384 -410.86532) (xy 346.480186 -410.858447)
			(xy 346.476582 -410.845184) (xy 346.473272 -410.839158) (xy 346.45692 -410.81081) (xy 346.431176 -410.750642)
			(xy 346.41375 -410.68756) (xy 346.404958 -410.622709) (xy 342.975152 -410.622709) (xy 342.966361 -410.687556)
			(xy 342.948936 -410.750635) (xy 342.923194 -410.810802) (xy 342.906858 -410.839158) (xy 342.903474 -410.845163)
			(xy 342.899751 -410.858431) (xy 342.899492 -410.86532) (xy 342.899492 -411.151324) (xy 342.899034 -411.161435)
			(xy 342.891287 -411.180116) (xy 342.876982 -411.19441) (xy 342.858296 -411.202142) (xy 342.848184 -411.202632)
			(xy 342.131904 -411.202632) (xy 342.121799 -411.202112) (xy 342.103128 -411.194382) (xy 342.088834 -411.180096)
			(xy 342.081093 -411.161428) (xy 342.080596 -411.151324) (xy 342.080596 -410.86532) (xy 342.080356 -410.858429)
			(xy 342.076618 -410.845163) (xy 342.07323 -410.839158) (xy 342.056879 -410.810809) (xy 342.031137 -410.750641)
			(xy 342.013713 -410.687559) (xy 342.004921 -410.622708) (xy 338.575116 -410.622708) (xy 338.566324 -410.687557)
			(xy 338.548898 -410.750636) (xy 338.523154 -410.810802) (xy 338.506816 -410.839158) (xy 338.503517 -410.845191)
			(xy 338.499901 -410.858448) (xy 338.499704 -410.86532) (xy 338.499704 -411.151324) (xy 338.499298 -411.161479)
			(xy 338.491495 -411.180231) (xy 338.477094 -411.194554) (xy 338.458299 -411.202253) (xy 338.448142 -411.202632)
			(xy 337.731862 -411.202632) (xy 337.721729 -411.202204) (xy 337.703002 -411.194458) (xy 337.688646 -411.180154)
			(xy 337.680833 -411.161455) (xy 337.6803 -411.151324) (xy 337.6803 -410.86532) (xy 337.6801 -410.858447)
			(xy 337.676497 -410.845185) (xy 337.673188 -410.839158) (xy 337.656836 -410.81081) (xy 337.63109 -410.750642)
			(xy 337.613664 -410.68756) (xy 337.604871 -410.622709) (xy 334.175066 -410.622709) (xy 334.166275 -410.687556)
			(xy 334.148851 -410.750635) (xy 334.12311 -410.810802) (xy 334.106774 -410.839158) (xy 334.103391 -410.845164)
			(xy 334.099667 -410.858431) (xy 334.099408 -410.86532) (xy 334.099408 -411.151324) (xy 334.098935 -411.161433)
			(xy 334.091191 -411.180111) (xy 334.07689 -411.194404) (xy 334.05821 -411.20214) (xy 334.0481 -411.202632)
			(xy 333.33182 -411.202632) (xy 333.321716 -411.202099) (xy 333.303045 -411.194374) (xy 333.28875 -411.180092)
			(xy 333.281009 -411.161427) (xy 333.280512 -411.151324) (xy 333.280512 -410.86532) (xy 333.280305 -410.858425)
			(xy 333.276559 -410.845153) (xy 333.273146 -410.839158) (xy 333.256795 -410.810809) (xy 333.231052 -410.750641)
			(xy 333.213627 -410.687559) (xy 333.204835 -410.622708) (xy 326.525636 -410.622708) (xy 326.525636 -412.090108)
			(xy 331.003918 -412.090108) (xy 331.007909 -412.027941) (xy 331.019818 -411.966794) (xy 331.039447 -411.907673)
			(xy 331.066476 -411.851547) (xy 331.10046 -411.799338) (xy 331.140842 -411.751903) (xy 331.186958 -411.710022)
			(xy 331.23805 -411.674382) (xy 331.293281 -411.645568) (xy 331.351743 -411.624054) (xy 331.412477 -411.610192)
			(xy 331.474484 -411.60421) (xy 331.536747 -411.606206) (xy 331.598244 -411.616149) (xy 331.657965 -411.633873)
			(xy 331.714928 -411.65909) (xy 331.768199 -411.691383) (xy 331.816904 -411.730223) (xy 331.860241 -411.774973)
			(xy 331.897501 -411.824897) (xy 331.92807 -411.879176) (xy 331.951448 -411.936919) (xy 331.967249 -411.997177)
			(xy 331.975215 -412.05896) (xy 331.975714 -412.090108) (xy 335.40396 -412.090108) (xy 335.407951 -412.027941)
			(xy 335.41986 -411.966794) (xy 335.439489 -411.907673) (xy 335.466518 -411.851547) (xy 335.500502 -411.799338)
			(xy 335.540884 -411.751903) (xy 335.587 -411.710022) (xy 335.638092 -411.674382) (xy 335.693323 -411.645568)
			(xy 335.751785 -411.624054) (xy 335.812519 -411.610192) (xy 335.874526 -411.60421) (xy 335.936789 -411.606206)
			(xy 335.998286 -411.616149) (xy 336.058007 -411.633873) (xy 336.11497 -411.65909) (xy 336.168241 -411.691383)
			(xy 336.216946 -411.730223) (xy 336.260283 -411.774973) (xy 336.297543 -411.824897) (xy 336.328112 -411.879176)
			(xy 336.35149 -411.936919) (xy 336.367291 -411.997177) (xy 336.375257 -412.05896) (xy 336.375756 -412.090108)
			(xy 339.804002 -412.090108) (xy 339.807993 -412.027941) (xy 339.819902 -411.966794) (xy 339.839531 -411.907673)
			(xy 339.86656 -411.851547) (xy 339.900544 -411.799338) (xy 339.940926 -411.751903) (xy 339.987042 -411.710022)
			(xy 340.038134 -411.674382) (xy 340.093365 -411.645568) (xy 340.151827 -411.624054) (xy 340.212561 -411.610192)
			(xy 340.274568 -411.60421) (xy 340.336831 -411.606206) (xy 340.398328 -411.616149) (xy 340.458049 -411.633873)
			(xy 340.515012 -411.65909) (xy 340.568283 -411.691383) (xy 340.616988 -411.730223) (xy 340.660325 -411.774973)
			(xy 340.697585 -411.824897) (xy 340.728154 -411.879176) (xy 340.751532 -411.936919) (xy 340.767333 -411.997177)
			(xy 340.775299 -412.05896) (xy 340.775798 -412.090108) (xy 344.20379 -412.090108) (xy 344.207781 -412.027941)
			(xy 344.21969 -411.966794) (xy 344.239319 -411.907673) (xy 344.266348 -411.851547) (xy 344.300332 -411.799338)
			(xy 344.340714 -411.751903) (xy 344.38683 -411.710022) (xy 344.437922 -411.674382) (xy 344.493153 -411.645568)
			(xy 344.551615 -411.624054) (xy 344.612349 -411.610192) (xy 344.674356 -411.60421) (xy 344.736619 -411.606206)
			(xy 344.798116 -411.616149) (xy 344.857837 -411.633873) (xy 344.9148 -411.65909) (xy 344.968071 -411.691383)
			(xy 345.016776 -411.730223) (xy 345.060113 -411.774973) (xy 345.097373 -411.824897) (xy 345.127942 -411.879176)
			(xy 345.15132 -411.936919) (xy 345.167121 -411.997177) (xy 345.175087 -412.05896) (xy 345.175586 -412.090108)
			(xy 348.603832 -412.090108) (xy 348.607823 -412.027941) (xy 348.619732 -411.966794) (xy 348.639361 -411.907673)
			(xy 348.66639 -411.851547) (xy 348.700374 -411.799338) (xy 348.740756 -411.751903) (xy 348.786872 -411.710022)
			(xy 348.837964 -411.674382) (xy 348.893195 -411.645568) (xy 348.951657 -411.624054) (xy 349.012391 -411.610192)
			(xy 349.074398 -411.60421) (xy 349.136661 -411.606206) (xy 349.198158 -411.616149) (xy 349.257879 -411.633873)
			(xy 349.314842 -411.65909) (xy 349.368113 -411.691383) (xy 349.416818 -411.730223) (xy 349.460155 -411.774973)
			(xy 349.497415 -411.824897) (xy 349.527984 -411.879176) (xy 349.551362 -411.936919) (xy 349.567163 -411.997177)
			(xy 349.575129 -412.05896) (xy 349.575628 -412.090108) (xy 375.00383 -412.090108) (xy 375.007821 -412.027941)
			(xy 375.01973 -411.966794) (xy 375.039359 -411.907673) (xy 375.066388 -411.851547) (xy 375.100372 -411.799338)
			(xy 375.140754 -411.751903) (xy 375.18687 -411.710022) (xy 375.237962 -411.674382) (xy 375.293193 -411.645568)
			(xy 375.351655 -411.624054) (xy 375.412389 -411.610192) (xy 375.474396 -411.60421) (xy 375.536659 -411.606206)
			(xy 375.598156 -411.616149) (xy 375.657877 -411.633873) (xy 375.71484 -411.65909) (xy 375.768111 -411.691383)
			(xy 375.816816 -411.730223) (xy 375.860153 -411.774973) (xy 375.897413 -411.824897) (xy 375.927982 -411.879176)
			(xy 375.95136 -411.936919) (xy 375.967161 -411.997177) (xy 375.975127 -412.05896) (xy 375.975626 -412.090108)
			(xy 379.403872 -412.090108) (xy 379.407863 -412.027941) (xy 379.419772 -411.966794) (xy 379.439401 -411.907673)
			(xy 379.46643 -411.851547) (xy 379.500414 -411.799338) (xy 379.540796 -411.751903) (xy 379.586912 -411.710022)
			(xy 379.638004 -411.674382) (xy 379.693235 -411.645568) (xy 379.751697 -411.624054) (xy 379.812431 -411.610192)
			(xy 379.874438 -411.60421) (xy 379.936701 -411.606206) (xy 379.998198 -411.616149) (xy 380.057919 -411.633873)
			(xy 380.114882 -411.65909) (xy 380.168153 -411.691383) (xy 380.216858 -411.730223) (xy 380.260195 -411.774973)
			(xy 380.297455 -411.824897) (xy 380.328024 -411.879176) (xy 380.351402 -411.936919) (xy 380.367203 -411.997177)
			(xy 380.375169 -412.05896) (xy 380.375668 -412.090108) (xy 383.803914 -412.090108) (xy 383.807905 -412.027941)
			(xy 383.819814 -411.966794) (xy 383.839443 -411.907673) (xy 383.866472 -411.851547) (xy 383.900456 -411.799338)
			(xy 383.940838 -411.751903) (xy 383.986954 -411.710022) (xy 384.038046 -411.674382) (xy 384.093277 -411.645568)
			(xy 384.151739 -411.624054) (xy 384.212473 -411.610192) (xy 384.27448 -411.60421) (xy 384.336743 -411.606206)
			(xy 384.39824 -411.616149) (xy 384.457961 -411.633873) (xy 384.514924 -411.65909) (xy 384.568195 -411.691383)
			(xy 384.6169 -411.730223) (xy 384.660237 -411.774973) (xy 384.697497 -411.824897) (xy 384.728066 -411.879176)
			(xy 384.751444 -411.936919) (xy 384.767245 -411.997177) (xy 384.775211 -412.05896) (xy 384.77571 -412.090108)
			(xy 388.203702 -412.090108) (xy 388.207693 -412.027941) (xy 388.219602 -411.966794) (xy 388.239231 -411.907673)
			(xy 388.26626 -411.851547) (xy 388.300244 -411.799338) (xy 388.340626 -411.751903) (xy 388.386742 -411.710022)
			(xy 388.437834 -411.674382) (xy 388.493065 -411.645568) (xy 388.551527 -411.624054) (xy 388.612261 -411.610192)
			(xy 388.674268 -411.60421) (xy 388.736531 -411.606206) (xy 388.798028 -411.616149) (xy 388.857749 -411.633873)
			(xy 388.914712 -411.65909) (xy 388.967983 -411.691383) (xy 389.016688 -411.730223) (xy 389.060025 -411.774973)
			(xy 389.097285 -411.824897) (xy 389.127854 -411.879176) (xy 389.151232 -411.936919) (xy 389.167033 -411.997177)
			(xy 389.174999 -412.05896) (xy 389.175498 -412.090108) (xy 392.603744 -412.090108) (xy 392.607735 -412.027941)
			(xy 392.619644 -411.966794) (xy 392.639273 -411.907673) (xy 392.666302 -411.851547) (xy 392.700286 -411.799338)
			(xy 392.740668 -411.751903) (xy 392.786784 -411.710022) (xy 392.837876 -411.674382) (xy 392.893107 -411.645568)
			(xy 392.951569 -411.624054) (xy 393.012303 -411.610192) (xy 393.07431 -411.60421) (xy 393.136573 -411.606206)
			(xy 393.19807 -411.616149) (xy 393.257791 -411.633873) (xy 393.314754 -411.65909) (xy 393.368025 -411.691383)
			(xy 393.41673 -411.730223) (xy 393.460067 -411.774973) (xy 393.497327 -411.824897) (xy 393.527896 -411.879176)
			(xy 393.551274 -411.936919) (xy 393.567075 -411.997177) (xy 393.575041 -412.05896) (xy 393.57554 -412.090108)
			(xy 393.575041 -412.121256) (xy 393.567075 -412.183039) (xy 393.551274 -412.243297) (xy 393.527896 -412.30104)
			(xy 393.497327 -412.355319) (xy 393.460067 -412.405243) (xy 393.41673 -412.449993) (xy 393.368025 -412.488833)
			(xy 393.314754 -412.521126) (xy 393.257791 -412.546343) (xy 393.19807 -412.564067) (xy 393.136573 -412.57401)
			(xy 393.07431 -412.576006) (xy 393.012303 -412.570024) (xy 392.951569 -412.556162) (xy 392.893107 -412.534648)
			(xy 392.837876 -412.505834) (xy 392.786784 -412.470194) (xy 392.740668 -412.428313) (xy 392.700286 -412.380878)
			(xy 392.666302 -412.328669) (xy 392.639273 -412.272543) (xy 392.619644 -412.213422) (xy 392.607735 -412.152275)
			(xy 392.603744 -412.090108) (xy 389.175498 -412.090108) (xy 389.174999 -412.121256) (xy 389.167033 -412.183039)
			(xy 389.151232 -412.243297) (xy 389.127854 -412.30104) (xy 389.097285 -412.355319) (xy 389.060025 -412.405243)
			(xy 389.016688 -412.449993) (xy 388.967983 -412.488833) (xy 388.914712 -412.521126) (xy 388.857749 -412.546343)
			(xy 388.798028 -412.564067) (xy 388.736531 -412.57401) (xy 388.674268 -412.576006) (xy 388.612261 -412.570024)
			(xy 388.551527 -412.556162) (xy 388.493065 -412.534648) (xy 388.437834 -412.505834) (xy 388.386742 -412.470194)
			(xy 388.340626 -412.428313) (xy 388.300244 -412.380878) (xy 388.26626 -412.328669) (xy 388.239231 -412.272543)
			(xy 388.219602 -412.213422) (xy 388.207693 -412.152275) (xy 388.203702 -412.090108) (xy 384.77571 -412.090108)
			(xy 384.775211 -412.121256) (xy 384.767245 -412.183039) (xy 384.751444 -412.243297) (xy 384.728066 -412.30104)
			(xy 384.697497 -412.355319) (xy 384.660237 -412.405243) (xy 384.6169 -412.449993) (xy 384.568195 -412.488833)
			(xy 384.514924 -412.521126) (xy 384.457961 -412.546343) (xy 384.39824 -412.564067) (xy 384.336743 -412.57401)
			(xy 384.27448 -412.576006) (xy 384.212473 -412.570024) (xy 384.151739 -412.556162) (xy 384.093277 -412.534648)
			(xy 384.038046 -412.505834) (xy 383.986954 -412.470194) (xy 383.940838 -412.428313) (xy 383.900456 -412.380878)
			(xy 383.866472 -412.328669) (xy 383.839443 -412.272543) (xy 383.819814 -412.213422) (xy 383.807905 -412.152275)
			(xy 383.803914 -412.090108) (xy 380.375668 -412.090108) (xy 380.375169 -412.121256) (xy 380.367203 -412.183039)
			(xy 380.351402 -412.243297) (xy 380.328024 -412.30104) (xy 380.297455 -412.355319) (xy 380.260195 -412.405243)
			(xy 380.216858 -412.449993) (xy 380.168153 -412.488833) (xy 380.114882 -412.521126) (xy 380.057919 -412.546343)
			(xy 379.998198 -412.564067) (xy 379.936701 -412.57401) (xy 379.874438 -412.576006) (xy 379.812431 -412.570024)
			(xy 379.751697 -412.556162) (xy 379.693235 -412.534648) (xy 379.638004 -412.505834) (xy 379.586912 -412.470194)
			(xy 379.540796 -412.428313) (xy 379.500414 -412.380878) (xy 379.46643 -412.328669) (xy 379.439401 -412.272543)
			(xy 379.419772 -412.213422) (xy 379.407863 -412.152275) (xy 379.403872 -412.090108) (xy 375.975626 -412.090108)
			(xy 375.975127 -412.121256) (xy 375.967161 -412.183039) (xy 375.95136 -412.243297) (xy 375.927982 -412.30104)
			(xy 375.897413 -412.355319) (xy 375.860153 -412.405243) (xy 375.816816 -412.449993) (xy 375.768111 -412.488833)
			(xy 375.71484 -412.521126) (xy 375.657877 -412.546343) (xy 375.598156 -412.564067) (xy 375.536659 -412.57401)
			(xy 375.474396 -412.576006) (xy 375.412389 -412.570024) (xy 375.351655 -412.556162) (xy 375.293193 -412.534648)
			(xy 375.237962 -412.505834) (xy 375.18687 -412.470194) (xy 375.140754 -412.428313) (xy 375.100372 -412.380878)
			(xy 375.066388 -412.328669) (xy 375.039359 -412.272543) (xy 375.01973 -412.213422) (xy 375.007821 -412.152275)
			(xy 375.00383 -412.090108) (xy 349.575628 -412.090108) (xy 349.575129 -412.121256) (xy 349.567163 -412.183039)
			(xy 349.551362 -412.243297) (xy 349.527984 -412.30104) (xy 349.497415 -412.355319) (xy 349.460155 -412.405243)
			(xy 349.416818 -412.449993) (xy 349.368113 -412.488833) (xy 349.314842 -412.521126) (xy 349.257879 -412.546343)
			(xy 349.198158 -412.564067) (xy 349.136661 -412.57401) (xy 349.074398 -412.576006) (xy 349.012391 -412.570024)
			(xy 348.951657 -412.556162) (xy 348.893195 -412.534648) (xy 348.837964 -412.505834) (xy 348.786872 -412.470194)
			(xy 348.740756 -412.428313) (xy 348.700374 -412.380878) (xy 348.66639 -412.328669) (xy 348.639361 -412.272543)
			(xy 348.619732 -412.213422) (xy 348.607823 -412.152275) (xy 348.603832 -412.090108) (xy 345.175586 -412.090108)
			(xy 345.175087 -412.121256) (xy 345.167121 -412.183039) (xy 345.15132 -412.243297) (xy 345.127942 -412.30104)
			(xy 345.097373 -412.355319) (xy 345.060113 -412.405243) (xy 345.016776 -412.449993) (xy 344.968071 -412.488833)
			(xy 344.9148 -412.521126) (xy 344.857837 -412.546343) (xy 344.798116 -412.564067) (xy 344.736619 -412.57401)
			(xy 344.674356 -412.576006) (xy 344.612349 -412.570024) (xy 344.551615 -412.556162) (xy 344.493153 -412.534648)
			(xy 344.437922 -412.505834) (xy 344.38683 -412.470194) (xy 344.340714 -412.428313) (xy 344.300332 -412.380878)
			(xy 344.266348 -412.328669) (xy 344.239319 -412.272543) (xy 344.21969 -412.213422) (xy 344.207781 -412.152275)
			(xy 344.20379 -412.090108) (xy 340.775798 -412.090108) (xy 340.775299 -412.121256) (xy 340.767333 -412.183039)
			(xy 340.751532 -412.243297) (xy 340.728154 -412.30104) (xy 340.697585 -412.355319) (xy 340.660325 -412.405243)
			(xy 340.616988 -412.449993) (xy 340.568283 -412.488833) (xy 340.515012 -412.521126) (xy 340.458049 -412.546343)
			(xy 340.398328 -412.564067) (xy 340.336831 -412.57401) (xy 340.274568 -412.576006) (xy 340.212561 -412.570024)
			(xy 340.151827 -412.556162) (xy 340.093365 -412.534648) (xy 340.038134 -412.505834) (xy 339.987042 -412.470194)
			(xy 339.940926 -412.428313) (xy 339.900544 -412.380878) (xy 339.86656 -412.328669) (xy 339.839531 -412.272543)
			(xy 339.819902 -412.213422) (xy 339.807993 -412.152275) (xy 339.804002 -412.090108) (xy 336.375756 -412.090108)
			(xy 336.375257 -412.121256) (xy 336.367291 -412.183039) (xy 336.35149 -412.243297) (xy 336.328112 -412.30104)
			(xy 336.297543 -412.355319) (xy 336.260283 -412.405243) (xy 336.216946 -412.449993) (xy 336.168241 -412.488833)
			(xy 336.11497 -412.521126) (xy 336.058007 -412.546343) (xy 335.998286 -412.564067) (xy 335.936789 -412.57401)
			(xy 335.874526 -412.576006) (xy 335.812519 -412.570024) (xy 335.751785 -412.556162) (xy 335.693323 -412.534648)
			(xy 335.638092 -412.505834) (xy 335.587 -412.470194) (xy 335.540884 -412.428313) (xy 335.500502 -412.380878)
			(xy 335.466518 -412.328669) (xy 335.439489 -412.272543) (xy 335.41986 -412.213422) (xy 335.407951 -412.152275)
			(xy 335.40396 -412.090108) (xy 331.975714 -412.090108) (xy 331.975215 -412.121256) (xy 331.967249 -412.183039)
			(xy 331.951448 -412.243297) (xy 331.92807 -412.30104) (xy 331.897501 -412.355319) (xy 331.860241 -412.405243)
			(xy 331.816904 -412.449993) (xy 331.768199 -412.488833) (xy 331.714928 -412.521126) (xy 331.657965 -412.546343)
			(xy 331.598244 -412.564067) (xy 331.536747 -412.57401) (xy 331.474484 -412.576006) (xy 331.412477 -412.570024)
			(xy 331.351743 -412.556162) (xy 331.293281 -412.534648) (xy 331.23805 -412.505834) (xy 331.186958 -412.470194)
			(xy 331.140842 -412.428313) (xy 331.10046 -412.380878) (xy 331.066476 -412.328669) (xy 331.039447 -412.272543)
			(xy 331.019818 -412.213422) (xy 331.007909 -412.152275) (xy 331.003918 -412.090108) (xy 326.525636 -412.090108)
			(xy 326.525636 -416.51682) (xy 326.526761 -416.526325) (xy 326.535071 -416.543551) (xy 326.549084 -416.556569)
			(xy 326.566874 -416.56359) (xy 326.576436 -416.564064) (xy 401.023328 -416.564064) (xy 401.032909 -416.563674)
			(xy 401.050746 -416.556677) (xy 401.064777 -416.54363) (xy 401.073051 -416.526348) (xy 401.074128 -416.51682)
			(xy 401.074128 -394.27912) (xy 414.47466 -394.27912) (xy 414.484685 -394.279533) (xy 414.503212 -394.287197)
			(xy 414.517392 -394.301371) (xy 414.525063 -394.319895) (xy 414.52546 -394.32992) (xy 414.52546 -394.353034)
			(xy 414.525968 -394.353542) (xy 414.525968 -409.522892) (xy 419.00475 -409.522892) (xy 419.004754 -409.457446)
			(xy 419.013552 -409.392594) (xy 419.030984 -409.329513) (xy 419.056735 -409.269346) (xy 419.073076 -409.24099)
			(xy 419.076393 -409.234966) (xy 419.079998 -409.221702) (xy 419.080188 -409.214828) (xy 419.080188 -408.465528)
			(xy 419.079987 -408.458655) (xy 419.076385 -408.445393) (xy 419.073076 -408.439366) (xy 419.056731 -408.411014)
			(xy 419.030985 -408.350847) (xy 419.013558 -408.287766) (xy 419.004766 -408.222915) (xy 419.004767 -408.157471)
			(xy 419.013561 -408.092621) (xy 419.03099 -408.02954) (xy 419.056737 -407.969374) (xy 419.073076 -407.941018)
			(xy 419.076383 -407.934989) (xy 419.079994 -407.921729) (xy 419.080188 -407.914856) (xy 419.080188 -407.628852)
			(xy 419.080582 -407.618696) (xy 419.088391 -407.599945) (xy 419.102796 -407.585624) (xy 419.121592 -407.577924)
			(xy 419.13175 -407.577544) (xy 419.84803 -407.577544) (xy 419.858159 -407.578002) (xy 419.876882 -407.58574)
			(xy 419.891237 -407.600035) (xy 419.899055 -407.618725) (xy 419.899592 -407.628852) (xy 419.899592 -407.914856)
			(xy 419.899802 -407.921728) (xy 419.903398 -407.934991) (xy 419.906704 -407.941018) (xy 419.923033 -407.969378)
			(xy 419.948776 -408.029545) (xy 419.966201 -408.092624) (xy 419.974994 -408.157472) (xy 419.974995 -408.222914)
			(xy 419.966204 -408.287763) (xy 419.94878 -408.350842) (xy 419.923039 -408.411009) (xy 419.906704 -408.439366)
			(xy 419.903402 -408.445397) (xy 419.899788 -408.458656) (xy 419.899592 -408.465528) (xy 419.899592 -409.214828)
			(xy 419.899774 -409.221702) (xy 419.903389 -409.234965) (xy 419.906704 -409.24099) (xy 419.92301 -409.269363)
			(xy 419.948754 -409.329527) (xy 419.966182 -409.392603) (xy 419.974978 -409.457449) (xy 419.974982 -409.522889)
			(xy 419.966195 -409.587736) (xy 419.948774 -409.650815) (xy 419.923038 -409.710981) (xy 419.906704 -409.739338)
			(xy 419.903376 -409.745356) (xy 419.899779 -409.758625) (xy 419.899592 -409.7655) (xy 419.899592 -410.051504)
			(xy 419.899181 -410.061659) (xy 419.891383 -410.080413) (xy 419.876983 -410.094737) (xy 419.858187 -410.102435)
			(xy 419.84803 -410.102812) (xy 419.13175 -410.102812) (xy 419.121633 -410.102234) (xy 419.102923 -410.094532)
			(xy 419.088567 -410.080274) (xy 419.080736 -410.061618) (xy 419.080188 -410.051504) (xy 419.080188 -409.7655)
			(xy 419.079997 -409.758627) (xy 419.076388 -409.745364) (xy 419.073076 -409.739338) (xy 419.056707 -409.710999)
			(xy 419.030964 -409.650829) (xy 419.01354 -409.587745) (xy 419.00475 -409.522892) (xy 414.525968 -409.522892)
			(xy 414.525968 -410.622709) (xy 421.204656 -410.622709) (xy 421.204658 -410.557264) (xy 421.213453 -410.492413)
			(xy 421.230883 -410.429333) (xy 421.256631 -410.369166) (xy 421.27297 -410.34081) (xy 421.276332 -410.334794)
			(xy 421.280069 -410.321534) (xy 421.280336 -410.314648) (xy 421.280336 -409.565348) (xy 421.280115 -409.558454)
			(xy 421.276379 -409.545182) (xy 421.27297 -409.539186) (xy 421.256642 -409.510825) (xy 421.230895 -409.450659)
			(xy 421.213467 -409.38758) (xy 421.204672 -409.322732) (xy 421.20467 -409.257289) (xy 421.213463 -409.19244)
			(xy 421.230889 -409.12936) (xy 421.256632 -409.069194) (xy 421.27297 -409.040838) (xy 421.276358 -409.034835)
			(xy 421.280078 -409.021565) (xy 421.280336 -409.014676) (xy 421.280336 -408.728672) (xy 421.280694 -408.718543)
			(xy 421.288458 -408.699832) (xy 421.302793 -408.685517) (xy 421.321515 -408.67778) (xy 421.331644 -408.677364)
			(xy 422.047924 -408.677364) (xy 422.05803 -408.677864) (xy 422.076702 -408.685603) (xy 422.090994 -408.699895)
			(xy 422.098735 -408.718566) (xy 422.099232 -408.728672) (xy 422.099232 -409.014676) (xy 422.09947 -409.021567)
			(xy 422.103209 -409.034833) (xy 422.106598 -409.040838) (xy 422.122944 -409.069189) (xy 422.148685 -409.129357)
			(xy 422.166109 -409.192438) (xy 422.1749 -409.257289) (xy 422.174899 -409.322732) (xy 422.166105 -409.387582)
			(xy 422.148679 -409.450662) (xy 422.122935 -409.510829) (xy 422.115985 -409.522892) (xy 423.4048 -409.522892)
			(xy 423.404804 -409.457447) (xy 423.413601 -409.392595) (xy 423.431031 -409.329514) (xy 423.456779 -409.269346)
			(xy 423.473118 -409.24099) (xy 423.476483 -409.234975) (xy 423.480218 -409.221715) (xy 423.480484 -409.214828)
			(xy 423.480484 -408.465528) (xy 423.480242 -408.458637) (xy 423.476506 -408.445371) (xy 423.473118 -408.439366)
			(xy 423.456775 -408.411013) (xy 423.431032 -408.350846) (xy 423.413607 -408.287765) (xy 423.404816 -408.222915)
			(xy 423.404817 -408.157472) (xy 423.41361 -408.092622) (xy 423.431037 -408.029541) (xy 423.456781 -407.969374)
			(xy 423.473118 -407.941018) (xy 423.476473 -407.934998) (xy 423.480215 -407.921742) (xy 423.480484 -407.914856)
			(xy 423.480484 -407.628852) (xy 423.480946 -407.618742) (xy 423.488696 -407.600066) (xy 423.503 -407.585774)
			(xy 423.521682 -407.578038) (xy 423.531792 -407.577544) (xy 424.248072 -407.577544) (xy 424.258172 -407.578106)
			(xy 424.276839 -407.585825) (xy 424.291133 -407.600097) (xy 424.298879 -407.618753) (xy 424.29938 -407.628852)
			(xy 424.29938 -407.914856) (xy 424.299598 -407.92175) (xy 424.303336 -407.935022) (xy 424.306746 -407.941018)
			(xy 424.323077 -407.969378) (xy 424.348822 -408.029543) (xy 424.36625 -408.092623) (xy 424.375044 -408.157472)
			(xy 424.375045 -408.222914) (xy 424.366253 -408.287764) (xy 424.348827 -408.350844) (xy 424.323083 -408.41101)
			(xy 424.306746 -408.439366) (xy 424.303393 -408.445387) (xy 424.29965 -408.458643) (xy 424.29938 -408.465528)
			(xy 424.29938 -409.214828) (xy 424.299609 -409.221721) (xy 424.30334 -409.234993) (xy 424.306746 -409.24099)
			(xy 424.323053 -409.269363) (xy 424.348801 -409.329526) (xy 424.366231 -409.392602) (xy 424.375028 -409.457449)
			(xy 424.375032 -409.522889) (xy 424.366244 -409.587737) (xy 424.348821 -409.650816) (xy 424.323081 -409.710982)
			(xy 424.306746 -409.739338) (xy 424.303368 -409.745346) (xy 424.299642 -409.758612) (xy 424.29938 -409.7655)
			(xy 424.29938 -410.051504) (xy 424.298987 -410.061629) (xy 424.291234 -410.080337) (xy 424.27691 -410.094651)
			(xy 424.258197 -410.102393) (xy 424.248072 -410.102812) (xy 423.531792 -410.102812) (xy 423.521684 -410.102322)
			(xy 423.503008 -410.094584) (xy 423.488714 -410.080288) (xy 423.480978 -410.061612) (xy 423.480484 -410.051504)
			(xy 423.480484 -409.7655) (xy 423.480253 -409.758608) (xy 423.476509 -409.745342) (xy 423.473118 -409.739338)
			(xy 423.456751 -409.710998) (xy 423.431011 -409.650828) (xy 423.413589 -409.587744) (xy 423.4048 -409.522892)
			(xy 422.115985 -409.522892) (xy 422.106598 -409.539186) (xy 422.103242 -409.545205) (xy 422.099501 -409.558462)
			(xy 422.099232 -409.565348) (xy 422.099232 -410.314648) (xy 422.099459 -410.321541) (xy 422.103192 -410.334813)
			(xy 422.106598 -410.34081) (xy 422.122921 -410.369174) (xy 422.148664 -410.429339) (xy 422.16609 -410.492418)
			(xy 422.174884 -410.557266) (xy 422.174886 -410.622707) (xy 422.174886 -410.622708) (xy 425.604706 -410.622708)
			(xy 425.604708 -410.557264) (xy 425.613502 -410.492414) (xy 425.63093 -410.429334) (xy 425.656674 -410.369166)
			(xy 425.673012 -410.34081) (xy 425.676324 -410.334784) (xy 425.679931 -410.321521) (xy 425.680124 -410.314648)
			(xy 425.680124 -409.565348) (xy 425.679911 -409.558476) (xy 425.676317 -409.545214) (xy 425.673012 -409.539186)
			(xy 425.656686 -409.510824) (xy 425.630942 -409.450658) (xy 425.613516 -409.387579) (xy 425.604722 -409.322731)
			(xy 425.604721 -409.257289) (xy 425.613512 -409.192441) (xy 425.630935 -409.129361) (xy 425.656676 -409.069194)
			(xy 425.673012 -409.040838) (xy 425.676314 -409.034807) (xy 425.679927 -409.021548) (xy 425.680124 -409.014676)
			(xy 425.680124 -408.728672) (xy 425.680499 -408.718513) (xy 425.688308 -408.699755) (xy 425.70272 -408.685432)
			(xy 425.721525 -408.677738) (xy 425.731686 -408.677364) (xy 426.447966 -408.677364) (xy 426.458093 -408.677855)
			(xy 426.476818 -408.685576) (xy 426.491177 -408.699862) (xy 426.498993 -408.718547) (xy 426.499528 -408.728672)
			(xy 426.499528 -409.014676) (xy 426.499726 -409.021549) (xy 426.50333 -409.034812) (xy 426.50664 -409.040838)
			(xy 426.522988 -409.069188) (xy 426.548732 -409.129356) (xy 426.566158 -409.192437) (xy 426.57495 -409.257288)
			(xy 426.574949 -409.322732) (xy 426.566154 -409.387583) (xy 426.548725 -409.450663) (xy 426.522979 -409.51083)
			(xy 426.516029 -409.522892) (xy 427.804836 -409.522892) (xy 427.80484 -409.457446) (xy 427.813638 -409.392595)
			(xy 427.83107 -409.329513) (xy 427.85682 -409.269346) (xy 427.87316 -409.24099) (xy 427.876475 -409.234965)
			(xy 427.880081 -409.221702) (xy 427.880272 -409.214828) (xy 427.880272 -408.465528) (xy 427.880073 -408.458655)
			(xy 427.87647 -408.445392) (xy 427.87316 -408.439366) (xy 427.856815 -408.411014) (xy 427.831071 -408.350846)
			(xy 427.813644 -408.287765) (xy 427.804852 -408.222915) (xy 427.804853 -408.157471) (xy 427.813647 -408.092621)
			(xy 427.831075 -408.029541) (xy 427.856821 -407.969374) (xy 427.87316 -407.941018) (xy 427.876465 -407.934989)
			(xy 427.880077 -407.921729) (xy 427.880272 -407.914856) (xy 427.880272 -407.628852) (xy 427.880682 -407.618698)
			(xy 427.888488 -407.59995) (xy 427.902887 -407.58563) (xy 427.921678 -407.577927) (xy 427.931834 -407.577544)
			(xy 428.648114 -407.577544) (xy 428.658242 -407.578015) (xy 428.676964 -407.585749) (xy 428.69132 -407.600039)
			(xy 428.699138 -407.618726) (xy 428.699676 -407.628852) (xy 428.699676 -407.914856) (xy 428.699888 -407.921728)
			(xy 428.703483 -407.93499) (xy 428.706788 -407.941018) (xy 428.723118 -407.969378) (xy 428.748861 -408.029544)
			(xy 428.766287 -408.092624) (xy 428.77508 -408.157472) (xy 428.775081 -408.222914) (xy 428.76629 -408.287763)
			(xy 428.748865 -408.350843) (xy 428.723124 -408.41101) (xy 428.706788 -408.439366) (xy 428.703485 -408.445396)
			(xy 428.699872 -408.458656) (xy 428.699676 -408.465528) (xy 428.699676 -409.214828) (xy 428.69986 -409.221702)
			(xy 428.703474 -409.234964) (xy 428.706788 -409.24099) (xy 428.723094 -409.269363) (xy 428.748839 -409.329526)
			(xy 428.766268 -409.392603) (xy 428.775064 -409.457449) (xy 428.775069 -409.522889) (xy 428.766281 -409.587737)
			(xy 428.74886 -409.650815) (xy 428.723122 -409.710982) (xy 428.706788 -409.739338) (xy 428.703459 -409.745356)
			(xy 428.699863 -409.758625) (xy 428.699676 -409.7655) (xy 428.699676 -410.051504) (xy 428.699281 -410.061661)
			(xy 428.69148 -410.080418) (xy 428.677074 -410.094742) (xy 428.658274 -410.102438) (xy 428.648114 -410.102812)
			(xy 427.931834 -410.102812) (xy 427.921716 -410.102247) (xy 427.903005 -410.09454) (xy 427.88865 -410.080278)
			(xy 427.88082 -410.061619) (xy 427.880272 -410.051504) (xy 427.880272 -409.7655) (xy 427.880083 -409.758626)
			(xy 427.876473 -409.745364) (xy 427.87316 -409.739338) (xy 427.856791 -409.710999) (xy 427.831049 -409.650828)
			(xy 427.813625 -409.587745) (xy 427.804836 -409.522892) (xy 426.516029 -409.522892) (xy 426.50664 -409.539186)
			(xy 426.503334 -409.545215) (xy 426.499722 -409.558475) (xy 426.499528 -409.565348) (xy 426.499528 -410.314648)
			(xy 426.499736 -410.32152) (xy 426.503333 -410.334783) (xy 426.50664 -410.34081) (xy 426.522964 -410.369173)
			(xy 426.548711 -410.429338) (xy 426.566139 -410.492417) (xy 426.574934 -410.557265) (xy 426.574936 -410.622707)
			(xy 426.574936 -410.622708) (xy 430.004742 -410.622708) (xy 430.004744 -410.557264) (xy 430.013539 -410.492414)
			(xy 430.030968 -410.429333) (xy 430.056715 -410.369166) (xy 430.073054 -410.34081) (xy 430.076415 -410.334793)
			(xy 430.080153 -410.321534) (xy 430.08042 -410.314648) (xy 430.08042 -409.565348) (xy 430.0802 -409.558454)
			(xy 430.076463 -409.545182) (xy 430.073054 -409.539186) (xy 430.056726 -409.510824) (xy 430.030981 -409.450659)
			(xy 430.013553 -409.38758) (xy 430.004758 -409.322731) (xy 430.004757 -409.257289) (xy 430.013548 -409.19244)
			(xy 430.030974 -409.12936) (xy 430.056717 -409.069194) (xy 430.073054 -409.040838) (xy 430.07644 -409.034834)
			(xy 430.080161 -409.021565) (xy 430.08042 -409.014676) (xy 430.08042 -408.728672) (xy 430.080863 -408.718559)
			(xy 430.088613 -408.699876) (xy 430.102923 -408.685582) (xy 430.121614 -408.677852) (xy 430.131728 -408.677364)
			(xy 430.848008 -408.677364) (xy 430.858113 -408.677878) (xy 430.876784 -408.685611) (xy 430.891077 -408.699899)
			(xy 430.898818 -408.718567) (xy 430.899316 -408.728672) (xy 430.899316 -409.014676) (xy 430.899556 -409.021567)
			(xy 430.903294 -409.034833) (xy 430.906682 -409.040838) (xy 430.923029 -409.069189) (xy 430.948771 -409.129357)
			(xy 430.966195 -409.192438) (xy 430.974987 -409.257289) (xy 430.974985 -409.322732) (xy 430.966191 -409.387582)
			(xy 430.948764 -409.450662) (xy 430.92302 -409.51083) (xy 430.91607 -409.522892) (xy 432.204626 -409.522892)
			(xy 432.20463 -409.457446) (xy 432.213427 -409.392595) (xy 432.230859 -409.329513) (xy 432.256608 -409.269346)
			(xy 432.272948 -409.24099) (xy 432.276262 -409.234965) (xy 432.279869 -409.221702) (xy 432.28006 -409.214828)
			(xy 432.28006 -408.465528) (xy 432.279862 -408.458655) (xy 432.276259 -408.445392) (xy 432.272948 -408.439366)
			(xy 432.256604 -408.411014) (xy 432.23086 -408.350846) (xy 432.213434 -408.287765) (xy 432.204642 -408.222915)
			(xy 432.204642 -408.157471) (xy 432.213437 -408.092621) (xy 432.230864 -408.029541) (xy 432.25661 -407.969374)
			(xy 432.272948 -407.941018) (xy 432.276252 -407.934988) (xy 432.279865 -407.921729) (xy 432.28006 -407.914856)
			(xy 432.28006 -407.628852) (xy 432.280482 -407.6187) (xy 432.288286 -407.599954) (xy 432.302681 -407.585634)
			(xy 432.321468 -407.577929) (xy 432.331622 -407.577544) (xy 433.047902 -407.577544) (xy 433.058029 -407.578025)
			(xy 433.076751 -407.585754) (xy 433.091108 -407.600042) (xy 433.098926 -407.618727) (xy 433.099464 -407.628852)
			(xy 433.099464 -407.914856) (xy 433.099677 -407.921728) (xy 433.103271 -407.93499) (xy 433.106576 -407.941018)
			(xy 433.122906 -407.969378) (xy 433.14865 -408.029544) (xy 433.166076 -408.092623) (xy 433.17487 -408.157472)
			(xy 433.17487 -408.190192) (xy 436.603656 -408.190192) (xy 436.607647 -408.128025) (xy 436.619556 -408.066878)
			(xy 436.639185 -408.007757) (xy 436.666214 -407.951631) (xy 436.700198 -407.899422) (xy 436.74058 -407.851987)
			(xy 436.786696 -407.810106) (xy 436.837788 -407.774466) (xy 436.893019 -407.745652) (xy 436.951481 -407.724138)
			(xy 437.012215 -407.710276) (xy 437.074222 -407.704294) (xy 437.136485 -407.70629) (xy 437.197982 -407.716233)
			(xy 437.257703 -407.733957) (xy 437.314666 -407.759174) (xy 437.367937 -407.791467) (xy 437.416642 -407.830307)
			(xy 437.459979 -407.875057) (xy 437.497239 -407.924981) (xy 437.527808 -407.97926) (xy 437.551186 -408.037003)
			(xy 437.566987 -408.097261) (xy 437.574953 -408.159044) (xy 437.575452 -408.190192) (xy 437.574953 -408.22134)
			(xy 437.566987 -408.283123) (xy 437.551186 -408.343381) (xy 437.527808 -408.401124) (xy 437.497239 -408.455403)
			(xy 437.459979 -408.505327) (xy 437.416642 -408.550077) (xy 437.367937 -408.588917) (xy 437.314666 -408.62121)
			(xy 437.257703 -408.646427) (xy 437.197982 -408.664151) (xy 437.136485 -408.674094) (xy 437.074222 -408.67609)
			(xy 437.012215 -408.670108) (xy 436.951481 -408.656246) (xy 436.893019 -408.634732) (xy 436.837788 -408.605918)
			(xy 436.786696 -408.570278) (xy 436.74058 -408.528397) (xy 436.700198 -408.480962) (xy 436.666214 -408.428753)
			(xy 436.639185 -408.372627) (xy 436.619556 -408.313506) (xy 436.607647 -408.252359) (xy 436.603656 -408.190192)
			(xy 433.17487 -408.190192) (xy 433.174871 -408.222914) (xy 433.166079 -408.287763) (xy 433.148654 -408.350843)
			(xy 433.122912 -408.41101) (xy 433.106576 -408.439366) (xy 433.103272 -408.445396) (xy 433.09966 -408.458656)
			(xy 433.099464 -408.465528) (xy 433.099464 -409.214828) (xy 433.09965 -409.221702) (xy 433.103263 -409.234964)
			(xy 433.106576 -409.24099) (xy 433.122882 -409.269363) (xy 433.148628 -409.329526) (xy 433.166058 -409.392603)
			(xy 433.174854 -409.457449) (xy 433.174858 -409.522889) (xy 433.16607 -409.587737) (xy 433.148649 -409.650816)
			(xy 433.12291 -409.710982) (xy 433.106576 -409.739338) (xy 433.103246 -409.745355) (xy 433.09965 -409.758625)
			(xy 433.099464 -409.7655) (xy 433.099464 -410.051504) (xy 433.099081 -410.061663) (xy 433.091277 -410.080422)
			(xy 433.076868 -410.094747) (xy 433.058063 -410.10244) (xy 433.047902 -410.102812) (xy 432.331622 -410.102812)
			(xy 432.321503 -410.102257) (xy 432.302792 -410.094546) (xy 432.288437 -410.080281) (xy 432.280608 -410.06162)
			(xy 432.28006 -410.051504) (xy 432.28006 -409.7655) (xy 432.279873 -409.758626) (xy 432.276262 -409.745363)
			(xy 432.272948 -409.739338) (xy 432.25658 -409.710999) (xy 432.230838 -409.650828) (xy 432.213415 -409.587745)
			(xy 432.204626 -409.522892) (xy 430.91607 -409.522892) (xy 430.906682 -409.539186) (xy 430.903325 -409.545205)
			(xy 430.899585 -409.558462) (xy 430.899316 -409.565348) (xy 430.899316 -410.314648) (xy 430.899567 -410.321538)
			(xy 430.903297 -410.334804) (xy 430.906682 -410.34081) (xy 430.923005 -410.369174) (xy 430.948749 -410.429339)
			(xy 430.966176 -410.492418) (xy 430.974971 -410.557265) (xy 430.974972 -410.622707) (xy 430.974972 -410.622708)
			(xy 434.404792 -410.622708) (xy 434.404794 -410.557265) (xy 434.413588 -410.492415) (xy 434.431015 -410.429334)
			(xy 434.456759 -410.369167) (xy 434.473096 -410.34081) (xy 434.476407 -410.334783) (xy 434.480015 -410.321521)
			(xy 434.480208 -410.314648) (xy 434.480208 -409.565348) (xy 434.479996 -409.558476) (xy 434.476401 -409.545214)
			(xy 434.473096 -409.539186) (xy 434.45677 -409.510824) (xy 434.431028 -409.450658) (xy 434.413602 -409.387579)
			(xy 434.404808 -409.322731) (xy 434.404807 -409.257289) (xy 434.413597 -409.192441) (xy 434.431021 -409.129361)
			(xy 434.456761 -409.069195) (xy 434.473096 -409.040838) (xy 434.476397 -409.034807) (xy 434.480011 -409.021548)
			(xy 434.480208 -409.014676) (xy 434.480208 -408.728672) (xy 434.480599 -408.718515) (xy 434.488405 -408.69976)
			(xy 434.502811 -408.685438) (xy 434.521611 -408.67774) (xy 434.53177 -408.677364) (xy 435.24805 -408.677364)
			(xy 435.258176 -408.677868) (xy 435.276901 -408.685584) (xy 435.29126 -408.699866) (xy 435.299077 -408.718548)
			(xy 435.299612 -408.728672) (xy 435.299612 -409.014676) (xy 435.299812 -409.021549) (xy 435.303415 -409.034811)
			(xy 435.306724 -409.040838) (xy 435.323073 -409.069188) (xy 435.348818 -409.129356) (xy 435.366244 -409.192437)
			(xy 435.375037 -409.257288) (xy 435.375035 -409.322732) (xy 435.36624 -409.387583) (xy 435.348811 -409.450664)
			(xy 435.331907 -409.490164) (xy 436.603656 -409.490164) (xy 436.607647 -409.427997) (xy 436.619556 -409.36685)
			(xy 436.639185 -409.307729) (xy 436.666214 -409.251603) (xy 436.700198 -409.199394) (xy 436.74058 -409.151959)
			(xy 436.786696 -409.110078) (xy 436.837788 -409.074438) (xy 436.893019 -409.045624) (xy 436.951481 -409.02411)
			(xy 437.012215 -409.010248) (xy 437.074222 -409.004266) (xy 437.136485 -409.006262) (xy 437.197982 -409.016205)
			(xy 437.257703 -409.033929) (xy 437.314666 -409.059146) (xy 437.367937 -409.091439) (xy 437.416642 -409.130279)
			(xy 437.459979 -409.175029) (xy 437.497239 -409.224953) (xy 437.527808 -409.279232) (xy 437.532172 -409.290012)
			(xy 438.803804 -409.290012) (xy 438.807795 -409.227845) (xy 438.819704 -409.166698) (xy 438.839333 -409.107577)
			(xy 438.866362 -409.051451) (xy 438.900346 -408.999242) (xy 438.940728 -408.951807) (xy 438.986844 -408.909926)
			(xy 439.037936 -408.874286) (xy 439.093167 -408.845472) (xy 439.151629 -408.823958) (xy 439.212363 -408.810096)
			(xy 439.27437 -408.804114) (xy 439.336633 -408.80611) (xy 439.39813 -408.816053) (xy 439.457851 -408.833777)
			(xy 439.514814 -408.858994) (xy 439.568085 -408.891287) (xy 439.61679 -408.930127) (xy 439.660127 -408.974877)
			(xy 439.697387 -409.024801) (xy 439.727956 -409.07908) (xy 439.751334 -409.136823) (xy 439.767135 -409.197081)
			(xy 439.775101 -409.258864) (xy 439.7756 -409.290012) (xy 439.775101 -409.32116) (xy 439.767135 -409.382943)
			(xy 439.751334 -409.443201) (xy 439.727956 -409.500944) (xy 439.697387 -409.555223) (xy 439.660127 -409.605147)
			(xy 439.61679 -409.649897) (xy 439.568085 -409.688737) (xy 439.514814 -409.72103) (xy 439.457851 -409.746247)
			(xy 439.39813 -409.763971) (xy 439.336633 -409.773914) (xy 439.27437 -409.77591) (xy 439.212363 -409.769928)
			(xy 439.151629 -409.756066) (xy 439.093167 -409.734552) (xy 439.037936 -409.705738) (xy 438.986844 -409.670098)
			(xy 438.940728 -409.628217) (xy 438.900346 -409.580782) (xy 438.866362 -409.528573) (xy 438.839333 -409.472447)
			(xy 438.819704 -409.413326) (xy 438.807795 -409.352179) (xy 438.803804 -409.290012) (xy 437.532172 -409.290012)
			(xy 437.551186 -409.336975) (xy 437.566987 -409.397233) (xy 437.574953 -409.459016) (xy 437.575452 -409.490164)
			(xy 437.574953 -409.521312) (xy 437.566987 -409.583095) (xy 437.551186 -409.643353) (xy 437.527808 -409.701096)
			(xy 437.497239 -409.755375) (xy 437.459979 -409.805299) (xy 437.416642 -409.850049) (xy 437.367937 -409.888889)
			(xy 437.314666 -409.921182) (xy 437.257703 -409.946399) (xy 437.197982 -409.964123) (xy 437.136485 -409.974066)
			(xy 437.074222 -409.976062) (xy 437.012215 -409.97008) (xy 436.951481 -409.956218) (xy 436.893019 -409.934704)
			(xy 436.837788 -409.90589) (xy 436.786696 -409.87025) (xy 436.74058 -409.828369) (xy 436.700198 -409.780934)
			(xy 436.666214 -409.728725) (xy 436.639185 -409.672599) (xy 436.619556 -409.613478) (xy 436.607647 -409.552331)
			(xy 436.603656 -409.490164) (xy 435.331907 -409.490164) (xy 435.323063 -409.51083) (xy 435.306724 -409.539186)
			(xy 435.303416 -409.545214) (xy 435.299806 -409.558475) (xy 435.299612 -409.565348) (xy 435.299612 -410.314648)
			(xy 435.299822 -410.32152) (xy 435.303418 -410.334783) (xy 435.306724 -410.34081) (xy 435.323049 -410.369173)
			(xy 435.348796 -410.429338) (xy 435.366225 -410.492417) (xy 435.375021 -410.557265) (xy 435.375022 -410.589984)
			(xy 438.803804 -410.589984) (xy 438.807795 -410.527817) (xy 438.819704 -410.46667) (xy 438.839333 -410.407549)
			(xy 438.866362 -410.351423) (xy 438.900346 -410.299214) (xy 438.940728 -410.251779) (xy 438.986844 -410.209898)
			(xy 439.037936 -410.174258) (xy 439.093167 -410.145444) (xy 439.151629 -410.12393) (xy 439.212363 -410.110068)
			(xy 439.27437 -410.104086) (xy 439.336633 -410.106082) (xy 439.39813 -410.116025) (xy 439.457851 -410.133749)
			(xy 439.514814 -410.158966) (xy 439.568085 -410.191259) (xy 439.61679 -410.230099) (xy 439.660127 -410.274849)
			(xy 439.697387 -410.324773) (xy 439.727956 -410.379052) (xy 439.751334 -410.436795) (xy 439.767135 -410.497053)
			(xy 439.775101 -410.558836) (xy 439.7756 -410.589984) (xy 439.775101 -410.621132) (xy 439.767135 -410.682915)
			(xy 439.751334 -410.743173) (xy 439.727956 -410.800916) (xy 439.697387 -410.855195) (xy 439.660127 -410.905119)
			(xy 439.61679 -410.949869) (xy 439.568085 -410.988709) (xy 439.514814 -411.021002) (xy 439.457851 -411.046219)
			(xy 439.39813 -411.063943) (xy 439.336633 -411.073886) (xy 439.27437 -411.075882) (xy 439.212363 -411.0699)
			(xy 439.151629 -411.056038) (xy 439.093167 -411.034524) (xy 439.037936 -411.00571) (xy 438.986844 -410.97007)
			(xy 438.940728 -410.928189) (xy 438.900346 -410.880754) (xy 438.866362 -410.828545) (xy 438.839333 -410.772419)
			(xy 438.819704 -410.713298) (xy 438.807795 -410.652151) (xy 438.803804 -410.589984) (xy 435.375022 -410.589984)
			(xy 435.375023 -410.622707) (xy 435.366231 -410.687557) (xy 435.348805 -410.750636) (xy 435.323061 -410.810802)
			(xy 435.306724 -410.839158) (xy 435.303426 -410.845191) (xy 435.299809 -410.858448) (xy 435.299612 -410.86532)
			(xy 435.299612 -411.151324) (xy 435.299198 -411.161478) (xy 435.291397 -411.180229) (xy 435.276998 -411.194551)
			(xy 435.258206 -411.202252) (xy 435.24805 -411.202632) (xy 434.53177 -411.202632) (xy 434.521638 -411.202197)
			(xy 434.502911 -411.194454) (xy 434.488554 -411.180152) (xy 434.480741 -411.161454) (xy 434.480208 -411.151324)
			(xy 434.480208 -410.86532) (xy 434.480008 -410.858447) (xy 434.476405 -410.845185) (xy 434.473096 -410.839158)
			(xy 434.456746 -410.810809) (xy 434.431006 -410.75064) (xy 434.413583 -410.687558) (xy 434.404792 -410.622708)
			(xy 430.974972 -410.622708) (xy 430.966182 -410.687556) (xy 430.948758 -410.750635) (xy 430.923018 -410.810802)
			(xy 430.906682 -410.839158) (xy 430.9033 -410.845164) (xy 430.899575 -410.858431) (xy 430.899316 -410.86532)
			(xy 430.899316 -411.151324) (xy 430.898835 -411.161432) (xy 430.891092 -411.180108) (xy 430.876795 -411.194401)
			(xy 430.858116 -411.202138) (xy 430.848008 -411.202632) (xy 430.131728 -411.202632) (xy 430.121611 -411.202162)
			(xy 430.102914 -411.194429) (xy 430.0886 -411.180129) (xy 430.080848 -411.16144) (xy 430.08042 -411.151324)
			(xy 430.08042 -410.86532) (xy 430.080212 -410.858425) (xy 430.076467 -410.845153) (xy 430.073054 -410.839158)
			(xy 430.056703 -410.810809) (xy 430.030959 -410.750641) (xy 430.013534 -410.687559) (xy 430.004742 -410.622708)
			(xy 426.574936 -410.622708) (xy 426.566145 -410.687556) (xy 426.54872 -410.750636) (xy 426.522977 -410.810802)
			(xy 426.50664 -410.839158) (xy 426.503343 -410.845192) (xy 426.499726 -410.858448) (xy 426.499528 -410.86532)
			(xy 426.499528 -411.151324) (xy 426.499099 -411.161476) (xy 426.4913 -411.180224) (xy 426.476907 -411.194545)
			(xy 426.45812 -411.202249) (xy 426.447966 -411.202632) (xy 425.731686 -411.202632) (xy 425.721555 -411.202184)
			(xy 425.702828 -411.194446) (xy 425.688472 -411.180148) (xy 425.680658 -411.161453) (xy 425.680124 -411.151324)
			(xy 425.680124 -410.86532) (xy 425.679921 -410.858448) (xy 425.67632 -410.845185) (xy 425.673012 -410.839158)
			(xy 425.656662 -410.810809) (xy 425.630921 -410.75064) (xy 425.613497 -410.687559) (xy 425.604706 -410.622708)
			(xy 422.174886 -410.622708) (xy 422.166096 -410.687555) (xy 422.148673 -410.750635) (xy 422.122933 -410.810801)
			(xy 422.106598 -410.839158) (xy 422.103217 -410.845165) (xy 422.099491 -410.858431) (xy 422.099232 -410.86532)
			(xy 422.099232 -411.151324) (xy 422.098735 -411.16143) (xy 422.090996 -411.180103) (xy 422.076703 -411.194396)
			(xy 422.05803 -411.202135) (xy 422.047924 -411.202632) (xy 421.331644 -411.202632) (xy 421.321528 -411.202149)
			(xy 421.302832 -411.194421) (xy 421.288517 -411.180125) (xy 421.280765 -411.161439) (xy 421.280336 -411.151324)
			(xy 421.280336 -410.86532) (xy 421.280126 -410.858425) (xy 421.276382 -410.845153) (xy 421.27297 -410.839158)
			(xy 421.256618 -410.81081) (xy 421.230874 -410.750641) (xy 421.213448 -410.68756) (xy 421.204656 -410.622709)
			(xy 414.525968 -410.622709) (xy 414.525968 -412.090108) (xy 419.003742 -412.090108) (xy 419.007733 -412.027941)
			(xy 419.019642 -411.966794) (xy 419.039271 -411.907673) (xy 419.0663 -411.851547) (xy 419.100284 -411.799338)
			(xy 419.140666 -411.751903) (xy 419.186782 -411.710022) (xy 419.237874 -411.674382) (xy 419.293105 -411.645568)
			(xy 419.351567 -411.624054) (xy 419.412301 -411.610192) (xy 419.474308 -411.60421) (xy 419.536571 -411.606206)
			(xy 419.598068 -411.616149) (xy 419.657789 -411.633873) (xy 419.714752 -411.65909) (xy 419.768023 -411.691383)
			(xy 419.816728 -411.730223) (xy 419.860065 -411.774973) (xy 419.897325 -411.824897) (xy 419.927894 -411.879176)
			(xy 419.951272 -411.936919) (xy 419.967073 -411.997177) (xy 419.975039 -412.05896) (xy 419.975538 -412.090108)
			(xy 423.403784 -412.090108) (xy 423.407775 -412.027941) (xy 423.419684 -411.966794) (xy 423.439313 -411.907673)
			(xy 423.466342 -411.851547) (xy 423.500326 -411.799338) (xy 423.540708 -411.751903) (xy 423.586824 -411.710022)
			(xy 423.637916 -411.674382) (xy 423.693147 -411.645568) (xy 423.751609 -411.624054) (xy 423.812343 -411.610192)
			(xy 423.87435 -411.60421) (xy 423.936613 -411.606206) (xy 423.99811 -411.616149) (xy 424.057831 -411.633873)
			(xy 424.114794 -411.65909) (xy 424.168065 -411.691383) (xy 424.21677 -411.730223) (xy 424.260107 -411.774973)
			(xy 424.297367 -411.824897) (xy 424.327936 -411.879176) (xy 424.351314 -411.936919) (xy 424.367115 -411.997177)
			(xy 424.375081 -412.05896) (xy 424.37558 -412.090108) (xy 427.803826 -412.090108) (xy 427.807817 -412.027941)
			(xy 427.819726 -411.966794) (xy 427.839355 -411.907673) (xy 427.866384 -411.851547) (xy 427.900368 -411.799338)
			(xy 427.94075 -411.751903) (xy 427.986866 -411.710022) (xy 428.037958 -411.674382) (xy 428.093189 -411.645568)
			(xy 428.151651 -411.624054) (xy 428.212385 -411.610192) (xy 428.274392 -411.60421) (xy 428.336655 -411.606206)
			(xy 428.398152 -411.616149) (xy 428.457873 -411.633873) (xy 428.514836 -411.65909) (xy 428.568107 -411.691383)
			(xy 428.616812 -411.730223) (xy 428.660149 -411.774973) (xy 428.697409 -411.824897) (xy 428.727978 -411.879176)
			(xy 428.751356 -411.936919) (xy 428.767157 -411.997177) (xy 428.775123 -412.05896) (xy 428.775622 -412.090108)
			(xy 432.203614 -412.090108) (xy 432.207605 -412.027941) (xy 432.219514 -411.966794) (xy 432.239143 -411.907673)
			(xy 432.266172 -411.851547) (xy 432.300156 -411.799338) (xy 432.340538 -411.751903) (xy 432.386654 -411.710022)
			(xy 432.437746 -411.674382) (xy 432.492977 -411.645568) (xy 432.551439 -411.624054) (xy 432.612173 -411.610192)
			(xy 432.67418 -411.60421) (xy 432.736443 -411.606206) (xy 432.79794 -411.616149) (xy 432.857661 -411.633873)
			(xy 432.914624 -411.65909) (xy 432.967895 -411.691383) (xy 433.0166 -411.730223) (xy 433.059937 -411.774973)
			(xy 433.097197 -411.824897) (xy 433.127766 -411.879176) (xy 433.151144 -411.936919) (xy 433.166945 -411.997177)
			(xy 433.174911 -412.05896) (xy 433.17541 -412.090108) (xy 436.603656 -412.090108) (xy 436.607647 -412.027941)
			(xy 436.619556 -411.966794) (xy 436.639185 -411.907673) (xy 436.666214 -411.851547) (xy 436.700198 -411.799338)
			(xy 436.74058 -411.751903) (xy 436.786696 -411.710022) (xy 436.837788 -411.674382) (xy 436.893019 -411.645568)
			(xy 436.951481 -411.624054) (xy 437.012215 -411.610192) (xy 437.074222 -411.60421) (xy 437.136485 -411.606206)
			(xy 437.197982 -411.616149) (xy 437.257703 -411.633873) (xy 437.314666 -411.65909) (xy 437.367937 -411.691383)
			(xy 437.416642 -411.730223) (xy 437.459979 -411.774973) (xy 437.497239 -411.824897) (xy 437.527808 -411.879176)
			(xy 437.551186 -411.936919) (xy 437.566987 -411.997177) (xy 437.574953 -412.05896) (xy 437.575452 -412.090108)
			(xy 437.574953 -412.121256) (xy 437.566987 -412.183039) (xy 437.551186 -412.243297) (xy 437.527808 -412.30104)
			(xy 437.497239 -412.355319) (xy 437.459979 -412.405243) (xy 437.416642 -412.449993) (xy 437.367937 -412.488833)
			(xy 437.314666 -412.521126) (xy 437.257703 -412.546343) (xy 437.197982 -412.564067) (xy 437.136485 -412.57401)
			(xy 437.074222 -412.576006) (xy 437.012215 -412.570024) (xy 436.951481 -412.556162) (xy 436.893019 -412.534648)
			(xy 436.837788 -412.505834) (xy 436.786696 -412.470194) (xy 436.74058 -412.428313) (xy 436.700198 -412.380878)
			(xy 436.666214 -412.328669) (xy 436.639185 -412.272543) (xy 436.619556 -412.213422) (xy 436.607647 -412.152275)
			(xy 436.603656 -412.090108) (xy 433.17541 -412.090108) (xy 433.174911 -412.121256) (xy 433.166945 -412.183039)
			(xy 433.151144 -412.243297) (xy 433.127766 -412.30104) (xy 433.097197 -412.355319) (xy 433.059937 -412.405243)
			(xy 433.0166 -412.449993) (xy 432.967895 -412.488833) (xy 432.914624 -412.521126) (xy 432.857661 -412.546343)
			(xy 432.79794 -412.564067) (xy 432.736443 -412.57401) (xy 432.67418 -412.576006) (xy 432.612173 -412.570024)
			(xy 432.551439 -412.556162) (xy 432.492977 -412.534648) (xy 432.437746 -412.505834) (xy 432.386654 -412.470194)
			(xy 432.340538 -412.428313) (xy 432.300156 -412.380878) (xy 432.266172 -412.328669) (xy 432.239143 -412.272543)
			(xy 432.219514 -412.213422) (xy 432.207605 -412.152275) (xy 432.203614 -412.090108) (xy 428.775622 -412.090108)
			(xy 428.775123 -412.121256) (xy 428.767157 -412.183039) (xy 428.751356 -412.243297) (xy 428.727978 -412.30104)
			(xy 428.697409 -412.355319) (xy 428.660149 -412.405243) (xy 428.616812 -412.449993) (xy 428.568107 -412.488833)
			(xy 428.514836 -412.521126) (xy 428.457873 -412.546343) (xy 428.398152 -412.564067) (xy 428.336655 -412.57401)
			(xy 428.274392 -412.576006) (xy 428.212385 -412.570024) (xy 428.151651 -412.556162) (xy 428.093189 -412.534648)
			(xy 428.037958 -412.505834) (xy 427.986866 -412.470194) (xy 427.94075 -412.428313) (xy 427.900368 -412.380878)
			(xy 427.866384 -412.328669) (xy 427.839355 -412.272543) (xy 427.819726 -412.213422) (xy 427.807817 -412.152275)
			(xy 427.803826 -412.090108) (xy 424.37558 -412.090108) (xy 424.375081 -412.121256) (xy 424.367115 -412.183039)
			(xy 424.351314 -412.243297) (xy 424.327936 -412.30104) (xy 424.297367 -412.355319) (xy 424.260107 -412.405243)
			(xy 424.21677 -412.449993) (xy 424.168065 -412.488833) (xy 424.114794 -412.521126) (xy 424.057831 -412.546343)
			(xy 423.99811 -412.564067) (xy 423.936613 -412.57401) (xy 423.87435 -412.576006) (xy 423.812343 -412.570024)
			(xy 423.751609 -412.556162) (xy 423.693147 -412.534648) (xy 423.637916 -412.505834) (xy 423.586824 -412.470194)
			(xy 423.540708 -412.428313) (xy 423.500326 -412.380878) (xy 423.466342 -412.328669) (xy 423.439313 -412.272543)
			(xy 423.419684 -412.213422) (xy 423.407775 -412.152275) (xy 423.403784 -412.090108) (xy 419.975538 -412.090108)
			(xy 419.975039 -412.121256) (xy 419.967073 -412.183039) (xy 419.951272 -412.243297) (xy 419.927894 -412.30104)
			(xy 419.897325 -412.355319) (xy 419.860065 -412.405243) (xy 419.816728 -412.449993) (xy 419.768023 -412.488833)
			(xy 419.714752 -412.521126) (xy 419.657789 -412.546343) (xy 419.598068 -412.564067) (xy 419.536571 -412.57401)
			(xy 419.474308 -412.576006) (xy 419.412301 -412.570024) (xy 419.351567 -412.556162) (xy 419.293105 -412.534648)
			(xy 419.237874 -412.505834) (xy 419.186782 -412.470194) (xy 419.140666 -412.428313) (xy 419.100284 -412.380878)
			(xy 419.0663 -412.328669) (xy 419.039271 -412.272543) (xy 419.019642 -412.213422) (xy 419.007733 -412.152275)
			(xy 419.003742 -412.090108) (xy 414.525968 -412.090108) (xy 414.525968 -416.520376) (xy 414.527611 -416.529352)
			(xy 414.536309 -416.545378) (xy 414.550067 -416.557347) (xy 414.567143 -416.563743) (xy 414.57626 -416.564064)
			(xy 441.55868 -416.564064) (xy 441.568743 -416.563626) (xy 441.587323 -416.555887) (xy 441.594748 -416.549078)
			(xy 442.64072 -415.503106) (xy 442.641228 -415.502598) (xy 442.647805 -415.495216) (xy 442.655242 -415.476916)
			(xy 442.655706 -415.467038) (xy 442.655706 -409.632404) (xy 442.656129 -409.622334) (xy 442.663843 -409.603729)
			(xy 442.670692 -409.596336) (xy 443.462156 -408.804872) (xy 443.469003 -408.797474) (xy 443.476734 -408.778876)
			(xy 443.477142 -408.768804) (xy 443.477142 -404.814532) (xy 443.477579 -404.804468) (xy 443.485315 -404.785886)
			(xy 443.492128 -404.778464) (xy 447.994532 -400.27606) (xy 448.00138 -400.268663) (xy 448.00911 -400.250064)
			(xy 448.009518 -400.239992) (xy 448.009518 -400.230086) (xy 448.008756 -400.225768) (xy 448.006141 -400.209639)
			(xy 448.00334 -400.177082) (xy 448.003168 -400.160744) (xy 448.003168 -400.160236) (xy 448.003678 -400.132404)
			(xy 448.011779 -400.077331) (xy 448.027798 -400.024021) (xy 448.051396 -399.973605) (xy 448.082072 -399.927155)
			(xy 448.119174 -399.885657) (xy 448.161913 -399.849993) (xy 448.209383 -399.82092) (xy 448.260575 -399.799056)
			(xy 448.3144 -399.784865) (xy 448.342004 -399.781268) (xy 448.351148 -399.780252) (xy 448.367404 -399.772124)
			(xy 448.392804 -399.744184) (xy 448.39382 -399.743168) (xy 448.40017 -399.736818) (xy 448.407536 -399.71853)
			(xy 448.407536 -356.853998) (xy 448.407008 -356.844039) (xy 448.399357 -356.825644) (xy 448.385311 -356.811514)
			(xy 448.376294 -356.807262) (xy 448.361816 -356.801166) (xy 448.331844 -356.807262) (xy 447.45021 -357.688896)
			(xy 447.443698 -357.696038) (xy 447.436109 -357.713797) (xy 447.435478 -357.72344) (xy 447.407284 -358.752902)
			(xy 447.407284 -358.941624) (xy 447.406672 -358.990439) (xy 447.397088 -359.087599) (xy 447.378042 -359.183354)
			(xy 447.349719 -359.276787) (xy 447.331592 -359.322116) (xy 445.965834 -362.61929) (xy 445.949247 -362.658177)
			(xy 445.910396 -362.733271) (xy 445.865321 -362.804802) (xy 445.814346 -362.872256) (xy 445.757838 -362.935147)
			(xy 445.696203 -362.993023) (xy 445.66332 -363.019594) (xy 441.24499 -366.517428) (xy 441.226569 -366.531791)
			(xy 441.188582 -366.558983) (xy 441.169044 -366.571784) (xy 438.079896 -368.577876) (xy 438.069622 -368.585345)
			(xy 438.057475 -368.607613) (xy 438.056782 -368.620294) (xy 438.056782 -368.990118) (xy 438.803804 -368.990118)
			(xy 438.807795 -368.927951) (xy 438.819704 -368.866804) (xy 438.839333 -368.807683) (xy 438.866362 -368.751557)
			(xy 438.900346 -368.699348) (xy 438.940728 -368.651913) (xy 438.986844 -368.610032) (xy 439.037936 -368.574392)
			(xy 439.093167 -368.545578) (xy 439.151629 -368.524064) (xy 439.212363 -368.510202) (xy 439.27437 -368.50422)
			(xy 439.336633 -368.506216) (xy 439.39813 -368.516159) (xy 439.457851 -368.533883) (xy 439.514814 -368.5591)
			(xy 439.568085 -368.591393) (xy 439.61679 -368.630233) (xy 439.660127 -368.674983) (xy 439.697387 -368.724907)
			(xy 439.727956 -368.779186) (xy 439.751334 -368.836929) (xy 439.767135 -368.897187) (xy 439.775101 -368.95897)
			(xy 439.7756 -368.990118) (xy 439.775101 -369.021266) (xy 439.767135 -369.083049) (xy 439.751334 -369.143307)
			(xy 439.727956 -369.20105) (xy 439.697387 -369.255329) (xy 439.660127 -369.305253) (xy 439.61679 -369.350003)
			(xy 439.568085 -369.388843) (xy 439.514814 -369.421136) (xy 439.457851 -369.446353) (xy 439.39813 -369.464077)
			(xy 439.336633 -369.47402) (xy 439.27437 -369.476016) (xy 439.212363 -369.470034) (xy 439.151629 -369.456172)
			(xy 439.093167 -369.434658) (xy 439.037936 -369.405844) (xy 438.986844 -369.370204) (xy 438.940728 -369.328323)
			(xy 438.900346 -369.280888) (xy 438.866362 -369.228679) (xy 438.839333 -369.172553) (xy 438.819704 -369.113432)
			(xy 438.807795 -369.052285) (xy 438.803804 -368.990118) (xy 438.056782 -368.990118) (xy 438.056782 -371.590062)
			(xy 438.803804 -371.590062) (xy 438.807795 -371.527895) (xy 438.819704 -371.466748) (xy 438.839333 -371.407627)
			(xy 438.866362 -371.351501) (xy 438.900346 -371.299292) (xy 438.940728 -371.251857) (xy 438.986844 -371.209976)
			(xy 439.037936 -371.174336) (xy 439.093167 -371.145522) (xy 439.151629 -371.124008) (xy 439.212363 -371.110146)
			(xy 439.27437 -371.104164) (xy 439.336633 -371.10616) (xy 439.39813 -371.116103) (xy 439.457851 -371.133827)
			(xy 439.514814 -371.159044) (xy 439.568085 -371.191337) (xy 439.61679 -371.230177) (xy 439.660127 -371.274927)
			(xy 439.697387 -371.324851) (xy 439.727956 -371.37913) (xy 439.751334 -371.436873) (xy 439.767135 -371.497131)
			(xy 439.775101 -371.558914) (xy 439.7756 -371.590062) (xy 439.775101 -371.62121) (xy 439.767135 -371.682993)
			(xy 439.751334 -371.743251) (xy 439.727956 -371.800994) (xy 439.697387 -371.855273) (xy 439.660127 -371.905197)
			(xy 439.61679 -371.949947) (xy 439.568085 -371.988787) (xy 439.514814 -372.02108) (xy 439.457851 -372.046297)
			(xy 439.39813 -372.064021) (xy 439.336633 -372.073964) (xy 439.27437 -372.07596) (xy 439.212363 -372.069978)
			(xy 439.151629 -372.056116) (xy 439.093167 -372.034602) (xy 439.037936 -372.005788) (xy 438.986844 -371.970148)
			(xy 438.940728 -371.928267) (xy 438.900346 -371.880832) (xy 438.866362 -371.828623) (xy 438.839333 -371.772497)
			(xy 438.819704 -371.713376) (xy 438.807795 -371.652229) (xy 438.803804 -371.590062) (xy 438.056782 -371.590062)
			(xy 438.056782 -372.890034) (xy 438.803804 -372.890034) (xy 438.807795 -372.827867) (xy 438.819704 -372.76672)
			(xy 438.839333 -372.707599) (xy 438.866362 -372.651473) (xy 438.900346 -372.599264) (xy 438.940728 -372.551829)
			(xy 438.986844 -372.509948) (xy 439.037936 -372.474308) (xy 439.093167 -372.445494) (xy 439.151629 -372.42398)
			(xy 439.212363 -372.410118) (xy 439.27437 -372.404136) (xy 439.336633 -372.406132) (xy 439.39813 -372.416075)
			(xy 439.457851 -372.433799) (xy 439.514814 -372.459016) (xy 439.568085 -372.491309) (xy 439.61679 -372.530149)
			(xy 439.660127 -372.574899) (xy 439.697387 -372.624823) (xy 439.727956 -372.679102) (xy 439.751334 -372.736845)
			(xy 439.767135 -372.797103) (xy 439.775101 -372.858886) (xy 439.7756 -372.890034) (xy 439.775101 -372.921182)
			(xy 439.767135 -372.982965) (xy 439.751334 -373.043223) (xy 439.727956 -373.100966) (xy 439.697387 -373.155245)
			(xy 439.660127 -373.205169) (xy 439.61679 -373.249919) (xy 439.568085 -373.288759) (xy 439.514814 -373.321052)
			(xy 439.457851 -373.346269) (xy 439.39813 -373.363993) (xy 439.336633 -373.373936) (xy 439.27437 -373.375932)
			(xy 439.212363 -373.36995) (xy 439.151629 -373.356088) (xy 439.093167 -373.334574) (xy 439.037936 -373.30576)
			(xy 438.986844 -373.27012) (xy 438.940728 -373.228239) (xy 438.900346 -373.180804) (xy 438.866362 -373.128595)
			(xy 438.839333 -373.072469) (xy 438.819704 -373.013348) (xy 438.807795 -372.952201) (xy 438.803804 -372.890034)
			(xy 438.056782 -372.890034) (xy 438.056782 -375.490232) (xy 438.803804 -375.490232) (xy 438.807795 -375.428065)
			(xy 438.819704 -375.366918) (xy 438.839333 -375.307797) (xy 438.866362 -375.251671) (xy 438.900346 -375.199462)
			(xy 438.940728 -375.152027) (xy 438.986844 -375.110146) (xy 439.037936 -375.074506) (xy 439.093167 -375.045692)
			(xy 439.151629 -375.024178) (xy 439.212363 -375.010316) (xy 439.27437 -375.004334) (xy 439.336633 -375.00633)
			(xy 439.39813 -375.016273) (xy 439.457851 -375.033997) (xy 439.514814 -375.059214) (xy 439.568085 -375.091507)
			(xy 439.61679 -375.130347) (xy 439.660127 -375.175097) (xy 439.697387 -375.225021) (xy 439.727956 -375.2793)
			(xy 439.751334 -375.337043) (xy 439.767135 -375.397301) (xy 439.775101 -375.459084) (xy 439.7756 -375.490232)
			(xy 439.775101 -375.52138) (xy 439.767135 -375.583163) (xy 439.751334 -375.643421) (xy 439.727956 -375.701164)
			(xy 439.697387 -375.755443) (xy 439.660127 -375.805367) (xy 439.61679 -375.850117) (xy 439.568085 -375.888957)
			(xy 439.514814 -375.92125) (xy 439.457851 -375.946467) (xy 439.39813 -375.964191) (xy 439.336633 -375.974134)
			(xy 439.27437 -375.97613) (xy 439.212363 -375.970148) (xy 439.151629 -375.956286) (xy 439.093167 -375.934772)
			(xy 439.037936 -375.905958) (xy 438.986844 -375.870318) (xy 438.940728 -375.828437) (xy 438.900346 -375.781002)
			(xy 438.866362 -375.728793) (xy 438.839333 -375.672667) (xy 438.819704 -375.613546) (xy 438.807795 -375.552399)
			(xy 438.803804 -375.490232) (xy 438.056782 -375.490232) (xy 438.056782 -376.790204) (xy 438.803804 -376.790204)
			(xy 438.807795 -376.728037) (xy 438.819704 -376.66689) (xy 438.839333 -376.607769) (xy 438.866362 -376.551643)
			(xy 438.900346 -376.499434) (xy 438.940728 -376.451999) (xy 438.986844 -376.410118) (xy 439.037936 -376.374478)
			(xy 439.093167 -376.345664) (xy 439.151629 -376.32415) (xy 439.212363 -376.310288) (xy 439.27437 -376.304306)
			(xy 439.336633 -376.306302) (xy 439.39813 -376.316245) (xy 439.457851 -376.333969) (xy 439.514814 -376.359186)
			(xy 439.568085 -376.391479) (xy 439.61679 -376.430319) (xy 439.660127 -376.475069) (xy 439.697387 -376.524993)
			(xy 439.727956 -376.579272) (xy 439.751334 -376.637015) (xy 439.767135 -376.697273) (xy 439.775101 -376.759056)
			(xy 439.7756 -376.790204) (xy 439.775101 -376.821352) (xy 439.767135 -376.883135) (xy 439.751334 -376.943393)
			(xy 439.727956 -377.001136) (xy 439.697387 -377.055415) (xy 439.660127 -377.105339) (xy 439.61679 -377.150089)
			(xy 439.568085 -377.188929) (xy 439.514814 -377.221222) (xy 439.457851 -377.246439) (xy 439.39813 -377.264163)
			(xy 439.336633 -377.274106) (xy 439.27437 -377.276102) (xy 439.212363 -377.27012) (xy 439.151629 -377.256258)
			(xy 439.093167 -377.234744) (xy 439.037936 -377.20593) (xy 438.986844 -377.17029) (xy 438.940728 -377.128409)
			(xy 438.900346 -377.080974) (xy 438.866362 -377.028765) (xy 438.839333 -376.972639) (xy 438.819704 -376.913518)
			(xy 438.807795 -376.852371) (xy 438.803804 -376.790204) (xy 438.056782 -376.790204) (xy 438.056782 -379.390148)
			(xy 438.803804 -379.390148) (xy 438.807795 -379.327981) (xy 438.819704 -379.266834) (xy 438.839333 -379.207713)
			(xy 438.866362 -379.151587) (xy 438.900346 -379.099378) (xy 438.940728 -379.051943) (xy 438.986844 -379.010062)
			(xy 439.037936 -378.974422) (xy 439.093167 -378.945608) (xy 439.151629 -378.924094) (xy 439.212363 -378.910232)
			(xy 439.27437 -378.90425) (xy 439.336633 -378.906246) (xy 439.39813 -378.916189) (xy 439.457851 -378.933913)
			(xy 439.514814 -378.95913) (xy 439.568085 -378.991423) (xy 439.61679 -379.030263) (xy 439.660127 -379.075013)
			(xy 439.697387 -379.124937) (xy 439.727956 -379.179216) (xy 439.751334 -379.236959) (xy 439.767135 -379.297217)
			(xy 439.775101 -379.359) (xy 439.7756 -379.390148) (xy 439.775101 -379.421296) (xy 439.767135 -379.483079)
			(xy 439.751334 -379.543337) (xy 439.727956 -379.60108) (xy 439.697387 -379.655359) (xy 439.660127 -379.705283)
			(xy 439.61679 -379.750033) (xy 439.568085 -379.788873) (xy 439.514814 -379.821166) (xy 439.457851 -379.846383)
			(xy 439.39813 -379.864107) (xy 439.336633 -379.87405) (xy 439.27437 -379.876046) (xy 439.212363 -379.870064)
			(xy 439.151629 -379.856202) (xy 439.093167 -379.834688) (xy 439.037936 -379.805874) (xy 438.986844 -379.770234)
			(xy 438.940728 -379.728353) (xy 438.900346 -379.680918) (xy 438.866362 -379.628709) (xy 438.839333 -379.572583)
			(xy 438.819704 -379.513462) (xy 438.807795 -379.452315) (xy 438.803804 -379.390148) (xy 438.056782 -379.390148)
			(xy 438.056782 -380.69012) (xy 438.803804 -380.69012) (xy 438.807795 -380.627953) (xy 438.819704 -380.566806)
			(xy 438.839333 -380.507685) (xy 438.866362 -380.451559) (xy 438.900346 -380.39935) (xy 438.940728 -380.351915)
			(xy 438.986844 -380.310034) (xy 439.037936 -380.274394) (xy 439.093167 -380.24558) (xy 439.151629 -380.224066)
			(xy 439.212363 -380.210204) (xy 439.27437 -380.204222) (xy 439.336633 -380.206218) (xy 439.39813 -380.216161)
			(xy 439.457851 -380.233885) (xy 439.514814 -380.259102) (xy 439.568085 -380.291395) (xy 439.61679 -380.330235)
			(xy 439.660127 -380.374985) (xy 439.697387 -380.424909) (xy 439.727956 -380.479188) (xy 439.751334 -380.536931)
			(xy 439.767135 -380.597189) (xy 439.775101 -380.658972) (xy 439.7756 -380.69012) (xy 439.775101 -380.721268)
			(xy 439.767135 -380.783051) (xy 439.751334 -380.843309) (xy 439.727956 -380.901052) (xy 439.697387 -380.955331)
			(xy 439.660127 -381.005255) (xy 439.61679 -381.050005) (xy 439.568085 -381.088845) (xy 439.514814 -381.121138)
			(xy 439.457851 -381.146355) (xy 439.39813 -381.164079) (xy 439.336633 -381.174022) (xy 439.27437 -381.176018)
			(xy 439.212363 -381.170036) (xy 439.151629 -381.156174) (xy 439.093167 -381.13466) (xy 439.037936 -381.105846)
			(xy 438.986844 -381.070206) (xy 438.940728 -381.028325) (xy 438.900346 -380.98089) (xy 438.866362 -380.928681)
			(xy 438.839333 -380.872555) (xy 438.819704 -380.813434) (xy 438.807795 -380.752287) (xy 438.803804 -380.69012)
			(xy 438.056782 -380.69012) (xy 438.056782 -383.290064) (xy 438.803804 -383.290064) (xy 438.807795 -383.227897)
			(xy 438.819704 -383.16675) (xy 438.839333 -383.107629) (xy 438.866362 -383.051503) (xy 438.900346 -382.999294)
			(xy 438.940728 -382.951859) (xy 438.986844 -382.909978) (xy 439.037936 -382.874338) (xy 439.093167 -382.845524)
			(xy 439.151629 -382.82401) (xy 439.212363 -382.810148) (xy 439.27437 -382.804166) (xy 439.336633 -382.806162)
			(xy 439.39813 -382.816105) (xy 439.457851 -382.833829) (xy 439.514814 -382.859046) (xy 439.568085 -382.891339)
			(xy 439.61679 -382.930179) (xy 439.660127 -382.974929) (xy 439.697387 -383.024853) (xy 439.727956 -383.079132)
			(xy 439.751334 -383.136875) (xy 439.767135 -383.197133) (xy 439.775101 -383.258916) (xy 439.7756 -383.290064)
			(xy 439.775101 -383.321212) (xy 439.767135 -383.382995) (xy 439.751334 -383.443253) (xy 439.727956 -383.500996)
			(xy 439.697387 -383.555275) (xy 439.660127 -383.605199) (xy 439.61679 -383.649949) (xy 439.568085 -383.688789)
			(xy 439.514814 -383.721082) (xy 439.457851 -383.746299) (xy 439.39813 -383.764023) (xy 439.336633 -383.773966)
			(xy 439.27437 -383.775962) (xy 439.212363 -383.76998) (xy 439.151629 -383.756118) (xy 439.093167 -383.734604)
			(xy 439.037936 -383.70579) (xy 438.986844 -383.67015) (xy 438.940728 -383.628269) (xy 438.900346 -383.580834)
			(xy 438.866362 -383.528625) (xy 438.839333 -383.472499) (xy 438.819704 -383.413378) (xy 438.807795 -383.352231)
			(xy 438.803804 -383.290064) (xy 438.056782 -383.290064) (xy 438.056782 -384.590036) (xy 438.803804 -384.590036)
			(xy 438.807795 -384.527869) (xy 438.819704 -384.466722) (xy 438.839333 -384.407601) (xy 438.866362 -384.351475)
			(xy 438.900346 -384.299266) (xy 438.940728 -384.251831) (xy 438.986844 -384.20995) (xy 439.037936 -384.17431)
			(xy 439.093167 -384.145496) (xy 439.151629 -384.123982) (xy 439.212363 -384.11012) (xy 439.27437 -384.104138)
			(xy 439.336633 -384.106134) (xy 439.39813 -384.116077) (xy 439.457851 -384.133801) (xy 439.514814 -384.159018)
			(xy 439.568085 -384.191311) (xy 439.61679 -384.230151) (xy 439.660127 -384.274901) (xy 439.697387 -384.324825)
			(xy 439.727956 -384.379104) (xy 439.751334 -384.436847) (xy 439.767135 -384.497105) (xy 439.775101 -384.558888)
			(xy 439.7756 -384.590036) (xy 439.775101 -384.621184) (xy 439.767135 -384.682967) (xy 439.751334 -384.743225)
			(xy 439.727956 -384.800968) (xy 439.697387 -384.855247) (xy 439.660127 -384.905171) (xy 439.61679 -384.949921)
			(xy 439.568085 -384.988761) (xy 439.514814 -385.021054) (xy 439.457851 -385.046271) (xy 439.39813 -385.063995)
			(xy 439.336633 -385.073938) (xy 439.27437 -385.075934) (xy 439.212363 -385.069952) (xy 439.151629 -385.05609)
			(xy 439.093167 -385.034576) (xy 439.037936 -385.005762) (xy 438.986844 -384.970122) (xy 438.940728 -384.928241)
			(xy 438.900346 -384.880806) (xy 438.866362 -384.828597) (xy 438.839333 -384.772471) (xy 438.819704 -384.71335)
			(xy 438.807795 -384.652203) (xy 438.803804 -384.590036) (xy 438.056782 -384.590036) (xy 438.056782 -397.59001)
			(xy 438.803804 -397.59001) (xy 438.807795 -397.527843) (xy 438.819704 -397.466696) (xy 438.839333 -397.407575)
			(xy 438.866362 -397.351449) (xy 438.900346 -397.29924) (xy 438.940728 -397.251805) (xy 438.986844 -397.209924)
			(xy 439.037936 -397.174284) (xy 439.093167 -397.14547) (xy 439.151629 -397.123956) (xy 439.212363 -397.110094)
			(xy 439.27437 -397.104112) (xy 439.336633 -397.106108) (xy 439.39813 -397.116051) (xy 439.457851 -397.133775)
			(xy 439.514814 -397.158992) (xy 439.568085 -397.191285) (xy 439.61679 -397.230125) (xy 439.660127 -397.274875)
			(xy 439.697387 -397.324799) (xy 439.727956 -397.379078) (xy 439.751334 -397.436821) (xy 439.767135 -397.497079)
			(xy 439.775101 -397.558862) (xy 439.7756 -397.59001) (xy 439.775101 -397.621158) (xy 439.767135 -397.682941)
			(xy 439.751334 -397.743199) (xy 439.727956 -397.800942) (xy 439.697387 -397.855221) (xy 439.660127 -397.905145)
			(xy 439.61679 -397.949895) (xy 439.568085 -397.988735) (xy 439.514814 -398.021028) (xy 439.457851 -398.046245)
			(xy 439.39813 -398.063969) (xy 439.336633 -398.073912) (xy 439.27437 -398.075908) (xy 439.212363 -398.069926)
			(xy 439.151629 -398.056064) (xy 439.093167 -398.03455) (xy 439.037936 -398.005736) (xy 438.986844 -397.970096)
			(xy 438.940728 -397.928215) (xy 438.900346 -397.88078) (xy 438.866362 -397.828571) (xy 438.839333 -397.772445)
			(xy 438.819704 -397.713324) (xy 438.807795 -397.652177) (xy 438.803804 -397.59001) (xy 438.056782 -397.59001)
			(xy 438.056782 -398.890236) (xy 438.803804 -398.890236) (xy 438.807795 -398.828069) (xy 438.819704 -398.766922)
			(xy 438.839333 -398.707801) (xy 438.866362 -398.651675) (xy 438.900346 -398.599466) (xy 438.940728 -398.552031)
			(xy 438.986844 -398.51015) (xy 439.037936 -398.47451) (xy 439.093167 -398.445696) (xy 439.151629 -398.424182)
			(xy 439.212363 -398.41032) (xy 439.27437 -398.404338) (xy 439.336633 -398.406334) (xy 439.39813 -398.416277)
			(xy 439.457851 -398.434001) (xy 439.514814 -398.459218) (xy 439.568085 -398.491511) (xy 439.61679 -398.530351)
			(xy 439.660127 -398.575101) (xy 439.697387 -398.625025) (xy 439.727956 -398.679304) (xy 439.751334 -398.737047)
			(xy 439.767135 -398.797305) (xy 439.775101 -398.859088) (xy 439.7756 -398.890236) (xy 439.775101 -398.921384)
			(xy 439.767135 -398.983167) (xy 439.751334 -399.043425) (xy 439.727956 -399.101168) (xy 439.697387 -399.155447)
			(xy 439.660127 -399.205371) (xy 439.61679 -399.250121) (xy 439.568085 -399.288961) (xy 439.514814 -399.321254)
			(xy 439.457851 -399.346471) (xy 439.39813 -399.364195) (xy 439.336633 -399.374138) (xy 439.27437 -399.376134)
			(xy 439.212363 -399.370152) (xy 439.151629 -399.35629) (xy 439.093167 -399.334776) (xy 439.037936 -399.305962)
			(xy 438.986844 -399.270322) (xy 438.940728 -399.228441) (xy 438.900346 -399.181006) (xy 438.866362 -399.128797)
			(xy 438.839333 -399.072671) (xy 438.819704 -399.01355) (xy 438.807795 -398.952403) (xy 438.803804 -398.890236)
			(xy 438.056782 -398.890236) (xy 438.056782 -400.78787) (xy 446.249042 -400.78787) (xy 446.253113 -400.732248)
			(xy 446.265239 -400.677811) (xy 446.285162 -400.62572) (xy 446.312458 -400.577085) (xy 446.346544 -400.532942)
			(xy 446.386693 -400.494233) (xy 446.432051 -400.461782) (xy 446.481651 -400.436281) (xy 446.534435 -400.418274)
			(xy 446.589278 -400.408144) (xy 446.645012 -400.406107) (xy 446.700449 -400.412207) (xy 446.754406 -400.426313)
			(xy 446.805735 -400.448125) (xy 446.853341 -400.477179) (xy 446.896209 -400.512854) (xy 446.933426 -400.554391)
			(xy 446.964199 -400.600904) (xy 446.987871 -400.651401) (xy 447.003939 -400.704808) (xy 447.012059 -400.759984)
			(xy 447.012568 -400.78787) (xy 447.012059 -400.815756) (xy 447.003939 -400.870932) (xy 446.987871 -400.924339)
			(xy 446.964199 -400.974836) (xy 446.933426 -401.021349) (xy 446.896209 -401.062886) (xy 446.853341 -401.098561)
			(xy 446.805735 -401.127615) (xy 446.754406 -401.149427) (xy 446.700449 -401.163533) (xy 446.645012 -401.169633)
			(xy 446.589278 -401.167596) (xy 446.534435 -401.157466) (xy 446.481651 -401.139459) (xy 446.432051 -401.113958)
			(xy 446.386693 -401.081507) (xy 446.346544 -401.042798) (xy 446.312458 -400.998655) (xy 446.285162 -400.95002)
			(xy 446.265239 -400.897929) (xy 446.253113 -400.843492) (xy 446.249042 -400.78787) (xy 438.056782 -400.78787)
			(xy 438.056782 -401.49018) (xy 438.803804 -401.49018) (xy 438.807795 -401.428013) (xy 438.819704 -401.366866)
			(xy 438.839333 -401.307745) (xy 438.866362 -401.251619) (xy 438.900346 -401.19941) (xy 438.940728 -401.151975)
			(xy 438.986844 -401.110094) (xy 439.037936 -401.074454) (xy 439.093167 -401.04564) (xy 439.151629 -401.024126)
			(xy 439.212363 -401.010264) (xy 439.27437 -401.004282) (xy 439.336633 -401.006278) (xy 439.39813 -401.016221)
			(xy 439.457851 -401.033945) (xy 439.514814 -401.059162) (xy 439.568085 -401.091455) (xy 439.61679 -401.130295)
			(xy 439.660127 -401.175045) (xy 439.697387 -401.224969) (xy 439.727956 -401.279248) (xy 439.751334 -401.336991)
			(xy 439.767135 -401.397249) (xy 439.775101 -401.459032) (xy 439.7756 -401.49018) (xy 439.775101 -401.521328)
			(xy 439.767135 -401.583111) (xy 439.751334 -401.643369) (xy 439.727956 -401.701112) (xy 439.697387 -401.755391)
			(xy 439.660127 -401.805315) (xy 439.61679 -401.850065) (xy 439.568085 -401.888905) (xy 439.514814 -401.921198)
			(xy 439.457851 -401.946415) (xy 439.39813 -401.964139) (xy 439.336633 -401.974082) (xy 439.27437 -401.976078)
			(xy 439.212363 -401.970096) (xy 439.151629 -401.956234) (xy 439.093167 -401.93472) (xy 439.037936 -401.905906)
			(xy 438.986844 -401.870266) (xy 438.940728 -401.828385) (xy 438.900346 -401.78095) (xy 438.866362 -401.728741)
			(xy 438.839333 -401.672615) (xy 438.819704 -401.613494) (xy 438.807795 -401.552347) (xy 438.803804 -401.49018)
			(xy 438.056782 -401.49018) (xy 438.056782 -402.790152) (xy 438.803804 -402.790152) (xy 438.807795 -402.727985)
			(xy 438.819704 -402.666838) (xy 438.839333 -402.607717) (xy 438.866362 -402.551591) (xy 438.900346 -402.499382)
			(xy 438.940728 -402.451947) (xy 438.986844 -402.410066) (xy 439.037936 -402.374426) (xy 439.093167 -402.345612)
			(xy 439.151629 -402.324098) (xy 439.212363 -402.310236) (xy 439.27437 -402.304254) (xy 439.336633 -402.30625)
			(xy 439.39813 -402.316193) (xy 439.457851 -402.333917) (xy 439.514814 -402.359134) (xy 439.568085 -402.391427)
			(xy 439.61679 -402.430267) (xy 439.660127 -402.475017) (xy 439.697387 -402.524941) (xy 439.727956 -402.57922)
			(xy 439.751334 -402.636963) (xy 439.767135 -402.697221) (xy 439.775101 -402.759004) (xy 439.7756 -402.790152)
			(xy 439.775101 -402.8213) (xy 439.767135 -402.883083) (xy 439.751334 -402.943341) (xy 439.727956 -403.001084)
			(xy 439.697387 -403.055363) (xy 439.660127 -403.105287) (xy 439.61679 -403.150037) (xy 439.568085 -403.188877)
			(xy 439.514814 -403.22117) (xy 439.457851 -403.246387) (xy 439.39813 -403.264111) (xy 439.336633 -403.274054)
			(xy 439.27437 -403.27605) (xy 439.212363 -403.270068) (xy 439.151629 -403.256206) (xy 439.093167 -403.234692)
			(xy 439.037936 -403.205878) (xy 438.986844 -403.170238) (xy 438.940728 -403.128357) (xy 438.900346 -403.080922)
			(xy 438.866362 -403.028713) (xy 438.839333 -402.972587) (xy 438.819704 -402.913466) (xy 438.807795 -402.852319)
			(xy 438.803804 -402.790152) (xy 438.056782 -402.790152) (xy 438.056782 -405.390096) (xy 438.803804 -405.390096)
			(xy 438.807795 -405.327929) (xy 438.819704 -405.266782) (xy 438.839333 -405.207661) (xy 438.866362 -405.151535)
			(xy 438.900346 -405.099326) (xy 438.940728 -405.051891) (xy 438.986844 -405.01001) (xy 439.037936 -404.97437)
			(xy 439.093167 -404.945556) (xy 439.151629 -404.924042) (xy 439.212363 -404.91018) (xy 439.27437 -404.904198)
			(xy 439.336633 -404.906194) (xy 439.39813 -404.916137) (xy 439.457851 -404.933861) (xy 439.514814 -404.959078)
			(xy 439.568085 -404.991371) (xy 439.61679 -405.030211) (xy 439.660127 -405.074961) (xy 439.697387 -405.124885)
			(xy 439.727956 -405.179164) (xy 439.751334 -405.236907) (xy 439.767135 -405.297165) (xy 439.775101 -405.358948)
			(xy 439.7756 -405.390096) (xy 439.775101 -405.421244) (xy 439.767135 -405.483027) (xy 439.751334 -405.543285)
			(xy 439.727956 -405.601028) (xy 439.697387 -405.655307) (xy 439.660127 -405.705231) (xy 439.61679 -405.749981)
			(xy 439.568085 -405.788821) (xy 439.514814 -405.821114) (xy 439.457851 -405.846331) (xy 439.39813 -405.864055)
			(xy 439.336633 -405.873998) (xy 439.27437 -405.875994) (xy 439.212363 -405.870012) (xy 439.151629 -405.85615)
			(xy 439.093167 -405.834636) (xy 439.037936 -405.805822) (xy 438.986844 -405.770182) (xy 438.940728 -405.728301)
			(xy 438.900346 -405.680866) (xy 438.866362 -405.628657) (xy 438.839333 -405.572531) (xy 438.819704 -405.51341)
			(xy 438.807795 -405.452263) (xy 438.803804 -405.390096) (xy 438.056782 -405.390096) (xy 438.056782 -406.690068)
			(xy 438.803804 -406.690068) (xy 438.807795 -406.627901) (xy 438.819704 -406.566754) (xy 438.839333 -406.507633)
			(xy 438.866362 -406.451507) (xy 438.900346 -406.399298) (xy 438.940728 -406.351863) (xy 438.986844 -406.309982)
			(xy 439.037936 -406.274342) (xy 439.093167 -406.245528) (xy 439.151629 -406.224014) (xy 439.212363 -406.210152)
			(xy 439.27437 -406.20417) (xy 439.336633 -406.206166) (xy 439.39813 -406.216109) (xy 439.457851 -406.233833)
			(xy 439.514814 -406.25905) (xy 439.568085 -406.291343) (xy 439.61679 -406.330183) (xy 439.660127 -406.374933)
			(xy 439.697387 -406.424857) (xy 439.727956 -406.479136) (xy 439.751334 -406.536879) (xy 439.767135 -406.597137)
			(xy 439.775101 -406.65892) (xy 439.7756 -406.690068) (xy 439.775101 -406.721216) (xy 439.767135 -406.782999)
			(xy 439.751334 -406.843257) (xy 439.727956 -406.901) (xy 439.697387 -406.955279) (xy 439.660127 -407.005203)
			(xy 439.61679 -407.049953) (xy 439.568085 -407.088793) (xy 439.514814 -407.121086) (xy 439.457851 -407.146303)
			(xy 439.39813 -407.164027) (xy 439.336633 -407.17397) (xy 439.27437 -407.175966) (xy 439.212363 -407.169984)
			(xy 439.151629 -407.156122) (xy 439.093167 -407.134608) (xy 439.037936 -407.105794) (xy 438.986844 -407.070154)
			(xy 438.940728 -407.028273) (xy 438.900346 -406.980838) (xy 438.866362 -406.928629) (xy 438.839333 -406.872503)
			(xy 438.819704 -406.813382) (xy 438.807795 -406.752235) (xy 438.803804 -406.690068) (xy 438.056782 -406.690068)
			(xy 438.056782 -406.700482) (xy 438.056343 -406.710545) (xy 438.048606 -406.729126) (xy 438.041796 -406.73655)
			(xy 437.6674 -407.110946) (xy 437.662186 -407.115854) (xy 437.649681 -407.122818) (xy 437.642762 -407.124662)
			(xy 437.631586 -407.127202) (xy 437.622696 -407.13406) (xy 437.618421 -407.137533) (xy 437.611368 -407.145991)
			(xy 437.608726 -407.150824) (xy 437.607202 -407.153618) (xy 437.607202 -407.153872) (xy 437.591522 -407.183619)
			(xy 437.554299 -407.239625) (xy 437.510854 -407.290953) (xy 437.461768 -407.336917) (xy 437.407699 -407.376901)
			(xy 437.349372 -407.410368) (xy 437.287568 -407.436871) (xy 437.223116 -407.456054) (xy 437.156878 -407.467661)
			(xy 437.089743 -407.471534) (xy 437.02261 -407.467624) (xy 436.956379 -407.455982) (xy 436.891937 -407.436764)
			(xy 436.830147 -407.410228) (xy 436.771838 -407.376729) (xy 436.717791 -407.336716) (xy 436.66873 -407.290726)
			(xy 436.625312 -407.239374) (xy 436.58812 -407.183348) (xy 436.572406 -407.153618) (xy 436.567791 -407.145505)
			(xy 436.553925 -407.133033) (xy 436.536518 -407.126338) (xy 436.527194 -407.125932) (xy 435.880764 -407.125932)
			(xy 435.872636 -407.128726) (xy 435.852795 -407.13537) (xy 435.812649 -407.147184) (xy 435.792372 -407.152348)
			(xy 435.782411 -407.155328) (xy 435.765899 -407.167926) (xy 435.760368 -407.176732) (xy 435.738427 -407.214982)
			(xy 435.688763 -407.287855) (xy 435.632858 -407.356057) (xy 435.571147 -407.419054) (xy 435.504114 -407.476356)
			(xy 435.432282 -407.527513) (xy 435.356212 -407.572126) (xy 435.2765 -407.609846) (xy 435.193767 -407.640379)
			(xy 435.108661 -407.663486) (xy 435.021847 -407.678986) (xy 434.934004 -407.686757) (xy 434.88991 -407.687272)
			(xy 434.889656 -407.687272) (xy 434.846618 -407.68682) (xy 434.760862 -407.6794) (xy 434.676066 -407.664612)
			(xy 434.592862 -407.642566) (xy 434.511869 -407.613425) (xy 434.472588 -407.595832) (xy 434.466746 -407.597356)
			(xy 434.444575 -407.605642) (xy 434.398696 -407.617286) (xy 434.351728 -407.62315) (xy 434.328062 -407.623518)
			(xy 434.327808 -407.623518) (xy 434.300556 -407.623033) (xy 434.246607 -407.615277) (xy 434.194311 -407.599923)
			(xy 434.144732 -407.577282) (xy 434.09888 -407.547816) (xy 434.057688 -407.512125) (xy 434.021994 -407.470935)
			(xy 433.992526 -407.425084) (xy 433.969883 -407.375506) (xy 433.954527 -407.323211) (xy 433.946769 -407.269262)
			(xy 433.9463 -407.24201) (xy 433.9463 -407.241502) (xy 433.946461 -407.227799) (xy 433.948494 -407.200468)
			(xy 433.950364 -407.186892) (xy 433.950618 -407.18486) (xy 433.950872 -407.180288) (xy 433.950872 -407.180034)
			(xy 433.951112 -407.169587) (xy 433.944171 -407.1499) (xy 433.93741 -407.141934) (xy 433.930298 -407.134314)
			(xy 433.910994 -407.125932) (xy 433.252372 -407.125932) (xy 433.24305 -407.126353) (xy 433.225644 -407.133039)
			(xy 433.211786 -407.145512) (xy 433.20716 -407.153618) (xy 433.191478 -407.18336) (xy 433.154255 -407.239357)
			(xy 433.110813 -407.290678) (xy 433.061732 -407.336638) (xy 433.007671 -407.376619) (xy 432.949353 -407.410088)
			(xy 432.887559 -407.436596) (xy 432.823117 -407.455788) (xy 432.756889 -407.467407) (xy 432.689762 -407.471297)
			(xy 432.622635 -407.467407) (xy 432.556407 -407.455788) (xy 432.491965 -407.436596) (xy 432.430171 -407.410088)
			(xy 432.371853 -407.376619) (xy 432.317792 -407.336638) (xy 432.268711 -407.290678) (xy 432.225269 -407.239357)
			(xy 432.188046 -407.18336) (xy 432.172364 -407.153618) (xy 432.167747 -407.14551) (xy 432.153879 -407.133049)
			(xy 432.136473 -407.126368) (xy 432.127152 -407.125932) (xy 431.480722 -407.125932) (xy 431.472594 -407.128726)
			(xy 431.452753 -407.135371) (xy 431.412608 -407.147188) (xy 431.39233 -407.152348) (xy 431.382362 -407.155319)
			(xy 431.365833 -407.167908) (xy 431.360326 -407.176732) (xy 431.338385 -407.214983) (xy 431.288723 -407.287859)
			(xy 431.232819 -407.356065) (xy 431.171109 -407.419066) (xy 431.104076 -407.476371) (xy 431.032245 -407.527533)
			(xy 430.956175 -407.57215) (xy 430.876462 -407.609875) (xy 430.79373 -407.640412) (xy 430.708623 -407.663524)
			(xy 430.621808 -407.679029) (xy 430.533962 -407.686805) (xy 430.489868 -407.687272) (xy 430.489614 -407.687272)
			(xy 430.446575 -407.686822) (xy 430.360818 -407.679408) (xy 430.27602 -407.664624) (xy 430.192814 -407.642582)
			(xy 430.111818 -407.613445) (xy 430.072546 -407.595832) (xy 430.066704 -407.597356) (xy 430.044533 -407.605646)
			(xy 429.998655 -407.617296) (xy 429.951687 -407.623168) (xy 429.92802 -407.623518) (xy 429.927766 -407.623518)
			(xy 429.900516 -407.62303) (xy 429.846571 -407.61527) (xy 429.79428 -407.599912) (xy 429.744707 -407.577269)
			(xy 429.69886 -407.547802) (xy 429.657673 -407.51211) (xy 429.621984 -407.470921) (xy 429.59252 -407.425072)
			(xy 429.56988 -407.375497) (xy 429.554525 -407.323205) (xy 429.546768 -407.26926) (xy 429.546258 -407.24201)
			(xy 429.546258 -407.241502) (xy 429.546419 -407.227799) (xy 429.548452 -407.200468) (xy 429.550322 -407.186892)
			(xy 429.550576 -407.18486) (xy 429.55083 -407.180288) (xy 429.55083 -407.180034) (xy 429.55107 -407.169588)
			(xy 429.544124 -407.149904) (xy 429.537368 -407.141934) (xy 429.530256 -407.134314) (xy 429.510952 -407.125932)
			(xy 428.852584 -407.125932) (xy 428.84326 -407.126351) (xy 428.825852 -407.133034) (xy 428.81199 -407.145507)
			(xy 428.807372 -407.153618) (xy 428.79169 -407.18336) (xy 428.754467 -407.239357) (xy 428.711025 -407.290678)
			(xy 428.661944 -407.336638) (xy 428.607883 -407.376619) (xy 428.549565 -407.410088) (xy 428.487771 -407.436596)
			(xy 428.423329 -407.455788) (xy 428.357101 -407.467407) (xy 428.289974 -407.471297) (xy 428.222847 -407.467407)
			(xy 428.156619 -407.455788) (xy 428.092177 -407.436596) (xy 428.030383 -407.410088) (xy 427.972065 -407.376619)
			(xy 427.918004 -407.336638) (xy 427.868923 -407.290678) (xy 427.825481 -407.239357) (xy 427.788258 -407.18336)
			(xy 427.772576 -407.153618) (xy 427.767959 -407.145508) (xy 427.754092 -407.133045) (xy 427.736686 -407.12636)
			(xy 427.727364 -407.125932) (xy 427.08068 -407.125932) (xy 427.072552 -407.128726) (xy 427.052711 -407.13537)
			(xy 427.012565 -407.147185) (xy 426.992288 -407.152348) (xy 426.982325 -407.155325) (xy 426.965808 -407.167921)
			(xy 426.960284 -407.176732) (xy 426.938343 -407.214982) (xy 426.88868 -407.287856) (xy 426.832775 -407.356059)
			(xy 426.771064 -407.419058) (xy 426.704031 -407.47636) (xy 426.632199 -407.527518) (xy 426.55613 -407.572133)
			(xy 426.476417 -407.609854) (xy 426.393684 -407.640388) (xy 426.308578 -407.663496) (xy 426.221764 -407.678997)
			(xy 426.13392 -407.686771) (xy 426.089826 -407.687272) (xy 426.089572 -407.687272) (xy 426.046534 -407.68682)
			(xy 425.960778 -407.679402) (xy 425.875981 -407.664616) (xy 425.792776 -407.64257) (xy 425.711782 -407.61343)
			(xy 425.672504 -407.595832) (xy 425.666662 -407.597356) (xy 425.644491 -407.605643) (xy 425.598613 -407.617289)
			(xy 425.551645 -407.623155) (xy 425.527978 -407.623518) (xy 425.527724 -407.623518) (xy 425.50047 -407.623057)
			(xy 425.446516 -407.615303) (xy 425.394214 -407.599949) (xy 425.34463 -407.577308) (xy 425.298773 -407.547841)
			(xy 425.257577 -407.512147) (xy 425.22188 -407.470954) (xy 425.192409 -407.425099) (xy 425.169763 -407.375518)
			(xy 425.154405 -407.323218) (xy 425.146646 -407.269264) (xy 425.146216 -407.24201) (xy 425.146216 -407.241502)
			(xy 425.146377 -407.227799) (xy 425.14841 -407.200468) (xy 425.15028 -407.186892) (xy 425.150534 -407.18486)
			(xy 425.150788 -407.180288) (xy 425.150788 -407.180034) (xy 425.151029 -407.169587) (xy 425.144089 -407.149898)
			(xy 425.137326 -407.141934) (xy 425.130214 -407.134314) (xy 425.11091 -407.125932) (xy 424.452542 -407.125932)
			(xy 424.443213 -407.126342) (xy 424.425788 -407.133012) (xy 424.411909 -407.145482) (xy 424.40733 -407.153618)
			(xy 424.391648 -407.18336) (xy 424.354425 -407.239357) (xy 424.310983 -407.290678) (xy 424.261902 -407.336638)
			(xy 424.207841 -407.376619) (xy 424.149523 -407.410088) (xy 424.087729 -407.436596) (xy 424.023287 -407.455788)
			(xy 423.957059 -407.467407) (xy 423.889932 -407.471297) (xy 423.822805 -407.467407) (xy 423.756577 -407.455788)
			(xy 423.692135 -407.436596) (xy 423.630341 -407.410088) (xy 423.572023 -407.376619) (xy 423.517962 -407.336638)
			(xy 423.468881 -407.290678) (xy 423.425439 -407.239357) (xy 423.388216 -407.18336) (xy 423.372534 -407.153618)
			(xy 423.367915 -407.145513) (xy 423.354046 -407.133061) (xy 423.336641 -407.12639) (xy 423.327322 -407.125932)
			(xy 422.680638 -407.125932) (xy 422.67251 -407.128726) (xy 422.652668 -407.135369) (xy 422.612523 -407.147183)
			(xy 422.592246 -407.152348) (xy 422.582276 -407.155317) (xy 422.565742 -407.167904) (xy 422.560242 -407.176732)
			(xy 422.538301 -407.214984) (xy 422.488639 -407.287861) (xy 422.432735 -407.356067) (xy 422.371026 -407.419069)
			(xy 422.303993 -407.476376) (xy 422.232162 -407.527538) (xy 422.156092 -407.572157) (xy 422.07638 -407.609883)
			(xy 421.993647 -407.640422) (xy 421.90854 -407.663534) (xy 421.821724 -407.67904) (xy 421.733879 -407.686819)
			(xy 421.689784 -407.687272) (xy 421.68953 -407.687272) (xy 421.646492 -407.686818) (xy 421.560737 -407.679397)
			(xy 421.475942 -407.664607) (xy 421.392738 -407.642558) (xy 421.311747 -407.613416) (xy 421.272462 -407.595832)
			(xy 421.26662 -407.597356) (xy 421.244449 -407.605641) (xy 421.19857 -407.617281) (xy 421.151602 -407.623142)
			(xy 421.127936 -407.623518) (xy 421.127682 -407.623518) (xy 421.100431 -407.623031) (xy 421.046485 -407.615272)
			(xy 420.994192 -407.599916) (xy 420.944616 -407.577274) (xy 420.898767 -407.547807) (xy 420.857578 -407.512116)
			(xy 420.821888 -407.470926) (xy 420.792422 -407.425077) (xy 420.769781 -407.375501) (xy 420.754426 -407.323207)
			(xy 420.746668 -407.269261) (xy 420.746174 -407.24201) (xy 420.746174 -407.241502) (xy 420.746335 -407.227799)
			(xy 420.748368 -407.200468) (xy 420.750238 -407.186892) (xy 420.750492 -407.18486) (xy 420.750746 -407.180288)
			(xy 420.750746 -407.180034) (xy 420.750986 -407.169587) (xy 420.744042 -407.149903) (xy 420.737284 -407.141934)
			(xy 420.730172 -407.134314) (xy 420.710868 -407.125932) (xy 420.0525 -407.125932) (xy 420.043175 -407.126349)
			(xy 420.025762 -407.133028) (xy 420.011895 -407.1455) (xy 420.007288 -407.153618) (xy 419.991606 -407.18336)
			(xy 419.954383 -407.239357) (xy 419.910941 -407.290678) (xy 419.86186 -407.336638) (xy 419.807799 -407.376619)
			(xy 419.749481 -407.410088) (xy 419.687687 -407.436596) (xy 419.623245 -407.455788) (xy 419.557017 -407.467407)
			(xy 419.48989 -407.471297) (xy 419.422763 -407.467407) (xy 419.356535 -407.455788) (xy 419.292093 -407.436596)
			(xy 419.230299 -407.410088) (xy 419.171981 -407.376619) (xy 419.11792 -407.336638) (xy 419.068839 -407.290678)
			(xy 419.025397 -407.239357) (xy 418.988174 -407.18336) (xy 418.972492 -407.153618) (xy 418.967876 -407.145507)
			(xy 418.954009 -407.133039) (xy 418.936603 -407.126348) (xy 418.92728 -407.125932) (xy 418.825934 -407.125932)
			(xy 418.815882 -407.125429) (xy 418.797317 -407.117712) (xy 418.789866 -407.110946) (xy 418.119052 -406.440132)
			(xy 418.112211 -406.432732) (xy 418.104493 -406.414134) (xy 418.104066 -406.404064) (xy 418.104066 -396.319756)
			(xy 418.103634 -396.30969) (xy 418.095905 -396.2911) (xy 418.08908 -396.283688) (xy 413.67329 -391.867898)
			(xy 413.666178 -391.860532) (xy 413.647382 -391.852912) (xy 406.51684 -391.852912) (xy 406.506004 -391.853416)
			(xy 406.486272 -391.862375) (xy 406.47874 -391.870184) (xy 406.428194 -391.927842) (xy 406.421511 -391.936175)
			(xy 406.415192 -391.956561) (xy 406.416002 -391.967212) (xy 406.416002 -391.967974) (xy 406.417508 -391.980111)
			(xy 406.41916 -392.004513) (xy 406.419304 -392.016742) (xy 406.418818 -392.043993) (xy 406.411062 -392.097941)
			(xy 406.395707 -392.150236) (xy 406.373065 -392.199813) (xy 406.343599 -392.245663) (xy 406.307908 -392.286854)
			(xy 406.266717 -392.322545) (xy 406.220867 -392.352011) (xy 406.17129 -392.374653) (xy 406.118995 -392.390008)
			(xy 406.065047 -392.397764) (xy 406.010545 -392.397764) (xy 405.956597 -392.390008) (xy 405.904302 -392.374653)
			(xy 405.854725 -392.352011) (xy 405.808875 -392.322545) (xy 405.767684 -392.286854) (xy 405.731993 -392.245663)
			(xy 405.702527 -392.199813) (xy 405.679885 -392.150236) (xy 405.66453 -392.097941) (xy 405.656774 -392.043993)
			(xy 405.656288 -392.016742) (xy 405.656423 -392.004513) (xy 405.658072 -391.980109) (xy 405.65959 -391.967974)
			(xy 405.65959 -391.967212) (xy 405.660268 -391.956574) (xy 405.653969 -391.936235) (xy 405.647398 -391.927842)
			(xy 405.596852 -391.870184) (xy 405.589318 -391.862383) (xy 405.569584 -391.853436) (xy 405.558752 -391.852912)
			(xy 400.906996 -391.852912) (xy 400.896926 -391.853336) (xy 400.878324 -391.861053) (xy 400.870928 -391.867898)
			(xy 395.634718 -397.104108) (xy 395.627352 -397.11122) (xy 395.619732 -397.130016) (xy 395.619732 -397.211804)
			(xy 395.620157 -397.221873) (xy 395.627876 -397.240474) (xy 395.634718 -397.247872) (xy 395.656653 -397.270691)
			(xy 395.695034 -397.321025) (xy 395.72655 -397.375918) (xy 395.750666 -397.434441) (xy 395.766973 -397.495601)
			(xy 395.775196 -397.558362) (xy 395.775688 -397.59001) (xy 395.775167 -397.621807) (xy 395.766866 -397.684858)
			(xy 395.750406 -397.746286) (xy 395.72607 -397.805041) (xy 395.694273 -397.860116) (xy 395.65556 -397.91057)
			(xy 395.610593 -397.95554) (xy 395.560141 -397.994256) (xy 395.505068 -398.026056) (xy 395.446315 -398.050396)
			(xy 395.384888 -398.06686) (xy 395.321837 -398.075166) (xy 395.29004 -398.075658) (xy 395.258394 -398.075144)
			(xy 395.195639 -398.066914) (xy 395.134485 -398.050602) (xy 395.075969 -398.026483) (xy 395.021081 -397.994968)
			(xy 394.970753 -397.956589) (xy 394.947902 -397.934688) (xy 394.940508 -397.927832) (xy 394.921909 -397.920083)
			(xy 394.911834 -397.919702) (xy 394.840206 -397.919702) (xy 394.830135 -397.920124) (xy 394.81153 -397.927837)
			(xy 394.804138 -397.934688) (xy 393.84859 -398.890236) (xy 394.803892 -398.890236) (xy 394.807883 -398.828069)
			(xy 394.819792 -398.766922) (xy 394.839421 -398.707801) (xy 394.86645 -398.651675) (xy 394.900434 -398.599466)
			(xy 394.940816 -398.552031) (xy 394.986932 -398.51015) (xy 395.038024 -398.47451) (xy 395.093255 -398.445696)
			(xy 395.151717 -398.424182) (xy 395.212451 -398.41032) (xy 395.274458 -398.404338) (xy 395.336721 -398.406334)
			(xy 395.398218 -398.416277) (xy 395.457939 -398.434001) (xy 395.514902 -398.459218) (xy 395.568173 -398.491511)
			(xy 395.616878 -398.530351) (xy 395.660215 -398.575101) (xy 395.697475 -398.625025) (xy 395.728044 -398.679304)
			(xy 395.751422 -398.737047) (xy 395.767223 -398.797305) (xy 395.775189 -398.859088) (xy 395.775688 -398.890236)
			(xy 395.775189 -398.921384) (xy 395.767223 -398.983167) (xy 395.751422 -399.043425) (xy 395.728044 -399.101168)
			(xy 395.697475 -399.155447) (xy 395.660215 -399.205371) (xy 395.616878 -399.250121) (xy 395.568173 -399.288961)
			(xy 395.514902 -399.321254) (xy 395.457939 -399.346471) (xy 395.398218 -399.364195) (xy 395.336721 -399.374138)
			(xy 395.274458 -399.376134) (xy 395.212451 -399.370152) (xy 395.151717 -399.35629) (xy 395.093255 -399.334776)
			(xy 395.038024 -399.305962) (xy 394.986932 -399.270322) (xy 394.940816 -399.228441) (xy 394.900434 -399.181006)
			(xy 394.86645 -399.128797) (xy 394.839421 -399.072671) (xy 394.819792 -399.01355) (xy 394.807883 -398.952403)
			(xy 394.803892 -398.890236) (xy 393.84859 -398.890236) (xy 393.685522 -399.053304) (xy 393.678156 -399.060416)
			(xy 393.670536 -399.079212) (xy 393.670536 -399.089372) (xy 393.670069 -399.124492) (xy 393.661684 -399.194229)
			(xy 393.644947 -399.262445) (xy 393.620103 -399.328143) (xy 393.587515 -399.390365) (xy 393.547659 -399.448201)
			(xy 393.501117 -399.500807) (xy 393.448569 -399.547414) (xy 393.390782 -399.587342) (xy 393.328601 -399.620007)
			(xy 393.262933 -399.644932) (xy 393.194738 -399.661754) (xy 393.125012 -399.670226) (xy 393.089892 -399.670778)
			(xy 393.057864 -399.670351) (xy 392.994199 -399.663294) (xy 392.931698 -399.649267) (xy 392.871123 -399.628442)
			(xy 392.81321 -399.60107) (xy 392.758665 -399.567486) (xy 392.708151 -399.528098) (xy 392.662283 -399.483385)
			(xy 392.641582 -399.458942) (xy 392.640566 -399.457672) (xy 392.63828 -399.455386) (xy 392.630808 -399.448054)
			(xy 392.611652 -399.439665) (xy 392.601196 -399.43913) (xy 391.738612 -399.43913) (xy 391.724896 -399.446242)
			(xy 391.715498 -399.452846) (xy 391.710418 -399.457164) (xy 391.706862 -399.462244) (xy 391.681522 -399.497626)
			(xy 391.625575 -399.564297) (xy 391.564029 -399.625837) (xy 391.497353 -399.681779) (xy 391.426055 -399.731696)
			(xy 391.350678 -399.775208) (xy 391.271794 -399.811985) (xy 391.190006 -399.841747) (xy 391.105934 -399.864266)
			(xy 391.02022 -399.879372) (xy 390.933516 -399.886949) (xy 390.889998 -399.88744) (xy 390.889744 -399.88744)
			(xy 390.846649 -399.886989) (xy 390.76078 -399.879554) (xy 390.675875 -399.864728) (xy 390.592569 -399.842622)
			(xy 390.511484 -399.8134) (xy 390.472168 -399.795746) (xy 390.467596 -399.797016) (xy 390.445349 -399.805363)
			(xy 390.399306 -399.81711) (xy 390.352162 -399.823054) (xy 390.328404 -399.823432) (xy 390.327896 -399.823432)
			(xy 390.300047 -399.822919) (xy 390.244941 -399.814807) (xy 390.191601 -399.798771) (xy 390.141158 -399.775151)
			(xy 390.094684 -399.744449) (xy 390.053167 -399.707318) (xy 390.017489 -399.664546) (xy 389.988408 -399.617042)
			(xy 389.96654 -399.565815) (xy 389.952352 -399.511954) (xy 389.948674 -399.484342) (xy 389.948674 -399.484088)
			(xy 389.947228 -399.474936) (xy 389.938728 -399.458488) (xy 389.924929 -399.446145) (xy 389.907638 -399.439524)
			(xy 389.898382 -399.43913) (xy 389.178546 -399.43913) (xy 389.168101 -399.439697) (xy 389.148965 -399.448096)
			(xy 389.141462 -399.455386) (xy 389.139176 -399.457672) (xy 389.13816 -399.458942) (xy 389.116088 -399.485028)
			(xy 389.066809 -399.532367) (xy 389.012309 -399.57359) (xy 388.953345 -399.608126) (xy 388.890731 -399.635496)
			(xy 388.825337 -399.655321) (xy 388.758066 -399.667327) (xy 388.68985 -399.671348) (xy 388.621634 -399.667327)
			(xy 388.554363 -399.655321) (xy 388.488969 -399.635496) (xy 388.426355 -399.608126) (xy 388.367391 -399.57359)
			(xy 388.312891 -399.532367) (xy 388.263612 -399.485028) (xy 388.24154 -399.458942) (xy 388.240524 -399.457672)
			(xy 388.238238 -399.455386) (xy 388.230769 -399.448045) (xy 388.211614 -399.439634) (xy 388.201154 -399.43913)
			(xy 387.33857 -399.43913) (xy 387.324854 -399.446242) (xy 387.315456 -399.452846) (xy 387.310376 -399.457164)
			(xy 387.30682 -399.462244) (xy 387.281481 -399.497628) (xy 387.225534 -399.564302) (xy 387.163989 -399.625846)
			(xy 387.097315 -399.681791) (xy 387.026017 -399.731712) (xy 386.95064 -399.775229) (xy 386.871757 -399.812011)
			(xy 386.789968 -399.841777) (xy 386.705896 -399.864301) (xy 386.620181 -399.879412) (xy 386.533475 -399.886994)
			(xy 386.489956 -399.88744) (xy 386.489702 -399.88744) (xy 386.446607 -399.886987) (xy 386.36074 -399.879549)
			(xy 386.275836 -399.864719) (xy 386.192531 -399.84261) (xy 386.111448 -399.813385) (xy 386.072126 -399.795746)
			(xy 386.067554 -399.797016) (xy 386.045307 -399.805361) (xy 385.999264 -399.817102) (xy 385.95212 -399.823041)
			(xy 385.928362 -399.823432) (xy 385.927854 -399.823432) (xy 385.900002 -399.822923) (xy 385.844891 -399.814818)
			(xy 385.791543 -399.798787) (xy 385.741093 -399.775171) (xy 385.694612 -399.744471) (xy 385.653088 -399.70734)
			(xy 385.617403 -399.664566) (xy 385.588316 -399.617059) (xy 385.566445 -399.565829) (xy 385.552254 -399.511963)
			(xy 385.548632 -399.484342) (xy 385.548632 -399.484088) (xy 385.547187 -399.474931) (xy 385.53869 -399.458473)
			(xy 385.524892 -399.446115) (xy 385.5076 -399.439477) (xy 385.49834 -399.43913) (xy 384.778758 -399.43913)
			(xy 384.768312 -399.439695) (xy 384.749173 -399.44809) (xy 384.741674 -399.455386) (xy 384.739388 -399.457672)
			(xy 384.738372 -399.458942) (xy 384.7163 -399.485028) (xy 384.667021 -399.532367) (xy 384.612521 -399.57359)
			(xy 384.553557 -399.608126) (xy 384.490943 -399.635496) (xy 384.425549 -399.655321) (xy 384.358278 -399.667327)
			(xy 384.290062 -399.671348) (xy 384.221846 -399.667327) (xy 384.154575 -399.655321) (xy 384.089181 -399.635496)
			(xy 384.026567 -399.608126) (xy 383.967603 -399.57359) (xy 383.913103 -399.532367) (xy 383.863824 -399.485028)
			(xy 383.841752 -399.458942) (xy 383.840736 -399.457672) (xy 383.83845 -399.455386) (xy 383.830982 -399.448043)
			(xy 383.811826 -399.439628) (xy 383.801366 -399.43913) (xy 382.938528 -399.43913) (xy 382.924812 -399.446242)
			(xy 382.915414 -399.452846) (xy 382.910334 -399.457164) (xy 382.906778 -399.462244) (xy 382.881439 -399.497627)
			(xy 382.825491 -399.564298) (xy 382.763945 -399.625839) (xy 382.69727 -399.681782) (xy 382.625972 -399.7317)
			(xy 382.550595 -399.775214) (xy 382.471712 -399.811992) (xy 382.389923 -399.841755) (xy 382.305851 -399.864276)
			(xy 382.220137 -399.879383) (xy 382.133432 -399.886962) (xy 382.089914 -399.88744) (xy 382.08966 -399.88744)
			(xy 382.046565 -399.886989) (xy 381.960696 -399.879556) (xy 381.87579 -399.864731) (xy 381.792483 -399.842626)
			(xy 381.711397 -399.813406) (xy 381.672084 -399.795746) (xy 381.667512 -399.797016) (xy 381.645265 -399.805364)
			(xy 381.599223 -399.817112) (xy 381.552078 -399.823059) (xy 381.52832 -399.823432) (xy 381.527812 -399.823432)
			(xy 381.499962 -399.82292) (xy 381.444855 -399.81481) (xy 381.391512 -399.798775) (xy 381.341068 -399.775156)
			(xy 381.294592 -399.744455) (xy 381.253073 -399.707324) (xy 381.217393 -399.664552) (xy 381.18831 -399.617047)
			(xy 381.166442 -399.565819) (xy 381.152253 -399.511956) (xy 381.14859 -399.484342) (xy 381.14859 -399.484088)
			(xy 381.147144 -399.474934) (xy 381.138645 -399.458484) (xy 381.124846 -399.446137) (xy 381.107556 -399.439511)
			(xy 381.098298 -399.43913) (xy 380.378716 -399.43913) (xy 380.368273 -399.439702) (xy 380.349146 -399.448109)
			(xy 380.341632 -399.455386) (xy 380.339346 -399.457672) (xy 380.33833 -399.458942) (xy 380.316258 -399.485028)
			(xy 380.266979 -399.532367) (xy 380.212479 -399.57359) (xy 380.153515 -399.608126) (xy 380.090901 -399.635496)
			(xy 380.025507 -399.655321) (xy 379.958236 -399.667327) (xy 379.89002 -399.671348) (xy 379.821804 -399.667327)
			(xy 379.754533 -399.655321) (xy 379.689139 -399.635496) (xy 379.626525 -399.608126) (xy 379.567561 -399.57359)
			(xy 379.513061 -399.532367) (xy 379.463782 -399.485028) (xy 379.44171 -399.458942) (xy 379.440694 -399.457672)
			(xy 379.438408 -399.455386) (xy 379.430937 -399.448049) (xy 379.411782 -399.43965) (xy 379.401324 -399.43913)
			(xy 378.538486 -399.43913) (xy 378.52477 -399.446242) (xy 378.515372 -399.452846) (xy 378.510292 -399.457164)
			(xy 378.506736 -399.462244) (xy 378.481397 -399.497628) (xy 378.425451 -399.564303) (xy 378.363906 -399.625848)
			(xy 378.297232 -399.681795) (xy 378.225934 -399.731717) (xy 378.150557 -399.775235) (xy 378.071674 -399.812018)
			(xy 377.989885 -399.841785) (xy 377.905813 -399.864311) (xy 377.820097 -399.879423) (xy 377.733391 -399.887007)
			(xy 377.689872 -399.88744) (xy 377.689618 -399.88744) (xy 377.646523 -399.886987) (xy 377.560655 -399.879551)
			(xy 377.475751 -399.864723) (xy 377.392445 -399.842614) (xy 377.311361 -399.813391) (xy 377.272042 -399.795746)
			(xy 377.26747 -399.797016) (xy 377.245223 -399.805362) (xy 377.19918 -399.817105) (xy 377.152036 -399.823046)
			(xy 377.128278 -399.823432) (xy 377.12777 -399.823432) (xy 377.099917 -399.822924) (xy 377.044804 -399.814821)
			(xy 376.991455 -399.798791) (xy 376.941002 -399.775176) (xy 376.89452 -399.744477) (xy 376.852994 -399.707346)
			(xy 376.817307 -399.664572) (xy 376.788219 -399.617064) (xy 376.766346 -399.565832) (xy 376.752154 -399.511965)
			(xy 376.748548 -399.484342) (xy 376.748548 -399.484088) (xy 376.747101 -399.474937) (xy 376.7386 -399.458494)
			(xy 376.7248 -399.446158) (xy 376.707511 -399.439545) (xy 376.698256 -399.43913) (xy 375.978674 -399.43913)
			(xy 375.968226 -399.439692) (xy 375.949083 -399.448083) (xy 375.94159 -399.455386) (xy 375.939304 -399.457672)
			(xy 375.938288 -399.458942) (xy 375.917617 -399.483408) (xy 375.871733 -399.528101) (xy 375.821208 -399.567472)
			(xy 375.766657 -399.601042) (xy 375.708742 -399.628403) (xy 375.648166 -399.649222) (xy 375.585667 -399.663247)
			(xy 375.522004 -399.670306) (xy 375.489978 -399.670778) (xy 375.454888 -399.670247) (xy 375.385219 -399.661785)
			(xy 375.317078 -399.644989) (xy 375.251458 -399.620101) (xy 375.189317 -399.587486) (xy 375.131559 -399.547619)
			(xy 375.079028 -399.501081) (xy 375.032489 -399.44855) (xy 374.99262 -399.390794) (xy 374.960004 -399.328653)
			(xy 374.935115 -399.263034) (xy 374.918317 -399.194893) (xy 374.909854 -399.125224) (xy 374.909334 -399.090134)
			(xy 374.909863 -399.055567) (xy 374.918143 -398.98693) (xy 374.925844 -398.953228) (xy 374.927537 -398.944684)
			(xy 374.925731 -398.927371) (xy 374.918265 -398.911646) (xy 374.912382 -398.905222) (xy 374.269508 -398.262348)
			(xy 374.262669 -398.254947) (xy 374.254952 -398.236349) (xy 374.254522 -398.22628) (xy 374.254522 -367.75771)
			(xy 374.254232 -367.749836) (xy 374.249452 -367.73483) (xy 374.245124 -367.728246) (xy 374.000014 -367.381536)
			(xy 373.971793 -367.340548) (xy 373.92271 -367.253975) (xy 373.882481 -367.162949) (xy 373.86641 -367.115852)
			(xy 373.864886 -367.111026) (xy 373.837454 -367.062258) (xy 373.832628 -367.065052) (xy 373.78513 -366.99952)
			(xy 373.780304 -366.995456) (xy 373.748499 -366.967966) (xy 373.68913 -366.908437) (xy 373.63499 -366.844117)
			(xy 373.610378 -366.810036) (xy 373.298974 -366.3696) (xy 373.276628 -366.337391) (xy 373.236465 -366.27006)
			(xy 373.201708 -366.199787) (xy 373.172571 -366.127003) (xy 373.160544 -366.089692) (xy 373.158258 -366.081818)
			(xy 373.138954 -366.055148) (xy 373.132096 -366.050322) (xy 373.097797 -366.025478) (xy 373.033078 -365.970841)
			(xy 372.973221 -365.910918) (xy 372.918655 -365.846139) (xy 372.893844 -365.811816) (xy 372.593108 -365.386366)
			(xy 372.568828 -365.351282) (xy 372.525672 -365.277672) (xy 372.488977 -365.200638) (xy 372.45901 -365.120746)
			(xy 372.447058 -365.079788) (xy 372.445026 -365.07166) (xy 372.42623 -365.044228) (xy 372.419626 -365.039402)
			(xy 372.379115 -365.007939) (xy 372.304085 -364.93799) (xy 372.236632 -364.860709) (xy 372.20652 -364.819184)
			(xy 371.892068 -364.37443) (xy 371.868428 -364.340259) (xy 371.826263 -364.268653) (xy 371.790206 -364.193785)
			(xy 371.760508 -364.116175) (xy 371.737374 -364.036362) (xy 371.728746 -363.995716) (xy 371.726714 -363.985048)
			(xy 371.081046 -363.071156) (xy 371.075458 -363.064552) (xy 364.715552 -356.704646) (xy 364.708708 -356.697247)
			(xy 364.700985 -356.678648) (xy 364.700566 -356.668578) (xy 364.700566 -341.395304) (xy 364.692946 -341.376508)
			(xy 364.68558 -341.369396) (xy 363.993938 -340.677754) (xy 363.987095 -340.670355) (xy 363.979371 -340.651756)
			(xy 363.978952 -340.641686) (xy 363.978952 -339.6742) (xy 363.971332 -339.655404) (xy 363.963966 -339.648292)
			(xy 363.383322 -339.067648) (xy 363.375922 -339.060808) (xy 363.357323 -339.053095) (xy 363.347254 -339.052662)
			(xy 353.970336 -339.052662) (xy 353.960338 -339.053015) (xy 353.94182 -339.060547) (xy 353.927598 -339.074595)
			(xy 353.923346 -339.08365) (xy 353.923346 -339.083904) (xy 353.919795 -339.093349) (xy 353.919686 -339.11351)
			(xy 353.927403 -339.132136) (xy 353.934268 -339.13953) (xy 357.822246 -343.027254) (xy 357.840356 -343.046036)
			(xy 357.871035 -343.088235) (xy 357.89473 -343.134716) (xy 357.910856 -343.184333) (xy 357.919016 -343.235864)
			(xy 357.919528 -343.26195) (xy 357.919528 -359.3084) (xy 363.411514 -359.3084) (xy 363.415585 -359.252778)
			(xy 363.427711 -359.198341) (xy 363.447634 -359.14625) (xy 363.47493 -359.097615) (xy 363.509016 -359.053472)
			(xy 363.549165 -359.014763) (xy 363.594523 -358.982312) (xy 363.644123 -358.956811) (xy 363.696907 -358.938804)
			(xy 363.75175 -358.928674) (xy 363.807484 -358.926637) (xy 363.862921 -358.932737) (xy 363.916878 -358.946843)
			(xy 363.968207 -358.968655) (xy 364.015813 -358.997709) (xy 364.058681 -359.033384) (xy 364.095898 -359.074921)
			(xy 364.126671 -359.121434) (xy 364.150343 -359.171931) (xy 364.166411 -359.225338) (xy 364.174531 -359.280514)
			(xy 364.17504 -359.3084) (xy 365.189514 -359.3084) (xy 365.193585 -359.252778) (xy 365.205711 -359.198341)
			(xy 365.225634 -359.14625) (xy 365.25293 -359.097615) (xy 365.287016 -359.053472) (xy 365.327165 -359.014763)
			(xy 365.372523 -358.982312) (xy 365.422123 -358.956811) (xy 365.474907 -358.938804) (xy 365.52975 -358.928674)
			(xy 365.585484 -358.926637) (xy 365.640921 -358.932737) (xy 365.694878 -358.946843) (xy 365.746207 -358.968655)
			(xy 365.793813 -358.997709) (xy 365.836681 -359.033384) (xy 365.873898 -359.074921) (xy 365.904671 -359.121434)
			(xy 365.928343 -359.171931) (xy 365.944411 -359.225338) (xy 365.952531 -359.280514) (xy 365.95304 -359.3084)
			(xy 365.952531 -359.336286) (xy 365.944411 -359.391462) (xy 365.928343 -359.444869) (xy 365.904671 -359.495366)
			(xy 365.873898 -359.541879) (xy 365.836681 -359.583416) (xy 365.793813 -359.619091) (xy 365.746207 -359.648145)
			(xy 365.694878 -359.669957) (xy 365.640921 -359.684063) (xy 365.585484 -359.690163) (xy 365.52975 -359.688126)
			(xy 365.474907 -359.677996) (xy 365.422123 -359.659989) (xy 365.372523 -359.634488) (xy 365.327165 -359.602037)
			(xy 365.287016 -359.563328) (xy 365.25293 -359.519185) (xy 365.225634 -359.47055) (xy 365.205711 -359.418459)
			(xy 365.193585 -359.364022) (xy 365.189514 -359.3084) (xy 364.17504 -359.3084) (xy 364.174531 -359.336286)
			(xy 364.166411 -359.391462) (xy 364.150343 -359.444869) (xy 364.126671 -359.495366) (xy 364.095898 -359.541879)
			(xy 364.058681 -359.583416) (xy 364.015813 -359.619091) (xy 363.968207 -359.648145) (xy 363.916878 -359.669957)
			(xy 363.862921 -359.684063) (xy 363.807484 -359.690163) (xy 363.75175 -359.688126) (xy 363.696907 -359.677996)
			(xy 363.644123 -359.659989) (xy 363.594523 -359.634488) (xy 363.549165 -359.602037) (xy 363.509016 -359.563328)
			(xy 363.47493 -359.519185) (xy 363.447634 -359.47055) (xy 363.427711 -359.418459) (xy 363.415585 -359.364022)
			(xy 363.411514 -359.3084) (xy 357.919528 -359.3084) (xy 357.919528 -362.256578) (xy 357.922322 -362.26877)
			(xy 357.92537 -362.274612) (xy 357.939099 -362.302085) (xy 357.958565 -362.360331) (xy 357.968446 -362.420944)
			(xy 357.969058 -362.45165) (xy 357.968572 -362.478901) (xy 357.960816 -362.532849) (xy 357.945461 -362.585144)
			(xy 357.922819 -362.634721) (xy 357.893353 -362.680571) (xy 357.857662 -362.721762) (xy 357.816471 -362.757453)
			(xy 357.770621 -362.786919) (xy 357.721044 -362.809561) (xy 357.668749 -362.824916) (xy 357.614801 -362.832672)
			(xy 357.560299 -362.832672) (xy 357.506351 -362.824916) (xy 357.454056 -362.809561) (xy 357.404479 -362.786919)
			(xy 357.358629 -362.757453) (xy 357.317438 -362.721762) (xy 357.281747 -362.680571) (xy 357.252281 -362.634721)
			(xy 357.229639 -362.585144) (xy 357.214284 -362.532849) (xy 357.206528 -362.478901) (xy 357.206042 -362.45165)
			(xy 357.206676 -362.420945) (xy 357.216549 -362.360333) (xy 357.236001 -362.302084) (xy 357.24973 -362.274612)
			(xy 357.252778 -362.26877) (xy 357.255572 -362.256578) (xy 357.255572 -343.420446) (xy 357.255138 -343.410381)
			(xy 357.247407 -343.391793) (xy 357.240586 -343.384378) (xy 352.923856 -339.067648) (xy 352.916744 -339.060282)
			(xy 352.897948 -339.052662) (xy 351.66554 -339.052662) (xy 351.646744 -339.060282) (xy 351.639632 -339.067648)
			(xy 351.076514 -339.630766) (xy 351.069677 -339.638168) (xy 351.061964 -339.656766) (xy 351.061528 -339.666834)
			(xy 351.061528 -368.41684) (xy 351.062046 -368.428286) (xy 351.071954 -368.448922) (xy 351.080578 -368.456464)
			(xy 351.15119 -368.513106) (xy 351.173542 -368.51844) (xy 351.184972 -368.5159) (xy 351.210743 -368.510579)
			(xy 351.263054 -368.504851) (xy 351.289366 -368.50447) (xy 351.290128 -368.50447) (xy 351.321923 -368.504992)
			(xy 351.384967 -368.513295) (xy 351.446389 -368.529756) (xy 351.505137 -368.554093) (xy 351.560206 -368.58589)
			(xy 351.610653 -368.624602) (xy 351.655616 -368.669568) (xy 351.694326 -368.720018) (xy 351.726119 -368.775088)
			(xy 351.750453 -368.833837) (xy 351.76691 -368.89526) (xy 351.77521 -368.958305) (xy 351.77521 -369.021895)
			(xy 351.76691 -369.08494) (xy 351.750453 -369.146363) (xy 351.726119 -369.205112) (xy 351.694326 -369.260182)
			(xy 351.655616 -369.310632) (xy 351.610653 -369.355598) (xy 351.560206 -369.39431) (xy 351.505137 -369.426107)
			(xy 351.446389 -369.450444) (xy 351.384967 -369.466905) (xy 351.321923 -369.475208) (xy 351.290128 -369.475766)
			(xy 351.289366 -369.475766) (xy 351.263053 -369.475411) (xy 351.210738 -369.469687) (xy 351.184972 -369.464336)
			(xy 351.173542 -369.461796) (xy 351.15119 -369.46713) (xy 351.080578 -369.523772) (xy 351.072057 -369.5314)
			(xy 351.062148 -369.551978) (xy 351.061528 -369.563396) (xy 351.061528 -371.016784) (xy 351.062159 -371.028202)
			(xy 351.072058 -371.04878) (xy 351.080578 -371.056408) (xy 351.15119 -371.11305) (xy 351.173542 -371.118384)
			(xy 351.184972 -371.115844) (xy 351.210743 -371.110523) (xy 351.263054 -371.104797) (xy 351.289366 -371.104414)
			(xy 351.290128 -371.104414) (xy 351.321926 -371.104936) (xy 351.384978 -371.11324) (xy 351.446407 -371.129703)
			(xy 351.505162 -371.154043) (xy 351.560237 -371.185843) (xy 351.61069 -371.22456) (xy 351.655658 -371.269531)
			(xy 351.694372 -371.319987) (xy 351.726169 -371.375063) (xy 351.750506 -371.433819) (xy 351.766965 -371.495249)
			(xy 351.775266 -371.558302) (xy 351.775266 -371.621898) (xy 351.766965 -371.684951) (xy 351.750506 -371.746381)
			(xy 351.726169 -371.805137) (xy 351.694372 -371.860213) (xy 351.655658 -371.910669) (xy 351.61069 -371.95564)
			(xy 351.560237 -371.994357) (xy 351.505162 -372.026157) (xy 351.446407 -372.050497) (xy 351.384978 -372.06696)
			(xy 351.321926 -372.075264) (xy 351.290128 -372.07571) (xy 351.289366 -372.07571) (xy 351.263053 -372.075355)
			(xy 351.210738 -372.06963) (xy 351.184972 -372.06428) (xy 351.173542 -372.06174) (xy 351.15119 -372.067074)
			(xy 351.080578 -372.123716) (xy 351.072064 -372.131347) (xy 351.062173 -372.151925) (xy 351.061528 -372.16334)
			(xy 351.061528 -372.316756) (xy 351.062153 -372.328177) (xy 351.072045 -372.348764) (xy 351.080578 -372.35638)
			(xy 351.15119 -372.413022) (xy 351.173542 -372.418356) (xy 351.184972 -372.415816) (xy 351.210743 -372.410496)
			(xy 351.263054 -372.404769) (xy 351.289366 -372.404386) (xy 351.290128 -372.404386) (xy 351.321922 -372.404908)
			(xy 351.384964 -372.413211) (xy 351.446384 -372.429671) (xy 351.50513 -372.454008) (xy 351.560197 -372.485803)
			(xy 351.610642 -372.524514) (xy 351.655604 -372.569479) (xy 351.694312 -372.619927) (xy 351.726105 -372.674995)
			(xy 351.750438 -372.733743) (xy 351.766895 -372.795163) (xy 351.775194 -372.858206) (xy 351.775194 -372.921794)
			(xy 351.766895 -372.984837) (xy 351.750438 -373.046257) (xy 351.726105 -373.105005) (xy 351.694312 -373.160073)
			(xy 351.655604 -373.210521) (xy 351.610642 -373.255486) (xy 351.560197 -373.294197) (xy 351.50513 -373.325992)
			(xy 351.446384 -373.350329) (xy 351.384964 -373.366789) (xy 351.321922 -373.375092) (xy 351.290128 -373.375682)
			(xy 351.289366 -373.375682) (xy 351.263053 -373.375327) (xy 351.210738 -373.369603) (xy 351.184972 -373.364252)
			(xy 351.173542 -373.361712) (xy 351.15119 -373.367046) (xy 351.080578 -373.423688) (xy 351.072059 -373.431317)
			(xy 351.062157 -373.451895) (xy 351.061528 -373.463312) (xy 351.061528 -374.916954) (xy 351.062153 -374.928375)
			(xy 351.072044 -374.948963) (xy 351.080578 -374.956578) (xy 351.15119 -375.01322) (xy 351.173542 -375.018554)
			(xy 351.184972 -375.016014) (xy 351.210743 -375.010694) (xy 351.263054 -375.004967) (xy 351.289366 -375.004584)
			(xy 351.290128 -375.004584) (xy 351.321922 -375.005106) (xy 351.384965 -375.013409) (xy 351.446385 -375.029869)
			(xy 351.505131 -375.054206) (xy 351.560198 -375.086002) (xy 351.610644 -375.124713) (xy 351.655606 -375.169677)
			(xy 351.694314 -375.220125) (xy 351.726107 -375.275194) (xy 351.75044 -375.333942) (xy 351.766897 -375.395363)
			(xy 351.775196 -375.458406) (xy 351.775196 -375.521994) (xy 351.766897 -375.585037) (xy 351.75044 -375.646458)
			(xy 351.726107 -375.705206) (xy 351.694314 -375.760275) (xy 351.655606 -375.810723) (xy 351.610644 -375.855687)
			(xy 351.560198 -375.894398) (xy 351.505131 -375.926194) (xy 351.446385 -375.950531) (xy 351.384965 -375.966991)
			(xy 351.321922 -375.975294) (xy 351.290128 -375.97588) (xy 351.289366 -375.97588) (xy 351.263053 -375.975525)
			(xy 351.210738 -375.969801) (xy 351.184972 -375.96445) (xy 351.173542 -375.96191) (xy 351.15119 -375.967244)
			(xy 351.080578 -376.023886) (xy 351.072059 -376.031515) (xy 351.062156 -376.052093) (xy 351.061528 -376.06351)
			(xy 351.061528 -376.216926) (xy 351.062043 -376.228374) (xy 351.071948 -376.249014) (xy 351.080578 -376.25655)
			(xy 351.15119 -376.313192) (xy 351.173542 -376.318526) (xy 351.184972 -376.315986) (xy 351.210743 -376.310665)
			(xy 351.263054 -376.304938) (xy 351.289366 -376.304556) (xy 351.290128 -376.304556) (xy 351.321924 -376.305078)
			(xy 351.38497 -376.313381) (xy 351.446394 -376.329843) (xy 351.505143 -376.354181) (xy 351.560213 -376.385978)
			(xy 351.610662 -376.424692) (xy 351.655627 -376.469659) (xy 351.694337 -376.52011) (xy 351.726132 -376.575182)
			(xy 351.750466 -376.633933) (xy 351.766924 -376.695357) (xy 351.775224 -376.758404) (xy 351.775224 -376.821996)
			(xy 351.766924 -376.885043) (xy 351.750466 -376.946467) (xy 351.726132 -377.005218) (xy 351.694337 -377.06029)
			(xy 351.655627 -377.110741) (xy 351.610662 -377.155708) (xy 351.560213 -377.194422) (xy 351.505143 -377.226219)
			(xy 351.446394 -377.250557) (xy 351.38497 -377.267019) (xy 351.321924 -377.275322) (xy 351.290128 -377.275852)
			(xy 351.289366 -377.275852) (xy 351.263053 -377.275497) (xy 351.210738 -377.269773) (xy 351.184972 -377.264422)
			(xy 351.173542 -377.261882) (xy 351.15119 -377.267216) (xy 351.080578 -377.323858) (xy 351.072054 -377.331485)
			(xy 351.06214 -377.352063) (xy 351.061528 -377.363482) (xy 351.061528 -378.81687) (xy 351.062156 -378.828289)
			(xy 351.072052 -378.848872) (xy 351.080578 -378.856494) (xy 351.15119 -378.913136) (xy 351.173542 -378.91847)
			(xy 351.184972 -378.91593) (xy 351.210743 -378.910609) (xy 351.263054 -378.904883) (xy 351.289366 -378.9045)
			(xy 351.290128 -378.9045) (xy 351.321921 -378.905022) (xy 351.384962 -378.913324) (xy 351.446379 -378.929785)
			(xy 351.505124 -378.95412) (xy 351.560189 -378.985915) (xy 351.610633 -379.024625) (xy 351.655594 -379.069588)
			(xy 351.670025 -379.088396) (xy 362.932978 -379.088396) (xy 362.937049 -379.032774) (xy 362.949175 -378.978337)
			(xy 362.969098 -378.926246) (xy 362.996394 -378.877611) (xy 363.03048 -378.833468) (xy 363.070629 -378.794759)
			(xy 363.115987 -378.762308) (xy 363.165587 -378.736807) (xy 363.218371 -378.7188) (xy 363.273214 -378.70867)
			(xy 363.328948 -378.706633) (xy 363.384385 -378.712733) (xy 363.438342 -378.726839) (xy 363.489671 -378.748651)
			(xy 363.537277 -378.777705) (xy 363.580145 -378.81338) (xy 363.617362 -378.854917) (xy 363.648135 -378.90143)
			(xy 363.671807 -378.951927) (xy 363.687875 -379.005334) (xy 363.695995 -379.06051) (xy 363.696504 -379.088396)
			(xy 363.695995 -379.116282) (xy 363.687875 -379.171458) (xy 363.671807 -379.224865) (xy 363.648135 -379.275362)
			(xy 363.617362 -379.321875) (xy 363.580145 -379.363412) (xy 363.537277 -379.399087) (xy 363.489671 -379.428141)
			(xy 363.438342 -379.449953) (xy 363.384385 -379.464059) (xy 363.328948 -379.470159) (xy 363.273214 -379.468122)
			(xy 363.218371 -379.457992) (xy 363.165587 -379.439985) (xy 363.115987 -379.414484) (xy 363.070629 -379.382033)
			(xy 363.03048 -379.343324) (xy 362.996394 -379.299181) (xy 362.969098 -379.250546) (xy 362.949175 -379.198455)
			(xy 362.937049 -379.144018) (xy 362.932978 -379.088396) (xy 351.670025 -379.088396) (xy 351.694301 -379.120034)
			(xy 351.726092 -379.175102) (xy 351.750424 -379.233847) (xy 351.766881 -379.295266) (xy 351.77518 -379.358307)
			(xy 351.77518 -379.421893) (xy 351.766881 -379.484934) (xy 351.750424 -379.546353) (xy 351.726092 -379.605098)
			(xy 351.697096 -379.655324) (xy 360.52074 -379.655324) (xy 360.524811 -379.599702) (xy 360.536937 -379.545265)
			(xy 360.55686 -379.493174) (xy 360.584156 -379.444539) (xy 360.618242 -379.400396) (xy 360.658391 -379.361687)
			(xy 360.703749 -379.329236) (xy 360.753349 -379.303735) (xy 360.806133 -379.285728) (xy 360.860976 -379.275598)
			(xy 360.91671 -379.273561) (xy 360.972147 -379.279661) (xy 361.026104 -379.293767) (xy 361.077433 -379.315579)
			(xy 361.125039 -379.344633) (xy 361.167907 -379.380308) (xy 361.205124 -379.421845) (xy 361.235897 -379.468358)
			(xy 361.259569 -379.518855) (xy 361.275637 -379.572262) (xy 361.283757 -379.627438) (xy 361.284266 -379.655324)
			(xy 361.283757 -379.68321) (xy 361.275637 -379.738386) (xy 361.259569 -379.791793) (xy 361.235897 -379.84229)
			(xy 361.205124 -379.888803) (xy 361.167907 -379.93034) (xy 361.125039 -379.966015) (xy 361.077433 -379.995069)
			(xy 361.026104 -380.016881) (xy 360.972147 -380.030987) (xy 360.91671 -380.037087) (xy 360.860976 -380.03505)
			(xy 360.806133 -380.02492) (xy 360.753349 -380.006913) (xy 360.703749 -379.981412) (xy 360.658391 -379.948961)
			(xy 360.618242 -379.910252) (xy 360.584156 -379.866109) (xy 360.55686 -379.817474) (xy 360.536937 -379.765383)
			(xy 360.524811 -379.710946) (xy 360.52074 -379.655324) (xy 351.697096 -379.655324) (xy 351.694301 -379.660166)
			(xy 351.655594 -379.710612) (xy 351.610633 -379.755575) (xy 351.560189 -379.794285) (xy 351.505124 -379.82608)
			(xy 351.446379 -379.850415) (xy 351.384962 -379.866876) (xy 351.321921 -379.875178) (xy 351.290128 -379.875796)
			(xy 351.289366 -379.875796) (xy 351.263053 -379.875441) (xy 351.210738 -379.869716) (xy 351.184972 -379.864366)
			(xy 351.173542 -379.861826) (xy 351.15119 -379.86716) (xy 351.080578 -379.923802) (xy 351.072062 -379.931432)
			(xy 351.062165 -379.95201) (xy 351.061528 -379.963426) (xy 351.061528 -380.116842) (xy 351.062046 -380.128288)
			(xy 351.071955 -380.148923) (xy 351.080578 -380.156466) (xy 351.15119 -380.213108) (xy 351.173542 -380.218442)
			(xy 351.184972 -380.215902) (xy 351.210743 -380.210581) (xy 351.263054 -380.204853) (xy 351.289366 -380.204472)
			(xy 351.290128 -380.204472) (xy 351.321922 -380.204994) (xy 351.384967 -380.213297) (xy 351.446388 -380.229758)
			(xy 351.505136 -380.254095) (xy 351.560204 -380.285892) (xy 351.610652 -380.324604) (xy 351.655615 -380.369569)
			(xy 351.694324 -380.420019) (xy 351.726117 -380.475089) (xy 351.750451 -380.533838) (xy 351.766908 -380.59526)
			(xy 351.775208 -380.658306) (xy 351.775208 -380.721895) (xy 351.766908 -380.78494) (xy 351.750451 -380.846362)
			(xy 351.726117 -380.905111) (xy 351.694324 -380.960181) (xy 351.655615 -381.010631) (xy 351.610652 -381.055596)
			(xy 351.560204 -381.094308) (xy 351.505136 -381.126105) (xy 351.446388 -381.150442) (xy 351.384967 -381.166903)
			(xy 351.321922 -381.175206) (xy 351.290128 -381.175768) (xy 351.289366 -381.175768) (xy 351.263053 -381.175413)
			(xy 351.210738 -381.169689) (xy 351.184972 -381.164338) (xy 351.173542 -381.161798) (xy 351.15119 -381.167132)
			(xy 351.080578 -381.223774) (xy 351.072057 -381.231402) (xy 351.062149 -381.25198) (xy 351.061528 -381.263398)
			(xy 351.061528 -381.714502) (xy 360.796838 -381.714502) (xy 360.800909 -381.65888) (xy 360.813035 -381.604443)
			(xy 360.832958 -381.552352) (xy 360.860254 -381.503717) (xy 360.89434 -381.459574) (xy 360.934489 -381.420865)
			(xy 360.979847 -381.388414) (xy 361.029447 -381.362913) (xy 361.082231 -381.344906) (xy 361.137074 -381.334776)
			(xy 361.192808 -381.332739) (xy 361.248245 -381.338839) (xy 361.302202 -381.352945) (xy 361.353531 -381.374757)
			(xy 361.401137 -381.403811) (xy 361.444005 -381.439486) (xy 361.481222 -381.481023) (xy 361.511995 -381.527536)
			(xy 361.535667 -381.578033) (xy 361.551735 -381.63144) (xy 361.559855 -381.686616) (xy 361.560364 -381.714502)
			(xy 361.559855 -381.742388) (xy 361.551735 -381.797564) (xy 361.535667 -381.850971) (xy 361.511995 -381.901468)
			(xy 361.481222 -381.947981) (xy 361.444005 -381.989518) (xy 361.401137 -382.025193) (xy 361.353531 -382.054247)
			(xy 361.302202 -382.076059) (xy 361.248245 -382.090165) (xy 361.192808 -382.096265) (xy 361.137074 -382.094228)
			(xy 361.082231 -382.084098) (xy 361.029447 -382.066091) (xy 360.979847 -382.04059) (xy 360.934489 -382.008139)
			(xy 360.89434 -381.96943) (xy 360.860254 -381.925287) (xy 360.832958 -381.876652) (xy 360.813035 -381.824561)
			(xy 360.800909 -381.770124) (xy 360.796838 -381.714502) (xy 351.061528 -381.714502) (xy 351.061528 -382.716786)
			(xy 351.062159 -382.728204) (xy 351.072059 -382.748781) (xy 351.080578 -382.75641) (xy 351.15119 -382.813052)
			(xy 351.173542 -382.818386) (xy 351.184972 -382.815846) (xy 351.210743 -382.810525) (xy 351.263054 -382.804798)
			(xy 351.289366 -382.804416) (xy 351.290128 -382.804416) (xy 351.321926 -382.804938) (xy 351.384978 -382.813242)
			(xy 351.446406 -382.829705) (xy 351.505161 -382.854045) (xy 351.560236 -382.885845) (xy 351.610689 -382.924562)
			(xy 351.655657 -382.969532) (xy 351.694371 -383.019988) (xy 351.726168 -383.075064) (xy 351.750504 -383.13382)
			(xy 351.766963 -383.19525) (xy 351.775264 -383.258302) (xy 351.775264 -383.321898) (xy 351.766963 -383.38495)
			(xy 351.750504 -383.44638) (xy 351.726168 -383.505136) (xy 351.694371 -383.560212) (xy 351.655657 -383.610668)
			(xy 351.610689 -383.655638) (xy 351.560236 -383.694355) (xy 351.505161 -383.726155) (xy 351.446406 -383.750495)
			(xy 351.384978 -383.766958) (xy 351.321926 -383.775262) (xy 351.290128 -383.775712) (xy 351.289366 -383.775712)
			(xy 351.263053 -383.775357) (xy 351.210738 -383.769632) (xy 351.184972 -383.764282) (xy 351.173542 -383.761742)
			(xy 351.15119 -383.767076) (xy 351.080578 -383.823718) (xy 351.072064 -383.831349) (xy 351.062174 -383.851927)
			(xy 351.061528 -383.863342) (xy 351.061528 -384.016758) (xy 351.062154 -384.028179) (xy 351.072046 -384.048765)
			(xy 351.080578 -384.056382) (xy 351.15119 -384.113024) (xy 351.173542 -384.118358) (xy 351.184972 -384.115818)
			(xy 351.210743 -384.110498) (xy 351.263054 -384.104771) (xy 351.289366 -384.104388) (xy 351.290128 -384.104388)
			(xy 351.321921 -384.10491) (xy 351.384964 -384.113213) (xy 351.446383 -384.129673) (xy 351.505129 -384.154009)
			(xy 351.560196 -384.185805) (xy 351.610641 -384.224516) (xy 351.655603 -384.26948) (xy 351.694311 -384.319928)
			(xy 351.726103 -384.374996) (xy 351.750436 -384.433743) (xy 351.766893 -384.495164) (xy 351.775192 -384.558207)
			(xy 351.775192 -384.621793) (xy 351.766893 -384.684836) (xy 351.750436 -384.746257) (xy 351.726103 -384.805004)
			(xy 351.694311 -384.860072) (xy 351.655603 -384.91052) (xy 351.610641 -384.955484) (xy 351.560196 -384.994195)
			(xy 351.505129 -385.025991) (xy 351.446383 -385.050327) (xy 351.384964 -385.066787) (xy 351.321921 -385.07509)
			(xy 351.290128 -385.075684) (xy 351.289366 -385.075684) (xy 351.263053 -385.075329) (xy 351.210738 -385.069605)
			(xy 351.184972 -385.064254) (xy 351.173542 -385.061714) (xy 351.15119 -385.067048) (xy 351.080578 -385.12369)
			(xy 351.072059 -385.131319) (xy 351.062158 -385.151897) (xy 351.061528 -385.163314) (xy 351.061528 -386.172456)
			(xy 361.296202 -386.172456) (xy 361.300273 -386.116834) (xy 361.312399 -386.062397) (xy 361.332322 -386.010306)
			(xy 361.359618 -385.961671) (xy 361.393704 -385.917528) (xy 361.433853 -385.878819) (xy 361.479211 -385.846368)
			(xy 361.528811 -385.820867) (xy 361.581595 -385.80286) (xy 361.636438 -385.79273) (xy 361.692172 -385.790693)
			(xy 361.747609 -385.796793) (xy 361.801566 -385.810899) (xy 361.852895 -385.832711) (xy 361.900501 -385.861765)
			(xy 361.943369 -385.89744) (xy 361.980586 -385.938977) (xy 362.011359 -385.98549) (xy 362.035031 -386.035987)
			(xy 362.051099 -386.089394) (xy 362.059219 -386.14457) (xy 362.059728 -386.172456) (xy 362.059219 -386.200342)
			(xy 362.051099 -386.255518) (xy 362.035031 -386.308925) (xy 362.011359 -386.359422) (xy 361.980586 -386.405935)
			(xy 361.943369 -386.447472) (xy 361.900501 -386.483147) (xy 361.852895 -386.512201) (xy 361.801566 -386.534013)
			(xy 361.747609 -386.548119) (xy 361.692172 -386.554219) (xy 361.636438 -386.552182) (xy 361.581595 -386.542052)
			(xy 361.528811 -386.524045) (xy 361.479211 -386.498544) (xy 361.433853 -386.466093) (xy 361.393704 -386.427384)
			(xy 361.359618 -386.383241) (xy 361.332322 -386.334606) (xy 361.312399 -386.282515) (xy 361.300273 -386.228078)
			(xy 361.296202 -386.172456) (xy 351.061528 -386.172456) (xy 351.061528 -387.9723) (xy 362.73308 -387.9723)
			(xy 362.737151 -387.916678) (xy 362.749277 -387.862241) (xy 362.7692 -387.81015) (xy 362.796496 -387.761515)
			(xy 362.830582 -387.717372) (xy 362.870731 -387.678663) (xy 362.916089 -387.646212) (xy 362.965689 -387.620711)
			(xy 363.018473 -387.602704) (xy 363.073316 -387.592574) (xy 363.12905 -387.590537) (xy 363.184487 -387.596637)
			(xy 363.238444 -387.610743) (xy 363.289773 -387.632555) (xy 363.337379 -387.661609) (xy 363.380247 -387.697284)
			(xy 363.417464 -387.738821) (xy 363.448237 -387.785334) (xy 363.471909 -387.835831) (xy 363.487977 -387.889238)
			(xy 363.490893 -387.909054) (xy 366.166144 -387.909054) (xy 366.170215 -387.853432) (xy 366.182341 -387.798995)
			(xy 366.202264 -387.746904) (xy 366.22956 -387.698269) (xy 366.263646 -387.654126) (xy 366.303795 -387.615417)
			(xy 366.349153 -387.582966) (xy 366.398753 -387.557465) (xy 366.451537 -387.539458) (xy 366.50638 -387.529328)
			(xy 366.562114 -387.527291) (xy 366.617551 -387.533391) (xy 366.671508 -387.547497) (xy 366.722837 -387.569309)
			(xy 366.770443 -387.598363) (xy 366.813311 -387.634038) (xy 366.850528 -387.675575) (xy 366.881301 -387.722088)
			(xy 366.904973 -387.772585) (xy 366.921041 -387.825992) (xy 366.929161 -387.881168) (xy 366.92967 -387.909054)
			(xy 366.929161 -387.93694) (xy 366.921041 -387.992116) (xy 366.904973 -388.045523) (xy 366.881301 -388.09602)
			(xy 366.850528 -388.142533) (xy 366.813311 -388.18407) (xy 366.770443 -388.219745) (xy 366.722837 -388.248799)
			(xy 366.671508 -388.270611) (xy 366.617551 -388.284717) (xy 366.562114 -388.290817) (xy 366.50638 -388.28878)
			(xy 366.451537 -388.27865) (xy 366.398753 -388.260643) (xy 366.349153 -388.235142) (xy 366.303795 -388.202691)
			(xy 366.263646 -388.163982) (xy 366.22956 -388.119839) (xy 366.202264 -388.071204) (xy 366.182341 -388.019113)
			(xy 366.170215 -387.964676) (xy 366.166144 -387.909054) (xy 363.490893 -387.909054) (xy 363.496097 -387.944414)
			(xy 363.496606 -387.9723) (xy 363.496097 -388.000186) (xy 363.487977 -388.055362) (xy 363.471909 -388.108769)
			(xy 363.448237 -388.159266) (xy 363.417464 -388.205779) (xy 363.380247 -388.247316) (xy 363.337379 -388.282991)
			(xy 363.289773 -388.312045) (xy 363.238444 -388.333857) (xy 363.184487 -388.347963) (xy 363.12905 -388.354063)
			(xy 363.073316 -388.352026) (xy 363.018473 -388.341896) (xy 362.965689 -388.323889) (xy 362.916089 -388.298388)
			(xy 362.870731 -388.265937) (xy 362.830582 -388.227228) (xy 362.796496 -388.183085) (xy 362.7692 -388.13445)
			(xy 362.749277 -388.082359) (xy 362.737151 -388.027922) (xy 362.73308 -387.9723) (xy 351.061528 -387.9723)
			(xy 351.061528 -388.842504) (xy 366.936272 -388.842504) (xy 366.940343 -388.786882) (xy 366.952469 -388.732445)
			(xy 366.972392 -388.680354) (xy 366.999688 -388.631719) (xy 367.033774 -388.587576) (xy 367.073923 -388.548867)
			(xy 367.119281 -388.516416) (xy 367.168881 -388.490915) (xy 367.221665 -388.472908) (xy 367.276508 -388.462778)
			(xy 367.332242 -388.460741) (xy 367.387679 -388.466841) (xy 367.441636 -388.480947) (xy 367.492965 -388.502759)
			(xy 367.540571 -388.531813) (xy 367.583439 -388.567488) (xy 367.620656 -388.609025) (xy 367.651429 -388.655538)
			(xy 367.675101 -388.706035) (xy 367.691169 -388.759442) (xy 367.699289 -388.814618) (xy 367.699798 -388.842504)
			(xy 367.699289 -388.87039) (xy 367.691169 -388.925566) (xy 367.675101 -388.978973) (xy 367.651429 -389.02947)
			(xy 367.620656 -389.075983) (xy 367.583439 -389.11752) (xy 367.540571 -389.153195) (xy 367.492965 -389.182249)
			(xy 367.441636 -389.204061) (xy 367.387679 -389.218167) (xy 367.332242 -389.224267) (xy 367.276508 -389.22223)
			(xy 367.221665 -389.2121) (xy 367.168881 -389.194093) (xy 367.119281 -389.168592) (xy 367.073923 -389.136141)
			(xy 367.033774 -389.097432) (xy 366.999688 -389.053289) (xy 366.972392 -389.004654) (xy 366.952469 -388.952563)
			(xy 366.940343 -388.898126) (xy 366.936272 -388.842504) (xy 351.061528 -388.842504) (xy 351.061528 -390.28878)
			(xy 357.386126 -390.28878) (xy 357.390197 -390.233158) (xy 357.402323 -390.178721) (xy 357.422246 -390.12663)
			(xy 357.449542 -390.077995) (xy 357.483628 -390.033852) (xy 357.523777 -389.995143) (xy 357.569135 -389.962692)
			(xy 357.618735 -389.937191) (xy 357.671519 -389.919184) (xy 357.726362 -389.909054) (xy 357.782096 -389.907017)
			(xy 357.837533 -389.913117) (xy 357.89149 -389.927223) (xy 357.942819 -389.949035) (xy 357.990425 -389.978089)
			(xy 358.033293 -390.013764) (xy 358.07051 -390.055301) (xy 358.101283 -390.101814) (xy 358.124955 -390.152311)
			(xy 358.141023 -390.205718) (xy 358.149143 -390.260894) (xy 358.149652 -390.28878) (xy 358.149143 -390.316666)
			(xy 358.141023 -390.371842) (xy 358.124955 -390.425249) (xy 358.101283 -390.475746) (xy 358.07051 -390.522259)
			(xy 358.033293 -390.563796) (xy 357.990425 -390.599471) (xy 357.942819 -390.628525) (xy 357.89149 -390.650337)
			(xy 357.837533 -390.664443) (xy 357.782096 -390.670543) (xy 357.726362 -390.668506) (xy 357.671519 -390.658376)
			(xy 357.618735 -390.640369) (xy 357.569135 -390.614868) (xy 357.523777 -390.582417) (xy 357.483628 -390.543708)
			(xy 357.449542 -390.499565) (xy 357.422246 -390.45093) (xy 357.402323 -390.398839) (xy 357.390197 -390.344402)
			(xy 357.386126 -390.28878) (xy 351.061528 -390.28878) (xy 351.061528 -391.26541) (xy 365.668812 -391.26541)
			(xy 365.672883 -391.209788) (xy 365.685009 -391.155351) (xy 365.704932 -391.10326) (xy 365.732228 -391.054625)
			(xy 365.766314 -391.010482) (xy 365.806463 -390.971773) (xy 365.851821 -390.939322) (xy 365.901421 -390.913821)
			(xy 365.954205 -390.895814) (xy 366.009048 -390.885684) (xy 366.064782 -390.883647) (xy 366.120219 -390.889747)
			(xy 366.174176 -390.903853) (xy 366.225505 -390.925665) (xy 366.273111 -390.954719) (xy 366.315979 -390.990394)
			(xy 366.353196 -391.031931) (xy 366.383969 -391.078444) (xy 366.407641 -391.128941) (xy 366.423709 -391.182348)
			(xy 366.431829 -391.237524) (xy 366.432338 -391.26541) (xy 366.431829 -391.293296) (xy 366.423709 -391.348472)
			(xy 366.407641 -391.401879) (xy 366.383969 -391.452376) (xy 366.353196 -391.498889) (xy 366.315979 -391.540426)
			(xy 366.273111 -391.576101) (xy 366.225505 -391.605155) (xy 366.174176 -391.626967) (xy 366.120219 -391.641073)
			(xy 366.064782 -391.647173) (xy 366.009048 -391.645136) (xy 365.954205 -391.635006) (xy 365.901421 -391.616999)
			(xy 365.851821 -391.591498) (xy 365.806463 -391.559047) (xy 365.766314 -391.520338) (xy 365.732228 -391.476195)
			(xy 365.704932 -391.42756) (xy 365.685009 -391.375469) (xy 365.672883 -391.321032) (xy 365.668812 -391.26541)
			(xy 351.061528 -391.26541) (xy 351.061528 -392.684254) (xy 363.702852 -392.684254) (xy 363.706923 -392.628632)
			(xy 363.719049 -392.574195) (xy 363.738972 -392.522104) (xy 363.766268 -392.473469) (xy 363.800354 -392.429326)
			(xy 363.840503 -392.390617) (xy 363.885861 -392.358166) (xy 363.935461 -392.332665) (xy 363.988245 -392.314658)
			(xy 364.043088 -392.304528) (xy 364.098822 -392.302491) (xy 364.154259 -392.308591) (xy 364.208216 -392.322697)
			(xy 364.259545 -392.344509) (xy 364.307151 -392.373563) (xy 364.350019 -392.409238) (xy 364.387236 -392.450775)
			(xy 364.418009 -392.497288) (xy 364.441681 -392.547785) (xy 364.457749 -392.601192) (xy 364.465869 -392.656368)
			(xy 364.466378 -392.684254) (xy 364.465869 -392.71214) (xy 364.457749 -392.767316) (xy 364.441681 -392.820723)
			(xy 364.418009 -392.87122) (xy 364.387236 -392.917733) (xy 364.350019 -392.95927) (xy 364.307151 -392.994945)
			(xy 364.259545 -393.023999) (xy 364.208216 -393.045811) (xy 364.154259 -393.059917) (xy 364.098822 -393.066017)
			(xy 364.043088 -393.06398) (xy 363.988245 -393.05385) (xy 363.935461 -393.035843) (xy 363.885861 -393.010342)
			(xy 363.840503 -392.977891) (xy 363.800354 -392.939182) (xy 363.766268 -392.895039) (xy 363.738972 -392.846404)
			(xy 363.719049 -392.794313) (xy 363.706923 -392.739876) (xy 363.702852 -392.684254) (xy 351.061528 -392.684254)
			(xy 351.061528 -393.459716) (xy 357.18572 -393.459716) (xy 357.189791 -393.404094) (xy 357.201917 -393.349657)
			(xy 357.22184 -393.297566) (xy 357.249136 -393.248931) (xy 357.283222 -393.204788) (xy 357.323371 -393.166079)
			(xy 357.368729 -393.133628) (xy 357.418329 -393.108127) (xy 357.471113 -393.09012) (xy 357.525956 -393.07999)
			(xy 357.58169 -393.077953) (xy 357.637127 -393.084053) (xy 357.691084 -393.098159) (xy 357.742413 -393.119971)
			(xy 357.790019 -393.149025) (xy 357.832887 -393.1847) (xy 357.870104 -393.226237) (xy 357.900877 -393.27275)
			(xy 357.924549 -393.323247) (xy 357.940617 -393.376654) (xy 357.948737 -393.43183) (xy 357.949246 -393.459716)
			(xy 357.948737 -393.487602) (xy 357.940617 -393.542778) (xy 357.924549 -393.596185) (xy 357.900877 -393.646682)
			(xy 357.870104 -393.693195) (xy 357.832887 -393.734732) (xy 357.790019 -393.770407) (xy 357.742413 -393.799461)
			(xy 357.691084 -393.821273) (xy 357.637127 -393.835379) (xy 357.58169 -393.841479) (xy 357.525956 -393.839442)
			(xy 357.471113 -393.829312) (xy 357.418329 -393.811305) (xy 357.368729 -393.785804) (xy 357.323371 -393.753353)
			(xy 357.283222 -393.714644) (xy 357.249136 -393.670501) (xy 357.22184 -393.621866) (xy 357.201917 -393.569775)
			(xy 357.189791 -393.515338) (xy 357.18572 -393.459716) (xy 351.061528 -393.459716) (xy 351.061528 -396.063724)
			(xy 357.261158 -396.063724) (xy 357.265229 -396.008102) (xy 357.277355 -395.953665) (xy 357.297278 -395.901574)
			(xy 357.324574 -395.852939) (xy 357.35866 -395.808796) (xy 357.398809 -395.770087) (xy 357.444167 -395.737636)
			(xy 357.493767 -395.712135) (xy 357.546551 -395.694128) (xy 357.601394 -395.683998) (xy 357.657128 -395.681961)
			(xy 357.712565 -395.688061) (xy 357.766522 -395.702167) (xy 357.817851 -395.723979) (xy 357.865457 -395.753033)
			(xy 357.908325 -395.788708) (xy 357.945542 -395.830245) (xy 357.976315 -395.876758) (xy 357.999987 -395.927255)
			(xy 358.016055 -395.980662) (xy 358.024175 -396.035838) (xy 358.024684 -396.063724) (xy 358.024175 -396.09161)
			(xy 358.016055 -396.146786) (xy 357.999987 -396.200193) (xy 357.976315 -396.25069) (xy 357.945542 -396.297203)
			(xy 357.908325 -396.33874) (xy 357.865457 -396.374415) (xy 357.817851 -396.403469) (xy 357.766522 -396.425281)
			(xy 357.712565 -396.439387) (xy 357.657128 -396.445487) (xy 357.601394 -396.44345) (xy 357.546551 -396.43332)
			(xy 357.493767 -396.415313) (xy 357.444167 -396.389812) (xy 357.398809 -396.357361) (xy 357.35866 -396.318652)
			(xy 357.324574 -396.274509) (xy 357.297278 -396.225874) (xy 357.277355 -396.173783) (xy 357.265229 -396.119346)
			(xy 357.261158 -396.063724) (xy 351.061528 -396.063724) (xy 351.061528 -397.016732) (xy 351.061929 -397.025622)
			(xy 365.416844 -397.025622) (xy 365.420915 -396.97) (xy 365.433041 -396.915563) (xy 365.452964 -396.863472)
			(xy 365.48026 -396.814837) (xy 365.514346 -396.770694) (xy 365.554495 -396.731985) (xy 365.599853 -396.699534)
			(xy 365.649453 -396.674033) (xy 365.702237 -396.656026) (xy 365.75708 -396.645896) (xy 365.812814 -396.643859)
			(xy 365.868251 -396.649959) (xy 365.922208 -396.664065) (xy 365.973537 -396.685877) (xy 366.021143 -396.714931)
			(xy 366.064011 -396.750606) (xy 366.101048 -396.791942) (xy 366.335308 -396.791942) (xy 366.339379 -396.73632)
			(xy 366.351505 -396.681883) (xy 366.371428 -396.629792) (xy 366.398724 -396.581157) (xy 366.43281 -396.537014)
			(xy 366.472959 -396.498305) (xy 366.518317 -396.465854) (xy 366.567917 -396.440353) (xy 366.620701 -396.422346)
			(xy 366.675544 -396.412216) (xy 366.731278 -396.410179) (xy 366.786715 -396.416279) (xy 366.840672 -396.430385)
			(xy 366.892001 -396.452197) (xy 366.939607 -396.481251) (xy 366.982475 -396.516926) (xy 367.019692 -396.558463)
			(xy 367.050465 -396.604976) (xy 367.074137 -396.655473) (xy 367.090205 -396.70888) (xy 367.098325 -396.764056)
			(xy 367.098834 -396.791942) (xy 367.098325 -396.819828) (xy 367.090205 -396.875004) (xy 367.074137 -396.928411)
			(xy 367.050465 -396.978908) (xy 367.019692 -397.025421) (xy 366.982475 -397.066958) (xy 366.939607 -397.102633)
			(xy 366.892001 -397.131687) (xy 366.840672 -397.153499) (xy 366.786715 -397.167605) (xy 366.731278 -397.173705)
			(xy 366.675544 -397.171668) (xy 366.620701 -397.161538) (xy 366.567917 -397.143531) (xy 366.518317 -397.11803)
			(xy 366.472959 -397.085579) (xy 366.43281 -397.04687) (xy 366.398724 -397.002727) (xy 366.371428 -396.954092)
			(xy 366.351505 -396.902001) (xy 366.339379 -396.847564) (xy 366.335308 -396.791942) (xy 366.101048 -396.791942)
			(xy 366.101228 -396.792143) (xy 366.132001 -396.838656) (xy 366.155673 -396.889153) (xy 366.171741 -396.94256)
			(xy 366.179861 -396.997736) (xy 366.18037 -397.025622) (xy 366.179861 -397.053508) (xy 366.171741 -397.108684)
			(xy 366.155673 -397.162091) (xy 366.132001 -397.212588) (xy 366.101228 -397.259101) (xy 366.064011 -397.300638)
			(xy 366.021143 -397.336313) (xy 365.973537 -397.365367) (xy 365.922208 -397.387179) (xy 365.868251 -397.401285)
			(xy 365.812814 -397.407385) (xy 365.75708 -397.405348) (xy 365.702237 -397.395218) (xy 365.649453 -397.377211)
			(xy 365.599853 -397.35171) (xy 365.554495 -397.319259) (xy 365.514346 -397.28055) (xy 365.48026 -397.236407)
			(xy 365.452964 -397.187772) (xy 365.433041 -397.135681) (xy 365.420915 -397.081244) (xy 365.416844 -397.025622)
			(xy 351.061929 -397.025622) (xy 351.062044 -397.028179) (xy 351.071951 -397.048817) (xy 351.080578 -397.056356)
			(xy 351.15119 -397.112998) (xy 351.173542 -397.118332) (xy 351.184972 -397.115792) (xy 351.210743 -397.110471)
			(xy 351.263054 -397.104743) (xy 351.289366 -397.104362) (xy 351.290128 -397.104362) (xy 351.321923 -397.104884)
			(xy 351.384969 -397.113187) (xy 351.446392 -397.129649) (xy 351.50514 -397.153986) (xy 351.56021 -397.185783)
			(xy 351.610658 -397.224496) (xy 351.655622 -397.269463) (xy 351.694332 -397.319913) (xy 351.726126 -397.374985)
			(xy 351.75046 -397.433735) (xy 351.766918 -397.495159) (xy 351.775218 -397.558205) (xy 351.775218 -397.621795)
			(xy 351.766918 -397.684841) (xy 351.75046 -397.746265) (xy 351.726126 -397.805015) (xy 351.694332 -397.860087)
			(xy 351.655622 -397.910537) (xy 351.610658 -397.955504) (xy 351.56021 -397.994217) (xy 351.50514 -398.026014)
			(xy 351.446392 -398.050351) (xy 351.384969 -398.066813) (xy 351.321923 -398.075116) (xy 351.290128 -398.075658)
			(xy 351.289366 -398.075658) (xy 351.263053 -398.075303) (xy 351.210738 -398.069579) (xy 351.184972 -398.064228)
			(xy 351.173542 -398.061688) (xy 351.15119 -398.067022) (xy 351.080578 -398.123664) (xy 351.072055 -398.131291)
			(xy 351.062144 -398.151869) (xy 351.061528 -398.163288) (xy 351.061528 -398.316958) (xy 351.062154 -398.328379)
			(xy 351.072046 -398.348965) (xy 351.080578 -398.356582) (xy 351.15119 -398.413224) (xy 351.173542 -398.418558)
			(xy 351.184972 -398.416018) (xy 351.210743 -398.410698) (xy 351.263054 -398.404971) (xy 351.289366 -398.404588)
			(xy 351.290128 -398.404588) (xy 351.321921 -398.40511) (xy 351.384964 -398.413413) (xy 351.446383 -398.429873)
			(xy 351.48161 -398.444466) (xy 363.577884 -398.444466) (xy 363.581955 -398.388844) (xy 363.594081 -398.334407)
			(xy 363.614004 -398.282316) (xy 363.6413 -398.233681) (xy 363.675386 -398.189538) (xy 363.715535 -398.150829)
			(xy 363.760893 -398.118378) (xy 363.810493 -398.092877) (xy 363.863277 -398.07487) (xy 363.91812 -398.06474)
			(xy 363.973854 -398.062703) (xy 364.029291 -398.068803) (xy 364.083248 -398.082909) (xy 364.134577 -398.104721)
			(xy 364.182183 -398.133775) (xy 364.225051 -398.16945) (xy 364.262268 -398.210987) (xy 364.293041 -398.2575)
			(xy 364.316713 -398.307997) (xy 364.332781 -398.361404) (xy 364.340901 -398.41658) (xy 364.34141 -398.444466)
			(xy 364.340901 -398.472352) (xy 364.332781 -398.527528) (xy 364.316713 -398.580935) (xy 364.293041 -398.631432)
			(xy 364.262268 -398.677945) (xy 364.225051 -398.719482) (xy 364.182183 -398.755157) (xy 364.134577 -398.784211)
			(xy 364.083248 -398.806023) (xy 364.029291 -398.820129) (xy 363.973854 -398.826229) (xy 363.91812 -398.824192)
			(xy 363.863277 -398.814062) (xy 363.810493 -398.796055) (xy 363.760893 -398.770554) (xy 363.715535 -398.738103)
			(xy 363.675386 -398.699394) (xy 363.6413 -398.655251) (xy 363.614004 -398.606616) (xy 363.594081 -398.554525)
			(xy 363.581955 -398.500088) (xy 363.577884 -398.444466) (xy 351.48161 -398.444466) (xy 351.505129 -398.454209)
			(xy 351.560196 -398.486005) (xy 351.610641 -398.524716) (xy 351.655603 -398.56968) (xy 351.694311 -398.620128)
			(xy 351.726103 -398.675196) (xy 351.750436 -398.733943) (xy 351.766893 -398.795364) (xy 351.775192 -398.858407)
			(xy 351.775192 -398.921993) (xy 351.766893 -398.985036) (xy 351.750436 -399.046457) (xy 351.726103 -399.105204)
			(xy 351.694311 -399.160272) (xy 351.655603 -399.21072) (xy 351.646395 -399.219928) (xy 357.060752 -399.219928)
			(xy 357.064823 -399.164306) (xy 357.076949 -399.109869) (xy 357.096872 -399.057778) (xy 357.124168 -399.009143)
			(xy 357.158254 -398.965) (xy 357.198403 -398.926291) (xy 357.243761 -398.89384) (xy 357.293361 -398.868339)
			(xy 357.346145 -398.850332) (xy 357.400988 -398.840202) (xy 357.456722 -398.838165) (xy 357.512159 -398.844265)
			(xy 357.566116 -398.858371) (xy 357.617445 -398.880183) (xy 357.665051 -398.909237) (xy 357.707919 -398.944912)
			(xy 357.745136 -398.986449) (xy 357.775909 -399.032962) (xy 357.799581 -399.083459) (xy 357.815649 -399.136866)
			(xy 357.823769 -399.192042) (xy 357.824278 -399.219928) (xy 357.823769 -399.247814) (xy 357.815649 -399.30299)
			(xy 357.799581 -399.356397) (xy 357.775909 -399.406894) (xy 357.745136 -399.453407) (xy 357.707919 -399.494944)
			(xy 357.665051 -399.530619) (xy 357.617445 -399.559673) (xy 357.566116 -399.581485) (xy 357.512159 -399.595591)
			(xy 357.456722 -399.601691) (xy 357.400988 -399.599654) (xy 357.346145 -399.589524) (xy 357.293361 -399.571517)
			(xy 357.243761 -399.546016) (xy 357.198403 -399.513565) (xy 357.158254 -399.474856) (xy 357.124168 -399.430713)
			(xy 357.096872 -399.382078) (xy 357.076949 -399.329987) (xy 357.064823 -399.27555) (xy 357.060752 -399.219928)
			(xy 351.646395 -399.219928) (xy 351.610641 -399.255684) (xy 351.560196 -399.294395) (xy 351.505129 -399.326191)
			(xy 351.446383 -399.350527) (xy 351.384964 -399.366987) (xy 351.321921 -399.37529) (xy 351.290128 -399.375884)
			(xy 351.289366 -399.375884) (xy 351.263053 -399.375529) (xy 351.210738 -399.369805) (xy 351.184972 -399.364454)
			(xy 351.173542 -399.361914) (xy 351.15119 -399.367248) (xy 351.080578 -399.42389) (xy 351.072059 -399.431519)
			(xy 351.062158 -399.452097) (xy 351.061528 -399.463514) (xy 351.061528 -400.060668) (xy 351.061025 -400.07072)
			(xy 351.053306 -400.089284) (xy 351.046542 -400.096736) (xy 349.653098 -401.49018) (xy 350.80398 -401.49018)
			(xy 350.807971 -401.428013) (xy 350.81988 -401.366866) (xy 350.839509 -401.307745) (xy 350.866538 -401.251619)
			(xy 350.900522 -401.19941) (xy 350.940904 -401.151975) (xy 350.98702 -401.110094) (xy 351.038112 -401.074454)
			(xy 351.093343 -401.04564) (xy 351.151805 -401.024126) (xy 351.212539 -401.010264) (xy 351.274546 -401.004282)
			(xy 351.336809 -401.006278) (xy 351.398306 -401.016221) (xy 351.458027 -401.033945) (xy 351.51499 -401.059162)
			(xy 351.568261 -401.091455) (xy 351.616966 -401.130295) (xy 351.660303 -401.175045) (xy 351.697563 -401.224969)
			(xy 351.728132 -401.279248) (xy 351.75151 -401.336991) (xy 351.767311 -401.397249) (xy 351.775277 -401.459032)
			(xy 351.775776 -401.49018) (xy 351.775277 -401.521328) (xy 351.767311 -401.583111) (xy 351.75151 -401.643369)
			(xy 351.728132 -401.701112) (xy 351.715915 -401.722804) (xy 375.004847 -401.722804) (xy 375.00485 -401.657359)
			(xy 375.013646 -401.592508) (xy 375.031076 -401.529427) (xy 375.056824 -401.46926) (xy 375.073164 -401.440904)
			(xy 375.076474 -401.434877) (xy 375.080083 -401.421615) (xy 375.080276 -401.414742) (xy 375.080276 -400.665442)
			(xy 375.080071 -400.65857) (xy 375.076472 -400.645307) (xy 375.073164 -400.63928) (xy 375.056831 -400.610921)
			(xy 375.031085 -400.550755) (xy 375.013657 -400.487676) (xy 375.004863 -400.422827) (xy 375.004863 -400.357384)
			(xy 375.013655 -400.292534) (xy 375.031082 -400.229454) (xy 375.056826 -400.169288) (xy 375.073164 -400.140932)
			(xy 375.076464 -400.1349) (xy 375.080079 -400.121642) (xy 375.080276 -400.11477) (xy 375.080276 -399.828766)
			(xy 375.080637 -399.818587) (xy 375.08844 -399.799785) (xy 375.102845 -399.7854) (xy 375.121659 -399.777623)
			(xy 375.131838 -399.777204) (xy 375.848118 -399.777204) (xy 375.858273 -399.777718) (xy 375.877036 -399.785492)
			(xy 375.891399 -399.799851) (xy 375.899179 -399.818611) (xy 375.89968 -399.828766) (xy 375.89968 -400.11477)
			(xy 375.899886 -400.121642) (xy 375.903485 -400.134905) (xy 375.906792 -400.140932) (xy 375.923133 -400.169286)
			(xy 375.948875 -400.229453) (xy 375.9663 -400.292534) (xy 375.975092 -400.357384) (xy 375.975091 -400.422827)
			(xy 375.966298 -400.487676) (xy 375.948872 -400.550756) (xy 375.923129 -400.610923) (xy 375.906792 -400.63928)
			(xy 375.903484 -400.645308) (xy 375.899874 -400.658569) (xy 375.89968 -400.665442) (xy 375.89968 -401.414742)
			(xy 375.899897 -401.421613) (xy 375.903489 -401.434876) (xy 375.906792 -401.440904) (xy 375.92311 -401.469271)
			(xy 375.948854 -401.529435) (xy 375.966281 -401.592513) (xy 375.975076 -401.657361) (xy 375.975078 -401.722802)
			(xy 375.966289 -401.78765) (xy 375.948866 -401.850729) (xy 375.923127 -401.910896) (xy 375.906792 -401.939252)
			(xy 375.903458 -401.945267) (xy 375.899865 -401.958538) (xy 375.89968 -401.965414) (xy 375.89968 -402.251418)
			(xy 375.899182 -402.261575) (xy 375.891405 -402.280341) (xy 375.877041 -402.294705) (xy 375.858275 -402.302482)
			(xy 375.848118 -402.30298) (xy 375.131838 -402.30298) (xy 375.121671 -402.302505) (xy 375.102881 -402.294736)
			(xy 375.088495 -402.280366) (xy 375.080706 -402.261584) (xy 375.080276 -402.251418) (xy 375.080276 -401.965414)
			(xy 375.080082 -401.958541) (xy 375.076475 -401.945278) (xy 375.073164 -401.939252) (xy 375.056807 -401.910906)
			(xy 375.031064 -401.850738) (xy 375.013638 -401.787655) (xy 375.004847 -401.722804) (xy 351.715915 -401.722804)
			(xy 351.697563 -401.755391) (xy 351.660303 -401.805315) (xy 351.616966 -401.850065) (xy 351.568261 -401.888905)
			(xy 351.51499 -401.921198) (xy 351.458027 -401.946415) (xy 351.398306 -401.964139) (xy 351.336809 -401.974082)
			(xy 351.274546 -401.976078) (xy 351.212539 -401.970096) (xy 351.151805 -401.956234) (xy 351.093343 -401.93472)
			(xy 351.038112 -401.905906) (xy 350.98702 -401.870266) (xy 350.940904 -401.828385) (xy 350.900522 -401.78095)
			(xy 350.866538 -401.728741) (xy 350.839509 -401.672615) (xy 350.81988 -401.613494) (xy 350.807971 -401.552347)
			(xy 350.80398 -401.49018) (xy 349.653098 -401.49018) (xy 349.583248 -401.56003) (xy 349.575882 -401.567142)
			(xy 349.568262 -401.585938) (xy 349.568262 -401.604734) (xy 349.569024 -401.608798) (xy 349.572109 -401.628593)
			(xy 349.575413 -401.668521) (xy 349.575628 -401.688554) (xy 349.575628 -401.69084) (xy 349.575062 -401.722605)
			(xy 349.566681 -401.785581) (xy 349.550159 -401.846927) (xy 349.525779 -401.905594) (xy 349.493957 -401.960581)
			(xy 349.455236 -402.010949) (xy 349.410277 -402.055838) (xy 349.359849 -402.09448) (xy 349.304812 -402.126216)
			(xy 349.246106 -402.150504) (xy 349.184735 -402.16693) (xy 349.121746 -402.175212) (xy 349.08998 -402.175726)
			(xy 349.046546 -402.173694) (xy 349.034874 -402.173159) (xy 349.013048 -402.181431) (xy 348.997132 -402.198502)
			(xy 348.993206 -402.209508) (xy 348.978537 -402.255597) (xy 348.941419 -402.344919) (xy 348.895753 -402.430188)
			(xy 348.841975 -402.510588) (xy 348.780601 -402.58535) (xy 348.746826 -402.619972) (xy 348.576646 -402.790152)
			(xy 350.80398 -402.790152) (xy 350.807971 -402.727985) (xy 350.81988 -402.666838) (xy 350.839509 -402.607717)
			(xy 350.866538 -402.551591) (xy 350.900522 -402.499382) (xy 350.940904 -402.451947) (xy 350.98702 -402.410066)
			(xy 351.038112 -402.374426) (xy 351.093343 -402.345612) (xy 351.151805 -402.324098) (xy 351.212539 -402.310236)
			(xy 351.274546 -402.304254) (xy 351.336809 -402.30625) (xy 351.398306 -402.316193) (xy 351.458027 -402.333917)
			(xy 351.51499 -402.359134) (xy 351.568261 -402.391427) (xy 351.616966 -402.430267) (xy 351.660303 -402.475017)
			(xy 351.697563 -402.524941) (xy 351.728132 -402.57922) (xy 351.75151 -402.636963) (xy 351.767311 -402.697221)
			(xy 351.775277 -402.759004) (xy 351.775776 -402.790152) (xy 351.775277 -402.8213) (xy 351.775073 -402.822882)
			(xy 377.204727 -402.822882) (xy 377.204733 -402.757436) (xy 377.213532 -402.692583) (xy 377.230966 -402.629501)
			(xy 377.256717 -402.569334) (xy 377.273058 -402.540978) (xy 377.276431 -402.534967) (xy 377.280161 -402.521704)
			(xy 377.280424 -402.514816) (xy 377.280424 -401.765516) (xy 377.280217 -401.758621) (xy 377.276471 -401.745349)
			(xy 377.273058 -401.739354) (xy 377.256703 -401.711007) (xy 377.23096 -401.650839) (xy 377.213535 -401.587757)
			(xy 377.204743 -401.522905) (xy 377.204746 -401.457461) (xy 377.213541 -401.39261) (xy 377.230971 -401.329529)
			(xy 377.256719 -401.269362) (xy 377.273058 -401.241006) (xy 377.276421 -401.23499) (xy 377.280157 -401.22173)
			(xy 377.280424 -401.214844) (xy 377.280424 -400.92884) (xy 377.280849 -400.918717) (xy 377.288589 -400.90001)
			(xy 377.302903 -400.885693) (xy 377.321609 -400.877951) (xy 377.331732 -400.877532) (xy 378.048012 -400.877532)
			(xy 378.058139 -400.877907) (xy 378.076849 -400.885665) (xy 378.091164 -400.899994) (xy 378.098904 -400.918712)
			(xy 378.09932 -400.92884) (xy 378.09932 -401.214844) (xy 378.099572 -401.221734) (xy 378.103301 -401.235)
			(xy 378.106686 -401.241006) (xy 378.123006 -401.269372) (xy 378.14875 -401.329537) (xy 378.166177 -401.392615)
			(xy 378.174972 -401.457462) (xy 378.174974 -401.522903) (xy 378.166184 -401.587752) (xy 378.148761 -401.650831)
			(xy 378.123021 -401.710998) (xy 378.116221 -401.722803) (xy 379.404897 -401.722803) (xy 379.4049 -401.657359)
			(xy 379.413695 -401.592509) (xy 379.431123 -401.529428) (xy 379.456868 -401.469261) (xy 379.473206 -401.440904)
			(xy 379.476565 -401.434886) (xy 379.480305 -401.421628) (xy 379.480572 -401.414742) (xy 379.480572 -400.665442)
			(xy 379.480326 -400.658552) (xy 379.476593 -400.645285) (xy 379.473206 -400.63928) (xy 379.456875 -400.610921)
			(xy 379.431132 -400.550754) (xy 379.413706 -400.487675) (xy 379.404913 -400.422826) (xy 379.404913 -400.357384)
			(xy 379.413704 -400.292535) (xy 379.431129 -400.229455) (xy 379.45687 -400.169289) (xy 379.473206 -400.140932)
			(xy 379.476556 -400.13491) (xy 379.480301 -400.121655) (xy 379.480572 -400.11477) (xy 379.480572 -399.828766)
			(xy 379.481 -399.818633) (xy 379.488744 -399.799905) (xy 379.503049 -399.785549) (xy 379.521749 -399.777737)
			(xy 379.53188 -399.777204) (xy 380.24816 -399.777204) (xy 380.258312 -399.777655) (xy 380.277064 -399.785438)
			(xy 380.291389 -399.799826) (xy 380.29909 -399.818612) (xy 380.299468 -399.828766) (xy 380.299468 -400.11477)
			(xy 380.299682 -400.121664) (xy 380.303423 -400.134936) (xy 380.306834 -400.140932) (xy 380.323177 -400.169285)
			(xy 380.348922 -400.229452) (xy 380.366349 -400.292533) (xy 380.375142 -400.357383) (xy 380.375141 -400.422827)
			(xy 380.366347 -400.487677) (xy 380.348919 -400.550758) (xy 380.323173 -400.610924) (xy 380.306834 -400.63928)
			(xy 380.303475 -400.645298) (xy 380.299737 -400.658556) (xy 380.299468 -400.665442) (xy 380.299468 -401.414742)
			(xy 380.299692 -401.421636) (xy 380.303426 -401.434908) (xy 380.306834 -401.440904) (xy 380.323154 -401.46927)
			(xy 380.348901 -401.529434) (xy 380.36633 -401.592512) (xy 380.375126 -401.65736) (xy 380.375128 -401.722802)
			(xy 380.366338 -401.787651) (xy 380.348913 -401.85073) (xy 380.323171 -401.910896) (xy 380.306834 -401.939252)
			(xy 380.30345 -401.945257) (xy 380.299727 -401.958525) (xy 380.299468 -401.965414) (xy 380.299468 -402.251418)
			(xy 380.298989 -402.261545) (xy 380.291256 -402.280265) (xy 380.276968 -402.29462) (xy 380.258284 -402.30244)
			(xy 380.24816 -402.30298) (xy 379.53188 -402.30298) (xy 379.521722 -402.302595) (xy 379.502965 -402.294789)
			(xy 379.488642 -402.280381) (xy 379.480946 -402.261578) (xy 379.480572 -402.251418) (xy 379.480572 -401.965414)
			(xy 379.480337 -401.958523) (xy 379.476596 -401.945257) (xy 379.473206 -401.939252) (xy 379.456851 -401.910906)
			(xy 379.431111 -401.850736) (xy 379.413687 -401.787654) (xy 379.404897 -401.722803) (xy 378.116221 -401.722803)
			(xy 378.106686 -401.739354) (xy 378.103306 -401.745361) (xy 378.09958 -401.758627) (xy 378.09932 -401.765516)
			(xy 378.09932 -402.514816) (xy 378.099561 -402.521708) (xy 378.103284 -402.53498) (xy 378.106686 -402.540978)
			(xy 378.122982 -402.569357) (xy 378.148728 -402.629519) (xy 378.166158 -402.692594) (xy 378.174956 -402.757439)
			(xy 378.174961 -402.822879) (xy 378.174961 -402.822882) (xy 381.604777 -402.822882) (xy 381.604783 -402.757436)
			(xy 381.613581 -402.692584) (xy 381.631012 -402.629503) (xy 381.656761 -402.569335) (xy 381.6731 -402.540978)
			(xy 381.676423 -402.534957) (xy 381.680023 -402.52169) (xy 381.680212 -402.514816) (xy 381.680212 -401.765516)
			(xy 381.680013 -401.758643) (xy 381.676409 -401.745381) (xy 381.6731 -401.739354) (xy 381.656747 -401.711007)
			(xy 381.631007 -401.650838) (xy 381.613583 -401.587756) (xy 381.604793 -401.522905) (xy 381.604796 -401.457461)
			(xy 381.61359 -401.392611) (xy 381.631018 -401.32953) (xy 381.656763 -401.269363) (xy 381.6731 -401.241006)
			(xy 381.676413 -401.23498) (xy 381.68002 -401.221717) (xy 381.680212 -401.214844) (xy 381.680212 -400.92884)
			(xy 381.680655 -400.918687) (xy 381.688439 -400.899933) (xy 381.70283 -400.885608) (xy 381.721619 -400.877909)
			(xy 381.731774 -400.877532) (xy 382.448054 -400.877532) (xy 382.458177 -400.878064) (xy 382.476895 -400.885775)
			(xy 382.491253 -400.900048) (xy 382.499075 -400.91872) (xy 382.499616 -400.92884) (xy 382.499616 -401.214844)
			(xy 382.499827 -401.221716) (xy 382.503422 -401.234979) (xy 382.506728 -401.241006) (xy 382.523049 -401.269371)
			(xy 382.548797 -401.329535) (xy 382.566226 -401.392614) (xy 382.575022 -401.457462) (xy 382.575024 -401.522904)
			(xy 382.566233 -401.587753) (xy 382.548808 -401.650832) (xy 382.523065 -401.710998) (xy 382.516264 -401.722803)
			(xy 383.804934 -401.722803) (xy 383.804936 -401.657359) (xy 383.813732 -401.592508) (xy 383.831162 -401.529427)
			(xy 383.856909 -401.46926) (xy 383.873248 -401.440904) (xy 383.876557 -401.434877) (xy 383.880167 -401.421615)
			(xy 383.88036 -401.414742) (xy 383.88036 -400.665442) (xy 383.880157 -400.65857) (xy 383.876557 -400.645307)
			(xy 383.873248 -400.63928) (xy 383.856915 -400.610921) (xy 383.831171 -400.550755) (xy 383.813743 -400.487676)
			(xy 383.80495 -400.422826) (xy 383.804949 -400.357384) (xy 383.813741 -400.292534) (xy 383.831167 -400.229455)
			(xy 383.856911 -400.169288) (xy 383.873248 -400.140932) (xy 383.876547 -400.1349) (xy 383.880163 -400.121642)
			(xy 383.88036 -400.11477) (xy 383.88036 -399.828766) (xy 383.880806 -399.818603) (xy 383.888596 -399.799829)
			(xy 383.902976 -399.785464) (xy 383.921759 -399.777695) (xy 383.931922 -399.777204) (xy 384.648202 -399.777204)
			(xy 384.658356 -399.777731) (xy 384.677118 -399.7855) (xy 384.691482 -399.799855) (xy 384.699263 -399.818613)
			(xy 384.699764 -399.828766) (xy 384.699764 -400.11477) (xy 384.699972 -400.121642) (xy 384.70357 -400.134905)
			(xy 384.706876 -400.140932) (xy 384.723218 -400.169286) (xy 384.748961 -400.229453) (xy 384.766386 -400.292534)
			(xy 384.775178 -400.357384) (xy 384.775177 -400.422827) (xy 384.766384 -400.487676) (xy 384.748957 -400.550757)
			(xy 384.723213 -400.610924) (xy 384.706876 -400.63928) (xy 384.703567 -400.645307) (xy 384.699958 -400.658569)
			(xy 384.699764 -400.665442) (xy 384.699764 -401.414742) (xy 384.699982 -401.421613) (xy 384.703573 -401.434876)
			(xy 384.706876 -401.440904) (xy 384.723194 -401.469271) (xy 384.748939 -401.529435) (xy 384.766367 -401.592513)
			(xy 384.775162 -401.657361) (xy 384.775165 -401.722802) (xy 384.766375 -401.78765) (xy 384.748952 -401.850729)
			(xy 384.723211 -401.910896) (xy 384.706876 -401.939252) (xy 384.703541 -401.945267) (xy 384.699949 -401.958538)
			(xy 384.699764 -401.965414) (xy 384.699764 -402.251418) (xy 384.699282 -402.261577) (xy 384.691502 -402.280346)
			(xy 384.677133 -402.294711) (xy 384.658361 -402.302485) (xy 384.648202 -402.30298) (xy 383.931922 -402.30298)
			(xy 383.921754 -402.302518) (xy 383.902963 -402.294744) (xy 383.888578 -402.28037) (xy 383.88079 -402.261586)
			(xy 383.88036 -402.251418) (xy 383.88036 -401.965414) (xy 383.880168 -401.958541) (xy 383.87656 -401.945278)
			(xy 383.873248 -401.939252) (xy 383.856892 -401.910906) (xy 383.831149 -401.850737) (xy 383.813724 -401.787655)
			(xy 383.804934 -401.722803) (xy 382.516264 -401.722803) (xy 382.506728 -401.739354) (xy 382.503432 -401.745388)
			(xy 382.499814 -401.758644) (xy 382.499616 -401.765516) (xy 382.499616 -402.514816) (xy 382.4998 -402.52169)
			(xy 382.503413 -402.534953) (xy 382.506728 -402.540978) (xy 382.523026 -402.569356) (xy 382.548775 -402.629517)
			(xy 382.566207 -402.692593) (xy 382.575006 -402.757439) (xy 382.575011 -402.822879) (xy 382.575011 -402.822882)
			(xy 386.004814 -402.822882) (xy 386.004819 -402.757436) (xy 386.013618 -402.692584) (xy 386.031051 -402.629502)
			(xy 386.056801 -402.569334) (xy 386.073142 -402.540978) (xy 386.076513 -402.534966) (xy 386.080244 -402.521703)
			(xy 386.080508 -402.514816) (xy 386.080508 -401.765516) (xy 386.080267 -401.758625) (xy 386.07653 -401.745359)
			(xy 386.073142 -401.739354) (xy 386.056788 -401.711007) (xy 386.031045 -401.650838) (xy 386.01362 -401.587756)
			(xy 386.00483 -401.522905) (xy 386.004832 -401.457461) (xy 386.013627 -401.39261) (xy 386.031056 -401.329529)
			(xy 386.056803 -401.269362) (xy 386.073142 -401.241006) (xy 386.076503 -401.23499) (xy 386.080241 -401.22173)
			(xy 386.080508 -401.214844) (xy 386.080508 -400.92884) (xy 386.080949 -400.918719) (xy 386.088686 -400.900015)
			(xy 386.102995 -400.885699) (xy 386.121695 -400.877954) (xy 386.131816 -400.877532) (xy 386.848096 -400.877532)
			(xy 386.858222 -400.87792) (xy 386.876932 -400.885673) (xy 386.891247 -400.899998) (xy 386.898987 -400.918714)
			(xy 386.899404 -400.92884) (xy 386.899404 -401.214844) (xy 386.899658 -401.221734) (xy 386.903386 -401.235)
			(xy 386.90677 -401.241006) (xy 386.92309 -401.269372) (xy 386.948835 -401.329536) (xy 386.966263 -401.392614)
			(xy 386.975058 -401.457462) (xy 386.97506 -401.522904) (xy 386.96627 -401.587752) (xy 386.948847 -401.650831)
			(xy 386.923106 -401.710998) (xy 386.916305 -401.722803) (xy 388.204723 -401.722803) (xy 388.204726 -401.657359)
			(xy 388.213521 -401.592508) (xy 388.230951 -401.529427) (xy 388.256697 -401.46926) (xy 388.273036 -401.440904)
			(xy 388.276344 -401.434876) (xy 388.279955 -401.421615) (xy 388.280148 -401.414742) (xy 388.280148 -400.665442)
			(xy 388.279947 -400.658569) (xy 388.276346 -400.645306) (xy 388.273036 -400.63928) (xy 388.256704 -400.610921)
			(xy 388.23096 -400.550755) (xy 388.213533 -400.487675) (xy 388.204739 -400.422826) (xy 388.204738 -400.357384)
			(xy 388.213531 -400.292535) (xy 388.230956 -400.229455) (xy 388.256699 -400.169288) (xy 388.273036 -400.140932)
			(xy 388.276334 -400.134899) (xy 388.279951 -400.121642) (xy 388.280148 -400.11477) (xy 388.280148 -399.828766)
			(xy 388.280606 -399.818605) (xy 388.288393 -399.799833) (xy 388.30277 -399.785469) (xy 388.321548 -399.777697)
			(xy 388.33171 -399.777204) (xy 389.04799 -399.777204) (xy 389.058143 -399.777741) (xy 389.076905 -399.785506)
			(xy 389.09127 -399.799858) (xy 389.099051 -399.818613) (xy 389.099552 -399.828766) (xy 389.099552 -400.11477)
			(xy 389.099749 -400.121643) (xy 389.103353 -400.134906) (xy 389.106664 -400.140932) (xy 389.123006 -400.169285)
			(xy 389.14875 -400.229453) (xy 389.166175 -400.292533) (xy 389.174968 -400.357383) (xy 389.174967 -400.390106)
			(xy 392.603744 -400.390106) (xy 392.607735 -400.327939) (xy 392.619644 -400.266792) (xy 392.639273 -400.207671)
			(xy 392.666302 -400.151545) (xy 392.700286 -400.099336) (xy 392.740668 -400.051901) (xy 392.786784 -400.01002)
			(xy 392.837876 -399.97438) (xy 392.893107 -399.945566) (xy 392.951569 -399.924052) (xy 393.012303 -399.91019)
			(xy 393.07431 -399.904208) (xy 393.136573 -399.906204) (xy 393.19807 -399.916147) (xy 393.257791 -399.933871)
			(xy 393.314754 -399.959088) (xy 393.368025 -399.991381) (xy 393.41673 -400.030221) (xy 393.460067 -400.074971)
			(xy 393.497327 -400.124895) (xy 393.527896 -400.179174) (xy 393.551274 -400.236917) (xy 393.567075 -400.297175)
			(xy 393.575041 -400.358958) (xy 393.57554 -400.390106) (xy 393.575041 -400.421254) (xy 393.567075 -400.483037)
			(xy 393.551274 -400.543295) (xy 393.527896 -400.601038) (xy 393.497327 -400.655317) (xy 393.460067 -400.705241)
			(xy 393.41673 -400.749991) (xy 393.368025 -400.788831) (xy 393.314754 -400.821124) (xy 393.257791 -400.846341)
			(xy 393.19807 -400.864065) (xy 393.136573 -400.874008) (xy 393.07431 -400.876004) (xy 393.012303 -400.870022)
			(xy 392.951569 -400.85616) (xy 392.893107 -400.834646) (xy 392.837876 -400.805832) (xy 392.786784 -400.770192)
			(xy 392.740668 -400.728311) (xy 392.700286 -400.680876) (xy 392.666302 -400.628667) (xy 392.639273 -400.572541)
			(xy 392.619644 -400.51342) (xy 392.607735 -400.452273) (xy 392.603744 -400.390106) (xy 389.174967 -400.390106)
			(xy 389.174967 -400.422827) (xy 389.166173 -400.487677) (xy 389.148746 -400.550757) (xy 389.123002 -400.610924)
			(xy 389.106664 -400.63928) (xy 389.103361 -400.645311) (xy 389.099747 -400.65857) (xy 389.099552 -400.665442)
			(xy 389.099552 -401.414742) (xy 389.099759 -401.421614) (xy 389.103356 -401.434877) (xy 389.106664 -401.440904)
			(xy 389.122983 -401.46927) (xy 389.148728 -401.529435) (xy 389.166156 -401.592513) (xy 389.174952 -401.65736)
			(xy 389.174954 -401.722802) (xy 389.166164 -401.78765) (xy 389.148741 -401.850729) (xy 389.123 -401.910896)
			(xy 389.106664 -401.939252) (xy 389.103336 -401.94527) (xy 389.099738 -401.958539) (xy 389.099552 -401.965414)
			(xy 389.099552 -402.251418) (xy 389.099081 -402.261578) (xy 389.091299 -402.28035) (xy 389.076926 -402.294715)
			(xy 389.05815 -402.302487) (xy 389.04799 -402.30298) (xy 388.33171 -402.30298) (xy 388.321555 -402.302459)
			(xy 388.30279 -402.294691) (xy 388.288425 -402.280334) (xy 388.280647 -402.261573) (xy 388.280148 -402.251418)
			(xy 388.280148 -401.965414) (xy 388.279957 -401.958541) (xy 388.276349 -401.945278) (xy 388.273036 -401.939252)
			(xy 388.25668 -401.910906) (xy 388.230938 -401.850737) (xy 388.213514 -401.787655) (xy 388.204723 -401.722803)
			(xy 386.916305 -401.722803) (xy 386.90677 -401.739354) (xy 386.903389 -401.74536) (xy 386.899664 -401.758627)
			(xy 386.899404 -401.765516) (xy 386.899404 -402.514816) (xy 386.899669 -402.521705) (xy 386.90339 -402.534971)
			(xy 386.90677 -402.540978) (xy 386.923066 -402.569357) (xy 386.948814 -402.629518) (xy 386.966244 -402.692594)
			(xy 386.975042 -402.757439) (xy 386.975048 -402.822879) (xy 386.975048 -402.822882) (xy 390.40485 -402.822882)
			(xy 390.404855 -402.757435) (xy 390.413655 -402.692583) (xy 390.431089 -402.629501) (xy 390.456842 -402.569334)
			(xy 390.473184 -402.540978) (xy 390.476505 -402.534957) (xy 390.480107 -402.52169) (xy 390.480296 -402.514816)
			(xy 390.480296 -401.765516) (xy 390.480098 -401.758643) (xy 390.476494 -401.74538) (xy 390.473184 -401.739354)
			(xy 390.456828 -401.711008) (xy 390.431084 -401.650839) (xy 390.413657 -401.587757) (xy 390.404866 -401.522905)
			(xy 390.404868 -401.45746) (xy 390.413664 -401.392609) (xy 390.431095 -401.329528) (xy 390.456844 -401.269362)
			(xy 390.473184 -401.241006) (xy 390.476495 -401.23498) (xy 390.480103 -401.221717) (xy 390.480296 -401.214844)
			(xy 390.480296 -400.92884) (xy 390.480754 -400.918689) (xy 390.488536 -400.899938) (xy 390.502922 -400.885614)
			(xy 390.521705 -400.877912) (xy 390.531858 -400.877532) (xy 391.248138 -400.877532) (xy 391.258266 -400.877995)
			(xy 391.276987 -400.885734) (xy 391.291341 -400.900027) (xy 391.299161 -400.918714) (xy 391.2997 -400.92884)
			(xy 391.2997 -401.214844) (xy 391.299914 -401.221716) (xy 391.303507 -401.234978) (xy 391.306812 -401.241006)
			(xy 391.323134 -401.269371) (xy 391.348882 -401.329535) (xy 391.366312 -401.392613) (xy 391.375108 -401.457462)
			(xy 391.37511 -401.522904) (xy 391.366319 -401.587753) (xy 391.348893 -401.650832) (xy 391.332101 -401.690078)
			(xy 392.603744 -401.690078) (xy 392.607735 -401.627911) (xy 392.619644 -401.566764) (xy 392.639273 -401.507643)
			(xy 392.666302 -401.451517) (xy 392.700286 -401.399308) (xy 392.740668 -401.351873) (xy 392.786784 -401.309992)
			(xy 392.837876 -401.274352) (xy 392.893107 -401.245538) (xy 392.951569 -401.224024) (xy 393.012303 -401.210162)
			(xy 393.07431 -401.20418) (xy 393.136573 -401.206176) (xy 393.19807 -401.216119) (xy 393.257791 -401.233843)
			(xy 393.314754 -401.25906) (xy 393.368025 -401.291353) (xy 393.41673 -401.330193) (xy 393.460067 -401.374943)
			(xy 393.497327 -401.424867) (xy 393.527896 -401.479146) (xy 393.532363 -401.49018) (xy 394.803892 -401.49018)
			(xy 394.807883 -401.428013) (xy 394.819792 -401.366866) (xy 394.839421 -401.307745) (xy 394.86645 -401.251619)
			(xy 394.900434 -401.19941) (xy 394.940816 -401.151975) (xy 394.986932 -401.110094) (xy 395.038024 -401.074454)
			(xy 395.093255 -401.04564) (xy 395.151717 -401.024126) (xy 395.212451 -401.010264) (xy 395.274458 -401.004282)
			(xy 395.336721 -401.006278) (xy 395.398218 -401.016221) (xy 395.457939 -401.033945) (xy 395.514902 -401.059162)
			(xy 395.568173 -401.091455) (xy 395.616878 -401.130295) (xy 395.660215 -401.175045) (xy 395.697475 -401.224969)
			(xy 395.728044 -401.279248) (xy 395.751422 -401.336991) (xy 395.767223 -401.397249) (xy 395.775189 -401.459032)
			(xy 395.775688 -401.49018) (xy 395.775189 -401.521328) (xy 395.767223 -401.583111) (xy 395.751422 -401.643369)
			(xy 395.728044 -401.701112) (xy 395.697475 -401.755391) (xy 395.660215 -401.805315) (xy 395.616878 -401.850065)
			(xy 395.568173 -401.888905) (xy 395.514902 -401.921198) (xy 395.457939 -401.946415) (xy 395.398218 -401.964139)
			(xy 395.336721 -401.974082) (xy 395.274458 -401.976078) (xy 395.212451 -401.970096) (xy 395.151717 -401.956234)
			(xy 395.093255 -401.93472) (xy 395.038024 -401.905906) (xy 394.986932 -401.870266) (xy 394.940816 -401.828385)
			(xy 394.900434 -401.78095) (xy 394.86645 -401.728741) (xy 394.839421 -401.672615) (xy 394.819792 -401.613494)
			(xy 394.807883 -401.552347) (xy 394.803892 -401.49018) (xy 393.532363 -401.49018) (xy 393.551274 -401.536889)
			(xy 393.567075 -401.597147) (xy 393.575041 -401.65893) (xy 393.57554 -401.690078) (xy 393.575041 -401.721226)
			(xy 393.567075 -401.783009) (xy 393.551274 -401.843267) (xy 393.527896 -401.90101) (xy 393.497327 -401.955289)
			(xy 393.460067 -402.005213) (xy 393.41673 -402.049963) (xy 393.368025 -402.088803) (xy 393.314754 -402.121096)
			(xy 393.257791 -402.146313) (xy 393.19807 -402.164037) (xy 393.136573 -402.17398) (xy 393.07431 -402.175976)
			(xy 393.012303 -402.169994) (xy 392.951569 -402.156132) (xy 392.893107 -402.134618) (xy 392.837876 -402.105804)
			(xy 392.786784 -402.070164) (xy 392.740668 -402.028283) (xy 392.700286 -401.980848) (xy 392.666302 -401.928639)
			(xy 392.639273 -401.872513) (xy 392.619644 -401.813392) (xy 392.607735 -401.752245) (xy 392.603744 -401.690078)
			(xy 391.332101 -401.690078) (xy 391.32315 -401.710998) (xy 391.306812 -401.739354) (xy 391.303514 -401.745387)
			(xy 391.299898 -401.758644) (xy 391.2997 -401.765516) (xy 391.2997 -402.514816) (xy 391.299886 -402.52169)
			(xy 391.303498 -402.534953) (xy 391.306812 -402.540978) (xy 391.32311 -402.569356) (xy 391.34886 -402.629517)
			(xy 391.366293 -402.692593) (xy 391.375092 -402.757439) (xy 391.375095 -402.790152) (xy 394.803892 -402.790152)
			(xy 394.807883 -402.727985) (xy 394.819792 -402.666838) (xy 394.839421 -402.607717) (xy 394.86645 -402.551591)
			(xy 394.900434 -402.499382) (xy 394.940816 -402.451947) (xy 394.986932 -402.410066) (xy 395.038024 -402.374426)
			(xy 395.093255 -402.345612) (xy 395.151717 -402.324098) (xy 395.212451 -402.310236) (xy 395.274458 -402.304254)
			(xy 395.336721 -402.30625) (xy 395.398218 -402.316193) (xy 395.457939 -402.333917) (xy 395.514902 -402.359134)
			(xy 395.568173 -402.391427) (xy 395.616878 -402.430267) (xy 395.660215 -402.475017) (xy 395.697475 -402.524941)
			(xy 395.728044 -402.57922) (xy 395.751422 -402.636963) (xy 395.767223 -402.697221) (xy 395.775189 -402.759004)
			(xy 395.775688 -402.790152) (xy 395.775189 -402.8213) (xy 395.767223 -402.883083) (xy 395.751422 -402.943341)
			(xy 395.728044 -403.001084) (xy 395.697475 -403.055363) (xy 395.660215 -403.105287) (xy 395.616878 -403.150037)
			(xy 395.568173 -403.188877) (xy 395.514902 -403.22117) (xy 395.457939 -403.246387) (xy 395.398218 -403.264111)
			(xy 395.336721 -403.274054) (xy 395.274458 -403.27605) (xy 395.212451 -403.270068) (xy 395.151717 -403.256206)
			(xy 395.093255 -403.234692) (xy 395.038024 -403.205878) (xy 394.986932 -403.170238) (xy 394.940816 -403.128357)
			(xy 394.900434 -403.080922) (xy 394.86645 -403.028713) (xy 394.839421 -402.972587) (xy 394.819792 -402.913466)
			(xy 394.807883 -402.852319) (xy 394.803892 -402.790152) (xy 391.375095 -402.790152) (xy 391.375098 -402.822879)
			(xy 391.36631 -402.887726) (xy 391.348888 -402.950805) (xy 391.323148 -403.01097) (xy 391.306812 -403.039326)
			(xy 391.303489 -403.045347) (xy 391.299888 -403.058613) (xy 391.2997 -403.065488) (xy 391.2997 -403.351492)
			(xy 391.299272 -403.361646) (xy 391.291479 -403.380398) (xy 391.277084 -403.394721) (xy 391.258294 -403.402421)
			(xy 391.248138 -403.4028) (xy 390.531858 -403.4028) (xy 390.521734 -403.402309) (xy 390.503019 -403.394575)
			(xy 390.488666 -403.380291) (xy 390.480841 -403.361614) (xy 390.480296 -403.351492) (xy 390.480296 -403.065488)
			(xy 390.480109 -403.058614) (xy 390.476498 -403.045352) (xy 390.473184 -403.039326) (xy 390.456805 -403.010993)
			(xy 390.431062 -402.950821) (xy 390.413638 -402.887736) (xy 390.40485 -402.822882) (xy 386.975048 -402.822882)
			(xy 386.966261 -402.887726) (xy 386.948841 -402.950804) (xy 386.923104 -403.01097) (xy 386.90677 -403.039326)
			(xy 386.903398 -403.045337) (xy 386.899667 -403.058601) (xy 386.899404 -403.065488) (xy 386.899404 -403.351492)
			(xy 386.898978 -403.361613) (xy 386.891233 -403.380316) (xy 386.87692 -403.394631) (xy 386.858217 -403.402377)
			(xy 386.848096 -403.4028) (xy 386.131816 -403.4028) (xy 386.121695 -403.402371) (xy 386.102991 -403.394628)
			(xy 386.088676 -403.380315) (xy 386.080931 -403.361613) (xy 386.080508 -403.351492) (xy 386.080508 -403.065488)
			(xy 386.08024 -403.058599) (xy 386.076521 -403.045333) (xy 386.073142 -403.039326) (xy 386.056764 -403.010992)
			(xy 386.031024 -402.95082) (xy 386.013602 -402.887736) (xy 386.004814 -402.822882) (xy 382.575011 -402.822882)
			(xy 382.566224 -402.887726) (xy 382.548802 -402.950805) (xy 382.523063 -403.01097) (xy 382.506728 -403.039326)
			(xy 382.503406 -403.045347) (xy 382.499804 -403.058614) (xy 382.499616 -403.065488) (xy 382.499616 -403.351492)
			(xy 382.499172 -403.361644) (xy 382.491382 -403.380393) (xy 382.476993 -403.394716) (xy 382.458207 -403.402419)
			(xy 382.448054 -403.4028) (xy 381.731774 -403.4028) (xy 381.721651 -403.402296) (xy 381.702936 -403.394567)
			(xy 381.688582 -403.380287) (xy 381.680757 -403.361613) (xy 381.680212 -403.351492) (xy 381.680212 -403.065488)
			(xy 381.680023 -403.058615) (xy 381.676413 -403.045352) (xy 381.6731 -403.039326) (xy 381.656723 -403.010992)
			(xy 381.630985 -402.95082) (xy 381.613565 -402.887735) (xy 381.604777 -402.822882) (xy 378.174961 -402.822882)
			(xy 378.166175 -402.887725) (xy 378.148756 -402.950804) (xy 378.123019 -403.01097) (xy 378.106686 -403.039326)
			(xy 378.103316 -403.045338) (xy 378.099584 -403.058601) (xy 378.09932 -403.065488) (xy 378.09932 -403.351492)
			(xy 378.098809 -403.361598) (xy 378.091078 -403.380272) (xy 378.076789 -403.394566) (xy 378.058118 -403.402305)
			(xy 378.048012 -403.4028) (xy 377.331732 -403.4028) (xy 377.321612 -403.402358) (xy 377.302909 -403.39462)
			(xy 377.288593 -403.380312) (xy 377.280847 -403.361612) (xy 377.280424 -403.351492) (xy 377.280424 -403.065488)
			(xy 377.280189 -403.058595) (xy 377.276462 -403.045323) (xy 377.273058 -403.039326) (xy 377.256679 -403.010992)
			(xy 377.230938 -402.950821) (xy 377.213516 -402.887736) (xy 377.204727 -402.822882) (xy 351.775073 -402.822882)
			(xy 351.767311 -402.883083) (xy 351.75151 -402.943341) (xy 351.728132 -403.001084) (xy 351.697563 -403.055363)
			(xy 351.660303 -403.105287) (xy 351.616966 -403.150037) (xy 351.568261 -403.188877) (xy 351.51499 -403.22117)
			(xy 351.458027 -403.246387) (xy 351.398306 -403.264111) (xy 351.336809 -403.274054) (xy 351.274546 -403.27605)
			(xy 351.212539 -403.270068) (xy 351.151805 -403.256206) (xy 351.093343 -403.234692) (xy 351.038112 -403.205878)
			(xy 350.98702 -403.170238) (xy 350.940904 -403.128357) (xy 350.900522 -403.080922) (xy 350.866538 -403.028713)
			(xy 350.839509 -402.972587) (xy 350.81988 -402.913466) (xy 350.807971 -402.852319) (xy 350.80398 -402.790152)
			(xy 348.576646 -402.790152) (xy 348.390464 -402.976334) (xy 348.3604 -403.005774) (xy 348.296048 -403.060002)
			(xy 348.227324 -403.108567) (xy 348.154722 -403.151118) (xy 348.078768 -403.187349) (xy 348.000011 -403.216996)
			(xy 347.91902 -403.239847) (xy 347.836381 -403.255735) (xy 347.79458 -403.26056) (xy 347.755718 -403.285706)
			(xy 347.733614 -403.323367) (xy 347.683754 -403.395067) (xy 347.627816 -403.462133) (xy 347.566226 -403.524049)
			(xy 347.499458 -403.580342) (xy 347.428022 -403.63058) (xy 347.352466 -403.674378) (xy 347.27337 -403.7114)
			(xy 347.191339 -403.741363) (xy 347.107001 -403.764038) (xy 347.021004 -403.779249) (xy 346.934006 -403.786882)
			(xy 346.89034 -403.787356) (xy 346.889832 -403.787356) (xy 346.848717 -403.786935) (xy 346.766766 -403.780162)
			(xy 346.685651 -403.766659) (xy 346.605925 -403.746518) (xy 346.52813 -403.719876) (xy 346.49029 -403.70379)
			(xy 346.481408 -403.700283) (xy 346.462342 -403.69949) (xy 346.453206 -403.702266) (xy 346.423639 -403.711895)
			(xy 346.36237 -403.722495) (xy 346.331286 -403.723348) (xy 346.325952 -403.723348) (xy 346.298795 -403.722723)
			(xy 346.245067 -403.714731) (xy 346.193015 -403.6992) (xy 346.143693 -403.676443) (xy 346.098096 -403.646922)
			(xy 346.057146 -403.611232) (xy 346.021673 -403.570095) (xy 345.992391 -403.524344) (xy 345.969895 -403.474902)
			(xy 345.954638 -403.422769) (xy 345.946928 -403.369) (xy 345.946476 -403.34184) (xy 345.946476 -403.341332)
			(xy 345.946855 -403.317075) (xy 345.953012 -403.268952) (xy 345.965231 -403.222002) (xy 345.973908 -403.199346)
			(xy 345.97594 -403.188932) (xy 345.959494 -403.150158) (xy 345.932424 -403.070397) (xy 345.912168 -402.988639)
			(xy 345.905074 -402.947124) (xy 345.903275 -402.938333) (xy 345.894459 -402.922715) (xy 345.880814 -402.911078)
			(xy 345.864001 -402.904838) (xy 345.855036 -402.904452) (xy 343.972388 -402.904452) (xy 343.962423 -402.90493)
			(xy 343.943989 -402.912509) (xy 343.936574 -402.919184) (xy 343.869264 -402.98624) (xy 343.836377 -403.018395)
			(xy 343.765635 -403.077185) (xy 343.689779 -403.129209) (xy 343.609453 -403.174024) (xy 343.525341 -403.211251)
			(xy 343.438157 -403.240572) (xy 343.393522 -403.25167) (xy 343.383108 -403.25421) (xy 343.366852 -403.265894)
			(xy 343.360756 -403.276308) (xy 343.360502 -403.27707) (xy 343.338547 -403.315304) (xy 343.288862 -403.388144)
			(xy 343.232941 -403.456314) (xy 343.17122 -403.51928) (xy 343.104181 -403.576553) (xy 343.032348 -403.627683)
			(xy 342.956281 -403.672273) (xy 342.876576 -403.709973) (xy 342.793853 -403.74049) (xy 342.708759 -403.763586)
			(xy 342.621959 -403.779079) (xy 342.53413 -403.786849) (xy 342.490044 -403.787356) (xy 342.48979 -403.787356)
			(xy 342.448674 -403.786938) (xy 342.366722 -403.780169) (xy 342.285606 -403.76667) (xy 342.205878 -403.746533)
			(xy 342.12808 -403.719895) (xy 342.090248 -403.70379) (xy 342.081366 -403.700291) (xy 342.062306 -403.699513)
			(xy 342.053164 -403.702266) (xy 342.023596 -403.711892) (xy 341.962327 -403.722485) (xy 341.931244 -403.723348)
			(xy 341.92591 -403.723348) (xy 341.898751 -403.722727) (xy 341.845016 -403.714741) (xy 341.792957 -403.699215)
			(xy 341.743627 -403.676462) (xy 341.698023 -403.646942) (xy 341.657067 -403.611252) (xy 341.621587 -403.570114)
			(xy 341.592301 -403.52436) (xy 341.5698 -403.474914) (xy 341.55454 -403.422777) (xy 341.546829 -403.369002)
			(xy 341.546434 -403.34184) (xy 341.546434 -403.341332) (xy 341.546812 -403.317075) (xy 341.552969 -403.268952)
			(xy 341.565188 -403.222001) (xy 341.573866 -403.199346) (xy 341.575898 -403.188932) (xy 341.559452 -403.150159)
			(xy 341.53238 -403.070398) (xy 341.512123 -402.98864) (xy 341.505032 -402.947124) (xy 341.503232 -402.938336)
			(xy 341.494414 -402.922727) (xy 341.480768 -402.9111) (xy 341.463956 -402.904873) (xy 341.454994 -402.904452)
			(xy 339.572346 -402.904452) (xy 339.562384 -402.904937) (xy 339.543961 -402.912528) (xy 339.536532 -402.919184)
			(xy 339.469222 -402.98624) (xy 339.436336 -403.018396) (xy 339.365596 -403.07719) (xy 339.289741 -403.129219)
			(xy 339.209416 -403.174039) (xy 339.125305 -403.21127) (xy 339.038121 -403.240596) (xy 338.99348 -403.25167)
			(xy 338.983066 -403.25421) (xy 338.96681 -403.265894) (xy 338.960714 -403.276308) (xy 338.96046 -403.27707)
			(xy 338.938505 -403.315303) (xy 338.888819 -403.38814) (xy 338.832897 -403.456308) (xy 338.771175 -403.519272)
			(xy 338.704136 -403.576541) (xy 338.632302 -403.627669) (xy 338.556236 -403.672256) (xy 338.47653 -403.709953)
			(xy 338.393808 -403.740466) (xy 338.308715 -403.763558) (xy 338.221915 -403.779048) (xy 338.134087 -403.786814)
			(xy 338.090002 -403.787356) (xy 338.089748 -403.787356) (xy 338.048633 -403.786936) (xy 337.966681 -403.780164)
			(xy 337.885566 -403.766662) (xy 337.80584 -403.746522) (xy 337.728044 -403.719881) (xy 337.690206 -403.70379)
			(xy 337.681324 -403.70028) (xy 337.662256 -403.699481) (xy 337.653122 -403.702266) (xy 337.623554 -403.711889)
			(xy 337.562285 -403.722475) (xy 337.531202 -403.723348) (xy 337.525868 -403.723348) (xy 337.498711 -403.722724)
			(xy 337.444981 -403.714734) (xy 337.392927 -403.699204) (xy 337.343602 -403.676448) (xy 337.298003 -403.646927)
			(xy 337.257052 -403.611238) (xy 337.221577 -403.570101) (xy 337.192294 -403.524348) (xy 337.169796 -403.474905)
			(xy 337.154538 -403.422771) (xy 337.146829 -403.369) (xy 337.146392 -403.34184) (xy 337.146392 -403.341332)
			(xy 337.146771 -403.317075) (xy 337.152928 -403.268953) (xy 337.165148 -403.222002) (xy 337.173824 -403.199346)
			(xy 337.175856 -403.188932) (xy 337.159463 -403.150193) (xy 337.132484 -403.070513) (xy 337.112299 -402.988846)
			(xy 337.105244 -402.947378) (xy 337.105244 -402.947124) (xy 337.103444 -402.938335) (xy 337.094627 -402.922723)
			(xy 337.080981 -402.911094) (xy 337.064169 -402.904863) (xy 337.055206 -402.904452) (xy 335.183734 -402.904452)
			(xy 335.174267 -402.905267) (xy 335.156913 -402.91297) (xy 335.149952 -402.919438) (xy 335.09331 -402.976334)
			(xy 335.059969 -403.008916) (xy 334.988131 -403.068338) (xy 334.911013 -403.120727) (xy 334.829303 -403.165616)
			(xy 334.786732 -403.184614) (xy 334.782922 -403.186138) (xy 334.732733 -403.208613) (xy 334.62848 -403.243622)
			(xy 334.574896 -403.255988) (xy 334.569816 -403.259544) (xy 334.54824 -403.298939) (xy 334.499004 -403.37407)
			(xy 334.443209 -403.444468) (xy 334.381309 -403.509563) (xy 334.313805 -403.568826) (xy 334.241245 -403.621777)
			(xy 334.164216 -403.667988) (xy 334.083342 -403.707082) (xy 333.99928 -403.738745) (xy 333.912711 -403.762718)
			(xy 333.824337 -403.778808) (xy 333.734874 -403.786883) (xy 333.68996 -403.787356) (xy 333.689706 -403.787356)
			(xy 333.64859 -403.786938) (xy 333.566637 -403.780171) (xy 333.485521 -403.766673) (xy 333.405792 -403.746538)
			(xy 333.327994 -403.719901) (xy 333.290164 -403.70379) (xy 333.281282 -403.700287) (xy 333.26222 -403.699504)
			(xy 333.25308 -403.702266) (xy 333.223512 -403.711893) (xy 333.162243 -403.722489) (xy 333.13116 -403.723348)
			(xy 333.125826 -403.723348) (xy 333.09867 -403.722721) (xy 333.044945 -403.714726) (xy 332.992896 -403.699193)
			(xy 332.943577 -403.676435) (xy 332.897983 -403.646913) (xy 332.857037 -403.611223) (xy 332.821566 -403.570087)
			(xy 332.792287 -403.524337) (xy 332.769793 -403.474896) (xy 332.754537 -403.422766) (xy 332.746828 -403.368998)
			(xy 332.74635 -403.34184) (xy 332.74635 -403.341332) (xy 332.746728 -403.317075) (xy 332.752886 -403.268952)
			(xy 332.765104 -403.222001) (xy 332.773782 -403.199346) (xy 332.775814 -403.188932) (xy 332.759368 -403.150159)
			(xy 332.732295 -403.070398) (xy 332.712038 -402.98864) (xy 332.704948 -402.947124) (xy 332.703148 -402.938335)
			(xy 332.694331 -402.922722) (xy 332.680685 -402.911092) (xy 332.663873 -402.90486) (xy 332.65491 -402.904452)
			(xy 332.170532 -402.904452) (xy 332.160468 -402.904015) (xy 332.141886 -402.896278) (xy 332.134464 -402.889466)
			(xy 331.873606 -402.628608) (xy 331.844904 -402.622258) (xy 331.830934 -402.627338) (xy 331.789908 -402.641793)
			(xy 331.705887 -402.664329) (xy 331.62022 -402.679455) (xy 331.533562 -402.687054) (xy 331.490066 -402.687536)
			(xy 331.446942 -402.687057) (xy 331.361018 -402.679566) (xy 331.276062 -402.664687) (xy 331.192707 -402.64253)
			(xy 331.111575 -402.613262) (xy 331.072236 -402.595588) (xy 331.066902 -402.597112) (xy 331.044731 -402.605402)
			(xy 330.998854 -402.617053) (xy 330.951885 -402.622926) (xy 330.928218 -402.623274) (xy 330.927964 -402.623274)
			(xy 330.900715 -402.622785) (xy 330.846773 -402.615024) (xy 330.794485 -402.599666) (xy 330.744915 -402.577022)
			(xy 330.699071 -402.547554) (xy 330.657888 -402.511862) (xy 330.622204 -402.470673) (xy 330.592744 -402.424824)
			(xy 330.57011 -402.375249) (xy 330.554761 -402.322958) (xy 330.54701 -402.269015) (xy 330.546456 -402.241766)
			(xy 330.546456 -402.241512) (xy 330.546857 -402.217162) (xy 330.55308 -402.168862) (xy 330.56539 -402.121744)
			(xy 330.574142 -402.099018) (xy 330.576174 -402.089112) (xy 330.56011 -402.051318) (xy 330.53351 -401.973617)
			(xy 330.513382 -401.893994) (xy 330.499864 -401.812986) (xy 330.493045 -401.731142) (xy 330.492608 -401.690078)
			(xy 330.492608 -401.308062) (xy 330.49337 -401.271486) (xy 330.493878 -401.260564) (xy 330.486258 -401.24126)
			(xy 330.09459 -400.849592) (xy 330.087735 -400.842197) (xy 330.079989 -400.823598) (xy 330.079604 -400.813524)
			(xy 330.079604 -396.245334) (xy 330.079169 -396.235269) (xy 330.071438 -396.216682) (xy 330.064618 -396.209266)
			(xy 327.448418 -393.593066) (xy 327.441575 -393.585667) (xy 327.43385 -393.567068) (xy 327.433432 -393.556998)
			(xy 327.433432 -393.471654) (xy 327.416668 -393.446508) (xy 327.40219 -393.440412) (xy 326.989694 -393.267438)
			(xy 326.945175 -393.248137) (xy 326.859759 -393.202085) (xy 326.779225 -393.147947) (xy 326.704335 -393.086238)
			(xy 326.669654 -393.0523) (xy 323.97192 -390.349232) (xy 323.940195 -390.316688) (xy 323.882127 -390.246764)
			(xy 323.830653 -390.171853) (xy 323.7862 -390.092575) (xy 323.767196 -390.05129) (xy 323.295264 -388.994396)
			(xy 323.294756 -388.99338) (xy 322.829428 -388.037324) (xy 322.813077 -388.002876) (xy 322.785108 -387.931929)
			(xy 322.773548 -387.895592) (xy 322.704714 -387.672072) (xy 322.70319 -387.66877) (xy 308.596284 -356.078028)
			(xy 308.591875 -356.069338) (xy 308.577832 -356.055853) (xy 308.559788 -356.04854) (xy 308.550056 -356.048056)
			(xy 303.364138 -356.048056) (xy 303.354014 -356.048487) (xy 303.335331 -356.056291) (xy 303.32111 -356.070704)
			(xy 303.313556 -356.08949) (xy 303.313338 -356.099618) (xy 303.38014 -360.354626) (xy 303.38014 -360.357928)
			(xy 303.604676 -362.350558) (xy 303.60493 -362.353098) (xy 304.991516 -368.899186) (xy 304.991516 -368.89944)
			(xy 304.99685 -368.925348) (xy 304.99685 -368.92611) (xy 305.010566 -368.990118) (xy 306.803814 -368.990118)
			(xy 306.807805 -368.927951) (xy 306.819714 -368.866804) (xy 306.839343 -368.807683) (xy 306.866372 -368.751557)
			(xy 306.900356 -368.699348) (xy 306.940738 -368.651913) (xy 306.986854 -368.610032) (xy 307.037946 -368.574392)
			(xy 307.093177 -368.545578) (xy 307.151639 -368.524064) (xy 307.212373 -368.510202) (xy 307.27438 -368.50422)
			(xy 307.336643 -368.506216) (xy 307.39814 -368.516159) (xy 307.457861 -368.533883) (xy 307.514824 -368.5591)
			(xy 307.568095 -368.591393) (xy 307.6168 -368.630233) (xy 307.660137 -368.674983) (xy 307.697397 -368.724907)
			(xy 307.727966 -368.779186) (xy 307.751344 -368.836929) (xy 307.767145 -368.897187) (xy 307.775111 -368.95897)
			(xy 307.77561 -368.990118) (xy 307.775111 -369.021266) (xy 307.767145 -369.083049) (xy 307.751344 -369.143307)
			(xy 307.727966 -369.20105) (xy 307.697397 -369.255329) (xy 307.660137 -369.305253) (xy 307.6168 -369.350003)
			(xy 307.568095 -369.388843) (xy 307.514824 -369.421136) (xy 307.457861 -369.446353) (xy 307.39814 -369.464077)
			(xy 307.336643 -369.47402) (xy 307.27438 -369.476016) (xy 307.212373 -369.470034) (xy 307.151639 -369.456172)
			(xy 307.093177 -369.434658) (xy 307.037946 -369.405844) (xy 306.986854 -369.370204) (xy 306.940738 -369.328323)
			(xy 306.900356 -369.280888) (xy 306.866372 -369.228679) (xy 306.839343 -369.172553) (xy 306.819714 -369.113432)
			(xy 306.807805 -369.052285) (xy 306.803814 -368.990118) (xy 305.010566 -368.990118) (xy 305.014376 -369.007898)
			(xy 305.024565 -369.058658) (xy 305.035511 -369.161616) (xy 305.03622 -369.213384) (xy 305.03622 -369.932458)
			(xy 305.036654 -369.942523) (xy 305.044386 -369.96111) (xy 305.051206 -369.968526) (xy 305.079654 -369.99672)
			(xy 305.096926 -370.00434) (xy 305.106832 -370.004594) (xy 305.137886 -370.006179) (xy 305.199242 -370.016273)
			(xy 305.258807 -370.034115) (xy 305.315609 -370.059413) (xy 305.368717 -370.091753) (xy 305.417263 -370.130608)
			(xy 305.460454 -370.17534) (xy 305.497582 -370.225219) (xy 305.528041 -370.279429) (xy 305.551331 -370.337083)
			(xy 305.567074 -370.397237) (xy 305.57501 -370.458909) (xy 305.57501 -370.52109) (xy 305.567074 -370.582762)
			(xy 305.551332 -370.642917) (xy 305.528041 -370.70057) (xy 305.497583 -370.75478) (xy 305.460454 -370.804659)
			(xy 305.417264 -370.849392) (xy 305.368718 -370.888246) (xy 305.31561 -370.920587) (xy 305.258808 -370.945885)
			(xy 305.199242 -370.963727) (xy 305.137887 -370.973821) (xy 305.106832 -370.975382) (xy 305.096926 -370.975636)
			(xy 305.079654 -370.983256) (xy 305.051206 -371.01145) (xy 305.044367 -371.018851) (xy 305.03665 -371.037449)
			(xy 305.03622 -371.047518) (xy 305.03622 -371.232684) (xy 305.036659 -371.242747) (xy 305.044397 -371.261327)
			(xy 305.051206 -371.268752) (xy 305.079654 -371.296946) (xy 305.096926 -371.304566) (xy 305.106832 -371.30482)
			(xy 305.137884 -371.306405) (xy 305.199237 -371.316498) (xy 305.258799 -371.334339) (xy 305.315598 -371.359636)
			(xy 305.368703 -371.391975) (xy 305.417247 -371.430828) (xy 305.460435 -371.475558) (xy 305.497561 -371.525434)
			(xy 305.528018 -371.579641) (xy 305.532228 -371.590062) (xy 306.803814 -371.590062) (xy 306.807805 -371.527895)
			(xy 306.819714 -371.466748) (xy 306.839343 -371.407627) (xy 306.866372 -371.351501) (xy 306.900356 -371.299292)
			(xy 306.940738 -371.251857) (xy 306.986854 -371.209976) (xy 307.037946 -371.174336) (xy 307.093177 -371.145522)
			(xy 307.151639 -371.124008) (xy 307.212373 -371.110146) (xy 307.27438 -371.104164) (xy 307.336643 -371.10616)
			(xy 307.39814 -371.116103) (xy 307.457861 -371.133827) (xy 307.514824 -371.159044) (xy 307.568095 -371.191337)
			(xy 307.6168 -371.230177) (xy 307.660137 -371.274927) (xy 307.697397 -371.324851) (xy 307.727966 -371.37913)
			(xy 307.751344 -371.436873) (xy 307.767145 -371.497131) (xy 307.775111 -371.558914) (xy 307.77561 -371.590062)
			(xy 307.775111 -371.62121) (xy 307.767145 -371.682993) (xy 307.751344 -371.743251) (xy 307.727966 -371.800994)
			(xy 307.697397 -371.855273) (xy 307.660137 -371.905197) (xy 307.6168 -371.949947) (xy 307.568095 -371.988787)
			(xy 307.514824 -372.02108) (xy 307.457861 -372.046297) (xy 307.39814 -372.064021) (xy 307.336643 -372.073964)
			(xy 307.27438 -372.07596) (xy 307.212373 -372.069978) (xy 307.151639 -372.056116) (xy 307.093177 -372.034602)
			(xy 307.037946 -372.005788) (xy 306.986854 -371.970148) (xy 306.940738 -371.928267) (xy 306.900356 -371.880832)
			(xy 306.866372 -371.828623) (xy 306.839343 -371.772497) (xy 306.819714 -371.713376) (xy 306.807805 -371.652229)
			(xy 306.803814 -371.590062) (xy 305.532228 -371.590062) (xy 305.551307 -371.637292) (xy 305.567048 -371.697443)
			(xy 305.574984 -371.759112) (xy 305.574984 -371.821289) (xy 305.567048 -371.882958) (xy 305.551307 -371.943109)
			(xy 305.528017 -372.00076) (xy 305.49756 -372.054967) (xy 305.460434 -372.104843) (xy 305.417246 -372.149573)
			(xy 305.368702 -372.188425) (xy 305.315597 -372.220764) (xy 305.258798 -372.246061) (xy 305.199236 -372.263902)
			(xy 305.137883 -372.273995) (xy 305.106832 -372.275608) (xy 305.096926 -372.275862) (xy 305.079654 -372.283482)
			(xy 305.051206 -372.311676) (xy 305.044371 -372.319078) (xy 305.036663 -372.337677) (xy 305.03622 -372.347744)
			(xy 305.03622 -372.890034) (xy 306.803814 -372.890034) (xy 306.807805 -372.827867) (xy 306.819714 -372.76672)
			(xy 306.839343 -372.707599) (xy 306.866372 -372.651473) (xy 306.900356 -372.599264) (xy 306.940738 -372.551829)
			(xy 306.986854 -372.509948) (xy 307.037946 -372.474308) (xy 307.093177 -372.445494) (xy 307.151639 -372.42398)
			(xy 307.212373 -372.410118) (xy 307.27438 -372.404136) (xy 307.336643 -372.406132) (xy 307.39814 -372.416075)
			(xy 307.457861 -372.433799) (xy 307.514824 -372.459016) (xy 307.568095 -372.491309) (xy 307.6168 -372.530149)
			(xy 307.660137 -372.574899) (xy 307.697397 -372.624823) (xy 307.727966 -372.679102) (xy 307.751344 -372.736845)
			(xy 307.767145 -372.797103) (xy 307.775111 -372.858886) (xy 307.77561 -372.890034) (xy 307.775111 -372.921182)
			(xy 307.767145 -372.982965) (xy 307.751344 -373.043223) (xy 307.727966 -373.100966) (xy 307.697397 -373.155245)
			(xy 307.660137 -373.205169) (xy 307.6168 -373.249919) (xy 307.568095 -373.288759) (xy 307.514824 -373.321052)
			(xy 307.457861 -373.346269) (xy 307.39814 -373.363993) (xy 307.336643 -373.373936) (xy 307.27438 -373.375932)
			(xy 307.212373 -373.36995) (xy 307.151639 -373.356088) (xy 307.093177 -373.334574) (xy 307.037946 -373.30576)
			(xy 306.986854 -373.27012) (xy 306.940738 -373.228239) (xy 306.900356 -373.180804) (xy 306.866372 -373.128595)
			(xy 306.839343 -373.072469) (xy 306.819714 -373.013348) (xy 306.807805 -372.952201) (xy 306.803814 -372.890034)
			(xy 305.03622 -372.890034) (xy 305.03622 -373.832628) (xy 305.036649 -373.842696) (xy 305.044373 -373.861291)
			(xy 305.051206 -373.868696) (xy 305.079654 -373.89689) (xy 305.096926 -373.90451) (xy 305.106832 -373.904764)
			(xy 305.137888 -373.906349) (xy 305.199247 -373.916443) (xy 305.258817 -373.934286) (xy 305.315622 -373.959586)
			(xy 305.368733 -373.991928) (xy 305.417283 -374.030785) (xy 305.460476 -374.07552) (xy 305.497607 -374.125402)
			(xy 305.528067 -374.179615) (xy 305.55136 -374.237272) (xy 305.567103 -374.297431) (xy 305.575039 -374.359106)
			(xy 305.57504 -374.421291) (xy 305.567103 -374.482966) (xy 305.551361 -374.543125) (xy 305.528068 -374.600782)
			(xy 305.497608 -374.654995) (xy 305.460478 -374.704878) (xy 305.417285 -374.749613) (xy 305.368736 -374.78847)
			(xy 305.315624 -374.820813) (xy 305.258819 -374.846113) (xy 305.19925 -374.863956) (xy 305.137891 -374.874051)
			(xy 305.106832 -374.875552) (xy 305.096926 -374.875806) (xy 305.079654 -374.883426) (xy 305.051206 -374.91162)
			(xy 305.044362 -374.919019) (xy 305.036634 -374.937617) (xy 305.03622 -374.947688) (xy 305.03622 -375.1326)
			(xy 305.036644 -375.14267) (xy 305.04436 -375.161272) (xy 305.051206 -375.168668) (xy 305.079654 -375.196862)
			(xy 305.096926 -375.204482) (xy 305.106832 -375.204736) (xy 305.137883 -375.206321) (xy 305.199233 -375.216414)
			(xy 305.258794 -375.234254) (xy 305.315591 -375.259551) (xy 305.368694 -375.291889) (xy 305.417236 -375.33074)
			(xy 305.460423 -375.375469) (xy 305.497548 -375.425343) (xy 305.528003 -375.479548) (xy 305.532319 -375.490232)
			(xy 306.803814 -375.490232) (xy 306.807805 -375.428065) (xy 306.819714 -375.366918) (xy 306.839343 -375.307797)
			(xy 306.866372 -375.251671) (xy 306.900356 -375.199462) (xy 306.940738 -375.152027) (xy 306.986854 -375.110146)
			(xy 307.037946 -375.074506) (xy 307.093177 -375.045692) (xy 307.151639 -375.024178) (xy 307.212373 -375.010316)
			(xy 307.27438 -375.004334) (xy 307.336643 -375.00633) (xy 307.39814 -375.016273) (xy 307.457861 -375.033997)
			(xy 307.514824 -375.059214) (xy 307.568095 -375.091507) (xy 307.6168 -375.130347) (xy 307.660137 -375.175097)
			(xy 307.697397 -375.225021) (xy 307.727966 -375.2793) (xy 307.751344 -375.337043) (xy 307.767145 -375.397301)
			(xy 307.775111 -375.459084) (xy 307.77561 -375.490232) (xy 307.775111 -375.52138) (xy 307.767145 -375.583163)
			(xy 307.751344 -375.643421) (xy 307.727966 -375.701164) (xy 307.697397 -375.755443) (xy 307.660137 -375.805367)
			(xy 307.6168 -375.850117) (xy 307.568095 -375.888957) (xy 307.514824 -375.92125) (xy 307.457861 -375.946467)
			(xy 307.39814 -375.964191) (xy 307.336643 -375.974134) (xy 307.27438 -375.97613) (xy 307.212373 -375.970148)
			(xy 307.151639 -375.956286) (xy 307.093177 -375.934772) (xy 307.037946 -375.905958) (xy 306.986854 -375.870318)
			(xy 306.940738 -375.828437) (xy 306.900356 -375.781002) (xy 306.866372 -375.728793) (xy 306.839343 -375.672667)
			(xy 306.819714 -375.613546) (xy 306.807805 -375.552399) (xy 306.803814 -375.490232) (xy 305.532319 -375.490232)
			(xy 305.551292 -375.537197) (xy 305.567033 -375.597347) (xy 305.574968 -375.659013) (xy 305.574968 -375.721189)
			(xy 305.567032 -375.782855) (xy 305.551291 -375.843005) (xy 305.528003 -375.900653) (xy 305.497546 -375.954858)
			(xy 305.460421 -376.004733) (xy 305.417235 -376.049462) (xy 305.368692 -376.088313) (xy 305.315589 -376.12065)
			(xy 305.258792 -376.145946) (xy 305.199231 -376.163787) (xy 305.137881 -376.173879) (xy 305.106832 -376.175524)
			(xy 305.096926 -376.175778) (xy 305.079654 -376.183398) (xy 305.051206 -376.211592) (xy 305.044358 -376.21899)
			(xy 305.036619 -376.237588) (xy 305.03622 -376.24766) (xy 305.03622 -376.790204) (xy 306.803814 -376.790204)
			(xy 306.807805 -376.728037) (xy 306.819714 -376.66689) (xy 306.839343 -376.607769) (xy 306.866372 -376.551643)
			(xy 306.900356 -376.499434) (xy 306.940738 -376.451999) (xy 306.986854 -376.410118) (xy 307.037946 -376.374478)
			(xy 307.093177 -376.345664) (xy 307.151639 -376.32415) (xy 307.212373 -376.310288) (xy 307.27438 -376.304306)
			(xy 307.336643 -376.306302) (xy 307.39814 -376.316245) (xy 307.457861 -376.333969) (xy 307.514824 -376.359186)
			(xy 307.568095 -376.391479) (xy 307.6168 -376.430319) (xy 307.660137 -376.475069) (xy 307.697397 -376.524993)
			(xy 307.727966 -376.579272) (xy 307.751344 -376.637015) (xy 307.767145 -376.697273) (xy 307.775111 -376.759056)
			(xy 307.77561 -376.790204) (xy 307.775111 -376.821352) (xy 307.767145 -376.883135) (xy 307.751344 -376.943393)
			(xy 307.727966 -377.001136) (xy 307.697397 -377.055415) (xy 307.660137 -377.105339) (xy 307.6168 -377.150089)
			(xy 307.568095 -377.188929) (xy 307.514824 -377.221222) (xy 307.457861 -377.246439) (xy 307.39814 -377.264163)
			(xy 307.336643 -377.274106) (xy 307.27438 -377.276102) (xy 307.212373 -377.27012) (xy 307.151639 -377.256258)
			(xy 307.093177 -377.234744) (xy 307.037946 -377.20593) (xy 306.986854 -377.17029) (xy 306.940738 -377.128409)
			(xy 306.900356 -377.080974) (xy 306.866372 -377.028765) (xy 306.839343 -376.972639) (xy 306.819714 -376.913518)
			(xy 306.807805 -376.852371) (xy 306.803814 -376.790204) (xy 305.03622 -376.790204) (xy 305.03622 -377.732544)
			(xy 305.036652 -377.74261) (xy 305.04438 -377.761201) (xy 305.051206 -377.768612) (xy 305.079654 -377.796806)
			(xy 305.096926 -377.804426) (xy 305.106832 -377.80468) (xy 305.137887 -377.806265) (xy 305.199244 -377.816359)
			(xy 305.258812 -377.834201) (xy 305.315615 -377.8595) (xy 305.368725 -377.891842) (xy 305.417272 -377.930697)
			(xy 305.460464 -377.975431) (xy 305.497594 -378.025311) (xy 305.528053 -378.079522) (xy 305.551345 -378.137178)
			(xy 305.567087 -378.197334) (xy 305.575024 -378.259008) (xy 305.575024 -378.32119) (xy 305.567088 -378.382864)
			(xy 305.551345 -378.443021) (xy 305.528054 -378.500676) (xy 305.497595 -378.554887) (xy 305.460465 -378.604768)
			(xy 305.417274 -378.649502) (xy 305.368726 -378.688357) (xy 305.315616 -378.720699) (xy 305.258813 -378.745998)
			(xy 305.199246 -378.763841) (xy 305.137888 -378.773935) (xy 305.106832 -378.775468) (xy 305.096926 -378.775722)
			(xy 305.079654 -378.783342) (xy 305.051206 -378.811536) (xy 305.044365 -378.818936) (xy 305.036642 -378.837534)
			(xy 305.03622 -378.847604) (xy 305.03622 -379.032516) (xy 305.036647 -379.042584) (xy 305.044367 -379.061183)
			(xy 305.051206 -379.068584) (xy 305.079654 -379.096778) (xy 305.096926 -379.104398) (xy 305.106832 -379.104652)
			(xy 305.137882 -379.106237) (xy 305.19923 -379.11633) (xy 305.258789 -379.13417) (xy 305.315584 -379.159465)
			(xy 305.368685 -379.191802) (xy 305.417226 -379.230652) (xy 305.460411 -379.275379) (xy 305.497535 -379.325253)
			(xy 305.527989 -379.379456) (xy 305.532308 -379.390148) (xy 306.803814 -379.390148) (xy 306.807805 -379.327981)
			(xy 306.819714 -379.266834) (xy 306.839343 -379.207713) (xy 306.866372 -379.151587) (xy 306.900356 -379.099378)
			(xy 306.940738 -379.051943) (xy 306.986854 -379.010062) (xy 307.037946 -378.974422) (xy 307.093177 -378.945608)
			(xy 307.151639 -378.924094) (xy 307.212373 -378.910232) (xy 307.27438 -378.90425) (xy 307.336643 -378.906246)
			(xy 307.39814 -378.916189) (xy 307.457861 -378.933913) (xy 307.514824 -378.95913) (xy 307.568095 -378.991423)
			(xy 307.6168 -379.030263) (xy 307.660137 -379.075013) (xy 307.697397 -379.124937) (xy 307.727966 -379.179216)
			(xy 307.751344 -379.236959) (xy 307.767145 -379.297217) (xy 307.775111 -379.359) (xy 307.77561 -379.390148)
			(xy 307.775111 -379.421296) (xy 307.767145 -379.483079) (xy 307.751344 -379.543337) (xy 307.727966 -379.60108)
			(xy 307.697397 -379.655359) (xy 307.660137 -379.705283) (xy 307.6168 -379.750033) (xy 307.568095 -379.788873)
			(xy 307.514824 -379.821166) (xy 307.457861 -379.846383) (xy 307.39814 -379.864107) (xy 307.336643 -379.87405)
			(xy 307.27438 -379.876046) (xy 307.212373 -379.870064) (xy 307.151639 -379.856202) (xy 307.093177 -379.834688)
			(xy 307.037946 -379.805874) (xy 306.986854 -379.770234) (xy 306.940738 -379.728353) (xy 306.900356 -379.680918)
			(xy 306.866372 -379.628709) (xy 306.839343 -379.572583) (xy 306.819714 -379.513462) (xy 306.807805 -379.452315)
			(xy 306.803814 -379.390148) (xy 305.532308 -379.390148) (xy 305.551277 -379.437103) (xy 305.567017 -379.49725)
			(xy 305.574952 -379.558915) (xy 305.574952 -379.621088) (xy 305.567017 -379.682753) (xy 305.551276 -379.7429)
			(xy 305.527988 -379.800547) (xy 305.497533 -379.85475) (xy 305.460409 -379.904623) (xy 305.417224 -379.94935)
			(xy 305.368683 -379.9882) (xy 305.315581 -380.020537) (xy 305.258786 -380.045832) (xy 305.199227 -380.063671)
			(xy 305.137879 -380.073763) (xy 305.106832 -380.07544) (xy 305.096926 -380.075694) (xy 305.079654 -380.083314)
			(xy 305.051206 -380.111508) (xy 305.04436 -380.118907) (xy 305.036628 -380.137505) (xy 305.03622 -380.147576)
			(xy 305.03622 -380.69012) (xy 306.803814 -380.69012) (xy 306.807805 -380.627953) (xy 306.819714 -380.566806)
			(xy 306.839343 -380.507685) (xy 306.866372 -380.451559) (xy 306.900356 -380.39935) (xy 306.940738 -380.351915)
			(xy 306.986854 -380.310034) (xy 307.037946 -380.274394) (xy 307.093177 -380.24558) (xy 307.151639 -380.224066)
			(xy 307.212373 -380.210204) (xy 307.27438 -380.204222) (xy 307.336643 -380.206218) (xy 307.39814 -380.216161)
			(xy 307.457861 -380.233885) (xy 307.514824 -380.259102) (xy 307.568095 -380.291395) (xy 307.6168 -380.330235)
			(xy 307.660137 -380.374985) (xy 307.697397 -380.424909) (xy 307.727966 -380.479188) (xy 307.751344 -380.536931)
			(xy 307.767145 -380.597189) (xy 307.775111 -380.658972) (xy 307.77561 -380.69012) (xy 307.775111 -380.721268)
			(xy 307.767145 -380.783051) (xy 307.751344 -380.843309) (xy 307.727966 -380.901052) (xy 307.697397 -380.955331)
			(xy 307.660137 -381.005255) (xy 307.6168 -381.050005) (xy 307.568095 -381.088845) (xy 307.514824 -381.121138)
			(xy 307.457861 -381.146355) (xy 307.39814 -381.164079) (xy 307.336643 -381.174022) (xy 307.27438 -381.176018)
			(xy 307.212373 -381.170036) (xy 307.151639 -381.156174) (xy 307.093177 -381.13466) (xy 307.037946 -381.105846)
			(xy 306.986854 -381.070206) (xy 306.940738 -381.028325) (xy 306.900356 -380.98089) (xy 306.866372 -380.928681)
			(xy 306.839343 -380.872555) (xy 306.819714 -380.813434) (xy 306.807805 -380.752287) (xy 306.803814 -380.69012)
			(xy 305.03622 -380.69012) (xy 305.03622 -381.63246) (xy 305.036655 -381.642525) (xy 305.044387 -381.661112)
			(xy 305.051206 -381.668528) (xy 305.079654 -381.696722) (xy 305.096926 -381.704342) (xy 305.106832 -381.704596)
			(xy 305.137886 -381.706181) (xy 305.199241 -381.716275) (xy 305.258807 -381.734116) (xy 305.315608 -381.759415)
			(xy 305.368716 -381.791755) (xy 305.417262 -381.830609) (xy 305.460452 -381.875342) (xy 305.49758 -381.92522)
			(xy 305.528039 -381.97943) (xy 305.55133 -382.037083) (xy 305.567072 -382.097238) (xy 305.575008 -382.15891)
			(xy 305.575008 -382.22109) (xy 305.567072 -382.282761) (xy 305.55133 -382.342916) (xy 305.528039 -382.40057)
			(xy 305.497581 -382.454779) (xy 305.460453 -382.504658) (xy 305.417263 -382.54939) (xy 305.368717 -382.588244)
			(xy 305.315609 -382.620585) (xy 305.258807 -382.645883) (xy 305.199242 -382.663725) (xy 305.137886 -382.673819)
			(xy 305.106832 -382.675384) (xy 305.096926 -382.675638) (xy 305.079654 -382.683258) (xy 305.051206 -382.711452)
			(xy 305.044367 -382.718853) (xy 305.036651 -382.737451) (xy 305.03622 -382.74752) (xy 305.03622 -382.932686)
			(xy 305.036659 -382.942749) (xy 305.044398 -382.961329) (xy 305.051206 -382.968754) (xy 305.079654 -382.996948)
			(xy 305.096926 -383.004568) (xy 305.106832 -383.004822) (xy 305.137882 -383.006407) (xy 305.199231 -383.016501)
			(xy 305.258789 -383.034344) (xy 305.315582 -383.059643) (xy 305.368682 -383.091985) (xy 305.417219 -383.13084)
			(xy 305.460399 -383.175573) (xy 305.497515 -383.225451) (xy 305.527962 -383.27966) (xy 305.532163 -383.290064)
			(xy 306.803814 -383.290064) (xy 306.807805 -383.227897) (xy 306.819714 -383.16675) (xy 306.839343 -383.107629)
			(xy 306.866372 -383.051503) (xy 306.900356 -382.999294) (xy 306.940738 -382.951859) (xy 306.986854 -382.909978)
			(xy 307.037946 -382.874338) (xy 307.093177 -382.845524) (xy 307.151639 -382.82401) (xy 307.212373 -382.810148)
			(xy 307.27438 -382.804166) (xy 307.336643 -382.806162) (xy 307.39814 -382.816105) (xy 307.457861 -382.833829)
			(xy 307.514824 -382.859046) (xy 307.568095 -382.891339) (xy 307.6168 -382.930179) (xy 307.660137 -382.974929)
			(xy 307.697397 -383.024853) (xy 307.727966 -383.079132) (xy 307.751344 -383.136875) (xy 307.767145 -383.197133)
			(xy 307.775111 -383.258916) (xy 307.77561 -383.290064) (xy 307.775111 -383.321212) (xy 307.767145 -383.382995)
			(xy 307.751344 -383.443253) (xy 307.727966 -383.500996) (xy 307.697397 -383.555275) (xy 307.660137 -383.605199)
			(xy 307.6168 -383.649949) (xy 307.568095 -383.688789) (xy 307.514824 -383.721082) (xy 307.457861 -383.746299)
			(xy 307.39814 -383.764023) (xy 307.336643 -383.773966) (xy 307.27438 -383.775962) (xy 307.212373 -383.76998)
			(xy 307.151639 -383.756118) (xy 307.093177 -383.734604) (xy 307.037946 -383.70579) (xy 306.986854 -383.67015)
			(xy 306.940738 -383.628269) (xy 306.900356 -383.580834) (xy 306.866372 -383.528625) (xy 306.839343 -383.472499)
			(xy 306.819714 -383.413378) (xy 306.807805 -383.352231) (xy 306.803814 -383.290064) (xy 305.532163 -383.290064)
			(xy 305.551239 -383.337311) (xy 305.566968 -383.397462) (xy 305.574889 -383.459129) (xy 305.575462 -383.490216)
			(xy 305.574941 -383.522013) (xy 305.566639 -383.585062) (xy 305.550178 -383.646488) (xy 305.525841 -383.70524)
			(xy 305.494044 -383.760313) (xy 305.45533 -383.810764) (xy 305.410363 -383.855732) (xy 305.359911 -383.894445)
			(xy 305.304838 -383.926242) (xy 305.246086 -383.950579) (xy 305.18466 -383.967039) (xy 305.121611 -383.975341)
			(xy 305.089814 -383.975864) (xy 305.089306 -383.975864) (xy 305.070945 -383.975687) (xy 305.034329 -383.972891)
			(xy 305.016154 -383.970276) (xy 305.012344 -383.969768) (xy 305.01209 -383.969768) (xy 305.002689 -383.968699)
			(xy 304.984194 -383.972617) (xy 304.976022 -383.977388) (xy 304.959004 -383.98831) (xy 304.958496 -383.988818)
			(xy 304.952908 -383.99212) (xy 304.943764 -384.00228) (xy 304.939954 -384.010154) (xy 304.9397 -384.010408)
			(xy 304.913538 -384.061462) (xy 304.907442 -384.080766) (xy 304.904053 -384.109144) (xy 304.88987 -384.164505)
			(xy 304.867586 -384.217131) (xy 304.837698 -384.265842) (xy 304.800878 -384.309549) (xy 304.757948 -384.347272)
			(xy 304.70987 -384.378168) (xy 304.65772 -384.401545) (xy 304.630328 -384.409696) (xy 304.623724 -384.411474)
			(xy 304.612802 -384.417824) (xy 304.494946 -384.53568) (xy 304.482246 -384.548634) (xy 304.44079 -384.590036)
			(xy 306.803814 -384.590036) (xy 306.807805 -384.527869) (xy 306.819714 -384.466722) (xy 306.839343 -384.407601)
			(xy 306.866372 -384.351475) (xy 306.900356 -384.299266) (xy 306.940738 -384.251831) (xy 306.986854 -384.20995)
			(xy 307.037946 -384.17431) (xy 307.093177 -384.145496) (xy 307.151639 -384.123982) (xy 307.212373 -384.11012)
			(xy 307.27438 -384.104138) (xy 307.336643 -384.106134) (xy 307.39814 -384.116077) (xy 307.457861 -384.133801)
			(xy 307.514824 -384.159018) (xy 307.568095 -384.191311) (xy 307.6168 -384.230151) (xy 307.660137 -384.274901)
			(xy 307.697397 -384.324825) (xy 307.727966 -384.379104) (xy 307.751344 -384.436847) (xy 307.767145 -384.497105)
			(xy 307.775111 -384.558888) (xy 307.77561 -384.590036) (xy 307.775111 -384.621184) (xy 307.767145 -384.682967)
			(xy 307.751344 -384.743225) (xy 307.727966 -384.800968) (xy 307.697397 -384.855247) (xy 307.660137 -384.905171)
			(xy 307.6168 -384.949921) (xy 307.568095 -384.988761) (xy 307.514824 -385.021054) (xy 307.457861 -385.046271)
			(xy 307.39814 -385.063995) (xy 307.336643 -385.073938) (xy 307.27438 -385.075934) (xy 307.212373 -385.069952)
			(xy 307.151639 -385.05609) (xy 307.093177 -385.034576) (xy 307.037946 -385.005762) (xy 306.986854 -384.970122)
			(xy 306.940738 -384.928241) (xy 306.900356 -384.880806) (xy 306.866372 -384.828597) (xy 306.839343 -384.772471)
			(xy 306.819714 -384.71335) (xy 306.807805 -384.652203) (xy 306.803814 -384.590036) (xy 304.44079 -384.590036)
			(xy 304.28819 -384.742436) (xy 304.265838 -384.76428) (xy 304.253646 -384.776472) (xy 304.22157 -384.80782)
			(xy 304.152647 -384.865222) (xy 304.078808 -384.916143) (xy 304.000659 -384.960166) (xy 303.918843 -384.996927)
			(xy 303.834033 -385.026126) (xy 303.790604 -385.03733) (xy 303.779174 -385.041648) (xy 303.757741 -385.082693)
			(xy 303.70834 -385.161017) (xy 303.651891 -385.234426) (xy 303.588882 -385.302286) (xy 303.519855 -385.364014)
			(xy 303.445403 -385.419079) (xy 303.406048 -385.443476) (xy 303.397158 -385.449064) (xy 303.38522 -385.465574)
			(xy 303.369726 -385.534916) (xy 303.368047 -385.544734) (xy 303.371431 -385.564345) (xy 303.37633 -385.573016)
			(xy 303.376584 -385.573524) (xy 303.376838 -385.573778) (xy 303.394662 -385.602091) (xy 303.424415 -385.662017)
			(xy 303.44709 -385.724963) (xy 303.462387 -385.790096) (xy 303.470103 -385.856555) (xy 303.470564 -385.890008)
			(xy 303.470055 -385.924399) (xy 303.462264 -385.98983) (xy 318.109598 -385.98983) (xy 318.113669 -385.934208)
			(xy 318.125795 -385.879771) (xy 318.145718 -385.82768) (xy 318.173014 -385.779045) (xy 318.2071 -385.734902)
			(xy 318.247249 -385.696193) (xy 318.292607 -385.663742) (xy 318.342207 -385.638241) (xy 318.394991 -385.620234)
			(xy 318.449834 -385.610104) (xy 318.505568 -385.608067) (xy 318.561005 -385.614167) (xy 318.614962 -385.628273)
			(xy 318.666291 -385.650085) (xy 318.713897 -385.679139) (xy 318.756765 -385.714814) (xy 318.793982 -385.756351)
			(xy 318.824755 -385.802864) (xy 318.848427 -385.853361) (xy 318.864495 -385.906768) (xy 318.872615 -385.961944)
			(xy 318.873124 -385.98983) (xy 318.872615 -386.017716) (xy 318.864495 -386.072892) (xy 318.848427 -386.126299)
			(xy 318.824755 -386.176796) (xy 318.793982 -386.223309) (xy 318.756765 -386.264846) (xy 318.713897 -386.300521)
			(xy 318.666291 -386.329575) (xy 318.614962 -386.351387) (xy 318.561005 -386.365493) (xy 318.505568 -386.371593)
			(xy 318.449834 -386.369556) (xy 318.394991 -386.359426) (xy 318.342207 -386.341419) (xy 318.292607 -386.315918)
			(xy 318.247249 -386.283467) (xy 318.2071 -386.244758) (xy 318.173014 -386.200615) (xy 318.145718 -386.15198)
			(xy 318.125795 -386.099889) (xy 318.113669 -386.045452) (xy 318.109598 -385.98983) (xy 303.462264 -385.98983)
			(xy 303.461922 -385.9927) (xy 303.445772 -386.05956) (xy 303.42183 -386.124041) (xy 303.390432 -386.18524)
			(xy 303.35202 -386.242297) (xy 303.307132 -386.294414) (xy 303.282096 -386.317998) (xy 303.280826 -386.319268)
			(xy 303.278286 -386.322062) (xy 303.271951 -386.329334) (xy 303.264791 -386.347225) (xy 303.264316 -386.35686)
			(xy 303.264316 -388.06247) (xy 317.091058 -388.06247) (xy 317.095129 -388.006848) (xy 317.107255 -387.952411)
			(xy 317.127178 -387.90032) (xy 317.154474 -387.851685) (xy 317.18856 -387.807542) (xy 317.228709 -387.768833)
			(xy 317.274067 -387.736382) (xy 317.323667 -387.710881) (xy 317.376451 -387.692874) (xy 317.431294 -387.682744)
			(xy 317.487028 -387.680707) (xy 317.542465 -387.686807) (xy 317.596422 -387.700913) (xy 317.647751 -387.722725)
			(xy 317.695357 -387.751779) (xy 317.738225 -387.787454) (xy 317.775442 -387.828991) (xy 317.806215 -387.875504)
			(xy 317.829887 -387.926001) (xy 317.834952 -387.942836) (xy 320.392296 -387.942836) (xy 320.396367 -387.887214)
			(xy 320.408493 -387.832777) (xy 320.428416 -387.780686) (xy 320.455712 -387.732051) (xy 320.489798 -387.687908)
			(xy 320.529947 -387.649199) (xy 320.575305 -387.616748) (xy 320.624905 -387.591247) (xy 320.677689 -387.57324)
			(xy 320.732532 -387.56311) (xy 320.788266 -387.561073) (xy 320.843703 -387.567173) (xy 320.89766 -387.581279)
			(xy 320.948989 -387.603091) (xy 320.996595 -387.632145) (xy 321.039463 -387.66782) (xy 321.07668 -387.709357)
			(xy 321.107453 -387.75587) (xy 321.131125 -387.806367) (xy 321.147193 -387.859774) (xy 321.155313 -387.91495)
			(xy 321.155822 -387.942836) (xy 321.155313 -387.970722) (xy 321.147193 -388.025898) (xy 321.131125 -388.079305)
			(xy 321.107453 -388.129802) (xy 321.07668 -388.176315) (xy 321.039463 -388.217852) (xy 320.996595 -388.253527)
			(xy 320.948989 -388.282581) (xy 320.89766 -388.304393) (xy 320.843703 -388.318499) (xy 320.788266 -388.324599)
			(xy 320.732532 -388.322562) (xy 320.677689 -388.312432) (xy 320.624905 -388.294425) (xy 320.575305 -388.268924)
			(xy 320.529947 -388.236473) (xy 320.489798 -388.197764) (xy 320.455712 -388.153621) (xy 320.428416 -388.104986)
			(xy 320.408493 -388.052895) (xy 320.396367 -387.998458) (xy 320.392296 -387.942836) (xy 317.834952 -387.942836)
			(xy 317.845955 -387.979408) (xy 317.854075 -388.034584) (xy 317.854584 -388.06247) (xy 317.854075 -388.090356)
			(xy 317.845955 -388.145532) (xy 317.829887 -388.198939) (xy 317.806215 -388.249436) (xy 317.775442 -388.295949)
			(xy 317.738225 -388.337486) (xy 317.695357 -388.373161) (xy 317.647751 -388.402215) (xy 317.596422 -388.424027)
			(xy 317.542465 -388.438133) (xy 317.487028 -388.444233) (xy 317.431294 -388.442196) (xy 317.376451 -388.432066)
			(xy 317.323667 -388.414059) (xy 317.274067 -388.388558) (xy 317.228709 -388.356107) (xy 317.18856 -388.317398)
			(xy 317.154474 -388.273255) (xy 317.127178 -388.22462) (xy 317.107255 -388.172529) (xy 317.095129 -388.118092)
			(xy 317.091058 -388.06247) (xy 303.264316 -388.06247) (xy 303.264316 -388.958836) (xy 318.203832 -388.958836)
			(xy 318.207903 -388.903214) (xy 318.220029 -388.848777) (xy 318.239952 -388.796686) (xy 318.267248 -388.748051)
			(xy 318.301334 -388.703908) (xy 318.341483 -388.665199) (xy 318.386841 -388.632748) (xy 318.436441 -388.607247)
			(xy 318.489225 -388.58924) (xy 318.544068 -388.57911) (xy 318.599802 -388.577073) (xy 318.655239 -388.583173)
			(xy 318.709196 -388.597279) (xy 318.760525 -388.619091) (xy 318.808131 -388.648145) (xy 318.850999 -388.68382)
			(xy 318.888216 -388.725357) (xy 318.918989 -388.77187) (xy 318.942661 -388.822367) (xy 318.958729 -388.875774)
			(xy 318.966849 -388.93095) (xy 318.967358 -388.958836) (xy 321.520564 -388.958836) (xy 321.524635 -388.903214)
			(xy 321.536761 -388.848777) (xy 321.556684 -388.796686) (xy 321.58398 -388.748051) (xy 321.618066 -388.703908)
			(xy 321.658215 -388.665199) (xy 321.703573 -388.632748) (xy 321.753173 -388.607247) (xy 321.805957 -388.58924)
			(xy 321.8608 -388.57911) (xy 321.916534 -388.577073) (xy 321.971971 -388.583173) (xy 322.025928 -388.597279)
			(xy 322.077257 -388.619091) (xy 322.124863 -388.648145) (xy 322.167731 -388.68382) (xy 322.204948 -388.725357)
			(xy 322.235721 -388.77187) (xy 322.259393 -388.822367) (xy 322.275461 -388.875774) (xy 322.283581 -388.93095)
			(xy 322.28409 -388.958836) (xy 322.283581 -388.986722) (xy 322.275461 -389.041898) (xy 322.259393 -389.095305)
			(xy 322.235721 -389.145802) (xy 322.204948 -389.192315) (xy 322.167731 -389.233852) (xy 322.124863 -389.269527)
			(xy 322.077257 -389.298581) (xy 322.025928 -389.320393) (xy 321.971971 -389.334499) (xy 321.916534 -389.340599)
			(xy 321.8608 -389.338562) (xy 321.805957 -389.328432) (xy 321.753173 -389.310425) (xy 321.703573 -389.284924)
			(xy 321.658215 -389.252473) (xy 321.618066 -389.213764) (xy 321.58398 -389.169621) (xy 321.556684 -389.120986)
			(xy 321.536761 -389.068895) (xy 321.524635 -389.014458) (xy 321.520564 -388.958836) (xy 318.967358 -388.958836)
			(xy 318.966849 -388.986722) (xy 318.958729 -389.041898) (xy 318.942661 -389.095305) (xy 318.918989 -389.145802)
			(xy 318.888216 -389.192315) (xy 318.850999 -389.233852) (xy 318.808131 -389.269527) (xy 318.760525 -389.298581)
			(xy 318.709196 -389.320393) (xy 318.655239 -389.334499) (xy 318.599802 -389.340599) (xy 318.544068 -389.338562)
			(xy 318.489225 -389.328432) (xy 318.436441 -389.310425) (xy 318.386841 -389.284924) (xy 318.341483 -389.252473)
			(xy 318.301334 -389.213764) (xy 318.267248 -389.169621) (xy 318.239952 -389.120986) (xy 318.220029 -389.068895)
			(xy 318.207903 -389.014458) (xy 318.203832 -388.958836) (xy 303.264316 -388.958836) (xy 303.264316 -389.974836)
			(xy 317.228218 -389.974836) (xy 317.232289 -389.919214) (xy 317.244415 -389.864777) (xy 317.264338 -389.812686)
			(xy 317.291634 -389.764051) (xy 317.32572 -389.719908) (xy 317.365869 -389.681199) (xy 317.411227 -389.648748)
			(xy 317.460827 -389.623247) (xy 317.513611 -389.60524) (xy 317.568454 -389.59511) (xy 317.624188 -389.593073)
			(xy 317.679625 -389.599173) (xy 317.733582 -389.613279) (xy 317.784911 -389.635091) (xy 317.832517 -389.664145)
			(xy 317.875385 -389.69982) (xy 317.912602 -389.741357) (xy 317.943375 -389.78787) (xy 317.967047 -389.838367)
			(xy 317.983115 -389.891774) (xy 317.991235 -389.94695) (xy 317.991744 -389.974836) (xy 320.392296 -389.974836)
			(xy 320.396367 -389.919214) (xy 320.408493 -389.864777) (xy 320.428416 -389.812686) (xy 320.455712 -389.764051)
			(xy 320.489798 -389.719908) (xy 320.529947 -389.681199) (xy 320.575305 -389.648748) (xy 320.624905 -389.623247)
			(xy 320.677689 -389.60524) (xy 320.732532 -389.59511) (xy 320.788266 -389.593073) (xy 320.843703 -389.599173)
			(xy 320.89766 -389.613279) (xy 320.948989 -389.635091) (xy 320.996595 -389.664145) (xy 321.039463 -389.69982)
			(xy 321.07668 -389.741357) (xy 321.107453 -389.78787) (xy 321.131125 -389.838367) (xy 321.147193 -389.891774)
			(xy 321.155313 -389.94695) (xy 321.155822 -389.974836) (xy 321.155313 -390.002722) (xy 321.147193 -390.057898)
			(xy 321.131125 -390.111305) (xy 321.107453 -390.161802) (xy 321.07668 -390.208315) (xy 321.039463 -390.249852)
			(xy 320.996595 -390.285527) (xy 320.948989 -390.314581) (xy 320.89766 -390.336393) (xy 320.843703 -390.350499)
			(xy 320.788266 -390.356599) (xy 320.732532 -390.354562) (xy 320.677689 -390.344432) (xy 320.624905 -390.326425)
			(xy 320.575305 -390.300924) (xy 320.529947 -390.268473) (xy 320.489798 -390.229764) (xy 320.455712 -390.185621)
			(xy 320.428416 -390.136986) (xy 320.408493 -390.084895) (xy 320.396367 -390.030458) (xy 320.392296 -389.974836)
			(xy 317.991744 -389.974836) (xy 317.991235 -390.002722) (xy 317.983115 -390.057898) (xy 317.967047 -390.111305)
			(xy 317.943375 -390.161802) (xy 317.912602 -390.208315) (xy 317.875385 -390.249852) (xy 317.832517 -390.285527)
			(xy 317.784911 -390.314581) (xy 317.733582 -390.336393) (xy 317.679625 -390.350499) (xy 317.624188 -390.356599)
			(xy 317.568454 -390.354562) (xy 317.513611 -390.344432) (xy 317.460827 -390.326425) (xy 317.411227 -390.300924)
			(xy 317.365869 -390.268473) (xy 317.32572 -390.229764) (xy 317.291634 -390.185621) (xy 317.264338 -390.136986)
			(xy 317.244415 -390.084895) (xy 317.232289 -390.030458) (xy 317.228218 -389.974836) (xy 303.264316 -389.974836)
			(xy 303.264316 -390.990836) (xy 318.203832 -390.990836) (xy 318.207903 -390.935214) (xy 318.220029 -390.880777)
			(xy 318.239952 -390.828686) (xy 318.267248 -390.780051) (xy 318.301334 -390.735908) (xy 318.341483 -390.697199)
			(xy 318.386841 -390.664748) (xy 318.436441 -390.639247) (xy 318.489225 -390.62124) (xy 318.544068 -390.61111)
			(xy 318.599802 -390.609073) (xy 318.655239 -390.615173) (xy 318.709196 -390.629279) (xy 318.760525 -390.651091)
			(xy 318.808131 -390.680145) (xy 318.850999 -390.71582) (xy 318.888216 -390.757357) (xy 318.918989 -390.80387)
			(xy 318.942661 -390.854367) (xy 318.958729 -390.907774) (xy 318.966849 -390.96295) (xy 318.967358 -390.990836)
			(xy 321.482464 -390.990836) (xy 321.486535 -390.935214) (xy 321.498661 -390.880777) (xy 321.518584 -390.828686)
			(xy 321.54588 -390.780051) (xy 321.579966 -390.735908) (xy 321.620115 -390.697199) (xy 321.665473 -390.664748)
			(xy 321.715073 -390.639247) (xy 321.767857 -390.62124) (xy 321.8227 -390.61111) (xy 321.878434 -390.609073)
			(xy 321.933871 -390.615173) (xy 321.987828 -390.629279) (xy 322.039157 -390.651091) (xy 322.086763 -390.680145)
			(xy 322.129631 -390.71582) (xy 322.166848 -390.757357) (xy 322.197621 -390.80387) (xy 322.221293 -390.854367)
			(xy 322.237361 -390.907774) (xy 322.245481 -390.96295) (xy 322.24599 -390.990836) (xy 322.245481 -391.018722)
			(xy 322.237361 -391.073898) (xy 322.221293 -391.127305) (xy 322.197621 -391.177802) (xy 322.166848 -391.224315)
			(xy 322.129631 -391.265852) (xy 322.086763 -391.301527) (xy 322.039157 -391.330581) (xy 321.987828 -391.352393)
			(xy 321.933871 -391.366499) (xy 321.878434 -391.372599) (xy 321.8227 -391.370562) (xy 321.767857 -391.360432)
			(xy 321.715073 -391.342425) (xy 321.665473 -391.316924) (xy 321.620115 -391.284473) (xy 321.579966 -391.245764)
			(xy 321.54588 -391.201621) (xy 321.518584 -391.152986) (xy 321.498661 -391.100895) (xy 321.486535 -391.046458)
			(xy 321.482464 -390.990836) (xy 318.967358 -390.990836) (xy 318.966849 -391.018722) (xy 318.958729 -391.073898)
			(xy 318.942661 -391.127305) (xy 318.918989 -391.177802) (xy 318.888216 -391.224315) (xy 318.850999 -391.265852)
			(xy 318.808131 -391.301527) (xy 318.760525 -391.330581) (xy 318.709196 -391.352393) (xy 318.655239 -391.366499)
			(xy 318.599802 -391.372599) (xy 318.544068 -391.370562) (xy 318.489225 -391.360432) (xy 318.436441 -391.342425)
			(xy 318.386841 -391.316924) (xy 318.341483 -391.284473) (xy 318.301334 -391.245764) (xy 318.267248 -391.201621)
			(xy 318.239952 -391.152986) (xy 318.220029 -391.100895) (xy 318.207903 -391.046458) (xy 318.203832 -390.990836)
			(xy 303.264316 -390.990836) (xy 303.264316 -393.247372) (xy 303.264786 -393.257244) (xy 303.272245 -393.275528)
			(xy 303.278794 -393.282932) (xy 304.311304 -394.315696) (xy 304.326163 -394.330719) (xy 304.354747 -394.361845)
			(xy 304.368454 -394.377926) (xy 304.36947 -394.379196) (xy 304.397237 -394.410731) (xy 304.447909 -394.477764)
			(xy 304.492706 -394.548858) (xy 304.531304 -394.623498) (xy 304.547778 -394.662152) (xy 304.960782 -395.659102)
			(xy 304.978139 -395.702424) (xy 305.005572 -395.791634) (xy 305.024485 -395.88303) (xy 305.030124 -395.929358)
			(xy 305.03114 -395.938502) (xy 305.047142 -395.97076) (xy 305.054 -395.97711) (xy 305.076098 -395.99743)
			(xy 305.084988 -396.000986) (xy 305.093624 -396.004542) (xy 305.102768 -396.004796) (xy 305.133998 -396.006115)
			(xy 305.195754 -396.015787) (xy 305.255759 -396.033303) (xy 305.313021 -396.058373) (xy 305.366592 -396.090582)
			(xy 305.415589 -396.129398) (xy 305.4592 -396.17418) (xy 305.496706 -396.224187) (xy 305.527486 -396.278593)
			(xy 305.55103 -396.336498) (xy 305.566951 -396.396945) (xy 305.574985 -396.458936) (xy 305.575462 -396.49019)
			(xy 305.574968 -396.52128) (xy 305.567034 -396.582952) (xy 305.551295 -396.643108) (xy 305.528008 -396.700763)
			(xy 305.497554 -396.754975) (xy 305.460431 -396.804857) (xy 305.417246 -396.849595) (xy 305.368705 -396.888455)
			(xy 305.315601 -396.920803) (xy 305.258804 -396.946111) (xy 305.199242 -396.963963) (xy 305.137888 -396.974068)
			(xy 305.106832 -396.975584) (xy 305.096926 -396.975838) (xy 305.079654 -396.983458) (xy 305.051206 -397.011652)
			(xy 305.044367 -397.019053) (xy 305.036651 -397.037651) (xy 305.03622 -397.04772) (xy 305.03622 -397.232632)
			(xy 305.036649 -397.242699) (xy 305.044374 -397.261293) (xy 305.051206 -397.2687) (xy 305.079654 -397.296894)
			(xy 305.096926 -397.304514) (xy 305.106832 -397.304768) (xy 305.137887 -397.306353) (xy 305.199246 -397.316447)
			(xy 305.258815 -397.33429) (xy 305.31562 -397.359589) (xy 305.368731 -397.391932) (xy 305.41728 -397.430788)
			(xy 305.460473 -397.475523) (xy 305.497603 -397.525404) (xy 305.528064 -397.579617) (xy 305.532263 -397.59001)
			(xy 306.803814 -397.59001) (xy 306.807805 -397.527843) (xy 306.819714 -397.466696) (xy 306.839343 -397.407575)
			(xy 306.866372 -397.351449) (xy 306.900356 -397.29924) (xy 306.940738 -397.251805) (xy 306.986854 -397.209924)
			(xy 307.037946 -397.174284) (xy 307.093177 -397.14547) (xy 307.151639 -397.123956) (xy 307.212373 -397.110094)
			(xy 307.27438 -397.104112) (xy 307.336643 -397.106108) (xy 307.39814 -397.116051) (xy 307.457861 -397.133775)
			(xy 307.514824 -397.158992) (xy 307.568095 -397.191285) (xy 307.6168 -397.230125) (xy 307.660137 -397.274875)
			(xy 307.697397 -397.324799) (xy 307.727966 -397.379078) (xy 307.751344 -397.436821) (xy 307.767145 -397.497079)
			(xy 307.775111 -397.558862) (xy 307.77561 -397.59001) (xy 307.775111 -397.621158) (xy 307.767145 -397.682941)
			(xy 307.751344 -397.743199) (xy 307.727966 -397.800942) (xy 307.697397 -397.855221) (xy 307.660137 -397.905145)
			(xy 307.6168 -397.949895) (xy 307.568095 -397.988735) (xy 307.514824 -398.021028) (xy 307.457861 -398.046245)
			(xy 307.39814 -398.063969) (xy 307.336643 -398.073912) (xy 307.27438 -398.075908) (xy 307.212373 -398.069926)
			(xy 307.151639 -398.056064) (xy 307.093177 -398.03455) (xy 307.037946 -398.005736) (xy 306.986854 -397.970096)
			(xy 306.940738 -397.928215) (xy 306.900356 -397.88078) (xy 306.866372 -397.828571) (xy 306.839343 -397.772445)
			(xy 306.819714 -397.713324) (xy 306.807805 -397.652177) (xy 306.803814 -397.59001) (xy 305.532263 -397.59001)
			(xy 305.551356 -397.637274) (xy 305.567099 -397.697432) (xy 305.575036 -397.759107) (xy 305.575036 -397.821291)
			(xy 305.567099 -397.882966) (xy 305.551357 -397.943124) (xy 305.528065 -398.000781) (xy 305.497605 -398.054993)
			(xy 305.460475 -398.104875) (xy 305.417282 -398.14961) (xy 305.368733 -398.188467) (xy 305.315622 -398.220809)
			(xy 305.258818 -398.246109) (xy 305.199249 -398.263952) (xy 305.13789 -398.274047) (xy 305.106832 -398.275556)
			(xy 305.096926 -398.27581) (xy 305.079654 -398.28343) (xy 305.051206 -398.311624) (xy 305.044363 -398.319024)
			(xy 305.036636 -398.337622) (xy 305.03622 -398.347692) (xy 305.03622 -398.890236) (xy 306.803814 -398.890236)
			(xy 306.807805 -398.828069) (xy 306.819714 -398.766922) (xy 306.839343 -398.707801) (xy 306.866372 -398.651675)
			(xy 306.900356 -398.599466) (xy 306.940738 -398.552031) (xy 306.986854 -398.51015) (xy 307.037946 -398.47451)
			(xy 307.093177 -398.445696) (xy 307.151639 -398.424182) (xy 307.212373 -398.41032) (xy 307.27438 -398.404338)
			(xy 307.336643 -398.406334) (xy 307.39814 -398.416277) (xy 307.457861 -398.434001) (xy 307.514824 -398.459218)
			(xy 307.568095 -398.491511) (xy 307.6168 -398.530351) (xy 307.660137 -398.575101) (xy 307.697397 -398.625025)
			(xy 307.727966 -398.679304) (xy 307.751344 -398.737047) (xy 307.767145 -398.797305) (xy 307.775111 -398.859088)
			(xy 307.77561 -398.890236) (xy 307.775111 -398.921384) (xy 307.767145 -398.983167) (xy 307.751344 -399.043425)
			(xy 307.727966 -399.101168) (xy 307.697397 -399.155447) (xy 307.660137 -399.205371) (xy 307.6168 -399.250121)
			(xy 307.568095 -399.288961) (xy 307.514824 -399.321254) (xy 307.457861 -399.346471) (xy 307.39814 -399.364195)
			(xy 307.336643 -399.374138) (xy 307.27438 -399.376134) (xy 307.212373 -399.370152) (xy 307.151639 -399.35629)
			(xy 307.093177 -399.334776) (xy 307.037946 -399.305962) (xy 306.986854 -399.270322) (xy 306.940738 -399.228441)
			(xy 306.900356 -399.181006) (xy 306.866372 -399.128797) (xy 306.839343 -399.072671) (xy 306.819714 -399.01355)
			(xy 306.807805 -398.952403) (xy 306.803814 -398.890236) (xy 305.03622 -398.890236) (xy 305.03622 -399.832576)
			(xy 305.036657 -399.84264) (xy 305.044394 -399.861222) (xy 305.051206 -399.868644) (xy 305.079654 -399.896838)
			(xy 305.096926 -399.904458) (xy 305.106832 -399.904712) (xy 305.137885 -399.906297) (xy 305.199238 -399.91639)
			(xy 305.258802 -399.934232) (xy 305.315601 -399.959529) (xy 305.368707 -399.991869) (xy 305.417252 -400.030722)
			(xy 305.460441 -400.075452) (xy 305.497567 -400.12533) (xy 305.528025 -400.179537) (xy 305.551315 -400.237189)
			(xy 305.567056 -400.297341) (xy 305.574992 -400.359011) (xy 305.574992 -400.421189) (xy 305.567056 -400.482859)
			(xy 305.551314 -400.543012) (xy 305.528025 -400.600663) (xy 305.497567 -400.654871) (xy 305.46044 -400.704748)
			(xy 305.417251 -400.749479) (xy 305.368707 -400.788332) (xy 305.315601 -400.820671) (xy 305.258801 -400.845969)
			(xy 305.199238 -400.86381) (xy 305.137884 -400.873903) (xy 305.106832 -400.8755) (xy 305.096926 -400.875754)
			(xy 305.079654 -400.883374) (xy 305.051206 -400.911568) (xy 305.04437 -400.91897) (xy 305.036659 -400.937568)
			(xy 305.03622 -400.947636) (xy 305.03622 -401.132548) (xy 305.036652 -401.142614) (xy 305.044381 -401.161204)
			(xy 305.051206 -401.168616) (xy 305.079654 -401.19681) (xy 305.096926 -401.20443) (xy 305.106832 -401.204684)
			(xy 305.137886 -401.206269) (xy 305.199243 -401.216363) (xy 305.25881 -401.234205) (xy 305.315613 -401.259504)
			(xy 305.368722 -401.291845) (xy 305.41727 -401.3307) (xy 305.460461 -401.375434) (xy 305.49759 -401.425314)
			(xy 305.528049 -401.479524) (xy 305.532354 -401.49018) (xy 306.803814 -401.49018) (xy 306.807805 -401.428013)
			(xy 306.819714 -401.366866) (xy 306.839343 -401.307745) (xy 306.866372 -401.251619) (xy 306.900356 -401.19941)
			(xy 306.940738 -401.151975) (xy 306.986854 -401.110094) (xy 307.037946 -401.074454) (xy 307.093177 -401.04564)
			(xy 307.151639 -401.024126) (xy 307.212373 -401.010264) (xy 307.27438 -401.004282) (xy 307.336643 -401.006278)
			(xy 307.39814 -401.016221) (xy 307.457861 -401.033945) (xy 307.514824 -401.059162) (xy 307.568095 -401.091455)
			(xy 307.6168 -401.130295) (xy 307.660137 -401.175045) (xy 307.697397 -401.224969) (xy 307.727966 -401.279248)
			(xy 307.751344 -401.336991) (xy 307.767145 -401.397249) (xy 307.775111 -401.459032) (xy 307.77561 -401.49018)
			(xy 307.775111 -401.521328) (xy 307.767145 -401.583111) (xy 307.751344 -401.643369) (xy 307.727966 -401.701112)
			(xy 307.697397 -401.755391) (xy 307.660137 -401.805315) (xy 307.6168 -401.850065) (xy 307.568095 -401.888905)
			(xy 307.514824 -401.921198) (xy 307.457861 -401.946415) (xy 307.39814 -401.964139) (xy 307.336643 -401.974082)
			(xy 307.27438 -401.976078) (xy 307.212373 -401.970096) (xy 307.151639 -401.956234) (xy 307.093177 -401.93472)
			(xy 307.037946 -401.905906) (xy 306.986854 -401.870266) (xy 306.940738 -401.828385) (xy 306.900356 -401.78095)
			(xy 306.866372 -401.728741) (xy 306.839343 -401.672615) (xy 306.819714 -401.613494) (xy 306.807805 -401.552347)
			(xy 306.803814 -401.49018) (xy 305.532354 -401.49018) (xy 305.551341 -401.537179) (xy 305.567083 -401.597335)
			(xy 305.57502 -401.659008) (xy 305.57502 -401.72119) (xy 305.567084 -401.782863) (xy 305.551341 -401.843019)
			(xy 305.52805 -401.900674) (xy 305.497591 -401.954885) (xy 305.460462 -402.004765) (xy 305.417271 -402.049499)
			(xy 305.368724 -402.088354) (xy 305.315614 -402.120696) (xy 305.258812 -402.145994) (xy 305.199245 -402.163837)
			(xy 305.137888 -402.173931) (xy 305.106832 -402.175472) (xy 305.096926 -402.175726) (xy 305.079654 -402.183346)
			(xy 305.051206 -402.21154) (xy 305.044365 -402.21894) (xy 305.036644 -402.237539) (xy 305.03622 -402.247608)
			(xy 305.03622 -402.790152) (xy 306.803814 -402.790152) (xy 306.807805 -402.727985) (xy 306.819714 -402.666838)
			(xy 306.839343 -402.607717) (xy 306.866372 -402.551591) (xy 306.900356 -402.499382) (xy 306.940738 -402.451947)
			(xy 306.986854 -402.410066) (xy 307.037946 -402.374426) (xy 307.093177 -402.345612) (xy 307.151639 -402.324098)
			(xy 307.212373 -402.310236) (xy 307.27438 -402.304254) (xy 307.336643 -402.30625) (xy 307.39814 -402.316193)
			(xy 307.457861 -402.333917) (xy 307.514824 -402.359134) (xy 307.568095 -402.391427) (xy 307.6168 -402.430267)
			(xy 307.660137 -402.475017) (xy 307.697397 -402.524941) (xy 307.727966 -402.57922) (xy 307.751344 -402.636963)
			(xy 307.767145 -402.697221) (xy 307.775111 -402.759004) (xy 307.77561 -402.790152) (xy 307.775111 -402.8213)
			(xy 307.767145 -402.883083) (xy 307.751344 -402.943341) (xy 307.727966 -403.001084) (xy 307.697397 -403.055363)
			(xy 307.660137 -403.105287) (xy 307.6168 -403.150037) (xy 307.568095 -403.188877) (xy 307.514824 -403.22117)
			(xy 307.457861 -403.246387) (xy 307.39814 -403.264111) (xy 307.336643 -403.274054) (xy 307.27438 -403.27605)
			(xy 307.212373 -403.270068) (xy 307.151639 -403.256206) (xy 307.093177 -403.234692) (xy 307.037946 -403.205878)
			(xy 306.986854 -403.170238) (xy 306.940738 -403.128357) (xy 306.900356 -403.080922) (xy 306.866372 -403.028713)
			(xy 306.839343 -402.972587) (xy 306.819714 -402.913466) (xy 306.807805 -402.852319) (xy 306.803814 -402.790152)
			(xy 305.03622 -402.790152) (xy 305.03622 -403.732492) (xy 305.036642 -403.742562) (xy 305.044357 -403.761167)
			(xy 305.051206 -403.76856) (xy 305.079654 -403.796754) (xy 305.096926 -403.804374) (xy 305.106832 -403.804628)
			(xy 305.137884 -403.806213) (xy 305.199235 -403.816306) (xy 305.258797 -403.834147) (xy 305.315594 -403.859443)
			(xy 305.368699 -403.891782) (xy 305.417241 -403.930634) (xy 305.460429 -403.975363) (xy 305.497554 -404.025239)
			(xy 305.528011 -404.079445) (xy 305.5513 -404.137094) (xy 305.567041 -404.197245) (xy 305.574976 -404.258913)
			(xy 305.574976 -404.321089) (xy 305.56704 -404.382756) (xy 305.551299 -404.442907) (xy 305.52801 -404.500557)
			(xy 305.497553 -404.554763) (xy 305.460428 -404.604638) (xy 305.41724 -404.649367) (xy 305.368697 -404.688219)
			(xy 305.315593 -404.720557) (xy 305.258795 -404.745854) (xy 305.199234 -404.763694) (xy 305.137882 -404.773787)
			(xy 305.106832 -404.775416) (xy 305.096926 -404.77567) (xy 305.079654 -404.78329) (xy 305.051206 -404.811484)
			(xy 305.044372 -404.818887) (xy 305.036667 -404.837485) (xy 305.03622 -404.847552) (xy 305.03622 -405.032464)
			(xy 305.036655 -405.042529) (xy 305.044388 -405.061114) (xy 305.051206 -405.068532) (xy 305.079654 -405.096726)
			(xy 305.096926 -405.104346) (xy 305.106832 -405.1046) (xy 305.137885 -405.106185) (xy 305.19924 -405.116279)
			(xy 305.258805 -405.13412) (xy 305.315606 -405.159418) (xy 305.368714 -405.191758) (xy 305.41726 -405.230612)
			(xy 305.460449 -405.275344) (xy 305.497577 -405.325223) (xy 305.528035 -405.379432) (xy 305.532343 -405.390096)
			(xy 306.803814 -405.390096) (xy 306.807805 -405.327929) (xy 306.819714 -405.266782) (xy 306.839343 -405.207661)
			(xy 306.866372 -405.151535) (xy 306.900356 -405.099326) (xy 306.940738 -405.051891) (xy 306.986854 -405.01001)
			(xy 307.037946 -404.97437) (xy 307.093177 -404.945556) (xy 307.151639 -404.924042) (xy 307.212373 -404.91018)
			(xy 307.27438 -404.904198) (xy 307.336643 -404.906194) (xy 307.39814 -404.916137) (xy 307.457861 -404.933861)
			(xy 307.514824 -404.959078) (xy 307.568095 -404.991371) (xy 307.6168 -405.030211) (xy 307.660137 -405.074961)
			(xy 307.697397 -405.124885) (xy 307.727966 -405.179164) (xy 307.751344 -405.236907) (xy 307.767145 -405.297165)
			(xy 307.775111 -405.358948) (xy 307.77561 -405.390096) (xy 307.775111 -405.421244) (xy 307.767145 -405.483027)
			(xy 307.751344 -405.543285) (xy 307.727966 -405.601028) (xy 307.697397 -405.655307) (xy 307.660137 -405.705231)
			(xy 307.6168 -405.749981) (xy 307.568095 -405.788821) (xy 307.514824 -405.821114) (xy 307.457861 -405.846331)
			(xy 307.39814 -405.864055) (xy 307.336643 -405.873998) (xy 307.27438 -405.875994) (xy 307.212373 -405.870012)
			(xy 307.151639 -405.85615) (xy 307.093177 -405.834636) (xy 307.037946 -405.805822) (xy 306.986854 -405.770182)
			(xy 306.940738 -405.728301) (xy 306.900356 -405.680866) (xy 306.866372 -405.628657) (xy 306.839343 -405.572531)
			(xy 306.819714 -405.51341) (xy 306.807805 -405.452263) (xy 306.803814 -405.390096) (xy 305.532343 -405.390096)
			(xy 305.551326 -405.437085) (xy 305.567068 -405.497239) (xy 305.575004 -405.55891) (xy 305.575004 -405.62109)
			(xy 305.567068 -405.682761) (xy 305.551326 -405.742915) (xy 305.528035 -405.800568) (xy 305.497577 -405.854777)
			(xy 305.46045 -405.904655) (xy 305.41726 -405.949387) (xy 305.368714 -405.988241) (xy 305.315607 -406.020582)
			(xy 305.258806 -406.04588) (xy 305.199241 -406.063721) (xy 305.137886 -406.073815) (xy 305.106832 -406.075388)
			(xy 305.096926 -406.075642) (xy 305.079654 -406.083262) (xy 305.051206 -406.111456) (xy 305.044368 -406.118857)
			(xy 305.036653 -406.137455) (xy 305.03622 -406.147524) (xy 305.03622 -406.690068) (xy 306.803814 -406.690068)
			(xy 306.807805 -406.627901) (xy 306.819714 -406.566754) (xy 306.839343 -406.507633) (xy 306.866372 -406.451507)
			(xy 306.900356 -406.399298) (xy 306.940738 -406.351863) (xy 306.986854 -406.309982) (xy 307.037946 -406.274342)
			(xy 307.093177 -406.245528) (xy 307.151639 -406.224014) (xy 307.212373 -406.210152) (xy 307.27438 -406.20417)
			(xy 307.336643 -406.206166) (xy 307.39814 -406.216109) (xy 307.457861 -406.233833) (xy 307.514824 -406.25905)
			(xy 307.568095 -406.291343) (xy 307.6168 -406.330183) (xy 307.660137 -406.374933) (xy 307.697397 -406.424857)
			(xy 307.727966 -406.479136) (xy 307.751344 -406.536879) (xy 307.767145 -406.597137) (xy 307.775111 -406.65892)
			(xy 307.77561 -406.690068) (xy 307.775111 -406.721216) (xy 307.767145 -406.782999) (xy 307.751344 -406.843257)
			(xy 307.727966 -406.901) (xy 307.697397 -406.955279) (xy 307.660137 -407.005203) (xy 307.6168 -407.049953)
			(xy 307.568095 -407.088793) (xy 307.514824 -407.121086) (xy 307.457861 -407.146303) (xy 307.39814 -407.164027)
			(xy 307.336643 -407.17397) (xy 307.27438 -407.175966) (xy 307.212373 -407.169984) (xy 307.151639 -407.156122)
			(xy 307.093177 -407.134608) (xy 307.037946 -407.105794) (xy 306.986854 -407.070154) (xy 306.940738 -407.028273)
			(xy 306.900356 -406.980838) (xy 306.866372 -406.928629) (xy 306.839343 -406.872503) (xy 306.819714 -406.813382)
			(xy 306.807805 -406.752235) (xy 306.803814 -406.690068) (xy 305.03622 -406.690068) (xy 305.03622 -407.632662)
			(xy 305.036655 -407.642727) (xy 305.044387 -407.661313) (xy 305.051206 -407.66873) (xy 305.079654 -407.696924)
			(xy 305.096926 -407.704544) (xy 305.106832 -407.704798) (xy 305.137886 -407.706383) (xy 305.199241 -407.716477)
			(xy 305.258806 -407.734318) (xy 305.315607 -407.759616) (xy 305.368715 -407.791957) (xy 305.417261 -407.830811)
			(xy 305.460451 -407.875543) (xy 305.497579 -407.925422) (xy 305.528037 -407.979631) (xy 305.551328 -408.037284)
			(xy 305.56707 -408.097438) (xy 305.575006 -408.15911) (xy 305.575006 -408.22129) (xy 305.56707 -408.282961)
			(xy 305.551328 -408.343115) (xy 305.528037 -408.400769) (xy 305.497579 -408.454978) (xy 305.460451 -408.504857)
			(xy 305.417261 -408.549589) (xy 305.368715 -408.588443) (xy 305.315608 -408.620783) (xy 305.258807 -408.646081)
			(xy 305.199241 -408.663923) (xy 305.137886 -408.674017) (xy 305.106832 -408.675586) (xy 305.096926 -408.67584)
			(xy 305.079654 -408.68346) (xy 305.051206 -408.711654) (xy 305.044367 -408.719055) (xy 305.036652 -408.737653)
			(xy 305.03622 -408.747722) (xy 305.03622 -408.932634) (xy 305.03665 -408.942701) (xy 305.044375 -408.961295)
			(xy 305.051206 -408.968702) (xy 305.079654 -408.996896) (xy 305.096926 -409.004516) (xy 305.106832 -409.00477)
			(xy 305.137883 -409.006355) (xy 305.199235 -409.016449) (xy 305.258795 -409.034291) (xy 305.315592 -409.05959)
			(xy 305.368695 -409.091931) (xy 305.417235 -409.130785) (xy 305.460419 -409.175517) (xy 305.497541 -409.225395)
			(xy 305.527992 -409.279604) (xy 305.532196 -409.290012) (xy 306.803814 -409.290012) (xy 306.807805 -409.227845)
			(xy 306.819714 -409.166698) (xy 306.839343 -409.107577) (xy 306.866372 -409.051451) (xy 306.900356 -408.999242)
			(xy 306.940738 -408.951807) (xy 306.986854 -408.909926) (xy 307.037946 -408.874286) (xy 307.093177 -408.845472)
			(xy 307.151639 -408.823958) (xy 307.212373 -408.810096) (xy 307.27438 -408.804114) (xy 307.336643 -408.80611)
			(xy 307.39814 -408.816053) (xy 307.457861 -408.833777) (xy 307.514824 -408.858994) (xy 307.568095 -408.891287)
			(xy 307.6168 -408.930127) (xy 307.660137 -408.974877) (xy 307.697397 -409.024801) (xy 307.727966 -409.07908)
			(xy 307.751344 -409.136823) (xy 307.767145 -409.197081) (xy 307.775111 -409.258864) (xy 307.77561 -409.290012)
			(xy 307.775111 -409.32116) (xy 307.767145 -409.382943) (xy 307.751344 -409.443201) (xy 307.727966 -409.500944)
			(xy 307.697397 -409.555223) (xy 307.660137 -409.605147) (xy 307.6168 -409.649897) (xy 307.568095 -409.688737)
			(xy 307.514824 -409.72103) (xy 307.457861 -409.746247) (xy 307.39814 -409.763971) (xy 307.336643 -409.773914)
			(xy 307.27438 -409.77591) (xy 307.212373 -409.769928) (xy 307.151639 -409.756066) (xy 307.093177 -409.734552)
			(xy 307.037946 -409.705738) (xy 306.986854 -409.670098) (xy 306.940738 -409.628217) (xy 306.900356 -409.580782)
			(xy 306.866372 -409.528573) (xy 306.839343 -409.472447) (xy 306.819714 -409.413326) (xy 306.807805 -409.352179)
			(xy 306.803814 -409.290012) (xy 305.532196 -409.290012) (xy 305.551276 -409.337255) (xy 305.56701 -409.397408)
			(xy 305.574938 -409.459076) (xy 305.575462 -409.490164) (xy 305.574967 -409.521964) (xy 305.56667 -409.585021)
			(xy 305.550213 -409.646456) (xy 305.525878 -409.705217) (xy 305.494081 -409.760298) (xy 305.455366 -409.810758)
			(xy 305.410396 -409.855733) (xy 305.35994 -409.894453) (xy 305.304862 -409.926255) (xy 305.246103 -409.950597)
			(xy 305.18467 -409.96706) (xy 305.121614 -409.975364) (xy 305.089814 -409.975812) (xy 305.089306 -409.975812)
			(xy 305.070945 -409.975635) (xy 305.034329 -409.972839) (xy 305.016154 -409.970224) (xy 305.012344 -409.969716)
			(xy 305.01209 -409.969716) (xy 305.002688 -409.968647) (xy 304.984192 -409.972561) (xy 304.976022 -409.977336)
			(xy 304.959004 -409.988258) (xy 304.958496 -409.988766) (xy 304.952908 -409.992068) (xy 304.943764 -410.002228)
			(xy 304.939954 -410.010102) (xy 304.9397 -410.01061) (xy 304.922682 -410.044646) (xy 304.921412 -410.046932)
			(xy 304.92065 -410.04871) (xy 304.913792 -410.063188) (xy 304.91176 -410.067252) (xy 304.906934 -410.084524)
			(xy 304.906426 -410.088588) (xy 304.902253 -410.117873) (xy 304.886035 -410.174757) (xy 304.86123 -410.228455)
			(xy 304.828432 -410.27768) (xy 304.788428 -410.321251) (xy 304.742176 -410.358124) (xy 304.690786 -410.387414)
			(xy 304.663348 -410.398468) (xy 304.653188 -410.402278) (xy 304.465358 -410.589984) (xy 306.803814 -410.589984)
			(xy 306.807805 -410.527817) (xy 306.819714 -410.46667) (xy 306.839343 -410.407549) (xy 306.866372 -410.351423)
			(xy 306.900356 -410.299214) (xy 306.940738 -410.251779) (xy 306.986854 -410.209898) (xy 307.037946 -410.174258)
			(xy 307.093177 -410.145444) (xy 307.151639 -410.12393) (xy 307.212373 -410.110068) (xy 307.27438 -410.104086)
			(xy 307.336643 -410.106082) (xy 307.39814 -410.116025) (xy 307.457861 -410.133749) (xy 307.514824 -410.158966)
			(xy 307.568095 -410.191259) (xy 307.6168 -410.230099) (xy 307.660137 -410.274849) (xy 307.697397 -410.324773)
			(xy 307.727966 -410.379052) (xy 307.751344 -410.436795) (xy 307.767145 -410.497053) (xy 307.775111 -410.558836)
			(xy 307.77561 -410.589984) (xy 307.775111 -410.621132) (xy 307.767145 -410.682915) (xy 307.751344 -410.743173)
			(xy 307.727966 -410.800916) (xy 307.697397 -410.855195) (xy 307.660137 -410.905119) (xy 307.6168 -410.949869)
			(xy 307.568095 -410.988709) (xy 307.514824 -411.021002) (xy 307.457861 -411.046219) (xy 307.39814 -411.063943)
			(xy 307.336643 -411.073886) (xy 307.27438 -411.075882) (xy 307.212373 -411.0699) (xy 307.151639 -411.056038)
			(xy 307.093177 -411.034524) (xy 307.037946 -411.00571) (xy 306.986854 -410.97007) (xy 306.940738 -410.928189)
			(xy 306.900356 -410.880754) (xy 306.866372 -410.828545) (xy 306.839343 -410.772419) (xy 306.819714 -410.713298)
			(xy 306.807805 -410.652151) (xy 306.803814 -410.589984) (xy 304.465358 -410.589984) (xy 304.26914 -410.786072)
			(xy 304.236252 -410.818225) (xy 304.165509 -410.877012) (xy 304.089651 -410.929032) (xy 304.009325 -410.973845)
			(xy 303.925212 -411.011068) (xy 303.838028 -411.040386) (xy 303.793398 -411.051502) (xy 303.782984 -411.054042)
			(xy 303.766728 -411.065726) (xy 303.760632 -411.07614) (xy 303.760378 -411.076902) (xy 303.739231 -411.113739)
			(xy 303.691557 -411.184045) (xy 303.638078 -411.250043) (xy 303.579182 -411.311255) (xy 303.515294 -411.367237)
			(xy 303.446877 -411.417585) (xy 303.410874 -411.440122) (xy 303.410874 -411.440376) (xy 303.405286 -411.443678)
			(xy 303.401182 -411.446413) (xy 303.394017 -411.453191) (xy 303.391062 -411.45714) (xy 303.390808 -411.457648)
			(xy 303.387857 -411.461988) (xy 303.383621 -411.471588) (xy 303.382426 -411.476698) (xy 303.3776 -411.498542)
			(xy 303.376584 -411.50921) (xy 303.376584 -411.55874) (xy 303.376851 -411.565627) (xy 303.380587 -411.578887)
			(xy 303.38395 -411.584902) (xy 303.384204 -411.58541) (xy 303.384458 -411.585664) (xy 303.400853 -411.613189)
			(xy 303.428192 -411.671133) (xy 303.449 -411.731729) (xy 303.463027 -411.794244) (xy 303.470102 -411.857922)
			(xy 303.470564 -411.889956) (xy 303.470564 -411.89021) (xy 303.470055 -411.924601) (xy 303.461922 -411.992902)
			(xy 303.445771 -412.059761) (xy 303.434503 -412.090108) (xy 304.603666 -412.090108) (xy 304.607657 -412.027941)
			(xy 304.619566 -411.966794) (xy 304.639195 -411.907673) (xy 304.666224 -411.851547) (xy 304.700208 -411.799338)
			(xy 304.74059 -411.751903) (xy 304.786706 -411.710022) (xy 304.837798 -411.674382) (xy 304.893029 -411.645568)
			(xy 304.951491 -411.624054) (xy 305.012225 -411.610192) (xy 305.074232 -411.60421) (xy 305.136495 -411.606206)
			(xy 305.197992 -411.616149) (xy 305.257713 -411.633873) (xy 305.314676 -411.65909) (xy 305.367947 -411.691383)
			(xy 305.416652 -411.730223) (xy 305.459989 -411.774973) (xy 305.497249 -411.824897) (xy 305.527818 -411.879176)
			(xy 305.551196 -411.936919) (xy 305.566997 -411.997177) (xy 305.574963 -412.05896) (xy 305.575462 -412.090108)
			(xy 305.574963 -412.121256) (xy 305.566997 -412.183039) (xy 305.551196 -412.243297) (xy 305.527818 -412.30104)
			(xy 305.497249 -412.355319) (xy 305.459989 -412.405243) (xy 305.416652 -412.449993) (xy 305.367947 -412.488833)
			(xy 305.314676 -412.521126) (xy 305.257713 -412.546343) (xy 305.197992 -412.564067) (xy 305.136495 -412.57401)
			(xy 305.074232 -412.576006) (xy 305.012225 -412.570024) (xy 304.951491 -412.556162) (xy 304.893029 -412.534648)
			(xy 304.837798 -412.505834) (xy 304.786706 -412.470194) (xy 304.74059 -412.428313) (xy 304.700208 -412.380878)
			(xy 304.666224 -412.328669) (xy 304.639195 -412.272543) (xy 304.619566 -412.213422) (xy 304.607657 -412.152275)
			(xy 304.603666 -412.090108) (xy 303.434503 -412.090108) (xy 303.421829 -412.124243) (xy 303.390432 -412.185441)
			(xy 303.352019 -412.242499) (xy 303.307131 -412.294615) (xy 303.282096 -412.3182) (xy 303.280826 -412.31947)
			(xy 303.278286 -412.322264) (xy 303.271951 -412.329536) (xy 303.264792 -412.347427) (xy 303.264316 -412.357062)
			(xy 303.264316 -414.78581) (xy 303.264775 -414.795687) (xy 303.272218 -414.813987) (xy 303.278794 -414.82137)
			(xy 305.006502 -416.549078) (xy 305.00701 -416.549586) (xy 305.014391 -416.556172) (xy 305.032689 -416.563632)
			(xy 305.04257 -416.564064)
		)
		(stroke
			(width 0)
			(type solid)
		)
		(fill yes)
		(layer "In5.Cu")
		(net "GND")
	)
	(gr_poly
		(pts
			(xy 52.569872 -417.143692) (xy 52.579936 -417.143255) (xy 52.598521 -417.135522) (xy 52.60594 -417.128706)
			(xy 52.921154 -416.813238) (xy 52.927996 -416.805838) (xy 52.935715 -416.78724) (xy 52.93614 -416.77717)
			(xy 52.93614 -394.27785) (xy 52.936574 -394.267785) (xy 52.944305 -394.249197) (xy 52.951126 -394.241782)
			(xy 53.023008 -394.1699) (xy 53.030407 -394.163055) (xy 53.049005 -394.155323) (xy 53.059076 -394.154914)
			(xy 66.476626 -394.154914) (xy 66.486694 -394.155342) (xy 66.50529 -394.163065) (xy 66.512694 -394.1699)
			(xy 66.60769 -394.264896) (xy 66.614538 -394.272294) (xy 66.622276 -394.290892) (xy 66.622676 -394.300964)
			(xy 66.622676 -405.589994) (xy 71.424292 -405.589994) (xy 71.424879 -405.557265) (xy 71.433728 -405.492408)
			(xy 71.451213 -405.429328) (xy 71.477014 -405.369169) (xy 71.49338 -405.34082) (xy 71.496686 -405.334791)
			(xy 71.500298 -405.321531) (xy 71.500492 -405.314658) (xy 71.500492 -404.565358) (xy 71.500279 -404.558486)
			(xy 71.496685 -404.545224) (xy 71.49338 -404.539196) (xy 71.477011 -404.510849) (xy 71.45121 -404.450688)
			(xy 71.433722 -404.387608) (xy 71.424862 -404.322751) (xy 71.424292 -404.290022) (xy 71.424846 -404.257292)
			(xy 71.433705 -404.192433) (xy 71.451199 -404.129353) (xy 71.47701 -404.069196) (xy 71.49338 -404.040848)
			(xy 71.496712 -404.034832) (xy 71.500307 -404.021562) (xy 71.500492 -404.014686) (xy 71.500492 -403.728682)
			(xy 71.50101 -403.71856) (xy 71.508735 -403.699847) (xy 71.523011 -403.685493) (xy 71.541681 -403.677666)
			(xy 71.5518 -403.67712) (xy 72.26808 -403.67712) (xy 72.278235 -403.677538) (xy 72.296991 -403.685331)
			(xy 72.311316 -403.699729) (xy 72.319013 -403.718525) (xy 72.319388 -403.728682) (xy 72.319388 -404.014686)
			(xy 72.319587 -404.021559) (xy 72.32319 -404.034821) (xy 72.3265 -404.040848) (xy 72.342885 -404.069187)
			(xy 72.368682 -404.12935) (xy 72.386166 -404.192433) (xy 72.395021 -404.257292) (xy 72.395588 -404.290022)
			(xy 72.395011 -404.322751) (xy 72.386159 -404.387609) (xy 72.368672 -404.450689) (xy 72.342867 -404.510848)
			(xy 72.3265 -404.539196) (xy 72.323187 -404.545221) (xy 72.31958 -404.558485) (xy 72.319388 -404.565358)
			(xy 72.319388 -405.314658) (xy 72.319598 -405.32153) (xy 72.323194 -405.334793) (xy 72.3265 -405.34082)
			(xy 72.342874 -405.369165) (xy 72.368673 -405.429326) (xy 72.386161 -405.492407) (xy 72.395019 -405.557265)
			(xy 72.395588 -405.589994) (xy 72.395043 -405.622724) (xy 72.386182 -405.687583) (xy 72.368685 -405.750664)
			(xy 72.342871 -405.810821) (xy 72.3265 -405.839168) (xy 72.323197 -405.845198) (xy 72.319584 -405.858458)
			(xy 72.319388 -405.86533) (xy 72.319388 -406.151334) (xy 72.318902 -406.161459) (xy 72.311168 -406.180176)
			(xy 72.296883 -406.19453) (xy 72.278203 -406.202353) (xy 72.26808 -406.202896) (xy 71.5518 -406.202896)
			(xy 71.541645 -406.202478) (xy 71.522892 -406.194682) (xy 71.508569 -406.180284) (xy 71.50087 -406.161491)
			(xy 71.500492 -406.151334) (xy 71.500492 -405.86533) (xy 71.500289 -405.858458) (xy 71.496688 -405.845195)
			(xy 71.49338 -405.839168) (xy 71.477 -405.810827) (xy 71.451202 -405.750664) (xy 71.433717 -405.687582)
			(xy 71.42486 -405.622724) (xy 71.424292 -405.589994) (xy 66.622676 -405.589994) (xy 66.622676 -406.722792)
			(xy 73.624773 -406.722792) (xy 73.624777 -406.657353) (xy 73.633564 -406.592507) (xy 73.650975 -406.529427)
			(xy 73.676696 -406.469256) (xy 73.69302 -406.440894) (xy 73.696338 -406.434871) (xy 73.699941 -406.421606)
			(xy 73.700132 -406.414732) (xy 73.700132 -405.665432) (xy 73.699924 -405.65856) (xy 73.696326 -405.645297)
			(xy 73.69302 -405.63927) (xy 73.676695 -405.61091) (xy 73.650979 -405.550739) (xy 73.633572 -405.48766)
			(xy 73.624789 -405.422815) (xy 73.624789 -405.357378) (xy 73.633573 -405.292534) (xy 73.650981 -405.229455)
			(xy 73.676698 -405.169283) (xy 73.69302 -405.140922) (xy 73.696328 -405.134894) (xy 73.699938 -405.121633)
			(xy 73.700132 -405.11476) (xy 73.700132 -404.828756) (xy 73.700486 -404.818595) (xy 73.708302 -404.799836)
			(xy 73.72272 -404.785513) (xy 73.74153 -404.77782) (xy 73.751694 -404.777448) (xy 74.467974 -404.777448)
			(xy 74.4781 -404.777948) (xy 74.496822 -404.785669) (xy 74.51118 -404.799951) (xy 74.518998 -404.818633)
			(xy 74.519536 -404.828756) (xy 74.519536 -405.11476) (xy 74.519739 -405.121633) (xy 74.523339 -405.134895)
			(xy 74.526648 -405.140922) (xy 74.542967 -405.169285) (xy 74.568686 -405.229456) (xy 74.586095 -405.292534)
			(xy 74.594879 -405.357378) (xy 74.594879 -405.422815) (xy 74.586096 -405.487659) (xy 74.568688 -405.550738)
			(xy 74.54297 -405.610909) (xy 74.536176 -405.622714) (xy 75.824929 -405.622714) (xy 75.82493 -405.557276)
			(xy 75.833715 -405.492431) (xy 75.851125 -405.429352) (xy 75.876844 -405.369181) (xy 75.893168 -405.34082)
			(xy 75.896473 -405.334791) (xy 75.900085 -405.321531) (xy 75.90028 -405.314658) (xy 75.90028 -404.565358)
			(xy 75.900068 -404.558486) (xy 75.896474 -404.545223) (xy 75.893168 -404.539196) (xy 75.876864 -404.510825)
			(xy 75.851143 -404.450656) (xy 75.833731 -404.38758) (xy 75.824945 -404.322737) (xy 75.824942 -404.257301)
			(xy 75.833724 -404.192457) (xy 75.85113 -404.129379) (xy 75.876846 -404.069209) (xy 75.893168 -404.040848)
			(xy 75.896499 -404.034831) (xy 75.900094 -404.021561) (xy 75.90028 -404.014686) (xy 75.90028 -403.728682)
			(xy 75.90065 -403.718504) (xy 75.908449 -403.699701) (xy 75.922851 -403.685315) (xy 75.941664 -403.677538)
			(xy 75.951842 -403.67712) (xy 76.668122 -403.67712) (xy 76.678279 -403.677615) (xy 76.697045 -403.685393)
			(xy 76.711409 -403.699758) (xy 76.719186 -403.718525) (xy 76.719684 -403.728682) (xy 76.719684 -404.014686)
			(xy 76.719883 -404.021559) (xy 76.723487 -404.034821) (xy 76.726796 -404.040848) (xy 76.743136 -404.069199)
			(xy 76.76885 -404.129373) (xy 76.786255 -404.192454) (xy 76.795035 -404.2573) (xy 76.795033 -404.322738)
			(xy 76.786247 -404.387583) (xy 76.768837 -404.450662) (xy 76.743119 -404.510834) (xy 76.726796 -404.539196)
			(xy 76.723482 -404.545221) (xy 76.719876 -404.558485) (xy 76.719684 -404.565358) (xy 76.719684 -405.314658)
			(xy 76.719894 -405.32153) (xy 76.72349 -405.334793) (xy 76.726796 -405.34082) (xy 76.743112 -405.369184)
			(xy 76.768828 -405.429355) (xy 76.786236 -405.492433) (xy 76.795019 -405.557277) (xy 76.79502 -405.622713)
			(xy 76.786238 -405.687557) (xy 76.768832 -405.750635) (xy 76.743117 -405.810806) (xy 76.726796 -405.839168)
			(xy 76.723492 -405.845198) (xy 76.71988 -405.858458) (xy 76.719684 -405.86533) (xy 76.719684 -406.151334)
			(xy 76.719195 -406.161491) (xy 76.711414 -406.180257) (xy 76.697047 -406.19462) (xy 76.678279 -406.202397)
			(xy 76.668122 -406.202896) (xy 75.951842 -406.202896) (xy 75.941677 -406.202403) (xy 75.92289 -406.194638)
			(xy 75.908505 -406.180274) (xy 75.900712 -406.161498) (xy 75.90028 -406.151334) (xy 75.90028 -405.86533)
			(xy 75.900079 -405.858457) (xy 75.896477 -405.845195) (xy 75.893168 -405.839168) (xy 75.87684 -405.81081)
			(xy 75.851121 -405.750638) (xy 75.833713 -405.687559) (xy 75.824929 -405.622714) (xy 74.536176 -405.622714)
			(xy 74.526648 -405.63927) (xy 74.523348 -405.645302) (xy 74.519732 -405.65856) (xy 74.519536 -405.665432)
			(xy 74.519536 -406.414732) (xy 74.519711 -406.421607) (xy 74.523331 -406.434869) (xy 74.526648 -406.440894)
			(xy 74.542944 -406.46927) (xy 74.568664 -406.529438) (xy 74.586076 -406.592513) (xy 74.594863 -406.657355)
			(xy 74.594865 -406.690068) (xy 78.024228 -406.690068) (xy 78.024811 -406.657339) (xy 78.033664 -406.592482)
			(xy 78.051149 -406.529402) (xy 78.07695 -406.469243) (xy 78.093316 -406.440894) (xy 78.096634 -406.434871)
			(xy 78.100237 -406.421606) (xy 78.100428 -406.414732) (xy 78.100428 -405.665432) (xy 78.10022 -405.65856)
			(xy 78.096623 -405.645297) (xy 78.093316 -405.63927) (xy 78.07694 -405.610926) (xy 78.05114 -405.550765)
			(xy 78.033654 -405.487684) (xy 78.024797 -405.422826) (xy 78.024228 -405.390096) (xy 78.024779 -405.357366)
			(xy 78.033641 -405.292508) (xy 78.051136 -405.229428) (xy 78.076946 -405.16927) (xy 78.093316 -405.140922)
			(xy 78.096624 -405.134894) (xy 78.100234 -405.121633) (xy 78.100428 -405.11476) (xy 78.100428 -404.828756)
			(xy 78.10085 -404.818641) (xy 78.108607 -404.799956) (xy 78.122924 -404.785662) (xy 78.14162 -404.777934)
			(xy 78.151736 -404.777448) (xy 78.868016 -404.777448) (xy 78.878119 -404.777971) (xy 78.896788 -404.785704)
			(xy 78.91108 -404.799989) (xy 78.918823 -404.818653) (xy 78.919324 -404.828756) (xy 78.919324 -405.11476)
			(xy 78.919528 -405.121632) (xy 78.923128 -405.134895) (xy 78.926436 -405.140922) (xy 78.942804 -405.16927)
			(xy 78.968607 -405.229429) (xy 78.986096 -405.292509) (xy 78.994955 -405.357367) (xy 78.995524 -405.390096)
			(xy 78.994976 -405.422826) (xy 78.986114 -405.487685) (xy 78.968619 -405.550765) (xy 78.951787 -405.589994)
			(xy 80.224376 -405.589994) (xy 80.224965 -405.557265) (xy 80.233814 -405.492408) (xy 80.251298 -405.429328)
			(xy 80.277099 -405.369169) (xy 80.293464 -405.34082) (xy 80.296769 -405.33479) (xy 80.300381 -405.321531)
			(xy 80.300576 -405.314658) (xy 80.300576 -404.565358) (xy 80.300365 -404.558486) (xy 80.29677 -404.545223)
			(xy 80.293464 -404.539196) (xy 80.277103 -404.510844) (xy 80.251299 -404.450686) (xy 80.233807 -404.387607)
			(xy 80.224946 -404.322751) (xy 80.224376 -404.290022) (xy 80.224932 -404.257292) (xy 80.233791 -404.192434)
			(xy 80.251284 -404.129354) (xy 80.277094 -404.069196) (xy 80.293464 -404.040848) (xy 80.296794 -404.034831)
			(xy 80.30039 -404.021561) (xy 80.300576 -404.014686) (xy 80.300576 -403.728682) (xy 80.301013 -403.71855)
			(xy 80.308753 -403.699821) (xy 80.323055 -403.685464) (xy 80.341754 -403.677652) (xy 80.351884 -403.67712)
			(xy 81.068164 -403.67712) (xy 81.078318 -403.677552) (xy 81.097074 -403.685339) (xy 81.111399 -403.699733)
			(xy 81.119096 -403.718526) (xy 81.119472 -403.728682) (xy 81.119472 -404.014686) (xy 81.119673 -404.021559)
			(xy 81.123275 -404.034821) (xy 81.126584 -404.040848) (xy 81.142967 -404.069188) (xy 81.168765 -404.129351)
			(xy 81.18625 -404.192433) (xy 81.195105 -404.257292) (xy 81.195672 -404.290022) (xy 81.195084 -404.322751)
			(xy 81.186233 -404.387608) (xy 81.168749 -404.450688) (xy 81.142949 -404.510847) (xy 81.126584 -404.539196)
			(xy 81.12327 -404.545221) (xy 81.119664 -404.558484) (xy 81.119472 -404.565358) (xy 81.119472 -405.314658)
			(xy 81.119683 -405.32153) (xy 81.123279 -405.334792) (xy 81.126584 -405.34082) (xy 81.142956 -405.369166)
			(xy 81.168757 -405.429326) (xy 81.186245 -405.492407) (xy 81.195103 -405.557265) (xy 81.195672 -405.589994)
			(xy 81.195116 -405.622724) (xy 81.186256 -405.687582) (xy 81.168763 -405.750662) (xy 81.142953 -405.81082)
			(xy 81.126584 -405.839168) (xy 81.12328 -405.845198) (xy 81.119668 -405.858458) (xy 81.119472 -405.86533)
			(xy 81.119472 -406.151334) (xy 81.119002 -406.161461) (xy 81.111265 -406.180181) (xy 81.096974 -406.194536)
			(xy 81.078289 -406.202356) (xy 81.068164 -406.202896) (xy 80.351884 -406.202896) (xy 80.341728 -406.202492)
			(xy 80.322975 -406.19469) (xy 80.308652 -406.180288) (xy 80.300953 -406.161492) (xy 80.300576 -406.151334)
			(xy 80.300576 -405.86533) (xy 80.300375 -405.858457) (xy 80.296773 -405.845194) (xy 80.293464 -405.839168)
			(xy 80.277092 -405.810822) (xy 80.25129 -405.750662) (xy 80.233802 -405.687581) (xy 80.224944 -405.622723)
			(xy 80.224376 -405.589994) (xy 78.951787 -405.589994) (xy 78.942807 -405.610923) (xy 78.926436 -405.63927)
			(xy 78.923135 -405.645301) (xy 78.91952 -405.65856) (xy 78.919324 -405.665432) (xy 78.919324 -406.414732)
			(xy 78.919501 -406.421606) (xy 78.923119 -406.434869) (xy 78.926436 -406.440894) (xy 78.942793 -406.469248)
			(xy 78.968598 -406.529405) (xy 78.986091 -406.592483) (xy 78.994953 -406.657339) (xy 78.995524 -406.690068)
			(xy 78.994963 -406.722792) (xy 82.424859 -406.722792) (xy 82.424863 -406.657353) (xy 82.43365 -406.592507)
			(xy 82.451061 -406.529428) (xy 82.476781 -406.469256) (xy 82.493104 -406.440894) (xy 82.496421 -406.434871)
			(xy 82.500025 -406.421606) (xy 82.500216 -406.414732) (xy 82.500216 -405.665432) (xy 82.50001 -405.65856)
			(xy 82.496411 -405.645297) (xy 82.493104 -405.63927) (xy 82.476779 -405.61091) (xy 82.451064 -405.550738)
			(xy 82.433658 -405.487659) (xy 82.424875 -405.422815) (xy 82.424876 -405.357378) (xy 82.433659 -405.292534)
			(xy 82.451066 -405.229455) (xy 82.476783 -405.169284) (xy 82.493104 -405.140922) (xy 82.496411 -405.134894)
			(xy 82.500022 -405.121633) (xy 82.500216 -405.11476) (xy 82.500216 -404.828756) (xy 82.500586 -404.818597)
			(xy 82.508399 -404.799841) (xy 82.522811 -404.785518) (xy 82.541617 -404.777823) (xy 82.551778 -404.777448)
			(xy 83.268058 -404.777448) (xy 83.278183 -404.777961) (xy 83.296905 -404.785677) (xy 83.311263 -404.799955)
			(xy 83.319082 -404.818634) (xy 83.31962 -404.828756) (xy 83.31962 -405.11476) (xy 83.319825 -405.121632)
			(xy 83.323424 -405.134895) (xy 83.326732 -405.140922) (xy 83.343052 -405.169285) (xy 83.368771 -405.229455)
			(xy 83.386181 -405.292534) (xy 83.394965 -405.357378) (xy 83.394966 -405.422815) (xy 83.386182 -405.48766)
			(xy 83.368773 -405.550738) (xy 83.351994 -405.589994) (xy 84.624164 -405.589994) (xy 84.624755 -405.557265)
			(xy 84.633604 -405.492408) (xy 84.651087 -405.429328) (xy 84.676887 -405.369169) (xy 84.693252 -405.34082)
			(xy 84.696556 -405.33479) (xy 84.700169 -405.32153) (xy 84.700364 -405.314658) (xy 84.700364 -404.565358)
			(xy 84.700154 -404.558486) (xy 84.696559 -404.545223) (xy 84.693252 -404.539196) (xy 84.67689 -404.510845)
			(xy 84.651086 -404.450686) (xy 84.633595 -404.387607) (xy 84.624734 -404.322751) (xy 84.624164 -404.290022)
			(xy 84.624722 -404.257292) (xy 84.633581 -404.192434) (xy 84.651073 -404.129354) (xy 84.676883 -404.069196)
			(xy 84.693252 -404.040848) (xy 84.696581 -404.03483) (xy 84.700178 -404.021561) (xy 84.700364 -404.014686)
			(xy 84.700364 -403.728682) (xy 84.700812 -403.718551) (xy 84.70855 -403.699825) (xy 84.722849 -403.685468)
			(xy 84.741543 -403.677654) (xy 84.751672 -403.67712) (xy 85.467952 -403.67712) (xy 85.478105 -403.677561)
			(xy 85.496861 -403.685345) (xy 85.511186 -403.699736) (xy 85.518884 -403.718527) (xy 85.51926 -403.728682)
			(xy 85.51926 -404.014686) (xy 85.519462 -404.021558) (xy 85.523064 -404.034821) (xy 85.526372 -404.040848)
			(xy 85.542754 -404.069188) (xy 85.568553 -404.129351) (xy 85.586038 -404.192433) (xy 85.594893 -404.257292)
			(xy 85.59546 -404.290022) (xy 89.023706 -404.290022) (xy 89.027697 -404.227855) (xy 89.039606 -404.166708)
			(xy 89.059235 -404.107587) (xy 89.086264 -404.051461) (xy 89.120248 -403.999252) (xy 89.16063 -403.951817)
			(xy 89.206746 -403.909936) (xy 89.257838 -403.874296) (xy 89.313069 -403.845482) (xy 89.371531 -403.823968)
			(xy 89.432265 -403.810106) (xy 89.494272 -403.804124) (xy 89.556535 -403.80612) (xy 89.618032 -403.816063)
			(xy 89.677753 -403.833787) (xy 89.734716 -403.859004) (xy 89.787987 -403.891297) (xy 89.836692 -403.930137)
			(xy 89.880029 -403.974887) (xy 89.917289 -404.024811) (xy 89.947858 -404.07909) (xy 89.971236 -404.136833)
			(xy 89.987037 -404.197091) (xy 89.995003 -404.258874) (xy 89.995502 -404.290022) (xy 89.995003 -404.32117)
			(xy 89.987037 -404.382953) (xy 89.971236 -404.443211) (xy 89.947858 -404.500954) (xy 89.917289 -404.555233)
			(xy 89.880029 -404.605157) (xy 89.836692 -404.649907) (xy 89.787987 -404.688747) (xy 89.734716 -404.72104)
			(xy 89.677753 -404.746257) (xy 89.618032 -404.763981) (xy 89.556535 -404.773924) (xy 89.494272 -404.77592)
			(xy 89.432265 -404.769938) (xy 89.371531 -404.756076) (xy 89.313069 -404.734562) (xy 89.257838 -404.705748)
			(xy 89.206746 -404.670108) (xy 89.16063 -404.628227) (xy 89.120248 -404.580792) (xy 89.086264 -404.528583)
			(xy 89.059235 -404.472457) (xy 89.039606 -404.413336) (xy 89.027697 -404.352189) (xy 89.023706 -404.290022)
			(xy 85.59546 -404.290022) (xy 85.594874 -404.322751) (xy 85.586023 -404.387608) (xy 85.568538 -404.450688)
			(xy 85.542737 -404.510847) (xy 85.526372 -404.539196) (xy 85.523057 -404.54522) (xy 85.519452 -404.558484)
			(xy 85.51926 -404.565358) (xy 85.51926 -405.314658) (xy 85.519473 -405.32153) (xy 85.523067 -405.334792)
			(xy 85.526372 -405.34082) (xy 85.542743 -405.369166) (xy 85.568544 -405.429327) (xy 85.586032 -405.492407)
			(xy 85.594891 -405.557265) (xy 85.59546 -405.589994) (xy 85.594906 -405.622724) (xy 85.586045 -405.687582)
			(xy 85.568552 -405.750662) (xy 85.542742 -405.81082) (xy 85.526372 -405.839168) (xy 85.523067 -405.845197)
			(xy 85.519456 -405.858457) (xy 85.51926 -405.86533) (xy 85.51926 -406.151334) (xy 85.518801 -406.161463)
			(xy 85.511062 -406.180185) (xy 85.496768 -406.19454) (xy 85.478079 -406.202358) (xy 85.467952 -406.202896)
			(xy 84.751672 -406.202896) (xy 84.741516 -406.202501) (xy 84.722762 -406.194696) (xy 84.708439 -406.180291)
			(xy 84.700741 -406.161493) (xy 84.700364 -406.151334) (xy 84.700364 -405.86533) (xy 84.700165 -405.858457)
			(xy 84.696562 -405.845194) (xy 84.693252 -405.839168) (xy 84.676879 -405.810823) (xy 84.651078 -405.750662)
			(xy 84.63359 -405.687581) (xy 84.624732 -405.622723) (xy 84.624164 -405.589994) (xy 83.351994 -405.589994)
			(xy 83.343055 -405.610909) (xy 83.326732 -405.63927) (xy 83.323431 -405.645301) (xy 83.319816 -405.65856)
			(xy 83.31962 -405.665432) (xy 83.31962 -406.414732) (xy 83.319797 -406.421606) (xy 83.323415 -406.434869)
			(xy 83.326732 -406.440894) (xy 83.343028 -406.46927) (xy 83.36875 -406.529437) (xy 83.386162 -406.592513)
			(xy 83.394949 -406.657355) (xy 83.394951 -406.690068) (xy 86.824312 -406.690068) (xy 86.824884 -406.657339)
			(xy 86.833738 -406.592481) (xy 86.851226 -406.5294) (xy 86.877032 -406.469242) (xy 86.8934 -406.440894)
			(xy 86.896717 -406.43487) (xy 86.900321 -406.421606) (xy 86.900512 -406.414732) (xy 86.900512 -405.665432)
			(xy 86.900307 -405.65856) (xy 86.896707 -405.645297) (xy 86.8934 -405.63927) (xy 86.877022 -405.610927)
			(xy 86.851224 -405.550765) (xy 86.833737 -405.487684) (xy 86.82488 -405.422826) (xy 86.824312 -405.390096)
			(xy 86.824852 -405.357366) (xy 86.833715 -405.292506) (xy 86.851213 -405.229426) (xy 86.877028 -405.169269)
			(xy 86.8934 -405.140922) (xy 86.896707 -405.134894) (xy 86.900317 -405.121633) (xy 86.900512 -405.11476)
			(xy 86.900512 -404.828756) (xy 86.900949 -404.818643) (xy 86.908704 -404.799961) (xy 86.923015 -404.785668)
			(xy 86.941706 -404.777937) (xy 86.95182 -404.777448) (xy 87.6681 -404.777448) (xy 87.678202 -404.777984)
			(xy 87.696871 -404.785712) (xy 87.711163 -404.799993) (xy 87.718907 -404.818654) (xy 87.719408 -404.828756)
			(xy 87.719408 -405.11476) (xy 87.719614 -405.121632) (xy 87.723213 -405.134895) (xy 87.72652 -405.140922)
			(xy 87.742896 -405.169265) (xy 87.768695 -405.229427) (xy 87.786182 -405.292508) (xy 87.795039 -405.357367)
			(xy 87.795608 -405.390096) (xy 87.795062 -405.422826) (xy 87.7862 -405.487685) (xy 87.768704 -405.550765)
			(xy 87.751871 -405.589994) (xy 89.023706 -405.589994) (xy 89.027697 -405.527827) (xy 89.039606 -405.46668)
			(xy 89.059235 -405.407559) (xy 89.086264 -405.351433) (xy 89.120248 -405.299224) (xy 89.16063 -405.251789)
			(xy 89.206746 -405.209908) (xy 89.257838 -405.174268) (xy 89.313069 -405.145454) (xy 89.371531 -405.12394)
			(xy 89.432265 -405.110078) (xy 89.494272 -405.104096) (xy 89.556535 -405.106092) (xy 89.618032 -405.116035)
			(xy 89.677753 -405.133759) (xy 89.734716 -405.158976) (xy 89.787987 -405.191269) (xy 89.836692 -405.230109)
			(xy 89.880029 -405.274859) (xy 89.917289 -405.324783) (xy 89.947858 -405.379062) (xy 89.971236 -405.436805)
			(xy 89.987037 -405.497063) (xy 89.995003 -405.558846) (xy 89.995502 -405.589994) (xy 89.995003 -405.621142)
			(xy 89.987037 -405.682925) (xy 89.971236 -405.743183) (xy 89.947858 -405.800926) (xy 89.917289 -405.855205)
			(xy 89.880029 -405.905129) (xy 89.836692 -405.949879) (xy 89.787987 -405.988719) (xy 89.734716 -406.021012)
			(xy 89.677753 -406.046229) (xy 89.618032 -406.063953) (xy 89.556535 -406.073896) (xy 89.494272 -406.075892)
			(xy 89.432265 -406.06991) (xy 89.371531 -406.056048) (xy 89.313069 -406.034534) (xy 89.257838 -406.00572)
			(xy 89.206746 -405.97008) (xy 89.16063 -405.928199) (xy 89.120248 -405.880764) (xy 89.086264 -405.828555)
			(xy 89.059235 -405.772429) (xy 89.039606 -405.713308) (xy 89.027697 -405.652161) (xy 89.023706 -405.589994)
			(xy 87.751871 -405.589994) (xy 87.742891 -405.610923) (xy 87.72652 -405.63927) (xy 87.723217 -405.645301)
			(xy 87.719604 -405.65856) (xy 87.719408 -405.665432) (xy 87.719408 -406.414732) (xy 87.719587 -406.421606)
			(xy 87.723204 -406.434869) (xy 87.72652 -406.440894) (xy 87.742885 -406.469243) (xy 87.768687 -406.529403)
			(xy 87.786176 -406.592482) (xy 87.795037 -406.657339) (xy 87.795608 -406.690068) (xy 87.795049 -406.722792)
			(xy 91.224945 -406.722792) (xy 91.224949 -406.657353) (xy 91.233736 -406.592508) (xy 91.251146 -406.529428)
			(xy 91.276865 -406.469256) (xy 91.293188 -406.440894) (xy 91.296504 -406.43487) (xy 91.300109 -406.421606)
			(xy 91.3003 -406.414732) (xy 91.3003 -405.665432) (xy 91.300096 -405.65856) (xy 91.296496 -405.645297)
			(xy 91.293188 -405.63927) (xy 91.276864 -405.61091) (xy 91.251149 -405.550738) (xy 91.233743 -405.487659)
			(xy 91.224961 -405.422815) (xy 91.224962 -405.357378) (xy 91.233745 -405.292534) (xy 91.251152 -405.229455)
			(xy 91.276867 -405.169284) (xy 91.293188 -405.140922) (xy 91.296494 -405.134893) (xy 91.300105 -405.121633)
			(xy 91.3003 -405.11476) (xy 91.3003 -404.828756) (xy 91.300686 -404.818599) (xy 91.308496 -404.799846)
			(xy 91.322903 -404.785524) (xy 91.341703 -404.777826) (xy 91.351862 -404.777448) (xy 92.068142 -404.777448)
			(xy 92.078272 -404.777892) (xy 92.096996 -404.785635) (xy 92.111351 -404.799934) (xy 92.119167 -404.818628)
			(xy 92.119704 -404.828756) (xy 92.119704 -405.11476) (xy 92.119911 -405.121632) (xy 92.123509 -405.134895)
			(xy 92.126816 -405.140922) (xy 92.143136 -405.169285) (xy 92.168857 -405.229455) (xy 92.186267 -405.292533)
			(xy 92.195051 -405.357378) (xy 92.195052 -405.422815) (xy 92.186268 -405.48766) (xy 92.168859 -405.550739)
			(xy 92.143139 -405.610909) (xy 92.136345 -405.622713) (xy 115.425064 -405.622713) (xy 115.425064 -405.557277)
			(xy 115.433848 -405.492432) (xy 115.451255 -405.429353) (xy 115.476971 -405.369182) (xy 115.493292 -405.34082)
			(xy 115.496599 -405.334792) (xy 115.50021 -405.321531) (xy 115.500404 -405.314658) (xy 115.500404 -404.565358)
			(xy 115.500189 -404.558486) (xy 115.496596 -404.545224) (xy 115.493292 -404.539196) (xy 115.47699 -404.510824)
			(xy 115.451273 -404.450655) (xy 115.433865 -404.387578) (xy 115.42508 -404.322736) (xy 115.425077 -404.257302)
			(xy 115.433857 -404.192459) (xy 115.451261 -404.129381) (xy 115.476973 -404.06921) (xy 115.493292 -404.040848)
			(xy 115.496625 -404.034832) (xy 115.500219 -404.021562) (xy 115.500404 -404.014686) (xy 115.500404 -403.728682)
			(xy 115.500918 -403.718527) (xy 115.508692 -403.699764) (xy 115.523051 -403.685401) (xy 115.541811 -403.677621)
			(xy 115.551966 -403.67712) (xy 116.268246 -403.67712) (xy 116.278404 -403.677595) (xy 116.297171 -403.685382)
			(xy 116.311534 -403.699752) (xy 116.31931 -403.718523) (xy 116.319808 -403.728682) (xy 116.319808 -404.014686)
			(xy 116.320005 -404.021559) (xy 116.32361 -404.034822) (xy 116.32692 -404.040848) (xy 116.343262 -404.069199)
			(xy 116.36898 -404.129372) (xy 116.386388 -404.192453) (xy 116.39517 -404.257299) (xy 116.395167 -404.322738)
			(xy 116.38638 -404.387584) (xy 116.368968 -404.450664) (xy 116.343245 -404.510835) (xy 116.32692 -404.539196)
			(xy 116.323608 -404.545222) (xy 116.32 -404.558485) (xy 116.319808 -404.565358) (xy 116.319808 -405.314658)
			(xy 116.320015 -405.32153) (xy 116.323613 -405.334793) (xy 116.32692 -405.34082) (xy 116.343238 -405.369184)
			(xy 116.368959 -405.429354) (xy 116.386369 -405.492432) (xy 116.395154 -405.557276) (xy 116.395154 -405.622713)
			(xy 116.386371 -405.687558) (xy 116.368962 -405.750636) (xy 116.343243 -405.810807) (xy 116.32692 -405.839168)
			(xy 116.323618 -405.845199) (xy 116.320004 -405.858458) (xy 116.319808 -405.86533) (xy 116.319808 -406.151334)
			(xy 116.319296 -406.161488) (xy 116.311519 -406.180249) (xy 116.297159 -406.194612) (xy 116.2784 -406.202393)
			(xy 116.268246 -406.202896) (xy 115.551966 -406.202896) (xy 115.54181 -406.202395) (xy 115.523047 -406.194616)
			(xy 115.508684 -406.180253) (xy 115.500905 -406.16149) (xy 115.500404 -406.151334) (xy 115.500404 -405.86533)
			(xy 115.5002 -405.858458) (xy 115.4966 -405.845195) (xy 115.493292 -405.839168) (xy 115.476966 -405.810809)
			(xy 115.451251 -405.750637) (xy 115.433846 -405.687558) (xy 115.425064 -405.622713) (xy 92.136345 -405.622713)
			(xy 92.126816 -405.63927) (xy 92.123513 -405.6453) (xy 92.1199 -405.65856) (xy 92.119704 -405.665432)
			(xy 92.119704 -406.414732) (xy 92.119883 -406.421606) (xy 92.1235 -406.434869) (xy 92.126816 -406.440894)
			(xy 92.143113 -406.46927) (xy 92.168835 -406.529437) (xy 92.186248 -406.592513) (xy 92.195036 -406.657355)
			(xy 92.195037 -406.690068) (xy 117.624352 -406.690068) (xy 117.624932 -406.657339) (xy 117.633785 -406.592482)
			(xy 117.651271 -406.529401) (xy 117.677074 -406.469243) (xy 117.69344 -406.440894) (xy 117.696752 -406.434868)
			(xy 117.70036 -406.421605) (xy 117.700552 -406.414732) (xy 117.700552 -405.665432) (xy 117.700354 -405.658559)
			(xy 117.696751 -405.645296) (xy 117.69344 -405.63927) (xy 117.677066 -405.610925) (xy 117.651266 -405.550764)
			(xy 117.633778 -405.487683) (xy 117.624921 -405.422825) (xy 117.624352 -405.390096) (xy 117.6249 -405.357366)
			(xy 117.633762 -405.292507) (xy 117.651258 -405.229427) (xy 117.677069 -405.16927) (xy 117.69344 -405.140922)
			(xy 117.696742 -405.134891) (xy 117.700357 -405.121632) (xy 117.700552 -405.11476) (xy 117.700552 -404.828756)
			(xy 117.701048 -404.81865) (xy 117.708791 -404.79998) (xy 117.723084 -404.785689) (xy 117.741754 -404.777947)
			(xy 117.75186 -404.777448) (xy 118.46814 -404.777448) (xy 118.478245 -404.777951) (xy 118.496914 -404.785692)
			(xy 118.511206 -404.799983) (xy 118.518948 -404.818651) (xy 118.519448 -404.828756) (xy 118.519448 -405.11476)
			(xy 118.519649 -405.121633) (xy 118.52325 -405.134896) (xy 118.52656 -405.140922) (xy 118.542931 -405.169269)
			(xy 118.568732 -405.229429) (xy 118.58622 -405.292509) (xy 118.595079 -405.357367) (xy 118.595648 -405.390096)
			(xy 118.595096 -405.422826) (xy 118.586235 -405.487685) (xy 118.568741 -405.550765) (xy 118.551909 -405.589994)
			(xy 119.8245 -405.589994) (xy 119.825086 -405.557265) (xy 119.833935 -405.492408) (xy 119.85142 -405.429327)
			(xy 119.877222 -405.369169) (xy 119.893588 -405.34082) (xy 119.896895 -405.334791) (xy 119.900506 -405.321531)
			(xy 119.9007 -405.314658) (xy 119.9007 -404.565358) (xy 119.900486 -404.558486) (xy 119.896893 -404.545224)
			(xy 119.893588 -404.539196) (xy 119.87722 -404.510848) (xy 119.851419 -404.450688) (xy 119.83393 -404.387608)
			(xy 119.82507 -404.322751) (xy 119.8245 -404.290022) (xy 119.825053 -404.257292) (xy 119.833913 -404.192433)
			(xy 119.851407 -404.129353) (xy 119.877218 -404.069196) (xy 119.893588 -404.040848) (xy 119.89692 -404.034832)
			(xy 119.900515 -404.021562) (xy 119.9007 -404.014686) (xy 119.9007 -403.728682) (xy 119.90121 -403.718559)
			(xy 119.908937 -403.699845) (xy 119.923215 -403.685491) (xy 119.941888 -403.677665) (xy 119.952008 -403.67712)
			(xy 120.668288 -403.67712) (xy 120.678444 -403.677532) (xy 120.6972 -403.685327) (xy 120.711524 -403.699727)
			(xy 120.719221 -403.718524) (xy 120.719596 -403.728682) (xy 120.719596 -404.014686) (xy 120.719794 -404.021559)
			(xy 120.723398 -404.034822) (xy 120.726708 -404.040848) (xy 120.743093 -404.069186) (xy 120.76889 -404.12935)
			(xy 120.786374 -404.192433) (xy 120.795229 -404.257292) (xy 120.795796 -404.290022) (xy 120.795218 -404.322751)
			(xy 120.786366 -404.387609) (xy 120.768879 -404.450689) (xy 120.743075 -404.510848) (xy 120.726708 -404.539196)
			(xy 120.723395 -404.545222) (xy 120.719788 -404.558485) (xy 120.719596 -404.565358) (xy 120.719596 -405.314658)
			(xy 120.719805 -405.32153) (xy 120.723402 -405.334793) (xy 120.726708 -405.34082) (xy 120.743082 -405.369164)
			(xy 120.768882 -405.429326) (xy 120.786369 -405.492407) (xy 120.795227 -405.557265) (xy 120.795796 -405.589994)
			(xy 120.795251 -405.622724) (xy 120.786389 -405.687583) (xy 120.768893 -405.750664) (xy 120.74308 -405.810821)
			(xy 120.726708 -405.839168) (xy 120.723405 -405.845198) (xy 120.719792 -405.858458) (xy 120.719596 -405.86533)
			(xy 120.719596 -406.151334) (xy 120.719102 -406.161458) (xy 120.71137 -406.180174) (xy 120.697087 -406.194527)
			(xy 120.67841 -406.202352) (xy 120.668288 -406.202896) (xy 119.952008 -406.202896) (xy 119.941854 -406.202472)
			(xy 119.923101 -406.194678) (xy 119.908777 -406.180282) (xy 119.901078 -406.16149) (xy 119.9007 -406.151334)
			(xy 119.9007 -405.86533) (xy 119.900496 -405.858458) (xy 119.896896 -405.845195) (xy 119.893588 -405.839168)
			(xy 119.877209 -405.810826) (xy 119.85141 -405.750664) (xy 119.833925 -405.687582) (xy 119.825068 -405.622724)
			(xy 119.8245 -405.589994) (xy 118.551909 -405.589994) (xy 118.54293 -405.610922) (xy 118.52656 -405.63927)
			(xy 118.523261 -405.645302) (xy 118.519645 -405.65856) (xy 118.519448 -405.665432) (xy 118.519448 -406.414732)
			(xy 118.519622 -406.421607) (xy 118.523242 -406.43487) (xy 118.52656 -406.440894) (xy 118.542919 -406.469247)
			(xy 118.568724 -406.529405) (xy 118.586215 -406.592483) (xy 118.595077 -406.657339) (xy 118.595648 -406.690068)
			(xy 118.595084 -406.722792) (xy 122.02498 -406.722792) (xy 122.024984 -406.657353) (xy 122.033771 -406.592507)
			(xy 122.051183 -406.529427) (xy 122.076904 -406.469255) (xy 122.093228 -406.440894) (xy 122.096547 -406.434871)
			(xy 122.100149 -406.421606) (xy 122.10034 -406.414732) (xy 122.10034 -405.665432) (xy 122.100131 -405.65856)
			(xy 122.096534 -405.645297) (xy 122.093228 -405.63927) (xy 122.076903 -405.61091) (xy 122.051186 -405.550739)
			(xy 122.033779 -405.48766) (xy 122.024996 -405.422815) (xy 122.024996 -405.357378) (xy 122.03378 -405.292534)
			(xy 122.051188 -405.229455) (xy 122.076906 -405.169283) (xy 122.093228 -405.140922) (xy 122.096537 -405.134895)
			(xy 122.100146 -405.121633) (xy 122.10034 -405.11476) (xy 122.10034 -404.828756) (xy 122.100686 -404.818594)
			(xy 122.108504 -404.799833) (xy 122.122924 -404.78551) (xy 122.141737 -404.777819) (xy 122.151902 -404.777448)
			(xy 122.868182 -404.777448) (xy 122.878309 -404.777941) (xy 122.897031 -404.785665) (xy 122.911388 -404.799949)
			(xy 122.919207 -404.818632) (xy 122.919744 -404.828756) (xy 122.919744 -405.11476) (xy 122.919946 -405.121633)
			(xy 122.923547 -405.134896) (xy 122.926856 -405.140922) (xy 122.943175 -405.169285) (xy 122.968893 -405.229456)
			(xy 122.986302 -405.292534) (xy 122.995086 -405.357378) (xy 122.995086 -405.422815) (xy 122.986303 -405.487659)
			(xy 122.968895 -405.550738) (xy 122.943178 -405.610909) (xy 122.936384 -405.622714) (xy 124.225136 -405.622714)
			(xy 124.225137 -405.557276) (xy 124.233922 -405.492431) (xy 124.251332 -405.429352) (xy 124.277052 -405.369181)
			(xy 124.293376 -405.34082) (xy 124.296682 -405.334791) (xy 124.300294 -405.321531) (xy 124.300488 -405.314658)
			(xy 124.300488 -404.565358) (xy 124.300275 -404.558486) (xy 124.296681 -404.545223) (xy 124.293376 -404.539196)
			(xy 124.277071 -404.510825) (xy 124.25135 -404.450656) (xy 124.233938 -404.38758) (xy 124.225152 -404.322737)
			(xy 124.225149 -404.257301) (xy 124.233931 -404.192457) (xy 124.251337 -404.129379) (xy 124.277054 -404.069209)
			(xy 124.293376 -404.040848) (xy 124.296708 -404.034832) (xy 124.300303 -404.021562) (xy 124.300488 -404.014686)
			(xy 124.300488 -403.728682) (xy 124.30085 -403.718503) (xy 124.308651 -403.699698) (xy 124.323056 -403.685313)
			(xy 124.34187 -403.677537) (xy 124.35205 -403.67712) (xy 125.06833 -403.67712) (xy 125.078487 -403.677608)
			(xy 125.097254 -403.685389) (xy 125.111617 -403.699756) (xy 125.119394 -403.718524) (xy 125.119892 -403.728682)
			(xy 125.119892 -404.014686) (xy 125.12009 -404.021559) (xy 125.123694 -404.034822) (xy 125.127004 -404.040848)
			(xy 125.143344 -404.069199) (xy 125.169057 -404.129373) (xy 125.186462 -404.192454) (xy 125.195242 -404.2573)
			(xy 125.195239 -404.322738) (xy 125.186454 -404.387583) (xy 125.169045 -404.450662) (xy 125.143326 -404.510834)
			(xy 125.127004 -404.539196) (xy 125.123691 -404.545221) (xy 125.120084 -404.558485) (xy 125.119892 -404.565358)
			(xy 125.119892 -405.314658) (xy 125.120101 -405.32153) (xy 125.123698 -405.334793) (xy 125.127004 -405.34082)
			(xy 125.14332 -405.369185) (xy 125.169036 -405.429355) (xy 125.186443 -405.492433) (xy 125.195226 -405.557277)
			(xy 125.195227 -405.622713) (xy 125.186445 -405.687557) (xy 125.169039 -405.750635) (xy 125.143324 -405.810806)
			(xy 125.127004 -405.839168) (xy 125.123701 -405.845198) (xy 125.120088 -405.858458) (xy 125.119892 -405.86533)
			(xy 125.119892 -406.151334) (xy 125.119395 -406.16149) (xy 125.111615 -406.180254) (xy 125.097251 -406.194617)
			(xy 125.078486 -406.202396) (xy 125.06833 -406.202896) (xy 124.35205 -406.202896) (xy 124.341886 -406.202396)
			(xy 124.323099 -406.194634) (xy 124.308713 -406.180272) (xy 124.30092 -406.161497) (xy 124.300488 -406.151334)
			(xy 124.300488 -405.86533) (xy 124.300286 -405.858458) (xy 124.296685 -405.845195) (xy 124.293376 -405.839168)
			(xy 124.277048 -405.81081) (xy 124.251328 -405.750638) (xy 124.23392 -405.687559) (xy 124.225136 -405.622714)
			(xy 122.936384 -405.622714) (xy 122.926856 -405.63927) (xy 122.923556 -405.645302) (xy 122.91994 -405.65856)
			(xy 122.919744 -405.665432) (xy 122.919744 -406.414732) (xy 122.919918 -406.421607) (xy 122.923538 -406.43487)
			(xy 122.926856 -406.440894) (xy 122.943151 -406.46927) (xy 122.968872 -406.529438) (xy 122.986283 -406.592513)
			(xy 122.99507 -406.657355) (xy 122.995072 -406.690068) (xy 126.424436 -406.690068) (xy 126.425018 -406.657339)
			(xy 126.433871 -406.592482) (xy 126.451356 -406.529402) (xy 126.477158 -406.469243) (xy 126.493524 -406.440894)
			(xy 126.496843 -406.434871) (xy 126.500445 -406.421606) (xy 126.500636 -406.414732) (xy 126.500636 -405.665432)
			(xy 126.500427 -405.65856) (xy 126.49683 -405.645297) (xy 126.493524 -405.63927) (xy 126.477149 -405.610926)
			(xy 126.451349 -405.550765) (xy 126.433862 -405.487684) (xy 126.425005 -405.422825) (xy 126.424436 -405.390096)
			(xy 126.424986 -405.357366) (xy 126.433848 -405.292507) (xy 126.451343 -405.229428) (xy 126.477154 -405.16927)
			(xy 126.493524 -405.140922) (xy 126.496833 -405.134894) (xy 126.500442 -405.121633) (xy 126.500636 -405.11476)
			(xy 126.500636 -404.828756) (xy 126.50105 -404.81864) (xy 126.508809 -404.799954) (xy 126.523128 -404.785659)
			(xy 126.541827 -404.777933) (xy 126.551944 -404.777448) (xy 127.268224 -404.777448) (xy 127.278328 -404.777964)
			(xy 127.296997 -404.7857) (xy 127.311289 -404.799986) (xy 127.319032 -404.818652) (xy 127.319532 -404.828756)
			(xy 127.319532 -405.11476) (xy 127.319735 -405.121632) (xy 127.323335 -405.134895) (xy 127.326644 -405.140922)
			(xy 127.343013 -405.169269) (xy 127.368815 -405.229429) (xy 127.386304 -405.292509) (xy 127.395163 -405.357367)
			(xy 127.395732 -405.390096) (xy 127.395183 -405.422826) (xy 127.386321 -405.487685) (xy 127.368826 -405.550765)
			(xy 127.343015 -405.610922) (xy 127.336205 -405.622714) (xy 128.624926 -405.622714) (xy 128.624926 -405.557276)
			(xy 128.633711 -405.492431) (xy 128.651121 -405.429352) (xy 128.676841 -405.369181) (xy 128.693164 -405.34082)
			(xy 128.696469 -405.33479) (xy 128.700081 -405.321531) (xy 128.700276 -405.314658) (xy 128.700276 -404.565358)
			(xy 128.700065 -404.558486) (xy 128.69647 -404.545223) (xy 128.693164 -404.539196) (xy 128.67686 -404.510825)
			(xy 128.651139 -404.450656) (xy 128.633728 -404.38758) (xy 128.624942 -404.322737) (xy 128.624939 -404.257301)
			(xy 128.63372 -404.192457) (xy 128.651126 -404.12938) (xy 128.676842 -404.069209) (xy 128.693164 -404.040848)
			(xy 128.696494 -404.034831) (xy 128.70009 -404.021561) (xy 128.700276 -404.014686) (xy 128.700276 -403.728682)
			(xy 128.70065 -403.718505) (xy 128.708448 -403.699702) (xy 128.722849 -403.685317) (xy 128.74166 -403.677539)
			(xy 128.751838 -403.67712) (xy 129.468118 -403.67712) (xy 129.478275 -403.677618) (xy 129.497041 -403.685395)
			(xy 129.511405 -403.699759) (xy 129.519182 -403.718525) (xy 129.51968 -403.728682) (xy 129.51968 -404.014686)
			(xy 129.51988 -404.021559) (xy 129.523483 -404.034821) (xy 129.526792 -404.040848) (xy 129.543132 -404.069199)
			(xy 129.568846 -404.129373) (xy 129.586251 -404.192454) (xy 129.595032 -404.2573) (xy 129.59503 -404.290022)
			(xy 133.023872 -404.290022) (xy 133.027863 -404.227855) (xy 133.039772 -404.166708) (xy 133.059401 -404.107587)
			(xy 133.08643 -404.051461) (xy 133.120414 -403.999252) (xy 133.160796 -403.951817) (xy 133.206912 -403.909936)
			(xy 133.258004 -403.874296) (xy 133.313235 -403.845482) (xy 133.371697 -403.823968) (xy 133.432431 -403.810106)
			(xy 133.494438 -403.804124) (xy 133.556701 -403.80612) (xy 133.618198 -403.816063) (xy 133.677919 -403.833787)
			(xy 133.734882 -403.859004) (xy 133.788153 -403.891297) (xy 133.836858 -403.930137) (xy 133.880195 -403.974887)
			(xy 133.917455 -404.024811) (xy 133.948024 -404.07909) (xy 133.971402 -404.136833) (xy 133.987203 -404.197091)
			(xy 133.995169 -404.258874) (xy 133.995668 -404.290022) (xy 133.995169 -404.32117) (xy 133.987203 -404.382953)
			(xy 133.971402 -404.443211) (xy 133.948024 -404.500954) (xy 133.917455 -404.555233) (xy 133.880195 -404.605157)
			(xy 133.836858 -404.649907) (xy 133.788153 -404.688747) (xy 133.734882 -404.72104) (xy 133.677919 -404.746257)
			(xy 133.618198 -404.763981) (xy 133.556701 -404.773924) (xy 133.494438 -404.77592) (xy 133.432431 -404.769938)
			(xy 133.371697 -404.756076) (xy 133.313235 -404.734562) (xy 133.258004 -404.705748) (xy 133.206912 -404.670108)
			(xy 133.160796 -404.628227) (xy 133.120414 -404.580792) (xy 133.08643 -404.528583) (xy 133.059401 -404.472457)
			(xy 133.039772 -404.413336) (xy 133.027863 -404.352189) (xy 133.023872 -404.290022) (xy 129.59503 -404.290022)
			(xy 129.595029 -404.322738) (xy 129.586243 -404.387583) (xy 129.568834 -404.450663) (xy 129.543115 -404.510834)
			(xy 129.526792 -404.539196) (xy 129.523478 -404.545221) (xy 129.519872 -404.558484) (xy 129.51968 -404.565358)
			(xy 129.51968 -405.314658) (xy 129.51989 -405.32153) (xy 129.523486 -405.334793) (xy 129.526792 -405.34082)
			(xy 129.543108 -405.369184) (xy 129.568825 -405.429355) (xy 129.586232 -405.492433) (xy 129.595016 -405.557277)
			(xy 129.595016 -405.622713) (xy 129.586234 -405.687557) (xy 129.568828 -405.750635) (xy 129.543113 -405.810806)
			(xy 129.526792 -405.839168) (xy 129.523488 -405.845198) (xy 129.519876 -405.858458) (xy 129.51968 -405.86533)
			(xy 129.51968 -406.151334) (xy 129.519195 -406.161492) (xy 129.511413 -406.180258) (xy 129.497045 -406.194622)
			(xy 129.478276 -406.202398) (xy 129.468118 -406.202896) (xy 128.751838 -406.202896) (xy 128.741673 -406.202406)
			(xy 128.722886 -406.19464) (xy 128.708501 -406.180275) (xy 128.700708 -406.161498) (xy 128.700276 -406.151334)
			(xy 128.700276 -405.86533) (xy 128.700075 -405.858457) (xy 128.696473 -405.845194) (xy 128.693164 -405.839168)
			(xy 128.676836 -405.81081) (xy 128.651117 -405.750638) (xy 128.633709 -405.687559) (xy 128.624926 -405.622714)
			(xy 127.336205 -405.622714) (xy 127.326644 -405.63927) (xy 127.323343 -405.645302) (xy 127.319728 -405.65856)
			(xy 127.319532 -405.665432) (xy 127.319532 -406.414732) (xy 127.319708 -406.421606) (xy 127.323327 -406.434869)
			(xy 127.326644 -406.440894) (xy 127.343002 -406.469248) (xy 127.368807 -406.529405) (xy 127.386299 -406.592483)
			(xy 127.395161 -406.657339) (xy 127.395732 -406.690068) (xy 127.39517 -406.722792) (xy 130.825066 -406.722792)
			(xy 130.82507 -406.657353) (xy 130.833857 -406.592507) (xy 130.851268 -406.529428) (xy 130.876988 -406.469256)
			(xy 130.893312 -406.440894) (xy 130.89663 -406.434871) (xy 130.900233 -406.421606) (xy 130.900424 -406.414732)
			(xy 130.900424 -405.665432) (xy 130.900217 -405.65856) (xy 130.896619 -405.645297) (xy 130.893312 -405.63927)
			(xy 130.876987 -405.61091) (xy 130.851271 -405.550738) (xy 130.833865 -405.487659) (xy 130.825082 -405.422815)
			(xy 130.825082 -405.357378) (xy 130.833866 -405.292534) (xy 130.851274 -405.229455) (xy 130.87699 -405.169284)
			(xy 130.893312 -405.140922) (xy 130.89662 -405.134894) (xy 130.90023 -405.121633) (xy 130.900424 -405.11476)
			(xy 130.900424 -404.828756) (xy 130.900786 -404.818596) (xy 130.908601 -404.799838) (xy 130.923016 -404.785515)
			(xy 130.941823 -404.777822) (xy 130.951986 -404.777448) (xy 131.668266 -404.777448) (xy 131.678391 -404.777955)
			(xy 131.697113 -404.785673) (xy 131.711471 -404.799953) (xy 131.71929 -404.818633) (xy 131.719828 -404.828756)
			(xy 131.719828 -405.11476) (xy 131.720032 -405.121632) (xy 131.723632 -405.134895) (xy 131.72694 -405.140922)
			(xy 131.743259 -405.169285) (xy 131.768979 -405.229455) (xy 131.786388 -405.292534) (xy 131.795172 -405.357378)
			(xy 131.795173 -405.422815) (xy 131.786389 -405.487659) (xy 131.768981 -405.550738) (xy 131.752202 -405.589994)
			(xy 133.023872 -405.589994) (xy 133.027863 -405.527827) (xy 133.039772 -405.46668) (xy 133.059401 -405.407559)
			(xy 133.08643 -405.351433) (xy 133.120414 -405.299224) (xy 133.160796 -405.251789) (xy 133.206912 -405.209908)
			(xy 133.258004 -405.174268) (xy 133.313235 -405.145454) (xy 133.371697 -405.12394) (xy 133.432431 -405.110078)
			(xy 133.494438 -405.104096) (xy 133.556701 -405.106092) (xy 133.618198 -405.116035) (xy 133.677919 -405.133759)
			(xy 133.734882 -405.158976) (xy 133.788153 -405.191269) (xy 133.836858 -405.230109) (xy 133.880195 -405.274859)
			(xy 133.917455 -405.324783) (xy 133.948024 -405.379062) (xy 133.952491 -405.390096) (xy 135.22402 -405.390096)
			(xy 135.228011 -405.327929) (xy 135.23992 -405.266782) (xy 135.259549 -405.207661) (xy 135.286578 -405.151535)
			(xy 135.320562 -405.099326) (xy 135.360944 -405.051891) (xy 135.40706 -405.01001) (xy 135.458152 -404.97437)
			(xy 135.513383 -404.945556) (xy 135.571845 -404.924042) (xy 135.632579 -404.91018) (xy 135.694586 -404.904198)
			(xy 135.756849 -404.906194) (xy 135.818346 -404.916137) (xy 135.878067 -404.933861) (xy 135.93503 -404.959078)
			(xy 135.988301 -404.991371) (xy 136.037006 -405.030211) (xy 136.080343 -405.074961) (xy 136.117603 -405.124885)
			(xy 136.148172 -405.179164) (xy 136.17155 -405.236907) (xy 136.187351 -405.297165) (xy 136.195317 -405.358948)
			(xy 136.195816 -405.390096) (xy 136.195317 -405.421244) (xy 136.187351 -405.483027) (xy 136.17155 -405.543285)
			(xy 136.148172 -405.601028) (xy 136.117603 -405.655307) (xy 136.080343 -405.705231) (xy 136.037006 -405.749981)
			(xy 135.988301 -405.788821) (xy 135.93503 -405.821114) (xy 135.878067 -405.846331) (xy 135.818346 -405.864055)
			(xy 135.756849 -405.873998) (xy 135.694586 -405.875994) (xy 135.632579 -405.870012) (xy 135.571845 -405.85615)
			(xy 135.513383 -405.834636) (xy 135.458152 -405.805822) (xy 135.40706 -405.770182) (xy 135.360944 -405.728301)
			(xy 135.320562 -405.680866) (xy 135.286578 -405.628657) (xy 135.259549 -405.572531) (xy 135.23992 -405.51341)
			(xy 135.228011 -405.452263) (xy 135.22402 -405.390096) (xy 133.952491 -405.390096) (xy 133.971402 -405.436805)
			(xy 133.987203 -405.497063) (xy 133.995169 -405.558846) (xy 133.995668 -405.589994) (xy 133.995169 -405.621142)
			(xy 133.987203 -405.682925) (xy 133.971402 -405.743183) (xy 133.948024 -405.800926) (xy 133.917455 -405.855205)
			(xy 133.880195 -405.905129) (xy 133.836858 -405.949879) (xy 133.788153 -405.988719) (xy 133.734882 -406.021012)
			(xy 133.677919 -406.046229) (xy 133.618198 -406.063953) (xy 133.556701 -406.073896) (xy 133.494438 -406.075892)
			(xy 133.432431 -406.06991) (xy 133.371697 -406.056048) (xy 133.313235 -406.034534) (xy 133.258004 -406.00572)
			(xy 133.206912 -405.97008) (xy 133.160796 -405.928199) (xy 133.120414 -405.880764) (xy 133.08643 -405.828555)
			(xy 133.059401 -405.772429) (xy 133.039772 -405.713308) (xy 133.027863 -405.652161) (xy 133.023872 -405.589994)
			(xy 131.752202 -405.589994) (xy 131.743263 -405.610909) (xy 131.72694 -405.63927) (xy 131.723639 -405.645302)
			(xy 131.720024 -405.65856) (xy 131.719828 -405.665432) (xy 131.719828 -406.414732) (xy 131.720004 -406.421606)
			(xy 131.723623 -406.434869) (xy 131.72694 -406.440894) (xy 131.743236 -406.46927) (xy 131.768957 -406.529437)
			(xy 131.786369 -406.592513) (xy 131.795156 -406.657355) (xy 131.795158 -406.690068) (xy 135.22402 -406.690068)
			(xy 135.228011 -406.627901) (xy 135.23992 -406.566754) (xy 135.259549 -406.507633) (xy 135.286578 -406.451507)
			(xy 135.320562 -406.399298) (xy 135.360944 -406.351863) (xy 135.40706 -406.309982) (xy 135.458152 -406.274342)
			(xy 135.513383 -406.245528) (xy 135.571845 -406.224014) (xy 135.632579 -406.210152) (xy 135.694586 -406.20417)
			(xy 135.756849 -406.206166) (xy 135.818346 -406.216109) (xy 135.878067 -406.233833) (xy 135.93503 -406.25905)
			(xy 135.988301 -406.291343) (xy 136.037006 -406.330183) (xy 136.080343 -406.374933) (xy 136.117603 -406.424857)
			(xy 136.148172 -406.479136) (xy 136.17155 -406.536879) (xy 136.187351 -406.597137) (xy 136.195317 -406.65892)
			(xy 136.195816 -406.690068) (xy 136.195317 -406.721216) (xy 136.187351 -406.782999) (xy 136.17155 -406.843257)
			(xy 136.148172 -406.901) (xy 136.117603 -406.955279) (xy 136.080343 -407.005203) (xy 136.037006 -407.049953)
			(xy 135.988301 -407.088793) (xy 135.93503 -407.121086) (xy 135.878067 -407.146303) (xy 135.818346 -407.164027)
			(xy 135.756849 -407.17397) (xy 135.694586 -407.175966) (xy 135.632579 -407.169984) (xy 135.571845 -407.156122)
			(xy 135.513383 -407.134608) (xy 135.458152 -407.105794) (xy 135.40706 -407.070154) (xy 135.360944 -407.028273)
			(xy 135.320562 -406.980838) (xy 135.286578 -406.928629) (xy 135.259549 -406.872503) (xy 135.23992 -406.813382)
			(xy 135.228011 -406.752235) (xy 135.22402 -406.690068) (xy 131.795158 -406.690068) (xy 131.79516 -406.72279)
			(xy 131.78638 -406.787633) (xy 131.768975 -406.850711) (xy 131.743261 -406.910881) (xy 131.72694 -406.939242)
			(xy 131.723614 -406.945261) (xy 131.720015 -406.958529) (xy 131.719828 -406.965404) (xy 131.719828 -407.251408)
			(xy 131.719385 -407.261559) (xy 131.711592 -407.280306) (xy 131.697203 -407.294628) (xy 131.678419 -407.302333)
			(xy 131.668266 -407.302716) (xy 130.951986 -407.302716) (xy 130.941853 -407.302283) (xy 130.923123 -407.294543)
			(xy 130.908766 -407.28024) (xy 130.900955 -407.261539) (xy 130.900424 -407.251408) (xy 130.900424 -406.965404)
			(xy 130.900228 -406.958531) (xy 130.896622 -406.945268) (xy 130.893312 -406.939242) (xy 130.876963 -406.910895)
			(xy 130.85125 -406.850721) (xy 130.833846 -406.787639) (xy 130.825066 -406.722792) (xy 127.39517 -406.722792)
			(xy 127.39517 -406.722798) (xy 127.386313 -406.787656) (xy 127.368821 -406.850736) (xy 127.343013 -406.910894)
			(xy 127.326644 -406.939242) (xy 127.323318 -406.945261) (xy 127.319719 -406.958529) (xy 127.319532 -406.965404)
			(xy 127.319532 -407.251408) (xy 127.319022 -407.261513) (xy 127.311288 -407.280185) (xy 127.296999 -407.294479)
			(xy 127.278329 -407.302219) (xy 127.268224 -407.302716) (xy 126.551944 -407.302716) (xy 126.541826 -407.302248)
			(xy 126.523127 -407.294518) (xy 126.508812 -407.280217) (xy 126.501062 -407.261525) (xy 126.500636 -407.251408)
			(xy 126.500636 -406.965404) (xy 126.500438 -406.958531) (xy 126.496833 -406.945269) (xy 126.493524 -406.939242)
			(xy 126.477177 -406.910882) (xy 126.45137 -406.850727) (xy 126.433875 -406.78765) (xy 126.425009 -406.722796)
			(xy 126.424436 -406.690068) (xy 122.995072 -406.690068) (xy 122.995074 -406.72279) (xy 122.986294 -406.787633)
			(xy 122.96889 -406.85071) (xy 122.943176 -406.910881) (xy 122.926856 -406.939242) (xy 122.923531 -406.945262)
			(xy 122.919931 -406.958529) (xy 122.919744 -406.965404) (xy 122.919744 -407.251408) (xy 122.919286 -407.261557)
			(xy 122.911496 -407.280301) (xy 122.897111 -407.294623) (xy 122.878333 -407.30233) (xy 122.868182 -407.302716)
			(xy 122.151902 -407.302716) (xy 122.14177 -407.30227) (xy 122.123041 -407.294535) (xy 122.108683 -407.280236)
			(xy 122.100871 -407.261538) (xy 122.10034 -407.251408) (xy 122.10034 -406.965404) (xy 122.100141 -406.958531)
			(xy 122.096537 -406.945269) (xy 122.093228 -406.939242) (xy 122.076879 -406.910896) (xy 122.051165 -406.850721)
			(xy 122.03376 -406.787639) (xy 122.02498 -406.722792) (xy 118.595084 -406.722792) (xy 118.595084 -406.722798)
			(xy 118.586227 -406.787656) (xy 118.568736 -406.850736) (xy 118.542928 -406.910894) (xy 118.52656 -406.939242)
			(xy 118.523235 -406.945262) (xy 118.519635 -406.958529) (xy 118.519448 -406.965404) (xy 118.519448 -407.251408)
			(xy 118.518922 -407.261511) (xy 118.511191 -407.28018) (xy 118.496907 -407.294473) (xy 118.478243 -407.302216)
			(xy 118.46814 -407.302716) (xy 117.75186 -407.302716) (xy 117.741751 -407.302248) (xy 117.723075 -407.2945)
			(xy 117.708782 -407.280198) (xy 117.701046 -407.261518) (xy 117.700552 -407.251408) (xy 117.700552 -406.965404)
			(xy 117.700364 -406.95853) (xy 117.696754 -406.945267) (xy 117.69344 -406.939242) (xy 117.677095 -406.910881)
			(xy 117.651287 -406.850726) (xy 117.633792 -406.78765) (xy 117.624925 -406.722796) (xy 117.624352 -406.690068)
			(xy 92.195037 -406.690068) (xy 92.195039 -406.72279) (xy 92.186259 -406.787633) (xy 92.168853 -406.850711)
			(xy 92.143137 -406.910881) (xy 92.126816 -406.939242) (xy 92.123487 -406.94526) (xy 92.11989 -406.958529)
			(xy 92.119704 -406.965404) (xy 92.119704 -407.251408) (xy 92.119285 -407.261562) (xy 92.111487 -407.280314)
			(xy 92.09709 -407.294637) (xy 92.078298 -407.302337) (xy 92.068142 -407.302716) (xy 91.351862 -407.302716)
			(xy 91.341727 -407.302303) (xy 91.322997 -407.294555) (xy 91.308641 -407.280246) (xy 91.30083 -407.261541)
			(xy 91.3003 -407.251408) (xy 91.3003 -406.965404) (xy 91.300107 -406.958531) (xy 91.2965 -406.945268)
			(xy 91.293188 -406.939242) (xy 91.27684 -406.910895) (xy 91.251128 -406.85072) (xy 91.233725 -406.787638)
			(xy 91.224945 -406.722792) (xy 87.795049 -406.722792) (xy 87.795049 -406.722798) (xy 87.786191 -406.787656)
			(xy 87.768699 -406.850736) (xy 87.742889 -406.910894) (xy 87.72652 -406.939242) (xy 87.723192 -406.94526)
			(xy 87.719594 -406.958529) (xy 87.719408 -406.965404) (xy 87.719408 -407.251408) (xy 87.718921 -407.261516)
			(xy 87.711183 -407.280193) (xy 87.696886 -407.294487) (xy 87.678208 -407.302223) (xy 87.6681 -407.302716)
			(xy 86.95182 -407.302716) (xy 86.941701 -407.302268) (xy 86.923001 -407.29453) (xy 86.908686 -407.280223)
			(xy 86.900937 -407.261527) (xy 86.900512 -407.251408) (xy 86.900512 -406.965404) (xy 86.900317 -406.958531)
			(xy 86.896711 -406.945268) (xy 86.8934 -406.939242) (xy 86.877051 -406.910884) (xy 86.851245 -406.850727)
			(xy 86.833751 -406.787651) (xy 86.824885 -406.722796) (xy 86.824312 -406.690068) (xy 83.394951 -406.690068)
			(xy 83.394953 -406.72279) (xy 83.386173 -406.787633) (xy 83.368768 -406.850711) (xy 83.343053 -406.910881)
			(xy 83.326732 -406.939242) (xy 83.323405 -406.945261) (xy 83.319807 -406.958529) (xy 83.31962 -406.965404)
			(xy 83.31962 -407.251408) (xy 83.319185 -407.26156) (xy 83.311391 -407.280309) (xy 83.296998 -407.294631)
			(xy 83.278212 -407.302334) (xy 83.268058 -407.302716) (xy 82.551778 -407.302716) (xy 82.541644 -407.30229)
			(xy 82.522914 -407.294547) (xy 82.508557 -407.280242) (xy 82.500747 -407.26154) (xy 82.500216 -407.251408)
			(xy 82.500216 -406.965404) (xy 82.500021 -406.958531) (xy 82.496415 -406.945268) (xy 82.493104 -406.939242)
			(xy 82.476756 -406.910895) (xy 82.451043 -406.85072) (xy 82.433639 -406.787639) (xy 82.424859 -406.722792)
			(xy 78.994963 -406.722792) (xy 78.994963 -406.722798) (xy 78.986106 -406.787656) (xy 78.968614 -406.850736)
			(xy 78.942805 -406.910894) (xy 78.926436 -406.939242) (xy 78.923109 -406.945261) (xy 78.919511 -406.958529)
			(xy 78.919324 -406.965404) (xy 78.919324 -407.251408) (xy 78.918822 -407.261514) (xy 78.911086 -407.280188)
			(xy 78.896795 -407.294482) (xy 78.878122 -407.30222) (xy 78.868016 -407.302716) (xy 78.151736 -407.302716)
			(xy 78.141618 -407.302255) (xy 78.122918 -407.294521) (xy 78.108603 -407.280219) (xy 78.100854 -407.261526)
			(xy 78.100428 -407.251408) (xy 78.100428 -406.965404) (xy 78.100231 -406.958531) (xy 78.096626 -406.945269)
			(xy 78.093316 -406.939242) (xy 78.076969 -406.910883) (xy 78.051162 -406.850727) (xy 78.033667 -406.787651)
			(xy 78.024801 -406.722796) (xy 78.024228 -406.690068) (xy 74.594865 -406.690068) (xy 74.594867 -406.72279)
			(xy 74.586087 -406.787633) (xy 74.568683 -406.85071) (xy 74.542969 -406.910881) (xy 74.526648 -406.939242)
			(xy 74.523322 -406.945261) (xy 74.519723 -406.958529) (xy 74.519536 -406.965404) (xy 74.519536 -407.251408)
			(xy 74.519085 -407.261558) (xy 74.511294 -407.280304) (xy 74.496907 -407.294625) (xy 74.478126 -407.302331)
			(xy 74.467974 -407.302716) (xy 73.751694 -407.302716) (xy 73.741562 -407.302277) (xy 73.722832 -407.294539)
			(xy 73.708474 -407.280238) (xy 73.700663 -407.261538) (xy 73.700132 -407.251408) (xy 73.700132 -406.965404)
			(xy 73.699935 -406.958531) (xy 73.69633 -406.945269) (xy 73.69302 -406.939242) (xy 73.676671 -406.910895)
			(xy 73.650957 -406.850721) (xy 73.633553 -406.787639) (xy 73.624773 -406.722792) (xy 66.622676 -406.722792)
			(xy 66.622676 -409.490164) (xy 71.424292 -409.490164) (xy 71.424865 -409.457435) (xy 71.433719 -409.392577)
			(xy 71.451207 -409.329497) (xy 71.477013 -409.269338) (xy 71.49338 -409.24099) (xy 71.496697 -409.234966)
			(xy 71.500302 -409.221702) (xy 71.500492 -409.214828) (xy 71.500492 -408.465528) (xy 71.50029 -408.458655)
			(xy 71.496689 -408.445393) (xy 71.49338 -408.439366) (xy 71.476999 -408.411025) (xy 71.451201 -408.350863)
			(xy 71.433716 -408.28778) (xy 71.42486 -408.222922) (xy 71.424292 -408.190192) (xy 71.424878 -408.157463)
			(xy 71.433728 -408.092606) (xy 71.451212 -408.029526) (xy 71.477014 -407.969367) (xy 71.49338 -407.941018)
			(xy 71.496687 -407.934989) (xy 71.500298 -407.921729) (xy 71.500492 -407.914856) (xy 71.500492 -407.628852)
			(xy 71.500946 -407.618741) (xy 71.508698 -407.600063) (xy 71.523004 -407.585771) (xy 71.541689 -407.578036)
			(xy 71.5518 -407.577544) (xy 72.26808 -407.577544) (xy 72.278181 -407.5781) (xy 72.296848 -407.585821)
			(xy 72.311141 -407.600095) (xy 72.318887 -407.618752) (xy 72.319388 -407.628852) (xy 72.319388 -407.914856)
			(xy 72.319599 -407.921728) (xy 72.323194 -407.93499) (xy 72.3265 -407.941018) (xy 72.342873 -407.969363)
			(xy 72.368673 -408.029524) (xy 72.38616 -408.092605) (xy 72.395019 -408.157463) (xy 72.395588 -408.190192)
			(xy 72.395043 -408.222922) (xy 72.386181 -408.287781) (xy 72.368685 -408.350861) (xy 72.342871 -408.411019)
			(xy 72.3265 -408.439366) (xy 72.323197 -408.445397) (xy 72.319584 -408.458656) (xy 72.319388 -408.465528)
			(xy 72.319388 -409.214828) (xy 72.319571 -409.221702) (xy 72.323185 -409.234965) (xy 72.3265 -409.24099)
			(xy 72.342862 -409.269341) (xy 72.368664 -409.3295) (xy 72.386155 -409.392579) (xy 72.395017 -409.457435)
			(xy 72.395588 -409.490164) (xy 72.39503 -409.522894) (xy 72.386172 -409.587752) (xy 72.36868 -409.650833)
			(xy 72.34287 -409.71099) (xy 72.3265 -409.739338) (xy 72.323172 -409.745356) (xy 72.319575 -409.758625)
			(xy 72.319388 -409.7655) (xy 72.319388 -410.051504) (xy 72.318987 -410.061628) (xy 72.311235 -410.080334)
			(xy 72.296914 -410.094649) (xy 72.278204 -410.102392) (xy 72.26808 -410.102812) (xy 71.5518 -410.102812)
			(xy 71.541693 -410.102315) (xy 71.523017 -410.09458) (xy 71.508723 -410.080286) (xy 71.500986 -410.061611)
			(xy 71.500492 -410.051504) (xy 71.500492 -409.7655) (xy 71.500301 -409.758627) (xy 71.496692 -409.745364)
			(xy 71.49338 -409.739338) (xy 71.477028 -409.710982) (xy 71.451223 -409.650824) (xy 71.43373 -409.587747)
			(xy 71.424865 -409.522892) (xy 71.424292 -409.490164) (xy 66.622676 -409.490164) (xy 66.622676 -410.622705)
			(xy 73.624782 -410.622705) (xy 73.624784 -410.557267) (xy 73.633569 -410.492422) (xy 73.650979 -410.429343)
			(xy 73.676697 -410.369171) (xy 73.69302 -410.34081) (xy 73.696333 -410.334784) (xy 73.699939 -410.321521)
			(xy 73.700132 -410.314648) (xy 73.700132 -409.565348) (xy 73.699918 -409.558476) (xy 73.696324 -409.545214)
			(xy 73.69302 -409.539186) (xy 73.676709 -409.510819) (xy 73.650991 -409.450649) (xy 73.633582 -409.387571)
			(xy 73.624798 -409.322728) (xy 73.624797 -409.257292) (xy 73.633578 -409.192449) (xy 73.650984 -409.129371)
			(xy 73.676699 -409.069199) (xy 73.69302 -409.040838) (xy 73.696323 -409.034807) (xy 73.699936 -409.021548)
			(xy 73.700132 -409.014676) (xy 73.700132 -408.728672) (xy 73.700499 -408.718512) (xy 73.70831 -408.699753)
			(xy 73.722724 -408.685429) (xy 73.741532 -408.677736) (xy 73.751694 -408.677364) (xy 74.467974 -408.677364)
			(xy 74.478102 -408.677848) (xy 74.496827 -408.685572) (xy 74.511185 -408.69986) (xy 74.519001 -408.718546)
			(xy 74.519536 -408.728672) (xy 74.519536 -409.014676) (xy 74.519733 -409.021549) (xy 74.523337 -409.034812)
			(xy 74.526648 -409.040838) (xy 74.542981 -409.069194) (xy 74.568698 -409.129366) (xy 74.586106 -409.192446)
			(xy 74.594888 -409.257291) (xy 74.594887 -409.322729) (xy 74.586101 -409.387574) (xy 74.568691 -409.450654)
			(xy 74.542971 -409.510825) (xy 74.536028 -409.522889) (xy 75.824912 -409.522889) (xy 75.824916 -409.457449)
			(xy 75.833705 -409.392603) (xy 75.851119 -409.329523) (xy 75.876842 -409.269351) (xy 75.893168 -409.24099)
			(xy 75.896484 -409.234966) (xy 75.900089 -409.221702) (xy 75.90028 -409.214828) (xy 75.90028 -408.465528)
			(xy 75.90008 -408.458655) (xy 75.896477 -408.445393) (xy 75.893168 -408.439366) (xy 75.876838 -408.411009)
			(xy 75.85112 -408.350837) (xy 75.833711 -408.287757) (xy 75.824928 -408.222912) (xy 75.824929 -408.157474)
			(xy 75.833714 -408.092629) (xy 75.851124 -408.02955) (xy 75.876844 -407.969379) (xy 75.893168 -407.941018)
			(xy 75.896474 -407.934989) (xy 75.900085 -407.921729) (xy 75.90028 -407.914856) (xy 75.90028 -407.628852)
			(xy 75.900682 -407.618697) (xy 75.90849 -407.599948) (xy 75.922892 -407.585627) (xy 75.941685 -407.577925)
			(xy 75.951842 -407.577544) (xy 76.668122 -407.577544) (xy 76.678251 -407.578008) (xy 76.696973 -407.585744)
			(xy 76.711329 -407.600037) (xy 76.719147 -407.618726) (xy 76.719684 -407.628852) (xy 76.719684 -407.914856)
			(xy 76.719895 -407.921728) (xy 76.72349 -407.934991) (xy 76.726796 -407.941018) (xy 76.74311 -407.969383)
			(xy 76.768827 -408.029554) (xy 76.786234 -408.092632) (xy 76.795018 -408.157475) (xy 76.795019 -408.222911)
			(xy 76.786237 -408.287755) (xy 76.768831 -408.350833) (xy 76.743117 -408.411004) (xy 76.726796 -408.439366)
			(xy 76.723493 -408.445396) (xy 76.71988 -408.458656) (xy 76.719684 -408.465528) (xy 76.719684 -409.214828)
			(xy 76.719867 -409.221702) (xy 76.723482 -409.234965) (xy 76.726796 -409.24099) (xy 76.743087 -409.269368)
			(xy 76.768805 -409.329536) (xy 76.786215 -409.392611) (xy 76.795002 -409.457452) (xy 76.795006 -409.522886)
			(xy 76.786228 -409.587728) (xy 76.768826 -409.650806) (xy 76.743115 -409.710976) (xy 76.726796 -409.739338)
			(xy 76.723467 -409.745356) (xy 76.719871 -409.758625) (xy 76.719684 -409.7655) (xy 76.719684 -410.051504)
			(xy 76.719281 -410.06166) (xy 76.711481 -410.080416) (xy 76.697079 -410.09474) (xy 76.678281 -410.102436)
			(xy 76.668122 -410.102812) (xy 75.951842 -410.102812) (xy 75.941724 -410.10224) (xy 75.923014 -410.094536)
			(xy 75.908658 -410.080276) (xy 75.900828 -410.061618) (xy 75.90028 -410.051504) (xy 75.90028 -409.7655)
			(xy 75.90009 -409.758627) (xy 75.896481 -409.745364) (xy 75.893168 -409.739338) (xy 75.876814 -409.710994)
			(xy 75.851098 -409.650819) (xy 75.833692 -409.587737) (xy 75.824912 -409.522889) (xy 74.536028 -409.522889)
			(xy 74.526648 -409.539186) (xy 74.523342 -409.545215) (xy 74.51973 -409.558475) (xy 74.519536 -409.565348)
			(xy 74.519536 -410.314648) (xy 74.519743 -410.32152) (xy 74.523341 -410.334783) (xy 74.526648 -410.34081)
			(xy 74.542957 -410.369179) (xy 74.568677 -410.429348) (xy 74.586087 -410.492425) (xy 74.594872 -410.557268)
			(xy 74.594873 -410.589984) (xy 78.024228 -410.589984) (xy 78.024819 -410.557255) (xy 78.033669 -410.492398)
			(xy 78.051152 -410.429318) (xy 78.076951 -410.369159) (xy 78.093316 -410.34081) (xy 78.096628 -410.334784)
			(xy 78.100235 -410.321521) (xy 78.100428 -410.314648) (xy 78.100428 -409.565348) (xy 78.100214 -409.558476)
			(xy 78.096621 -409.545214) (xy 78.093316 -409.539186) (xy 78.076946 -409.510839) (xy 78.051145 -409.450679)
			(xy 78.033657 -409.387599) (xy 78.024798 -409.322741) (xy 78.024228 -409.290012) (xy 78.024787 -409.257282)
			(xy 78.033646 -409.192424) (xy 78.051139 -409.129344) (xy 78.076947 -409.069186) (xy 78.093316 -409.040838)
			(xy 78.096618 -409.034807) (xy 78.100232 -409.021548) (xy 78.100428 -409.014676) (xy 78.100428 -408.728672)
			(xy 78.100794 -408.718544) (xy 78.108556 -408.699835) (xy 78.122888 -408.68552) (xy 78.141608 -408.677781)
			(xy 78.151736 -408.677364) (xy 78.868016 -408.677364) (xy 78.878121 -408.677871) (xy 78.896793 -408.685608)
			(xy 78.911086 -408.699897) (xy 78.918826 -408.718567) (xy 78.919324 -408.728672) (xy 78.919324 -409.014676)
			(xy 78.919522 -409.021549) (xy 78.923126 -409.034812) (xy 78.926436 -409.040838) (xy 78.942811 -409.069182)
			(xy 78.968612 -409.129343) (xy 78.986099 -409.192424) (xy 78.994956 -409.257282) (xy 78.995524 -409.290012)
			(xy 78.994938 -409.322741) (xy 78.986088 -409.387598) (xy 78.968603 -409.450678) (xy 78.951668 -409.490164)
			(xy 80.224376 -409.490164) (xy 80.224951 -409.457435) (xy 80.233805 -409.392577) (xy 80.251293 -409.329497)
			(xy 80.277097 -409.269339) (xy 80.293464 -409.24099) (xy 80.296779 -409.234966) (xy 80.300385 -409.221702)
			(xy 80.300576 -409.214828) (xy 80.300576 -408.465528) (xy 80.300376 -408.458655) (xy 80.296774 -408.445392)
			(xy 80.293464 -408.439366) (xy 80.277091 -408.411021) (xy 80.25129 -408.35086) (xy 80.233802 -408.287779)
			(xy 80.224944 -408.222921) (xy 80.224376 -408.190192) (xy 80.224964 -408.157463) (xy 80.233814 -408.092606)
			(xy 80.251298 -408.029526) (xy 80.277099 -407.969367) (xy 80.293464 -407.941018) (xy 80.296769 -407.934989)
			(xy 80.300381 -407.921729) (xy 80.300576 -407.914856) (xy 80.300576 -407.628852) (xy 80.301045 -407.618743)
			(xy 80.308794 -407.600069) (xy 80.323095 -407.585776) (xy 80.341775 -407.578039) (xy 80.351884 -407.577544)
			(xy 81.068164 -407.577544) (xy 81.078264 -407.578113) (xy 81.09693 -407.585829) (xy 81.111224 -407.600099)
			(xy 81.11897 -407.618753) (xy 81.119472 -407.628852) (xy 81.119472 -407.914856) (xy 81.119684 -407.921728)
			(xy 81.123279 -407.93499) (xy 81.126584 -407.941018) (xy 81.142955 -407.969364) (xy 81.168756 -408.029525)
			(xy 81.186244 -408.092605) (xy 81.195103 -408.157463) (xy 81.195672 -408.190192) (xy 81.195115 -408.222922)
			(xy 81.186255 -408.28778) (xy 81.168762 -408.35086) (xy 81.142953 -408.411018) (xy 81.126584 -408.439366)
			(xy 81.12328 -408.445396) (xy 81.119668 -408.458656) (xy 81.119472 -408.465528) (xy 81.119472 -409.214828)
			(xy 81.119657 -409.221702) (xy 81.12327 -409.234964) (xy 81.126584 -409.24099) (xy 81.142944 -409.269342)
			(xy 81.168748 -409.329501) (xy 81.186239 -409.392579) (xy 81.195101 -409.457435) (xy 81.195672 -409.490164)
			(xy 81.195103 -409.522893) (xy 81.186246 -409.587751) (xy 81.168757 -409.650831) (xy 81.142952 -409.71099)
			(xy 81.126584 -409.739338) (xy 81.123255 -409.745355) (xy 81.119659 -409.758625) (xy 81.119472 -409.7655)
			(xy 81.119472 -410.051504) (xy 81.119086 -410.06163) (xy 81.111332 -410.080339) (xy 81.097006 -410.094654)
			(xy 81.078291 -410.102394) (xy 81.068164 -410.102812) (xy 80.351884 -410.102812) (xy 80.341776 -410.102328)
			(xy 80.3231 -410.094587) (xy 80.308806 -410.08029) (xy 80.30107 -410.061612) (xy 80.300576 -410.051504)
			(xy 80.300576 -409.7655) (xy 80.300387 -409.758627) (xy 80.296777 -409.745364) (xy 80.293464 -409.739338)
			(xy 80.27712 -409.710977) (xy 80.251311 -409.650822) (xy 80.233815 -409.587746) (xy 80.224949 -409.522892)
			(xy 80.224376 -409.490164) (xy 78.951668 -409.490164) (xy 78.942802 -409.510837) (xy 78.926436 -409.539186)
			(xy 78.923129 -409.545215) (xy 78.919518 -409.558475) (xy 78.919324 -409.565348) (xy 78.919324 -410.314648)
			(xy 78.919533 -410.32152) (xy 78.923129 -410.334783) (xy 78.926436 -410.34081) (xy 78.942799 -410.369161)
			(xy 78.968603 -410.429319) (xy 78.986094 -410.492398) (xy 78.994954 -410.557255) (xy 78.995524 -410.589984)
			(xy 78.99497 -410.622705) (xy 82.424868 -410.622705) (xy 82.42487 -410.557268) (xy 82.433655 -410.492423)
			(xy 82.451064 -410.429343) (xy 82.476782 -410.369172) (xy 82.493104 -410.34081) (xy 82.496415 -410.334784)
			(xy 82.500023 -410.321521) (xy 82.500216 -410.314648) (xy 82.500216 -409.565348) (xy 82.500003 -409.558476)
			(xy 82.496409 -409.545214) (xy 82.493104 -409.539186) (xy 82.476793 -409.510819) (xy 82.451076 -409.450649)
			(xy 82.433668 -409.387571) (xy 82.424884 -409.322728) (xy 82.424883 -409.257293) (xy 82.433664 -409.192449)
			(xy 82.451069 -409.129371) (xy 82.476784 -409.0692) (xy 82.493104 -409.040838) (xy 82.496406 -409.034807)
			(xy 82.500019 -409.021548) (xy 82.500216 -409.014676) (xy 82.500216 -408.728672) (xy 82.500599 -408.718514)
			(xy 82.508407 -408.699758) (xy 82.522815 -408.685435) (xy 82.541618 -408.677739) (xy 82.551778 -408.677364)
			(xy 83.268058 -408.677364) (xy 83.278185 -408.677862) (xy 83.29691 -408.68558) (xy 83.311268 -408.699864)
			(xy 83.319085 -408.718548) (xy 83.31962 -408.728672) (xy 83.31962 -409.014676) (xy 83.319819 -409.021549)
			(xy 83.323422 -409.034812) (xy 83.326732 -409.040838) (xy 83.343065 -409.069193) (xy 83.368783 -409.129366)
			(xy 83.386192 -409.192446) (xy 83.394974 -409.257291) (xy 83.394973 -409.322729) (xy 83.386187 -409.387575)
			(xy 83.368777 -409.450654) (xy 83.351888 -409.490164) (xy 84.624164 -409.490164) (xy 84.624741 -409.457435)
			(xy 84.633594 -409.392577) (xy 84.651081 -409.329497) (xy 84.676885 -409.269338) (xy 84.693252 -409.24099)
			(xy 84.696566 -409.234965) (xy 84.700173 -409.221702) (xy 84.700364 -409.214828) (xy 84.700364 -408.465528)
			(xy 84.700166 -408.458655) (xy 84.696562 -408.445392) (xy 84.693252 -408.439366) (xy 84.676878 -408.411021)
			(xy 84.651077 -408.350861) (xy 84.633589 -408.28778) (xy 84.624732 -408.222921) (xy 84.624164 -408.190192)
			(xy 84.624754 -408.157463) (xy 84.633603 -408.092606) (xy 84.651087 -408.029526) (xy 84.676887 -407.969367)
			(xy 84.693252 -407.941018) (xy 84.696556 -407.934988) (xy 84.700169 -407.921729) (xy 84.700364 -407.914856)
			(xy 84.700364 -407.628852) (xy 84.700845 -407.618745) (xy 84.708592 -407.600072) (xy 84.722889 -407.585781)
			(xy 84.741564 -407.578041) (xy 84.751672 -407.577544) (xy 85.467952 -407.577544) (xy 85.478051 -407.578123)
			(xy 85.496717 -407.585835) (xy 85.511012 -407.600102) (xy 85.518758 -407.618754) (xy 85.51926 -407.628852)
			(xy 85.51926 -407.914856) (xy 85.519474 -407.921728) (xy 85.523068 -407.93499) (xy 85.526372 -407.941018)
			(xy 85.542742 -407.969365) (xy 85.568543 -408.029525) (xy 85.586032 -408.092605) (xy 85.594891 -408.157463)
			(xy 85.59546 -408.190192) (xy 89.023706 -408.190192) (xy 89.027697 -408.128025) (xy 89.039606 -408.066878)
			(xy 89.059235 -408.007757) (xy 89.086264 -407.951631) (xy 89.120248 -407.899422) (xy 89.16063 -407.851987)
			(xy 89.206746 -407.810106) (xy 89.257838 -407.774466) (xy 89.313069 -407.745652) (xy 89.371531 -407.724138)
			(xy 89.432265 -407.710276) (xy 89.494272 -407.704294) (xy 89.556535 -407.70629) (xy 89.618032 -407.716233)
			(xy 89.677753 -407.733957) (xy 89.734716 -407.759174) (xy 89.787987 -407.791467) (xy 89.836692 -407.830307)
			(xy 89.880029 -407.875057) (xy 89.917289 -407.924981) (xy 89.947858 -407.97926) (xy 89.971236 -408.037003)
			(xy 89.987037 -408.097261) (xy 89.995003 -408.159044) (xy 89.995502 -408.190192) (xy 89.995003 -408.22134)
			(xy 89.987037 -408.283123) (xy 89.971236 -408.343381) (xy 89.947858 -408.401124) (xy 89.917289 -408.455403)
			(xy 89.880029 -408.505327) (xy 89.836692 -408.550077) (xy 89.787987 -408.588917) (xy 89.734716 -408.62121)
			(xy 89.677753 -408.646427) (xy 89.618032 -408.664151) (xy 89.556535 -408.674094) (xy 89.494272 -408.67609)
			(xy 89.432265 -408.670108) (xy 89.371531 -408.656246) (xy 89.313069 -408.634732) (xy 89.257838 -408.605918)
			(xy 89.206746 -408.570278) (xy 89.16063 -408.528397) (xy 89.120248 -408.480962) (xy 89.086264 -408.428753)
			(xy 89.059235 -408.372627) (xy 89.039606 -408.313506) (xy 89.027697 -408.252359) (xy 89.023706 -408.190192)
			(xy 85.59546 -408.190192) (xy 85.594905 -408.222922) (xy 85.586045 -408.28778) (xy 85.568551 -408.35086)
			(xy 85.542742 -408.411018) (xy 85.526372 -408.439366) (xy 85.523067 -408.445396) (xy 85.519456 -408.458656)
			(xy 85.51926 -408.465528) (xy 85.51926 -409.214828) (xy 85.519446 -409.221702) (xy 85.523059 -409.234964)
			(xy 85.526372 -409.24099) (xy 85.542731 -409.269343) (xy 85.568535 -409.329501) (xy 85.586027 -409.392579)
			(xy 85.594889 -409.457435) (xy 85.59546 -409.490164) (xy 85.594892 -409.522893) (xy 85.586036 -409.587751)
			(xy 85.568546 -409.650831) (xy 85.54274 -409.71099) (xy 85.526372 -409.739338) (xy 85.523042 -409.745355)
			(xy 85.519446 -409.758625) (xy 85.51926 -409.7655) (xy 85.51926 -410.051504) (xy 85.518886 -410.061632)
			(xy 85.511129 -410.080343) (xy 85.496799 -410.094659) (xy 85.47808 -410.102396) (xy 85.467952 -410.102812)
			(xy 84.751672 -410.102812) (xy 84.741563 -410.102338) (xy 84.722886 -410.094594) (xy 84.708593 -410.080293)
			(xy 84.700857 -410.061613) (xy 84.700364 -410.051504) (xy 84.700364 -409.7655) (xy 84.700176 -409.758626)
			(xy 84.696566 -409.745363) (xy 84.693252 -409.739338) (xy 84.676907 -409.710978) (xy 84.651099 -409.650823)
			(xy 84.633603 -409.587746) (xy 84.624737 -409.522892) (xy 84.624164 -409.490164) (xy 83.351888 -409.490164)
			(xy 83.343056 -409.510825) (xy 83.326732 -409.539186) (xy 83.323425 -409.545214) (xy 83.319814 -409.558475)
			(xy 83.31962 -409.565348) (xy 83.31962 -410.314648) (xy 83.319829 -410.32152) (xy 83.323426 -410.334783)
			(xy 83.326732 -410.34081) (xy 83.343042 -410.369178) (xy 83.368762 -410.429348) (xy 83.386173 -410.492425)
			(xy 83.394958 -410.557268) (xy 83.394959 -410.589984) (xy 86.824312 -410.589984) (xy 86.824891 -410.557255)
			(xy 86.833743 -410.492397) (xy 86.851229 -410.429317) (xy 86.877033 -410.369158) (xy 86.8934 -410.34081)
			(xy 86.896711 -410.334784) (xy 86.900319 -410.321521) (xy 86.900512 -410.314648) (xy 86.900512 -409.565348)
			(xy 86.9003 -409.558476) (xy 86.896705 -409.545214) (xy 86.8934 -409.539186) (xy 86.877029 -409.51084)
			(xy 86.851228 -409.450679) (xy 86.83374 -409.387599) (xy 86.824882 -409.322741) (xy 86.824312 -409.290012)
			(xy 86.824859 -409.257282) (xy 86.83372 -409.192423) (xy 86.851216 -409.129343) (xy 86.877029 -409.069185)
			(xy 86.8934 -409.040838) (xy 86.896701 -409.034807) (xy 86.900315 -409.021548) (xy 86.900512 -409.014676)
			(xy 86.900512 -408.728672) (xy 86.900962 -408.71856) (xy 86.908711 -408.699879) (xy 86.923019 -408.685585)
			(xy 86.941708 -408.677853) (xy 86.95182 -408.677364) (xy 87.6681 -408.677364) (xy 87.678204 -408.677884)
			(xy 87.696876 -408.685615) (xy 87.711169 -408.699901) (xy 87.71891 -408.718568) (xy 87.719408 -408.728672)
			(xy 87.719408 -409.014676) (xy 87.719608 -409.021549) (xy 87.723211 -409.034811) (xy 87.72652 -409.040838)
			(xy 87.742903 -409.069178) (xy 87.7687 -409.129341) (xy 87.786185 -409.192423) (xy 87.79504 -409.257282)
			(xy 87.795608 -409.290012) (xy 87.795024 -409.322741) (xy 87.786173 -409.387598) (xy 87.768688 -409.450679)
			(xy 87.751753 -409.490164) (xy 89.023706 -409.490164) (xy 89.027697 -409.427997) (xy 89.039606 -409.36685)
			(xy 89.059235 -409.307729) (xy 89.086264 -409.251603) (xy 89.120248 -409.199394) (xy 89.16063 -409.151959)
			(xy 89.206746 -409.110078) (xy 89.257838 -409.074438) (xy 89.313069 -409.045624) (xy 89.371531 -409.02411)
			(xy 89.432265 -409.010248) (xy 89.494272 -409.004266) (xy 89.556535 -409.006262) (xy 89.618032 -409.016205)
			(xy 89.677753 -409.033929) (xy 89.734716 -409.059146) (xy 89.787987 -409.091439) (xy 89.836692 -409.130279)
			(xy 89.880029 -409.175029) (xy 89.917289 -409.224953) (xy 89.947858 -409.279232) (xy 89.971236 -409.336975)
			(xy 89.987037 -409.397233) (xy 89.995003 -409.459016) (xy 89.995502 -409.490164) (xy 89.995003 -409.521312)
			(xy 89.987037 -409.583095) (xy 89.971236 -409.643353) (xy 89.947858 -409.701096) (xy 89.917289 -409.755375)
			(xy 89.880029 -409.805299) (xy 89.836692 -409.850049) (xy 89.787987 -409.888889) (xy 89.734716 -409.921182)
			(xy 89.677753 -409.946399) (xy 89.618032 -409.964123) (xy 89.556535 -409.974066) (xy 89.494272 -409.976062)
			(xy 89.432265 -409.97008) (xy 89.371531 -409.956218) (xy 89.313069 -409.934704) (xy 89.257838 -409.90589)
			(xy 89.206746 -409.87025) (xy 89.16063 -409.828369) (xy 89.120248 -409.780934) (xy 89.086264 -409.728725)
			(xy 89.059235 -409.672599) (xy 89.039606 -409.613478) (xy 89.027697 -409.552331) (xy 89.023706 -409.490164)
			(xy 87.751753 -409.490164) (xy 87.742886 -409.510837) (xy 87.72652 -409.539186) (xy 87.723212 -409.545214)
			(xy 87.719602 -409.558475) (xy 87.719408 -409.565348) (xy 87.719408 -410.314648) (xy 87.719619 -410.32152)
			(xy 87.723214 -410.334783) (xy 87.72652 -410.34081) (xy 87.742891 -410.369156) (xy 87.768691 -410.429317)
			(xy 87.786179 -410.492397) (xy 87.795038 -410.557255) (xy 87.795608 -410.589984) (xy 87.795057 -410.622705)
			(xy 91.224954 -410.622705) (xy 91.224956 -410.557268) (xy 91.233741 -410.492423) (xy 91.251149 -410.429344)
			(xy 91.276866 -410.369172) (xy 91.293188 -410.34081) (xy 91.296498 -410.334783) (xy 91.300107 -410.321521)
			(xy 91.3003 -410.314648) (xy 91.3003 -409.565348) (xy 91.30009 -409.558476) (xy 91.296494 -409.545213)
			(xy 91.293188 -409.539186) (xy 91.276878 -409.510819) (xy 91.251162 -409.450648) (xy 91.233754 -409.387571)
			(xy 91.22497 -409.322728) (xy 91.224969 -409.257293) (xy 91.23375 -409.192449) (xy 91.251155 -409.129371)
			(xy 91.276868 -409.0692) (xy 91.293188 -409.040838) (xy 91.296488 -409.034806) (xy 91.300103 -409.021548)
			(xy 91.3003 -409.014676) (xy 91.3003 -408.728672) (xy 91.300699 -408.718516) (xy 91.308503 -408.699763)
			(xy 91.322907 -408.685441) (xy 91.341704 -408.677742) (xy 91.351862 -408.677364) (xy 92.068142 -408.677364)
			(xy 92.078274 -408.677793) (xy 92.097001 -408.685539) (xy 92.111357 -408.699843) (xy 92.11917 -408.718542)
			(xy 92.119704 -408.728672) (xy 92.119704 -409.014676) (xy 92.119905 -409.021549) (xy 92.123507 -409.034811)
			(xy 92.126816 -409.040838) (xy 92.14315 -409.069193) (xy 92.168869 -409.129365) (xy 92.186277 -409.192445)
			(xy 92.195061 -409.257291) (xy 92.195059 -409.322729) (xy 92.186273 -409.387575) (xy 92.168862 -409.450654)
			(xy 92.14314 -409.510825) (xy 92.136197 -409.522888) (xy 115.425047 -409.522888) (xy 115.425051 -409.45745)
			(xy 115.433838 -409.392604) (xy 115.451249 -409.329524) (xy 115.476969 -409.269352) (xy 115.493292 -409.24099)
			(xy 115.49661 -409.234967) (xy 115.500214 -409.221702) (xy 115.500404 -409.214828) (xy 115.500404 -408.465528)
			(xy 115.500201 -408.458656) (xy 115.4966 -408.445393) (xy 115.493292 -408.439366) (xy 115.476964 -408.411008)
			(xy 115.45125 -408.350836) (xy 115.433844 -408.287756) (xy 115.425062 -408.222911) (xy 115.425063 -408.157475)
			(xy 115.433847 -408.09263) (xy 115.451254 -408.029551) (xy 115.476971 -407.96938) (xy 115.493292 -407.941018)
			(xy 115.4966 -407.93499) (xy 115.50021 -407.921729) (xy 115.500404 -407.914856) (xy 115.500404 -407.628852)
			(xy 115.500783 -407.618694) (xy 115.508595 -407.59994) (xy 115.523004 -407.585618) (xy 115.541806 -407.577921)
			(xy 115.551966 -407.577544) (xy 116.268246 -407.577544) (xy 116.278376 -407.577989) (xy 116.297099 -407.585733)
			(xy 116.311454 -407.600031) (xy 116.319271 -407.618724) (xy 116.319808 -407.628852) (xy 116.319808 -407.914856)
			(xy 116.320016 -407.921728) (xy 116.323613 -407.934991) (xy 116.32692 -407.941018) (xy 116.343237 -407.969383)
			(xy 116.368957 -408.029552) (xy 116.386367 -408.092631) (xy 116.395153 -408.157475) (xy 116.395154 -408.222911)
			(xy 116.38637 -408.287756) (xy 116.368962 -408.350835) (xy 116.343243 -408.411005) (xy 116.32692 -408.439366)
			(xy 116.323619 -408.445397) (xy 116.320004 -408.458656) (xy 116.319808 -408.465528) (xy 116.319808 -409.214828)
			(xy 116.319988 -409.221702) (xy 116.323604 -409.234965) (xy 116.32692 -409.24099) (xy 116.343213 -409.269368)
			(xy 116.368936 -409.329535) (xy 116.386349 -409.39261) (xy 116.395137 -409.457452) (xy 116.395141 -409.522887)
			(xy 116.386361 -409.58773) (xy 116.368956 -409.650807) (xy 116.343241 -409.710977) (xy 116.32692 -409.739338)
			(xy 116.323593 -409.745357) (xy 116.319995 -409.758625) (xy 116.319808 -409.7655) (xy 116.319808 -410.051504)
			(xy 116.319382 -410.061657) (xy 116.311586 -410.080408) (xy 116.297191 -410.094731) (xy 116.278401 -410.102432)
			(xy 116.268246 -410.102812) (xy 115.551966 -410.102812) (xy 115.541844 -410.102303) (xy 115.523131 -410.094574)
			(xy 115.508778 -410.080295) (xy 115.500951 -410.061624) (xy 115.500404 -410.051504) (xy 115.500404 -409.7655)
			(xy 115.500212 -409.758627) (xy 115.496604 -409.745364) (xy 115.493292 -409.739338) (xy 115.476941 -409.710993)
			(xy 115.451228 -409.650818) (xy 115.433825 -409.587736) (xy 115.425047 -409.522888) (xy 92.136197 -409.522888)
			(xy 92.126816 -409.539186) (xy 92.123507 -409.545214) (xy 92.119898 -409.558475) (xy 92.119704 -409.565348)
			(xy 92.119704 -410.314648) (xy 92.119915 -410.32152) (xy 92.12351 -410.334783) (xy 92.126816 -410.34081)
			(xy 92.143126 -410.369178) (xy 92.168847 -410.429347) (xy 92.186259 -410.492425) (xy 92.195045 -410.557268)
			(xy 92.195045 -410.589984) (xy 117.624352 -410.589984) (xy 117.624939 -410.557255) (xy 117.63379 -410.492398)
			(xy 117.651274 -410.429318) (xy 117.677075 -410.369159) (xy 117.69344 -410.34081) (xy 117.696746 -410.334781)
			(xy 117.700358 -410.321521) (xy 117.700552 -410.314648) (xy 117.700552 -409.565348) (xy 117.700348 -409.558476)
			(xy 117.696749 -409.545213) (xy 117.69344 -409.539186) (xy 117.677073 -409.510838) (xy 117.65127 -409.450678)
			(xy 117.633781 -409.387598) (xy 117.624922 -409.322741) (xy 117.624352 -409.290012) (xy 117.624907 -409.257282)
			(xy 117.633767 -409.192424) (xy 117.651261 -409.129344) (xy 117.67707 -409.069186) (xy 117.69344 -409.040838)
			(xy 117.696737 -409.034804) (xy 117.700354 -409.021548) (xy 117.700552 -409.014676) (xy 117.700552 -408.728672)
			(xy 117.701061 -408.718567) (xy 117.708799 -408.699898) (xy 117.723088 -408.685606) (xy 117.741756 -408.677863)
			(xy 117.75186 -408.677364) (xy 118.46814 -408.677364) (xy 118.478247 -408.677852) (xy 118.496919 -408.685596)
			(xy 118.511211 -408.699891) (xy 118.518951 -408.718565) (xy 118.519448 -408.728672) (xy 118.519448 -409.014676)
			(xy 118.519643 -409.021549) (xy 118.523249 -409.034812) (xy 118.52656 -409.040838) (xy 118.542937 -409.069181)
			(xy 118.568737 -409.129343) (xy 118.586224 -409.192424) (xy 118.59508 -409.257282) (xy 118.595648 -409.290012)
			(xy 118.595059 -409.322741) (xy 118.586209 -409.387598) (xy 118.568726 -409.450678) (xy 118.551791 -409.490164)
			(xy 119.8245 -409.490164) (xy 119.825072 -409.457435) (xy 119.833926 -409.392577) (xy 119.851415 -409.329497)
			(xy 119.87722 -409.269338) (xy 119.893588 -409.24099) (xy 119.896905 -409.234967) (xy 119.90051 -409.221702)
			(xy 119.9007 -409.214828) (xy 119.9007 -408.465528) (xy 119.900497 -408.458656) (xy 119.896896 -408.445393)
			(xy 119.893588 -408.439366) (xy 119.877208 -408.411025) (xy 119.85141 -408.350862) (xy 119.833924 -408.28778)
			(xy 119.825068 -408.222922) (xy 119.8245 -408.190192) (xy 119.825085 -408.157463) (xy 119.833935 -408.092606)
			(xy 119.85142 -408.029525) (xy 119.877222 -407.969367) (xy 119.893588 -407.941018) (xy 119.896895 -407.93499)
			(xy 119.900506 -407.921729) (xy 119.9007 -407.914856) (xy 119.9007 -407.628852) (xy 119.901146 -407.61874)
			(xy 119.908899 -407.600061) (xy 119.923208 -407.585768) (xy 119.941896 -407.578035) (xy 119.952008 -407.577544)
			(xy 120.668288 -407.577544) (xy 120.678389 -407.578094) (xy 120.697056 -407.585817) (xy 120.71135 -407.600093)
			(xy 120.719095 -407.618752) (xy 120.719596 -407.628852) (xy 120.719596 -407.914856) (xy 120.719805 -407.921728)
			(xy 120.723402 -407.934991) (xy 120.726708 -407.941018) (xy 120.743082 -407.969363) (xy 120.768881 -408.029524)
			(xy 120.786369 -408.092605) (xy 120.795227 -408.157463) (xy 120.795796 -408.190192) (xy 120.79525 -408.222922)
			(xy 120.786388 -408.287781) (xy 120.768893 -408.350861) (xy 120.74308 -408.411019) (xy 120.726708 -408.439366)
			(xy 120.723406 -408.445397) (xy 120.719792 -408.458656) (xy 120.719596 -408.465528) (xy 120.719596 -409.214828)
			(xy 120.719778 -409.221702) (xy 120.723393 -409.234965) (xy 120.726708 -409.24099) (xy 120.74307 -409.269341)
			(xy 120.768873 -409.3295) (xy 120.786363 -409.392579) (xy 120.795225 -409.457435) (xy 120.795796 -409.490164)
			(xy 120.795237 -409.522894) (xy 120.786379 -409.587752) (xy 120.768887 -409.650832) (xy 120.743077 -409.71099)
			(xy 120.726708 -409.739338) (xy 120.72338 -409.745356) (xy 120.719783 -409.758625) (xy 120.719596 -409.7655)
			(xy 120.719596 -410.051504) (xy 120.719187 -410.061627) (xy 120.711437 -410.080332) (xy 120.697118 -410.094646)
			(xy 120.678411 -410.10239) (xy 120.668288 -410.102812) (xy 119.952008 -410.102812) (xy 119.941888 -410.102378)
			(xy 119.923186 -410.094634) (xy 119.908872 -410.080324) (xy 119.901125 -410.061624) (xy 119.9007 -410.051504)
			(xy 119.9007 -409.7655) (xy 119.900508 -409.758627) (xy 119.8969 -409.745364) (xy 119.893588 -409.739338)
			(xy 119.877236 -409.710981) (xy 119.851431 -409.650824) (xy 119.833938 -409.587747) (xy 119.825073 -409.522892)
			(xy 119.8245 -409.490164) (xy 118.551791 -409.490164) (xy 118.542925 -409.510837) (xy 118.52656 -409.539186)
			(xy 118.523255 -409.545215) (xy 118.519642 -409.558475) (xy 118.519448 -409.565348) (xy 118.519448 -410.314648)
			(xy 118.519654 -410.32152) (xy 118.523252 -410.334783) (xy 118.52656 -410.34081) (xy 118.542926 -410.369159)
			(xy 118.568728 -410.429318) (xy 118.586218 -410.492398) (xy 118.595078 -410.557255) (xy 118.595648 -410.589984)
			(xy 118.595091 -410.622705) (xy 122.024989 -410.622705) (xy 122.024991 -410.557267) (xy 122.033776 -410.492422)
			(xy 122.051186 -410.429343) (xy 122.076905 -410.369171) (xy 122.093228 -410.34081) (xy 122.096541 -410.334785)
			(xy 122.100147 -410.321521) (xy 122.10034 -410.314648) (xy 122.10034 -409.565348) (xy 122.100125 -409.558477)
			(xy 122.096532 -409.545214) (xy 122.093228 -409.539186) (xy 122.076916 -409.510819) (xy 122.051198 -409.450649)
			(xy 122.033789 -409.387572) (xy 122.025005 -409.322728) (xy 122.025003 -409.257292) (xy 122.033785 -409.192449)
			(xy 122.051191 -409.12937) (xy 122.076907 -409.069199) (xy 122.093228 -409.040838) (xy 122.096531 -409.034808)
			(xy 122.100144 -409.021548) (xy 122.10034 -409.014676) (xy 122.10034 -408.728672) (xy 122.100699 -408.718511)
			(xy 122.108512 -408.69975) (xy 122.122928 -408.685426) (xy 122.141738 -408.677735) (xy 122.151902 -408.677364)
			(xy 122.868182 -408.677364) (xy 122.878311 -408.677842) (xy 122.897036 -408.685568) (xy 122.911394 -408.699858)
			(xy 122.919209 -408.718546) (xy 122.919744 -408.728672) (xy 122.919744 -409.014676) (xy 122.91994 -409.021549)
			(xy 122.923545 -409.034812) (xy 122.926856 -409.040838) (xy 122.943189 -409.069194) (xy 122.968905 -409.129366)
			(xy 122.986313 -409.192446) (xy 122.995095 -409.257291) (xy 122.995094 -409.322729) (xy 122.986309 -409.387574)
			(xy 122.968899 -409.450653) (xy 122.943179 -409.510825) (xy 122.936236 -409.522889) (xy 124.225119 -409.522889)
			(xy 124.225123 -409.457449) (xy 124.233912 -409.392602) (xy 124.251326 -409.329522) (xy 124.27705 -409.269351)
			(xy 124.293376 -409.24099) (xy 124.296693 -409.234966) (xy 124.300298 -409.221702) (xy 124.300488 -409.214828)
			(xy 124.300488 -408.465528) (xy 124.300287 -408.458655) (xy 124.296685 -408.445393) (xy 124.293376 -408.439366)
			(xy 124.277046 -408.411009) (xy 124.251327 -408.350837) (xy 124.233918 -408.287758) (xy 124.225135 -408.222912)
			(xy 124.225136 -408.157474) (xy 124.233921 -408.092629) (xy 124.251331 -408.02955) (xy 124.277052 -407.969379)
			(xy 124.293376 -407.941018) (xy 124.296683 -407.934989) (xy 124.300294 -407.921729) (xy 124.300488 -407.914856)
			(xy 124.300488 -407.628852) (xy 124.300882 -407.618696) (xy 124.308691 -407.599945) (xy 124.323096 -407.585624)
			(xy 124.341892 -407.577924) (xy 124.35205 -407.577544) (xy 125.06833 -407.577544) (xy 125.078459 -407.578002)
			(xy 125.097182 -407.58574) (xy 125.111537 -407.600035) (xy 125.119355 -407.618725) (xy 125.119892 -407.628852)
			(xy 125.119892 -407.914856) (xy 125.120102 -407.921728) (xy 125.123698 -407.934991) (xy 125.127004 -407.941018)
			(xy 125.143318 -407.969383) (xy 125.169034 -408.029554) (xy 125.186441 -408.092632) (xy 125.195225 -408.157475)
			(xy 125.195226 -408.222911) (xy 125.186444 -408.287755) (xy 125.169039 -408.350833) (xy 125.143324 -408.411004)
			(xy 125.127004 -408.439366) (xy 125.123702 -408.445397) (xy 125.120088 -408.458656) (xy 125.119892 -408.465528)
			(xy 125.119892 -409.214828) (xy 125.120074 -409.221702) (xy 125.123689 -409.234965) (xy 125.127004 -409.24099)
			(xy 125.143294 -409.269369) (xy 125.169013 -409.329536) (xy 125.186422 -409.392611) (xy 125.195209 -409.457452)
			(xy 125.195213 -409.522886) (xy 125.186435 -409.587728) (xy 125.169033 -409.650805) (xy 125.143322 -409.710976)
			(xy 125.127004 -409.739338) (xy 125.123676 -409.745356) (xy 125.120079 -409.758625) (xy 125.119892 -409.7655)
			(xy 125.119892 -410.051504) (xy 125.119481 -410.061659) (xy 125.111683 -410.080413) (xy 125.097283 -410.094737)
			(xy 125.078487 -410.102435) (xy 125.06833 -410.102812) (xy 124.35205 -410.102812) (xy 124.341933 -410.102234)
			(xy 124.323223 -410.094532) (xy 124.308867 -410.080274) (xy 124.301036 -410.061618) (xy 124.300488 -410.051504)
			(xy 124.300488 -409.7655) (xy 124.300297 -409.758627) (xy 124.296688 -409.745364) (xy 124.293376 -409.739338)
			(xy 124.277022 -409.710994) (xy 124.251305 -409.650819) (xy 124.233899 -409.587737) (xy 124.225119 -409.522889)
			(xy 122.936236 -409.522889) (xy 122.926856 -409.539186) (xy 122.923551 -409.545215) (xy 122.919938 -409.558475)
			(xy 122.919744 -409.565348) (xy 122.919744 -410.314648) (xy 122.91995 -410.32152) (xy 122.923548 -410.334783)
			(xy 122.926856 -410.34081) (xy 122.943165 -410.369179) (xy 122.968884 -410.429348) (xy 122.986294 -410.492425)
			(xy 122.995079 -410.557268) (xy 122.99508 -410.589984) (xy 126.424436 -410.589984) (xy 126.425025 -410.557255)
			(xy 126.433876 -410.492398) (xy 126.451359 -410.429318) (xy 126.477159 -410.369159) (xy 126.493524 -410.34081)
			(xy 126.496837 -410.334785) (xy 126.500443 -410.321521) (xy 126.500636 -410.314648) (xy 126.500636 -409.565348)
			(xy 126.500421 -409.558476) (xy 126.496828 -409.545214) (xy 126.493524 -409.539186) (xy 126.477155 -409.510839)
			(xy 126.451354 -409.450679) (xy 126.433865 -409.387598) (xy 126.425006 -409.322741) (xy 126.424436 -409.290012)
			(xy 126.424993 -409.257282) (xy 126.433853 -409.192424) (xy 126.451346 -409.129344) (xy 126.477155 -409.069186)
			(xy 126.493524 -409.040838) (xy 126.496827 -409.034808) (xy 126.50044 -409.021548) (xy 126.500636 -409.014676)
			(xy 126.500636 -408.728672) (xy 126.500994 -408.718543) (xy 126.508758 -408.699832) (xy 126.523093 -408.685517)
			(xy 126.541815 -408.67778) (xy 126.551944 -408.677364) (xy 127.268224 -408.677364) (xy 127.27833 -408.677864)
			(xy 127.297002 -408.685603) (xy 127.311294 -408.699895) (xy 127.319035 -408.718566) (xy 127.319532 -408.728672)
			(xy 127.319532 -409.014676) (xy 127.319729 -409.021549) (xy 127.323333 -409.034812) (xy 127.326644 -409.040838)
			(xy 127.343019 -409.069182) (xy 127.36882 -409.129343) (xy 127.386307 -409.192424) (xy 127.395164 -409.257282)
			(xy 127.395732 -409.290012) (xy 127.395145 -409.322741) (xy 127.386295 -409.387598) (xy 127.36881 -409.450678)
			(xy 127.343009 -409.510837) (xy 127.336052 -409.522889) (xy 128.624909 -409.522889) (xy 128.624913 -409.457449)
			(xy 128.633701 -409.392603) (xy 128.651115 -409.329523) (xy 128.676839 -409.269351) (xy 128.693164 -409.24099)
			(xy 128.696479 -409.234966) (xy 128.700085 -409.221702) (xy 128.700276 -409.214828) (xy 128.700276 -408.465528)
			(xy 128.700076 -408.458655) (xy 128.696474 -408.445392) (xy 128.693164 -408.439366) (xy 128.676834 -408.411009)
			(xy 128.651116 -408.350837) (xy 128.633708 -408.287757) (xy 128.624924 -408.222912) (xy 128.624925 -408.157474)
			(xy 128.63371 -408.092629) (xy 128.65112 -408.02955) (xy 128.67684 -407.969379) (xy 128.693164 -407.941018)
			(xy 128.696469 -407.934989) (xy 128.700081 -407.921729) (xy 128.700276 -407.914856) (xy 128.700276 -407.628852)
			(xy 128.700682 -407.618698) (xy 128.708489 -407.599949) (xy 128.72289 -407.585628) (xy 128.741682 -407.577926)
			(xy 128.751838 -407.577544) (xy 129.468118 -407.577544) (xy 129.478246 -407.578012) (xy 129.496969 -407.585746)
			(xy 129.511325 -407.600038) (xy 129.519143 -407.618726) (xy 129.51968 -407.628852) (xy 129.51968 -407.914856)
			(xy 129.519891 -407.921728) (xy 129.523486 -407.934991) (xy 129.526792 -407.941018) (xy 129.543106 -407.969383)
			(xy 129.568823 -408.029554) (xy 129.586231 -408.092632) (xy 129.595015 -408.157475) (xy 129.595015 -408.190192)
			(xy 133.023872 -408.190192) (xy 133.027863 -408.128025) (xy 133.039772 -408.066878) (xy 133.059401 -408.007757)
			(xy 133.08643 -407.951631) (xy 133.120414 -407.899422) (xy 133.160796 -407.851987) (xy 133.206912 -407.810106)
			(xy 133.258004 -407.774466) (xy 133.313235 -407.745652) (xy 133.371697 -407.724138) (xy 133.432431 -407.710276)
			(xy 133.494438 -407.704294) (xy 133.556701 -407.70629) (xy 133.618198 -407.716233) (xy 133.677919 -407.733957)
			(xy 133.734882 -407.759174) (xy 133.788153 -407.791467) (xy 133.836858 -407.830307) (xy 133.880195 -407.875057)
			(xy 133.917455 -407.924981) (xy 133.948024 -407.97926) (xy 133.971402 -408.037003) (xy 133.987203 -408.097261)
			(xy 133.995169 -408.159044) (xy 133.995668 -408.190192) (xy 133.995169 -408.22134) (xy 133.987203 -408.283123)
			(xy 133.971402 -408.343381) (xy 133.948024 -408.401124) (xy 133.917455 -408.455403) (xy 133.880195 -408.505327)
			(xy 133.836858 -408.550077) (xy 133.788153 -408.588917) (xy 133.734882 -408.62121) (xy 133.677919 -408.646427)
			(xy 133.618198 -408.664151) (xy 133.556701 -408.674094) (xy 133.494438 -408.67609) (xy 133.432431 -408.670108)
			(xy 133.371697 -408.656246) (xy 133.313235 -408.634732) (xy 133.258004 -408.605918) (xy 133.206912 -408.570278)
			(xy 133.160796 -408.528397) (xy 133.120414 -408.480962) (xy 133.08643 -408.428753) (xy 133.059401 -408.372627)
			(xy 133.039772 -408.313506) (xy 133.027863 -408.252359) (xy 133.023872 -408.190192) (xy 129.595015 -408.190192)
			(xy 129.595016 -408.222911) (xy 129.586234 -408.287755) (xy 129.568828 -408.350833) (xy 129.543113 -408.411004)
			(xy 129.526792 -408.439366) (xy 129.523489 -408.445396) (xy 129.519876 -408.458656) (xy 129.51968 -408.465528)
			(xy 129.51968 -409.214828) (xy 129.519864 -409.221702) (xy 129.523478 -409.234964) (xy 129.526792 -409.24099)
			(xy 129.543083 -409.269368) (xy 129.568802 -409.329536) (xy 129.586212 -409.392611) (xy 129.594999 -409.457452)
			(xy 129.595003 -409.522886) (xy 129.586224 -409.587728) (xy 129.568822 -409.650806) (xy 129.543111 -409.710976)
			(xy 129.526792 -409.739338) (xy 129.523463 -409.745356) (xy 129.519867 -409.758625) (xy 129.51968 -409.7655)
			(xy 129.51968 -410.051504) (xy 129.519281 -410.061661) (xy 129.511481 -410.080417) (xy 129.497077 -410.094741)
			(xy 129.478277 -410.102437) (xy 129.468118 -410.102812) (xy 128.751838 -410.102812) (xy 128.74172 -410.102244)
			(xy 128.72301 -410.094538) (xy 128.708654 -410.080277) (xy 128.700824 -410.061618) (xy 128.700276 -410.051504)
			(xy 128.700276 -409.7655) (xy 128.700087 -409.758627) (xy 128.696477 -409.745364) (xy 128.693164 -409.739338)
			(xy 128.67681 -409.710994) (xy 128.651094 -409.650819) (xy 128.633689 -409.587737) (xy 128.624909 -409.522889)
			(xy 127.336052 -409.522889) (xy 127.326644 -409.539186) (xy 127.323338 -409.545215) (xy 127.319726 -409.558475)
			(xy 127.319532 -409.565348) (xy 127.319532 -410.314648) (xy 127.31974 -410.32152) (xy 127.323337 -410.334783)
			(xy 127.326644 -410.34081) (xy 127.343008 -410.36916) (xy 127.368812 -410.429319) (xy 127.386302 -410.492398)
			(xy 127.395162 -410.557255) (xy 127.395732 -410.589984) (xy 127.395177 -410.622705) (xy 130.825075 -410.622705)
			(xy 130.825077 -410.557268) (xy 130.833862 -410.492422) (xy 130.851271 -410.429343) (xy 130.87699 -410.369172)
			(xy 130.893312 -410.34081) (xy 130.896624 -410.334784) (xy 130.900231 -410.321521) (xy 130.900424 -410.314648)
			(xy 130.900424 -409.565348) (xy 130.900211 -409.558476) (xy 130.896617 -409.545214) (xy 130.893312 -409.539186)
			(xy 130.877001 -409.510819) (xy 130.851284 -409.450649) (xy 130.833875 -409.387571) (xy 130.825091 -409.322728)
			(xy 130.82509 -409.257293) (xy 130.833871 -409.192449) (xy 130.851277 -409.129371) (xy 130.876991 -409.0692)
			(xy 130.893312 -409.040838) (xy 130.896614 -409.034807) (xy 130.900227 -409.021548) (xy 130.900424 -409.014676)
			(xy 130.900424 -408.728672) (xy 130.900799 -408.718513) (xy 130.908608 -408.699755) (xy 130.92302 -408.685432)
			(xy 130.941825 -408.677738) (xy 130.951986 -408.677364) (xy 131.668266 -408.677364) (xy 131.678393 -408.677855)
			(xy 131.697118 -408.685576) (xy 131.711477 -408.699862) (xy 131.719293 -408.718547) (xy 131.719828 -408.728672)
			(xy 131.719828 -409.014676) (xy 131.720026 -409.021549) (xy 131.72363 -409.034812) (xy 131.72694 -409.040838)
			(xy 131.743273 -409.069193) (xy 131.768991 -409.129366) (xy 131.786399 -409.192446) (xy 131.795181 -409.257291)
			(xy 131.79518 -409.322729) (xy 131.786394 -409.387575) (xy 131.768984 -409.450654) (xy 131.752096 -409.490164)
			(xy 133.023872 -409.490164) (xy 133.027863 -409.427997) (xy 133.039772 -409.36685) (xy 133.059401 -409.307729)
			(xy 133.08643 -409.251603) (xy 133.120414 -409.199394) (xy 133.160796 -409.151959) (xy 133.206912 -409.110078)
			(xy 133.258004 -409.074438) (xy 133.313235 -409.045624) (xy 133.371697 -409.02411) (xy 133.432431 -409.010248)
			(xy 133.494438 -409.004266) (xy 133.556701 -409.006262) (xy 133.618198 -409.016205) (xy 133.677919 -409.033929)
			(xy 133.734882 -409.059146) (xy 133.788153 -409.091439) (xy 133.836858 -409.130279) (xy 133.880195 -409.175029)
			(xy 133.917455 -409.224953) (xy 133.948024 -409.279232) (xy 133.952388 -409.290012) (xy 135.22402 -409.290012)
			(xy 135.228011 -409.227845) (xy 135.23992 -409.166698) (xy 135.259549 -409.107577) (xy 135.286578 -409.051451)
			(xy 135.320562 -408.999242) (xy 135.360944 -408.951807) (xy 135.40706 -408.909926) (xy 135.458152 -408.874286)
			(xy 135.513383 -408.845472) (xy 135.571845 -408.823958) (xy 135.632579 -408.810096) (xy 135.694586 -408.804114)
			(xy 135.756849 -408.80611) (xy 135.818346 -408.816053) (xy 135.878067 -408.833777) (xy 135.93503 -408.858994)
			(xy 135.988301 -408.891287) (xy 136.037006 -408.930127) (xy 136.080343 -408.974877) (xy 136.117603 -409.024801)
			(xy 136.148172 -409.07908) (xy 136.17155 -409.136823) (xy 136.187351 -409.197081) (xy 136.195317 -409.258864)
			(xy 136.195816 -409.290012) (xy 136.195317 -409.32116) (xy 136.187351 -409.382943) (xy 136.17155 -409.443201)
			(xy 136.148172 -409.500944) (xy 136.117603 -409.555223) (xy 136.080343 -409.605147) (xy 136.037006 -409.649897)
			(xy 135.988301 -409.688737) (xy 135.93503 -409.72103) (xy 135.878067 -409.746247) (xy 135.818346 -409.763971)
			(xy 135.756849 -409.773914) (xy 135.694586 -409.77591) (xy 135.632579 -409.769928) (xy 135.571845 -409.756066)
			(xy 135.513383 -409.734552) (xy 135.458152 -409.705738) (xy 135.40706 -409.670098) (xy 135.360944 -409.628217)
			(xy 135.320562 -409.580782) (xy 135.286578 -409.528573) (xy 135.259549 -409.472447) (xy 135.23992 -409.413326)
			(xy 135.228011 -409.352179) (xy 135.22402 -409.290012) (xy 133.952388 -409.290012) (xy 133.971402 -409.336975)
			(xy 133.987203 -409.397233) (xy 133.995169 -409.459016) (xy 133.995668 -409.490164) (xy 133.995169 -409.521312)
			(xy 133.987203 -409.583095) (xy 133.971402 -409.643353) (xy 133.948024 -409.701096) (xy 133.917455 -409.755375)
			(xy 133.880195 -409.805299) (xy 133.836858 -409.850049) (xy 133.788153 -409.888889) (xy 133.734882 -409.921182)
			(xy 133.677919 -409.946399) (xy 133.618198 -409.964123) (xy 133.556701 -409.974066) (xy 133.494438 -409.976062)
			(xy 133.432431 -409.97008) (xy 133.371697 -409.956218) (xy 133.313235 -409.934704) (xy 133.258004 -409.90589)
			(xy 133.206912 -409.87025) (xy 133.160796 -409.828369) (xy 133.120414 -409.780934) (xy 133.08643 -409.728725)
			(xy 133.059401 -409.672599) (xy 133.039772 -409.613478) (xy 133.027863 -409.552331) (xy 133.023872 -409.490164)
			(xy 131.752096 -409.490164) (xy 131.743264 -409.510825) (xy 131.72694 -409.539186) (xy 131.723634 -409.545215)
			(xy 131.720022 -409.558475) (xy 131.719828 -409.565348) (xy 131.719828 -410.314648) (xy 131.720036 -410.32152)
			(xy 131.723633 -410.334783) (xy 131.72694 -410.34081) (xy 131.743249 -410.369179) (xy 131.768969 -410.429348)
			(xy 131.78638 -410.492425) (xy 131.795165 -410.557268) (xy 131.795166 -410.589984) (xy 135.22402 -410.589984)
			(xy 135.228011 -410.527817) (xy 135.23992 -410.46667) (xy 135.259549 -410.407549) (xy 135.286578 -410.351423)
			(xy 135.320562 -410.299214) (xy 135.360944 -410.251779) (xy 135.40706 -410.209898) (xy 135.458152 -410.174258)
			(xy 135.513383 -410.145444) (xy 135.571845 -410.12393) (xy 135.632579 -410.110068) (xy 135.694586 -410.104086)
			(xy 135.756849 -410.106082) (xy 135.818346 -410.116025) (xy 135.878067 -410.133749) (xy 135.93503 -410.158966)
			(xy 135.988301 -410.191259) (xy 136.037006 -410.230099) (xy 136.080343 -410.274849) (xy 136.117603 -410.324773)
			(xy 136.148172 -410.379052) (xy 136.17155 -410.436795) (xy 136.187351 -410.497053) (xy 136.195317 -410.558836)
			(xy 136.195816 -410.589984) (xy 136.195317 -410.621132) (xy 136.187351 -410.682915) (xy 136.17155 -410.743173)
			(xy 136.148172 -410.800916) (xy 136.117603 -410.855195) (xy 136.080343 -410.905119) (xy 136.037006 -410.949869)
			(xy 135.988301 -410.988709) (xy 135.93503 -411.021002) (xy 135.878067 -411.046219) (xy 135.818346 -411.063943)
			(xy 135.756849 -411.073886) (xy 135.694586 -411.075882) (xy 135.632579 -411.0699) (xy 135.571845 -411.056038)
			(xy 135.513383 -411.034524) (xy 135.458152 -411.00571) (xy 135.40706 -410.97007) (xy 135.360944 -410.928189)
			(xy 135.320562 -410.880754) (xy 135.286578 -410.828545) (xy 135.259549 -410.772419) (xy 135.23992 -410.713298)
			(xy 135.228011 -410.652151) (xy 135.22402 -410.589984) (xy 131.795166 -410.589984) (xy 131.795167 -410.622704)
			(xy 131.786385 -410.687548) (xy 131.768978 -410.750626) (xy 131.743262 -410.810797) (xy 131.72694 -410.839158)
			(xy 131.723643 -410.845192) (xy 131.720026 -410.858448) (xy 131.719828 -410.86532) (xy 131.719828 -411.151324)
			(xy 131.719399 -411.161476) (xy 131.7116 -411.180224) (xy 131.697207 -411.194545) (xy 131.67842 -411.202249)
			(xy 131.668266 -411.202632) (xy 130.951986 -411.202632) (xy 130.941855 -411.202184) (xy 130.923128 -411.194446)
			(xy 130.908772 -411.180148) (xy 130.900958 -411.161453) (xy 130.900424 -411.151324) (xy 130.900424 -410.86532)
			(xy 130.900221 -410.858448) (xy 130.89662 -410.845185) (xy 130.893312 -410.839158) (xy 130.876977 -410.810804)
			(xy 130.851262 -410.750631) (xy 130.833857 -410.687551) (xy 130.825075 -410.622705) (xy 127.395177 -410.622705)
			(xy 127.395177 -410.622714) (xy 127.386318 -410.687572) (xy 127.368824 -410.750652) (xy 127.343014 -410.81081)
			(xy 127.326644 -410.839158) (xy 127.323348 -410.845192) (xy 127.31973 -410.858448) (xy 127.319532 -410.86532)
			(xy 127.319532 -411.151324) (xy 127.319035 -411.16143) (xy 127.311296 -411.180103) (xy 127.297003 -411.194396)
			(xy 127.27833 -411.202135) (xy 127.268224 -411.202632) (xy 126.551944 -411.202632) (xy 126.541828 -411.202149)
			(xy 126.523132 -411.194421) (xy 126.508817 -411.180125) (xy 126.501065 -411.161439) (xy 126.500636 -411.151324)
			(xy 126.500636 -410.86532) (xy 126.500432 -410.858448) (xy 126.496831 -410.845185) (xy 126.493524 -410.839158)
			(xy 126.477144 -410.810817) (xy 126.451345 -410.750654) (xy 126.433859 -410.687572) (xy 126.425004 -410.622714)
			(xy 126.424436 -410.589984) (xy 122.99508 -410.589984) (xy 122.995081 -410.622704) (xy 122.986299 -410.687548)
			(xy 122.968893 -410.750626) (xy 122.943177 -410.810797) (xy 122.926856 -410.839158) (xy 122.923561 -410.845192)
			(xy 122.919942 -410.858448) (xy 122.919744 -410.86532) (xy 122.919744 -411.151324) (xy 122.919299 -411.161474)
			(xy 122.911504 -411.180219) (xy 122.897115 -411.19454) (xy 122.878334 -411.202246) (xy 122.868182 -411.202632)
			(xy 122.151902 -411.202632) (xy 122.141772 -411.202171) (xy 122.123046 -411.194439) (xy 122.108688 -411.180144)
			(xy 122.100874 -411.161452) (xy 122.10034 -411.151324) (xy 122.10034 -410.86532) (xy 122.100135 -410.858448)
			(xy 122.096535 -410.845185) (xy 122.093228 -410.839158) (xy 122.076893 -410.810804) (xy 122.051177 -410.750631)
			(xy 122.033771 -410.687551) (xy 122.024989 -410.622705) (xy 118.595091 -410.622705) (xy 118.595091 -410.622714)
			(xy 118.586232 -410.687572) (xy 118.568739 -410.750652) (xy 118.542929 -410.81081) (xy 118.52656 -410.839158)
			(xy 118.523265 -410.845192) (xy 118.519646 -410.858448) (xy 118.519448 -410.86532) (xy 118.519448 -411.151324)
			(xy 118.518936 -411.161428) (xy 118.511199 -411.180098) (xy 118.496911 -411.19439) (xy 118.478244 -411.202133)
			(xy 118.46814 -411.202632) (xy 117.75186 -411.202632) (xy 117.741753 -411.202148) (xy 117.72308 -411.194404)
			(xy 117.708787 -411.180107) (xy 117.701048 -411.161431) (xy 117.700552 -411.151324) (xy 117.700552 -410.86532)
			(xy 117.700358 -410.858447) (xy 117.696752 -410.845184) (xy 117.69344 -410.839158) (xy 117.677062 -410.810816)
			(xy 117.651262 -410.750654) (xy 117.633776 -410.687572) (xy 117.62492 -410.622714) (xy 117.624352 -410.589984)
			(xy 92.195045 -410.589984) (xy 92.195046 -410.622704) (xy 92.186264 -410.687549) (xy 92.168856 -410.750627)
			(xy 92.143139 -410.810797) (xy 92.126816 -410.839158) (xy 92.123517 -410.845191) (xy 92.119901 -410.858448)
			(xy 92.119704 -410.86532) (xy 92.119704 -411.151324) (xy 92.119298 -411.161479) (xy 92.111495 -411.180231)
			(xy 92.097094 -411.194554) (xy 92.078299 -411.202253) (xy 92.068142 -411.202632) (xy 91.351862 -411.202632)
			(xy 91.341729 -411.202204) (xy 91.323002 -411.194458) (xy 91.308646 -411.180154) (xy 91.300833 -411.161455)
			(xy 91.3003 -411.151324) (xy 91.3003 -410.86532) (xy 91.3001 -410.858447) (xy 91.296497 -410.845185)
			(xy 91.293188 -410.839158) (xy 91.276854 -410.810804) (xy 91.25114 -410.75063) (xy 91.233735 -410.68755)
			(xy 91.224954 -410.622705) (xy 87.795057 -410.622705) (xy 87.795057 -410.622714) (xy 87.786196 -410.687573)
			(xy 87.768702 -410.750653) (xy 87.742891 -410.810811) (xy 87.72652 -410.839158) (xy 87.723222 -410.845191)
			(xy 87.719605 -410.858448) (xy 87.719408 -410.86532) (xy 87.719408 -411.151324) (xy 87.718935 -411.161433)
			(xy 87.711191 -411.180111) (xy 87.69689 -411.194404) (xy 87.67821 -411.20214) (xy 87.6681 -411.202632)
			(xy 86.95182 -411.202632) (xy 86.941716 -411.202099) (xy 86.923045 -411.194374) (xy 86.90875 -411.180092)
			(xy 86.901009 -411.161427) (xy 86.900512 -411.151324) (xy 86.900512 -410.86532) (xy 86.900311 -410.858447)
			(xy 86.896709 -410.845185) (xy 86.8934 -410.839158) (xy 86.877018 -410.810818) (xy 86.85122 -410.750655)
			(xy 86.833735 -410.687573) (xy 86.82488 -410.622714) (xy 86.824312 -410.589984) (xy 83.394959 -410.589984)
			(xy 83.39496 -410.622704) (xy 83.386178 -410.687548) (xy 83.368771 -410.750626) (xy 83.343054 -410.810797)
			(xy 83.326732 -410.839158) (xy 83.323435 -410.845191) (xy 83.319818 -410.858448) (xy 83.31962 -410.86532)
			(xy 83.31962 -411.151324) (xy 83.319199 -411.161477) (xy 83.311399 -411.180226) (xy 83.297003 -411.194548)
			(xy 83.278213 -411.202251) (xy 83.268058 -411.202632) (xy 82.551778 -411.202632) (xy 82.541646 -411.202191)
			(xy 82.522919 -411.194451) (xy 82.508563 -411.18015) (xy 82.500749 -411.161454) (xy 82.500216 -411.151324)
			(xy 82.500216 -410.86532) (xy 82.500015 -410.858447) (xy 82.496413 -410.845185) (xy 82.493104 -410.839158)
			(xy 82.476769 -410.810804) (xy 82.451055 -410.750631) (xy 82.433649 -410.68755) (xy 82.424868 -410.622705)
			(xy 78.99497 -410.622705) (xy 78.99497 -410.622714) (xy 78.986111 -410.687573) (xy 78.968617 -410.750653)
			(xy 78.942806 -410.81081) (xy 78.926436 -410.839158) (xy 78.923139 -410.845191) (xy 78.919522 -410.858448)
			(xy 78.919324 -410.86532) (xy 78.919324 -411.151324) (xy 78.918835 -411.161431) (xy 78.911094 -411.180106)
			(xy 78.896799 -411.194399) (xy 78.878123 -411.202137) (xy 78.868016 -411.202632) (xy 78.151736 -411.202632)
			(xy 78.14162 -411.202155) (xy 78.122923 -411.194425) (xy 78.108609 -411.180127) (xy 78.100857 -411.16144)
			(xy 78.100428 -411.151324) (xy 78.100428 -410.86532) (xy 78.100225 -410.858448) (xy 78.096624 -410.845185)
			(xy 78.093316 -410.839158) (xy 78.076935 -410.810817) (xy 78.051137 -410.750655) (xy 78.033651 -410.687573)
			(xy 78.024796 -410.622714) (xy 78.024228 -410.589984) (xy 74.594873 -410.589984) (xy 74.594874 -410.622704)
			(xy 74.586092 -410.687548) (xy 74.568686 -410.750626) (xy 74.54297 -410.810797) (xy 74.526648 -410.839158)
			(xy 74.523352 -410.845192) (xy 74.519734 -410.858448) (xy 74.519536 -410.86532) (xy 74.519536 -411.151324)
			(xy 74.519099 -411.161475) (xy 74.511302 -411.180221) (xy 74.496911 -411.194542) (xy 74.478127 -411.202248)
			(xy 74.467974 -411.202632) (xy 73.751694 -411.202632) (xy 73.741563 -411.202177) (xy 73.722837 -411.194442)
			(xy 73.70848 -411.180146) (xy 73.700666 -411.161452) (xy 73.700132 -411.151324) (xy 73.700132 -410.86532)
			(xy 73.699928 -410.858448) (xy 73.696328 -410.845185) (xy 73.69302 -410.839158) (xy 73.676685 -410.810804)
			(xy 73.650969 -410.750631) (xy 73.633564 -410.687551) (xy 73.624782 -410.622705) (xy 66.622676 -410.622705)
			(xy 66.622676 -412.090108) (xy 71.423792 -412.090108) (xy 71.427783 -412.027941) (xy 71.439692 -411.966794)
			(xy 71.459321 -411.907673) (xy 71.48635 -411.851547) (xy 71.520334 -411.799338) (xy 71.560716 -411.751903)
			(xy 71.606832 -411.710022) (xy 71.657924 -411.674382) (xy 71.713155 -411.645568) (xy 71.771617 -411.624054)
			(xy 71.832351 -411.610192) (xy 71.894358 -411.60421) (xy 71.956621 -411.606206) (xy 72.018118 -411.616149)
			(xy 72.077839 -411.633873) (xy 72.134802 -411.65909) (xy 72.188073 -411.691383) (xy 72.236778 -411.730223)
			(xy 72.280115 -411.774973) (xy 72.317375 -411.824897) (xy 72.347944 -411.879176) (xy 72.371322 -411.936919)
			(xy 72.387123 -411.997177) (xy 72.395089 -412.05896) (xy 72.395588 -412.090108) (xy 75.823834 -412.090108)
			(xy 75.827825 -412.027941) (xy 75.839734 -411.966794) (xy 75.859363 -411.907673) (xy 75.886392 -411.851547)
			(xy 75.920376 -411.799338) (xy 75.960758 -411.751903) (xy 76.006874 -411.710022) (xy 76.057966 -411.674382)
			(xy 76.113197 -411.645568) (xy 76.171659 -411.624054) (xy 76.232393 -411.610192) (xy 76.2944 -411.60421)
			(xy 76.356663 -411.606206) (xy 76.41816 -411.616149) (xy 76.477881 -411.633873) (xy 76.534844 -411.65909)
			(xy 76.588115 -411.691383) (xy 76.63682 -411.730223) (xy 76.680157 -411.774973) (xy 76.717417 -411.824897)
			(xy 76.747986 -411.879176) (xy 76.771364 -411.936919) (xy 76.787165 -411.997177) (xy 76.795131 -412.05896)
			(xy 76.79563 -412.090108) (xy 80.223876 -412.090108) (xy 80.227867 -412.027941) (xy 80.239776 -411.966794)
			(xy 80.259405 -411.907673) (xy 80.286434 -411.851547) (xy 80.320418 -411.799338) (xy 80.3608 -411.751903)
			(xy 80.406916 -411.710022) (xy 80.458008 -411.674382) (xy 80.513239 -411.645568) (xy 80.571701 -411.624054)
			(xy 80.632435 -411.610192) (xy 80.694442 -411.60421) (xy 80.756705 -411.606206) (xy 80.818202 -411.616149)
			(xy 80.877923 -411.633873) (xy 80.934886 -411.65909) (xy 80.988157 -411.691383) (xy 81.036862 -411.730223)
			(xy 81.080199 -411.774973) (xy 81.117459 -411.824897) (xy 81.148028 -411.879176) (xy 81.171406 -411.936919)
			(xy 81.187207 -411.997177) (xy 81.195173 -412.05896) (xy 81.195672 -412.090108) (xy 84.623664 -412.090108)
			(xy 84.627655 -412.027941) (xy 84.639564 -411.966794) (xy 84.659193 -411.907673) (xy 84.686222 -411.851547)
			(xy 84.720206 -411.799338) (xy 84.760588 -411.751903) (xy 84.806704 -411.710022) (xy 84.857796 -411.674382)
			(xy 84.913027 -411.645568) (xy 84.971489 -411.624054) (xy 85.032223 -411.610192) (xy 85.09423 -411.60421)
			(xy 85.156493 -411.606206) (xy 85.21799 -411.616149) (xy 85.277711 -411.633873) (xy 85.334674 -411.65909)
			(xy 85.387945 -411.691383) (xy 85.43665 -411.730223) (xy 85.479987 -411.774973) (xy 85.517247 -411.824897)
			(xy 85.547816 -411.879176) (xy 85.571194 -411.936919) (xy 85.586995 -411.997177) (xy 85.594961 -412.05896)
			(xy 85.59546 -412.090108) (xy 89.023706 -412.090108) (xy 89.027697 -412.027941) (xy 89.039606 -411.966794)
			(xy 89.059235 -411.907673) (xy 89.086264 -411.851547) (xy 89.120248 -411.799338) (xy 89.16063 -411.751903)
			(xy 89.206746 -411.710022) (xy 89.257838 -411.674382) (xy 89.313069 -411.645568) (xy 89.371531 -411.624054)
			(xy 89.432265 -411.610192) (xy 89.494272 -411.60421) (xy 89.556535 -411.606206) (xy 89.618032 -411.616149)
			(xy 89.677753 -411.633873) (xy 89.734716 -411.65909) (xy 89.787987 -411.691383) (xy 89.836692 -411.730223)
			(xy 89.880029 -411.774973) (xy 89.917289 -411.824897) (xy 89.947858 -411.879176) (xy 89.971236 -411.936919)
			(xy 89.987037 -411.997177) (xy 89.995003 -412.05896) (xy 89.995502 -412.090108) (xy 115.423958 -412.090108)
			(xy 115.427949 -412.027941) (xy 115.439858 -411.966794) (xy 115.459487 -411.907673) (xy 115.486516 -411.851547)
			(xy 115.5205 -411.799338) (xy 115.560882 -411.751903) (xy 115.606998 -411.710022) (xy 115.65809 -411.674382)
			(xy 115.713321 -411.645568) (xy 115.771783 -411.624054) (xy 115.832517 -411.610192) (xy 115.894524 -411.60421)
			(xy 115.956787 -411.606206) (xy 116.018284 -411.616149) (xy 116.078005 -411.633873) (xy 116.134968 -411.65909)
			(xy 116.188239 -411.691383) (xy 116.236944 -411.730223) (xy 116.280281 -411.774973) (xy 116.317541 -411.824897)
			(xy 116.34811 -411.879176) (xy 116.371488 -411.936919) (xy 116.387289 -411.997177) (xy 116.395255 -412.05896)
			(xy 116.395754 -412.090108) (xy 119.824 -412.090108) (xy 119.827991 -412.027941) (xy 119.8399 -411.966794)
			(xy 119.859529 -411.907673) (xy 119.886558 -411.851547) (xy 119.920542 -411.799338) (xy 119.960924 -411.751903)
			(xy 120.00704 -411.710022) (xy 120.058132 -411.674382) (xy 120.113363 -411.645568) (xy 120.171825 -411.624054)
			(xy 120.232559 -411.610192) (xy 120.294566 -411.60421) (xy 120.356829 -411.606206) (xy 120.418326 -411.616149)
			(xy 120.478047 -411.633873) (xy 120.53501 -411.65909) (xy 120.588281 -411.691383) (xy 120.636986 -411.730223)
			(xy 120.680323 -411.774973) (xy 120.717583 -411.824897) (xy 120.748152 -411.879176) (xy 120.77153 -411.936919)
			(xy 120.787331 -411.997177) (xy 120.795297 -412.05896) (xy 120.795796 -412.090108) (xy 124.224042 -412.090108)
			(xy 124.228033 -412.027941) (xy 124.239942 -411.966794) (xy 124.259571 -411.907673) (xy 124.2866 -411.851547)
			(xy 124.320584 -411.799338) (xy 124.360966 -411.751903) (xy 124.407082 -411.710022) (xy 124.458174 -411.674382)
			(xy 124.513405 -411.645568) (xy 124.571867 -411.624054) (xy 124.632601 -411.610192) (xy 124.694608 -411.60421)
			(xy 124.756871 -411.606206) (xy 124.818368 -411.616149) (xy 124.878089 -411.633873) (xy 124.935052 -411.65909)
			(xy 124.988323 -411.691383) (xy 125.037028 -411.730223) (xy 125.080365 -411.774973) (xy 125.117625 -411.824897)
			(xy 125.148194 -411.879176) (xy 125.171572 -411.936919) (xy 125.187373 -411.997177) (xy 125.195339 -412.05896)
			(xy 125.195838 -412.090108) (xy 128.62383 -412.090108) (xy 128.627821 -412.027941) (xy 128.63973 -411.966794)
			(xy 128.659359 -411.907673) (xy 128.686388 -411.851547) (xy 128.720372 -411.799338) (xy 128.760754 -411.751903)
			(xy 128.80687 -411.710022) (xy 128.857962 -411.674382) (xy 128.913193 -411.645568) (xy 128.971655 -411.624054)
			(xy 129.032389 -411.610192) (xy 129.094396 -411.60421) (xy 129.156659 -411.606206) (xy 129.218156 -411.616149)
			(xy 129.277877 -411.633873) (xy 129.33484 -411.65909) (xy 129.388111 -411.691383) (xy 129.436816 -411.730223)
			(xy 129.480153 -411.774973) (xy 129.517413 -411.824897) (xy 129.547982 -411.879176) (xy 129.57136 -411.936919)
			(xy 129.587161 -411.997177) (xy 129.595127 -412.05896) (xy 129.595626 -412.090108) (xy 133.023872 -412.090108)
			(xy 133.027863 -412.027941) (xy 133.039772 -411.966794) (xy 133.059401 -411.907673) (xy 133.08643 -411.851547)
			(xy 133.120414 -411.799338) (xy 133.160796 -411.751903) (xy 133.206912 -411.710022) (xy 133.258004 -411.674382)
			(xy 133.313235 -411.645568) (xy 133.371697 -411.624054) (xy 133.432431 -411.610192) (xy 133.494438 -411.60421)
			(xy 133.556701 -411.606206) (xy 133.618198 -411.616149) (xy 133.677919 -411.633873) (xy 133.734882 -411.65909)
			(xy 133.788153 -411.691383) (xy 133.836858 -411.730223) (xy 133.880195 -411.774973) (xy 133.917455 -411.824897)
			(xy 133.948024 -411.879176) (xy 133.971402 -411.936919) (xy 133.987203 -411.997177) (xy 133.995169 -412.05896)
			(xy 133.995668 -412.090108) (xy 133.995169 -412.121256) (xy 133.987203 -412.183039) (xy 133.971402 -412.243297)
			(xy 133.948024 -412.30104) (xy 133.917455 -412.355319) (xy 133.880195 -412.405243) (xy 133.836858 -412.449993)
			(xy 133.788153 -412.488833) (xy 133.734882 -412.521126) (xy 133.677919 -412.546343) (xy 133.618198 -412.564067)
			(xy 133.556701 -412.57401) (xy 133.494438 -412.576006) (xy 133.432431 -412.570024) (xy 133.371697 -412.556162)
			(xy 133.313235 -412.534648) (xy 133.258004 -412.505834) (xy 133.206912 -412.470194) (xy 133.160796 -412.428313)
			(xy 133.120414 -412.380878) (xy 133.08643 -412.328669) (xy 133.059401 -412.272543) (xy 133.039772 -412.213422)
			(xy 133.027863 -412.152275) (xy 133.023872 -412.090108) (xy 129.595626 -412.090108) (xy 129.595127 -412.121256)
			(xy 129.587161 -412.183039) (xy 129.57136 -412.243297) (xy 129.547982 -412.30104) (xy 129.517413 -412.355319)
			(xy 129.480153 -412.405243) (xy 129.436816 -412.449993) (xy 129.388111 -412.488833) (xy 129.33484 -412.521126)
			(xy 129.277877 -412.546343) (xy 129.218156 -412.564067) (xy 129.156659 -412.57401) (xy 129.094396 -412.576006)
			(xy 129.032389 -412.570024) (xy 128.971655 -412.556162) (xy 128.913193 -412.534648) (xy 128.857962 -412.505834)
			(xy 128.80687 -412.470194) (xy 128.760754 -412.428313) (xy 128.720372 -412.380878) (xy 128.686388 -412.328669)
			(xy 128.659359 -412.272543) (xy 128.63973 -412.213422) (xy 128.627821 -412.152275) (xy 128.62383 -412.090108)
			(xy 125.195838 -412.090108) (xy 125.195339 -412.121256) (xy 125.187373 -412.183039) (xy 125.171572 -412.243297)
			(xy 125.148194 -412.30104) (xy 125.117625 -412.355319) (xy 125.080365 -412.405243) (xy 125.037028 -412.449993)
			(xy 124.988323 -412.488833) (xy 124.935052 -412.521126) (xy 124.878089 -412.546343) (xy 124.818368 -412.564067)
			(xy 124.756871 -412.57401) (xy 124.694608 -412.576006) (xy 124.632601 -412.570024) (xy 124.571867 -412.556162)
			(xy 124.513405 -412.534648) (xy 124.458174 -412.505834) (xy 124.407082 -412.470194) (xy 124.360966 -412.428313)
			(xy 124.320584 -412.380878) (xy 124.2866 -412.328669) (xy 124.259571 -412.272543) (xy 124.239942 -412.213422)
			(xy 124.228033 -412.152275) (xy 124.224042 -412.090108) (xy 120.795796 -412.090108) (xy 120.795297 -412.121256)
			(xy 120.787331 -412.183039) (xy 120.77153 -412.243297) (xy 120.748152 -412.30104) (xy 120.717583 -412.355319)
			(xy 120.680323 -412.405243) (xy 120.636986 -412.449993) (xy 120.588281 -412.488833) (xy 120.53501 -412.521126)
			(xy 120.478047 -412.546343) (xy 120.418326 -412.564067) (xy 120.356829 -412.57401) (xy 120.294566 -412.576006)
			(xy 120.232559 -412.570024) (xy 120.171825 -412.556162) (xy 120.113363 -412.534648) (xy 120.058132 -412.505834)
			(xy 120.00704 -412.470194) (xy 119.960924 -412.428313) (xy 119.920542 -412.380878) (xy 119.886558 -412.328669)
			(xy 119.859529 -412.272543) (xy 119.8399 -412.213422) (xy 119.827991 -412.152275) (xy 119.824 -412.090108)
			(xy 116.395754 -412.090108) (xy 116.395255 -412.121256) (xy 116.387289 -412.183039) (xy 116.371488 -412.243297)
			(xy 116.34811 -412.30104) (xy 116.317541 -412.355319) (xy 116.280281 -412.405243) (xy 116.236944 -412.449993)
			(xy 116.188239 -412.488833) (xy 116.134968 -412.521126) (xy 116.078005 -412.546343) (xy 116.018284 -412.564067)
			(xy 115.956787 -412.57401) (xy 115.894524 -412.576006) (xy 115.832517 -412.570024) (xy 115.771783 -412.556162)
			(xy 115.713321 -412.534648) (xy 115.65809 -412.505834) (xy 115.606998 -412.470194) (xy 115.560882 -412.428313)
			(xy 115.5205 -412.380878) (xy 115.486516 -412.328669) (xy 115.459487 -412.272543) (xy 115.439858 -412.213422)
			(xy 115.427949 -412.152275) (xy 115.423958 -412.090108) (xy 89.995502 -412.090108) (xy 89.995003 -412.121256)
			(xy 89.987037 -412.183039) (xy 89.971236 -412.243297) (xy 89.947858 -412.30104) (xy 89.917289 -412.355319)
			(xy 89.880029 -412.405243) (xy 89.836692 -412.449993) (xy 89.787987 -412.488833) (xy 89.734716 -412.521126)
			(xy 89.677753 -412.546343) (xy 89.618032 -412.564067) (xy 89.556535 -412.57401) (xy 89.494272 -412.576006)
			(xy 89.432265 -412.570024) (xy 89.371531 -412.556162) (xy 89.313069 -412.534648) (xy 89.257838 -412.505834)
			(xy 89.206746 -412.470194) (xy 89.16063 -412.428313) (xy 89.120248 -412.380878) (xy 89.086264 -412.328669)
			(xy 89.059235 -412.272543) (xy 89.039606 -412.213422) (xy 89.027697 -412.152275) (xy 89.023706 -412.090108)
			(xy 85.59546 -412.090108) (xy 85.594961 -412.121256) (xy 85.586995 -412.183039) (xy 85.571194 -412.243297)
			(xy 85.547816 -412.30104) (xy 85.517247 -412.355319) (xy 85.479987 -412.405243) (xy 85.43665 -412.449993)
			(xy 85.387945 -412.488833) (xy 85.334674 -412.521126) (xy 85.277711 -412.546343) (xy 85.21799 -412.564067)
			(xy 85.156493 -412.57401) (xy 85.09423 -412.576006) (xy 85.032223 -412.570024) (xy 84.971489 -412.556162)
			(xy 84.913027 -412.534648) (xy 84.857796 -412.505834) (xy 84.806704 -412.470194) (xy 84.760588 -412.428313)
			(xy 84.720206 -412.380878) (xy 84.686222 -412.328669) (xy 84.659193 -412.272543) (xy 84.639564 -412.213422)
			(xy 84.627655 -412.152275) (xy 84.623664 -412.090108) (xy 81.195672 -412.090108) (xy 81.195173 -412.121256)
			(xy 81.187207 -412.183039) (xy 81.171406 -412.243297) (xy 81.148028 -412.30104) (xy 81.117459 -412.355319)
			(xy 81.080199 -412.405243) (xy 81.036862 -412.449993) (xy 80.988157 -412.488833) (xy 80.934886 -412.521126)
			(xy 80.877923 -412.546343) (xy 80.818202 -412.564067) (xy 80.756705 -412.57401) (xy 80.694442 -412.576006)
			(xy 80.632435 -412.570024) (xy 80.571701 -412.556162) (xy 80.513239 -412.534648) (xy 80.458008 -412.505834)
			(xy 80.406916 -412.470194) (xy 80.3608 -412.428313) (xy 80.320418 -412.380878) (xy 80.286434 -412.328669)
			(xy 80.259405 -412.272543) (xy 80.239776 -412.213422) (xy 80.227867 -412.152275) (xy 80.223876 -412.090108)
			(xy 76.79563 -412.090108) (xy 76.795131 -412.121256) (xy 76.787165 -412.183039) (xy 76.771364 -412.243297)
			(xy 76.747986 -412.30104) (xy 76.717417 -412.355319) (xy 76.680157 -412.405243) (xy 76.63682 -412.449993)
			(xy 76.588115 -412.488833) (xy 76.534844 -412.521126) (xy 76.477881 -412.546343) (xy 76.41816 -412.564067)
			(xy 76.356663 -412.57401) (xy 76.2944 -412.576006) (xy 76.232393 -412.570024) (xy 76.171659 -412.556162)
			(xy 76.113197 -412.534648) (xy 76.057966 -412.505834) (xy 76.006874 -412.470194) (xy 75.960758 -412.428313)
			(xy 75.920376 -412.380878) (xy 75.886392 -412.328669) (xy 75.859363 -412.272543) (xy 75.839734 -412.213422)
			(xy 75.827825 -412.152275) (xy 75.823834 -412.090108) (xy 72.395588 -412.090108) (xy 72.395089 -412.121256)
			(xy 72.387123 -412.183039) (xy 72.371322 -412.243297) (xy 72.347944 -412.30104) (xy 72.317375 -412.355319)
			(xy 72.280115 -412.405243) (xy 72.236778 -412.449993) (xy 72.188073 -412.488833) (xy 72.134802 -412.521126)
			(xy 72.077839 -412.546343) (xy 72.018118 -412.564067) (xy 71.956621 -412.57401) (xy 71.894358 -412.576006)
			(xy 71.832351 -412.570024) (xy 71.771617 -412.556162) (xy 71.713155 -412.534648) (xy 71.657924 -412.505834)
			(xy 71.606832 -412.470194) (xy 71.560716 -412.428313) (xy 71.520334 -412.380878) (xy 71.48635 -412.328669)
			(xy 71.459321 -412.272543) (xy 71.439692 -412.213422) (xy 71.427783 -412.152275) (xy 71.423792 -412.090108)
			(xy 66.622676 -412.090108) (xy 66.622676 -416.518852) (xy 66.623108 -416.528919) (xy 66.630833 -416.547512)
			(xy 66.637662 -416.55492) (xy 67.211448 -417.128706) (xy 67.218849 -417.135544) (xy 67.237447 -417.14326)
			(xy 67.247516 -417.143692) (xy 140.97254 -417.143692) (xy 140.982542 -417.143197) (xy 141.001018 -417.13553)
			(xy 141.015157 -417.121378) (xy 141.022806 -417.102894) (xy 141.02334 -417.092892) (xy 141.02334 -394.305282)
			(xy 141.023816 -394.293169) (xy 141.031307 -394.270131) (xy 141.045549 -394.250535) (xy 141.065149 -394.236298)
			(xy 141.088189 -394.228813) (xy 141.100302 -394.22832) (xy 153.709624 -394.22832) (xy 153.71963 -394.227828)
			(xy 153.738117 -394.220165) (xy 153.752267 -394.206014) (xy 153.759929 -394.187526) (xy 153.760424 -394.17752)
			(xy 153.760424 -391.07491) (xy 153.760003 -391.064838) (xy 153.752294 -391.046229) (xy 153.745438 -391.038842)
			(xy 152.647904 -389.941054) (xy 152.613659 -389.906022) (xy 152.551473 -389.830315) (xy 152.497015 -389.748873)
			(xy 152.450811 -389.66248) (xy 152.431496 -389.617458) (xy 152.027128 -388.641082) (xy 152.025122 -388.636518)
			(xy 152.019624 -388.628201) (xy 152.016206 -388.624572) (xy 151.120348 -387.728714) (xy 151.11351 -387.721313)
			(xy 151.105799 -387.702714) (xy 151.105362 -387.692646) (xy 151.105362 -386.424678) (xy 151.105272 -386.419658)
			(xy 151.103356 -386.409805) (xy 151.101552 -386.40512) (xy 150.84806 -385.792472) (xy 150.844067 -385.78388)
			(xy 150.830955 -385.770222) (xy 150.813793 -385.762226) (xy 150.804372 -385.76123) (xy 150.698708 -385.754372)
			(xy 150.673054 -385.768088) (xy 150.665942 -385.780534) (xy 150.651248 -385.805041) (xy 150.615672 -385.849754)
			(xy 150.573819 -385.888655) (xy 150.526629 -385.920873) (xy 150.475158 -385.945686) (xy 150.42056 -385.962538)
			(xy 150.364058 -385.971051) (xy 150.335488 -385.971542) (xy 150.308235 -385.971055) (xy 150.254284 -385.963297)
			(xy 150.201986 -385.947939) (xy 150.152406 -385.925295) (xy 150.106553 -385.895826) (xy 150.06536 -385.860131)
			(xy 150.029667 -385.818938) (xy 150.000199 -385.773084) (xy 149.977557 -385.723503) (xy 149.962201 -385.671205)
			(xy 149.954444 -385.617253) (xy 149.954444 -385.562747) (xy 149.962201 -385.508795) (xy 149.977557 -385.456497)
			(xy 150.000199 -385.406916) (xy 150.029667 -385.361062) (xy 150.06536 -385.319869) (xy 150.106553 -385.284174)
			(xy 150.152406 -385.254705) (xy 150.201986 -385.232061) (xy 150.254284 -385.216703) (xy 150.308235 -385.208945)
			(xy 150.335488 -385.208526) (xy 150.361137 -385.208961) (xy 150.411969 -385.215867) (xy 150.461418 -385.229515)
			(xy 150.508595 -385.249661) (xy 150.552651 -385.275942) (xy 150.592791 -385.307884) (xy 150.610824 -385.326128)
			(xy 150.618358 -385.333248) (xy 150.637447 -385.341276) (xy 150.658155 -385.341111) (xy 150.677114 -385.332779)
			(xy 150.69124 -385.317637) (xy 150.698236 -385.298146) (xy 150.6982 -385.287774) (xy 150.6982 -385.28752)
			(xy 150.696676 -385.228846) (xy 150.696676 -383.689098) (xy 150.696202 -383.678864) (xy 150.688212 -383.660018)
			(xy 150.673529 -383.645756) (xy 150.664164 -383.6416) (xy 150.575264 -383.607564) (xy 150.565544 -383.604369)
			(xy 150.545115 -383.605125) (xy 150.526582 -383.613754) (xy 150.519384 -383.621026) (xy 150.501226 -383.640489)
			(xy 150.460442 -383.674693) (xy 150.415296 -383.70289) (xy 150.366667 -383.724531) (xy 150.315499 -383.739195)
			(xy 150.262788 -383.746598) (xy 150.236174 -383.74701) (xy 150.208924 -383.746522) (xy 150.154979 -383.738763)
			(xy 150.102687 -383.723405) (xy 150.053113 -383.700763) (xy 150.007265 -383.671296) (xy 149.966078 -383.635604)
			(xy 149.930389 -383.594414) (xy 149.900925 -383.548565) (xy 149.878285 -383.498989) (xy 149.862932 -383.446696)
			(xy 149.855176 -383.39275) (xy 149.855176 -383.33825) (xy 149.862932 -383.284304) (xy 149.878285 -383.232011)
			(xy 149.900925 -383.182435) (xy 149.930389 -383.136586) (xy 149.966078 -383.095396) (xy 150.007265 -383.059704)
			(xy 150.053113 -383.030237) (xy 150.102687 -383.007595) (xy 150.154979 -382.992237) (xy 150.208924 -382.984478)
			(xy 150.236174 -382.983994) (xy 150.262784 -382.984462) (xy 150.315486 -382.991871) (xy 150.366646 -383.006536)
			(xy 150.41527 -383.02817) (xy 150.460415 -383.056355) (xy 150.501202 -383.090542) (xy 150.519384 -383.109978)
			(xy 150.52656 -383.117289) (xy 150.545096 -383.125969) (xy 150.565551 -383.126694) (xy 150.575264 -383.12344)
			(xy 150.664164 -383.089404) (xy 150.673575 -383.085305) (xy 150.688327 -383.071056) (xy 150.696303 -383.052162)
			(xy 150.696676 -383.041906) (xy 150.696676 -381.753618) (xy 150.696155 -381.743431) (xy 150.68813 -381.724697)
			(xy 150.673483 -381.710525) (xy 150.664164 -381.706374) (xy 150.560786 -381.666496) (xy 150.53056 -381.673608)
			(xy 150.519892 -381.685292) (xy 150.501738 -381.704576) (xy 150.461022 -381.738446) (xy 150.416011 -381.766356)
			(xy 150.367571 -381.787768) (xy 150.316633 -381.802272) (xy 150.264179 -381.809587) (xy 150.237698 -381.810006)
			(xy 150.210447 -381.80952) (xy 150.1565 -381.801763) (xy 150.104206 -381.786408) (xy 150.054629 -381.763767)
			(xy 150.008779 -381.734301) (xy 149.967589 -381.698609) (xy 149.931898 -381.65742) (xy 149.902432 -381.611569)
			(xy 149.879791 -381.561993) (xy 149.864436 -381.509698) (xy 149.85668 -381.455751) (xy 149.85668 -381.401249)
			(xy 149.864436 -381.347302) (xy 149.879791 -381.295007) (xy 149.902432 -381.245431) (xy 149.931898 -381.19958)
			(xy 149.967589 -381.158391) (xy 150.008779 -381.122699) (xy 150.054629 -381.093233) (xy 150.104206 -381.070592)
			(xy 150.1565 -381.055237) (xy 150.210447 -381.04748) (xy 150.237698 -381.04699) (xy 150.264177 -381.047442)
			(xy 150.316628 -381.054763) (xy 150.367563 -381.069264) (xy 150.416004 -381.090667) (xy 150.461021 -381.118561)
			(xy 150.501751 -381.152411) (xy 150.519892 -381.171704) (xy 150.53056 -381.183388) (xy 150.560786 -381.1905)
			(xy 150.664164 -381.150622) (xy 150.67353 -381.146542) (xy 150.688222 -381.132372) (xy 150.6962 -381.113584)
			(xy 150.696676 -381.103378) (xy 150.696676 -377.029218) (xy 150.696237 -377.019155) (xy 150.688499 -377.000574)
			(xy 150.68169 -376.99315) (xy 150.518114 -376.829574) (xy 150.510714 -376.822733) (xy 150.492115 -376.815018)
			(xy 150.482046 -376.814588) (xy 148.491956 -376.814588) (xy 148.481648 -376.81506) (xy 148.462695 -376.823173)
			(xy 148.448482 -376.838107) (xy 148.444458 -376.847608) (xy 147.989798 -378.072396) (xy 147.988348 -378.076696)
			(xy 147.986808 -378.085639) (xy 147.98675 -378.090176) (xy 147.98675 -378.606304) (xy 147.986325 -378.616373)
			(xy 147.978604 -378.634971) (xy 147.971764 -378.642372) (xy 147.926806 -378.68733) (xy 149.188168 -378.68733)
			(xy 149.192239 -378.631708) (xy 149.204365 -378.577271) (xy 149.224288 -378.52518) (xy 149.251584 -378.476545)
			(xy 149.28567 -378.432402) (xy 149.325819 -378.393693) (xy 149.371177 -378.361242) (xy 149.420777 -378.335741)
			(xy 149.473561 -378.317734) (xy 149.528404 -378.307604) (xy 149.584138 -378.305567) (xy 149.639575 -378.311667)
			(xy 149.693532 -378.325773) (xy 149.744861 -378.347585) (xy 149.792467 -378.376639) (xy 149.835335 -378.412314)
			(xy 149.872552 -378.453851) (xy 149.903325 -378.500364) (xy 149.926997 -378.550861) (xy 149.943065 -378.604268)
			(xy 149.951185 -378.659444) (xy 149.951694 -378.68733) (xy 149.951185 -378.715216) (xy 149.943065 -378.770392)
			(xy 149.926997 -378.823799) (xy 149.903325 -378.874296) (xy 149.872552 -378.920809) (xy 149.835335 -378.962346)
			(xy 149.792467 -378.998021) (xy 149.744861 -379.027075) (xy 149.693532 -379.048887) (xy 149.639575 -379.062993)
			(xy 149.584138 -379.069093) (xy 149.528404 -379.067056) (xy 149.473561 -379.056926) (xy 149.420777 -379.038919)
			(xy 149.371177 -379.013418) (xy 149.325819 -378.980967) (xy 149.28567 -378.942258) (xy 149.251584 -378.898115)
			(xy 149.224288 -378.84948) (xy 149.204365 -378.797389) (xy 149.192239 -378.742952) (xy 149.188168 -378.68733)
			(xy 147.926806 -378.68733) (xy 147.768564 -378.845572) (xy 147.762093 -378.852516) (xy 147.754413 -378.869859)
			(xy 147.753628 -378.88881) (xy 147.756372 -378.897896) (xy 147.790408 -378.998226) (xy 147.81276 -379.016514)
			(xy 147.827238 -379.018292) (xy 147.854446 -379.022324) (xy 147.9074 -379.037191) (xy 147.957671 -379.059507)
			(xy 148.004217 -379.088808) (xy 148.046075 -379.124489) (xy 148.082376 -379.165809) (xy 148.11237 -379.211912)
			(xy 148.135434 -379.261844) (xy 148.151091 -379.31457) (xy 148.159016 -379.368998) (xy 148.15947 -379.396498)
			(xy 148.159007 -379.42375) (xy 148.15125 -379.477699) (xy 148.135894 -379.529995) (xy 148.113251 -379.579573)
			(xy 148.083782 -379.625424) (xy 148.048088 -379.666613) (xy 148.006895 -379.702304) (xy 147.961041 -379.731768)
			(xy 147.911461 -379.754406) (xy 147.859164 -379.769757) (xy 147.805214 -379.777509) (xy 147.777962 -379.778006)
			(xy 147.751496 -379.777551) (xy 147.699072 -379.770229) (xy 147.648164 -379.755729) (xy 147.59975 -379.734331)
			(xy 147.554759 -379.706445) (xy 147.534122 -379.689868) (xy 147.533868 -379.689868) (xy 147.524051 -379.68269)
			(xy 147.50032 -379.677535) (xy 147.488402 -379.679962) (xy 147.408392 -379.701298) (xy 147.396795 -379.705158)
			(xy 147.378758 -379.721601) (xy 147.373848 -379.732794) (xy 147.31004 -379.904752) (xy 149.687786 -379.904752)
			(xy 149.691857 -379.84913) (xy 149.703983 -379.794693) (xy 149.723906 -379.742602) (xy 149.751202 -379.693967)
			(xy 149.785288 -379.649824) (xy 149.825437 -379.611115) (xy 149.870795 -379.578664) (xy 149.920395 -379.553163)
			(xy 149.973179 -379.535156) (xy 150.028022 -379.525026) (xy 150.083756 -379.522989) (xy 150.139193 -379.529089)
			(xy 150.19315 -379.543195) (xy 150.244479 -379.565007) (xy 150.292085 -379.594061) (xy 150.334953 -379.629736)
			(xy 150.37217 -379.671273) (xy 150.402943 -379.717786) (xy 150.426615 -379.768283) (xy 150.442683 -379.82169)
			(xy 150.450803 -379.876866) (xy 150.451312 -379.904752) (xy 150.450803 -379.932638) (xy 150.442683 -379.987814)
			(xy 150.426615 -380.041221) (xy 150.402943 -380.091718) (xy 150.37217 -380.138231) (xy 150.334953 -380.179768)
			(xy 150.292085 -380.215443) (xy 150.244479 -380.244497) (xy 150.19315 -380.266309) (xy 150.139193 -380.280415)
			(xy 150.083756 -380.286515) (xy 150.028022 -380.284478) (xy 149.973179 -380.274348) (xy 149.920395 -380.256341)
			(xy 149.870795 -380.23084) (xy 149.825437 -380.198389) (xy 149.785288 -380.15968) (xy 149.751202 -380.115537)
			(xy 149.723906 -380.066902) (xy 149.703983 -380.014811) (xy 149.691857 -379.960374) (xy 149.687786 -379.904752)
			(xy 147.31004 -379.904752) (xy 147.248118 -380.07163) (xy 147.244797 -380.081922) (xy 147.246218 -380.103481)
			(xy 147.256381 -380.122547) (xy 147.264628 -380.129542) (xy 147.287112 -380.147733) (xy 147.326849 -380.189751)
			(xy 147.359789 -380.237285) (xy 147.385177 -380.289247) (xy 147.402431 -380.344445) (xy 147.411155 -380.401616)
			(xy 147.411694 -380.430532) (xy 147.411206 -380.457781) (xy 147.403445 -380.511725) (xy 147.388087 -380.564015)
			(xy 147.365444 -380.613587) (xy 147.335977 -380.659432) (xy 147.300285 -380.700618) (xy 147.259096 -380.736304)
			(xy 147.213247 -380.765766) (xy 147.163672 -380.788403) (xy 147.11138 -380.803755) (xy 147.057435 -380.811509)
			(xy 147.030186 -380.81204) (xy 147.01139 -380.811532) (xy 146.994626 -380.81077) (xy 146.967194 -380.828804)
			(xy 146.639587 -381.7112) (xy 147.45284 -381.7112) (xy 147.456911 -381.655578) (xy 147.469037 -381.601141)
			(xy 147.48896 -381.54905) (xy 147.516256 -381.500415) (xy 147.550342 -381.456272) (xy 147.590491 -381.417563)
			(xy 147.635849 -381.385112) (xy 147.685449 -381.359611) (xy 147.738233 -381.341604) (xy 147.793076 -381.331474)
			(xy 147.84881 -381.329437) (xy 147.904247 -381.335537) (xy 147.958204 -381.349643) (xy 148.009533 -381.371455)
			(xy 148.057139 -381.400509) (xy 148.100007 -381.436184) (xy 148.137224 -381.477721) (xy 148.167997 -381.524234)
			(xy 148.191669 -381.574731) (xy 148.207737 -381.628138) (xy 148.215857 -381.683314) (xy 148.216366 -381.7112)
			(xy 148.215857 -381.739086) (xy 148.207737 -381.794262) (xy 148.191669 -381.847669) (xy 148.167997 -381.898166)
			(xy 148.137224 -381.944679) (xy 148.100007 -381.986216) (xy 148.057139 -382.021891) (xy 148.009533 -382.050945)
			(xy 147.958204 -382.072757) (xy 147.904247 -382.086863) (xy 147.84881 -382.092963) (xy 147.793076 -382.090926)
			(xy 147.738233 -382.080796) (xy 147.685449 -382.062789) (xy 147.635849 -382.037288) (xy 147.590491 -382.004837)
			(xy 147.550342 -381.966128) (xy 147.516256 -381.921985) (xy 147.48896 -381.87335) (xy 147.469037 -381.821259)
			(xy 147.456911 -381.766822) (xy 147.45284 -381.7112) (xy 146.639587 -381.7112) (xy 146.543776 -381.969264)
			(xy 146.542332 -381.973565) (xy 146.540805 -381.982507) (xy 146.540728 -381.987044) (xy 146.540728 -382.062736)
			(xy 146.541223 -382.072737) (xy 146.548889 -382.091212) (xy 146.563042 -382.105346) (xy 146.581527 -382.11299)
			(xy 146.591528 -382.113536) (xy 146.604228 -382.113536) (xy 146.61515 -382.107694) (xy 146.615658 -382.107694)
			(xy 146.643358 -382.093664) (xy 146.702174 -382.073776) (xy 146.763431 -382.063648) (xy 146.794474 -382.06299)
			(xy 146.821728 -382.063452) (xy 146.875682 -382.071206) (xy 146.927983 -382.086559) (xy 146.977567 -382.109201)
			(xy 147.023424 -382.138668) (xy 147.06462 -382.174362) (xy 147.100316 -382.215555) (xy 147.129787 -382.26141)
			(xy 147.152431 -382.310992) (xy 147.167789 -382.363292) (xy 147.175547 -382.417246) (xy 147.175547 -382.471754)
			(xy 147.167789 -382.525708) (xy 147.152431 -382.578008) (xy 147.129787 -382.62759) (xy 147.100316 -382.673445)
			(xy 147.06462 -382.714638) (xy 147.023424 -382.750332) (xy 146.977567 -382.779799) (xy 146.927983 -382.802441)
			(xy 146.875682 -382.817794) (xy 146.821728 -382.825548) (xy 146.794474 -382.826006) (xy 146.793966 -382.826006)
			(xy 146.763526 -382.82539) (xy 146.703422 -382.815688) (xy 146.674332 -382.806702) (xy 146.662648 -382.802638)
			(xy 146.638518 -382.806448) (xy 146.56181 -382.86182) (xy 146.552428 -382.869433) (xy 146.54143 -382.890906)
			(xy 146.540728 -382.902968) (xy 146.540728 -383.460498) (xy 147.395944 -383.460498) (xy 147.400015 -383.404876)
			(xy 147.412141 -383.350439) (xy 147.432064 -383.298348) (xy 147.45936 -383.249713) (xy 147.493446 -383.20557)
			(xy 147.533595 -383.166861) (xy 147.578953 -383.13441) (xy 147.628553 -383.108909) (xy 147.681337 -383.090902)
			(xy 147.73618 -383.080772) (xy 147.791914 -383.078735) (xy 147.847351 -383.084835) (xy 147.901308 -383.098941)
			(xy 147.952637 -383.120753) (xy 148.000243 -383.149807) (xy 148.043111 -383.185482) (xy 148.080328 -383.227019)
			(xy 148.111101 -383.273532) (xy 148.134773 -383.324029) (xy 148.150841 -383.377436) (xy 148.158961 -383.432612)
			(xy 148.15947 -383.460498) (xy 148.158961 -383.488384) (xy 148.150841 -383.54356) (xy 148.134773 -383.596967)
			(xy 148.111101 -383.647464) (xy 148.080328 -383.693977) (xy 148.043111 -383.735514) (xy 148.000243 -383.771189)
			(xy 147.952637 -383.800243) (xy 147.901308 -383.822055) (xy 147.847351 -383.836161) (xy 147.791914 -383.842261)
			(xy 147.73618 -383.840224) (xy 147.681337 -383.830094) (xy 147.628553 -383.812087) (xy 147.578953 -383.786586)
			(xy 147.533595 -383.754135) (xy 147.493446 -383.715426) (xy 147.45936 -383.671283) (xy 147.432064 -383.622648)
			(xy 147.412141 -383.570557) (xy 147.400015 -383.51612) (xy 147.395944 -383.460498) (xy 146.540728 -383.460498)
			(xy 146.540728 -384.217926) (xy 146.540301 -384.227995) (xy 146.532583 -384.246595) (xy 146.525742 -384.253994)
			(xy 146.187922 -384.591814) (xy 149.09876 -384.591814) (xy 149.102831 -384.536192) (xy 149.114957 -384.481755)
			(xy 149.13488 -384.429664) (xy 149.162176 -384.381029) (xy 149.196262 -384.336886) (xy 149.236411 -384.298177)
			(xy 149.281769 -384.265726) (xy 149.331369 -384.240225) (xy 149.384153 -384.222218) (xy 149.438996 -384.212088)
			(xy 149.49473 -384.210051) (xy 149.550167 -384.216151) (xy 149.604124 -384.230257) (xy 149.655453 -384.252069)
			(xy 149.703059 -384.281123) (xy 149.745927 -384.316798) (xy 149.783144 -384.358335) (xy 149.813917 -384.404848)
			(xy 149.837589 -384.455345) (xy 149.853657 -384.508752) (xy 149.861777 -384.563928) (xy 149.862286 -384.591814)
			(xy 149.861777 -384.6197) (xy 149.853657 -384.674876) (xy 149.837589 -384.728283) (xy 149.813917 -384.77878)
			(xy 149.783144 -384.825293) (xy 149.745927 -384.86683) (xy 149.703059 -384.902505) (xy 149.655453 -384.931559)
			(xy 149.604124 -384.953371) (xy 149.550167 -384.967477) (xy 149.49473 -384.973577) (xy 149.438996 -384.97154)
			(xy 149.384153 -384.96141) (xy 149.331369 -384.943403) (xy 149.281769 -384.917902) (xy 149.236411 -384.885451)
			(xy 149.196262 -384.846742) (xy 149.162176 -384.802599) (xy 149.13488 -384.753964) (xy 149.114957 -384.701873)
			(xy 149.102831 -384.647436) (xy 149.09876 -384.591814) (xy 146.187922 -384.591814) (xy 145.565622 -385.214114)
			(xy 145.559611 -385.220617) (xy 145.552035 -385.236607) (xy 145.550328 -385.254219) (xy 145.55216 -385.262882)
			(xy 145.574258 -385.347718) (xy 145.576797 -385.356106) (xy 145.58663 -385.370598) (xy 145.600768 -385.380933)
			(xy 145.609056 -385.383786) (xy 145.60931 -385.383786) (xy 145.635463 -385.391816) (xy 145.685326 -385.414325)
			(xy 145.731462 -385.443726) (xy 145.772927 -385.479414) (xy 145.808869 -385.520658) (xy 145.838552 -385.566613)
			(xy 145.861367 -385.616337) (xy 145.876847 -385.668809) (xy 145.884673 -385.722954) (xy 145.885154 -385.750308)
			(xy 145.884695 -385.776857) (xy 145.877327 -385.829442) (xy 145.862736 -385.880496) (xy 145.841203 -385.929032)
			(xy 145.813145 -385.974112) (xy 145.779104 -386.014863) (xy 145.739739 -386.050498) (xy 145.718022 -386.065776)
			(xy 145.709132 -386.071872) (xy 145.697956 -386.089398) (xy 145.685256 -386.17398) (xy 145.68419 -386.18439)
			(xy 145.689577 -386.204587) (xy 145.69567 -386.213096) (xy 145.695924 -386.21335) (xy 145.711637 -386.233705)
			(xy 145.738031 -386.277836) (xy 145.758255 -386.325114) (xy 145.771943 -386.374681) (xy 145.778846 -386.425637)
			(xy 145.779236 -386.451348) (xy 145.77875 -386.478599) (xy 145.770994 -386.532547) (xy 145.755639 -386.584842)
			(xy 145.732997 -386.634419) (xy 145.703531 -386.680269) (xy 145.66784 -386.72146) (xy 145.626649 -386.757151)
			(xy 145.580799 -386.786617) (xy 145.531222 -386.809259) (xy 145.478927 -386.824614) (xy 145.424979 -386.83237)
			(xy 145.370477 -386.83237) (xy 145.316529 -386.824614) (xy 145.264234 -386.809259) (xy 145.214657 -386.786617)
			(xy 145.168807 -386.757151) (xy 145.127616 -386.72146) (xy 145.091925 -386.680269) (xy 145.062459 -386.634419)
			(xy 145.039817 -386.584842) (xy 145.024462 -386.532547) (xy 145.016706 -386.478599) (xy 145.01622 -386.451348)
			(xy 145.016682 -386.424801) (xy 145.024056 -386.372221) (xy 145.038654 -386.321174) (xy 145.060193 -386.272645)
			(xy 145.088257 -386.227574) (xy 145.122303 -386.186832) (xy 145.161672 -386.151209) (xy 145.183352 -386.13588)
			(xy 145.192242 -386.129784) (xy 145.203418 -386.112258) (xy 145.216118 -386.027676) (xy 145.217196 -386.017262)
			(xy 145.211832 -385.997047) (xy 145.205704 -385.98856) (xy 145.20545 -385.988306) (xy 145.194215 -385.973932)
			(xy 145.174242 -385.943398) (xy 145.165572 -385.927346) (xy 145.161254 -385.919218) (xy 145.147284 -385.906518)
			(xy 145.138394 -385.903216) (xy 145.128814 -385.90017) (xy 145.108745 -385.900894) (xy 145.090479 -385.90924)
			(xy 145.076796 -385.923939) (xy 145.072862 -385.933188) (xy 144.366996 -387.835902) (xy 144.364042 -387.844841)
			(xy 144.364247 -387.863652) (xy 144.371241 -387.881117) (xy 144.37741 -387.888226) (xy 144.377664 -387.88848)
			(xy 144.397118 -387.909836) (xy 144.430011 -387.957322) (xy 144.455362 -388.009228) (xy 144.47259 -388.064365)
			(xy 144.481299 -388.121471) (xy 144.481804 -388.150354) (xy 144.48175 -388.153402) (xy 146.889468 -388.153402)
			(xy 146.893539 -388.09778) (xy 146.905665 -388.043343) (xy 146.925588 -387.991252) (xy 146.952884 -387.942617)
			(xy 146.98697 -387.898474) (xy 147.027119 -387.859765) (xy 147.072477 -387.827314) (xy 147.122077 -387.801813)
			(xy 147.174861 -387.783806) (xy 147.229704 -387.773676) (xy 147.285438 -387.771639) (xy 147.340875 -387.777739)
			(xy 147.394832 -387.791845) (xy 147.446161 -387.813657) (xy 147.493767 -387.842711) (xy 147.536635 -387.878386)
			(xy 147.573852 -387.919923) (xy 147.604625 -387.966436) (xy 147.628297 -388.016933) (xy 147.644365 -388.07034)
			(xy 147.652485 -388.125516) (xy 147.652994 -388.153402) (xy 147.652485 -388.181288) (xy 147.648141 -388.210806)
			(xy 148.921468 -388.210806) (xy 148.925539 -388.155184) (xy 148.937665 -388.100747) (xy 148.957588 -388.048656)
			(xy 148.984884 -388.000021) (xy 149.01897 -387.955878) (xy 149.059119 -387.917169) (xy 149.104477 -387.884718)
			(xy 149.154077 -387.859217) (xy 149.206861 -387.84121) (xy 149.261704 -387.83108) (xy 149.317438 -387.829043)
			(xy 149.372875 -387.835143) (xy 149.426832 -387.849249) (xy 149.478161 -387.871061) (xy 149.525767 -387.900115)
			(xy 149.568635 -387.93579) (xy 149.605852 -387.977327) (xy 149.636625 -388.02384) (xy 149.660297 -388.074337)
			(xy 149.676365 -388.127744) (xy 149.684485 -388.18292) (xy 149.684994 -388.210806) (xy 149.684485 -388.238692)
			(xy 149.676365 -388.293868) (xy 149.660297 -388.347275) (xy 149.636625 -388.397772) (xy 149.605852 -388.444285)
			(xy 149.568635 -388.485822) (xy 149.525767 -388.521497) (xy 149.478161 -388.550551) (xy 149.426832 -388.572363)
			(xy 149.372875 -388.586469) (xy 149.317438 -388.592569) (xy 149.261704 -388.590532) (xy 149.206861 -388.580402)
			(xy 149.154077 -388.562395) (xy 149.104477 -388.536894) (xy 149.059119 -388.504443) (xy 149.01897 -388.465734)
			(xy 148.984884 -388.421591) (xy 148.957588 -388.372956) (xy 148.937665 -388.320865) (xy 148.925539 -388.266428)
			(xy 148.921468 -388.210806) (xy 147.648141 -388.210806) (xy 147.644365 -388.236464) (xy 147.628297 -388.289871)
			(xy 147.604625 -388.340368) (xy 147.573852 -388.386881) (xy 147.536635 -388.428418) (xy 147.493767 -388.464093)
			(xy 147.446161 -388.493147) (xy 147.394832 -388.514959) (xy 147.340875 -388.529065) (xy 147.285438 -388.535165)
			(xy 147.229704 -388.533128) (xy 147.174861 -388.522998) (xy 147.122077 -388.504991) (xy 147.072477 -388.47949)
			(xy 147.027119 -388.447039) (xy 146.98697 -388.40833) (xy 146.952884 -388.364187) (xy 146.925588 -388.315552)
			(xy 146.905665 -388.263461) (xy 146.893539 -388.209024) (xy 146.889468 -388.153402) (xy 144.48175 -388.153402)
			(xy 144.481307 -388.178357) (xy 144.473111 -388.23376) (xy 144.456903 -388.28737) (xy 144.433031 -388.338034)
			(xy 144.402008 -388.384663) (xy 144.364501 -388.426256) (xy 144.321316 -388.461918) (xy 144.273381 -388.490883)
			(xy 144.221727 -388.512528) (xy 144.167463 -388.526389) (xy 144.139666 -388.52983) (xy 144.13029 -388.531218)
			(xy 144.113463 -388.539915) (xy 144.100922 -388.554111) (xy 144.097248 -388.56285) (xy 144.04709 -388.698486)
			(xy 144.600166 -388.698486) (xy 144.604237 -388.642864) (xy 144.616363 -388.588427) (xy 144.636286 -388.536336)
			(xy 144.663582 -388.487701) (xy 144.697668 -388.443558) (xy 144.737817 -388.404849) (xy 144.783175 -388.372398)
			(xy 144.832775 -388.346897) (xy 144.885559 -388.32889) (xy 144.940402 -388.31876) (xy 144.996136 -388.316723)
			(xy 145.051573 -388.322823) (xy 145.10553 -388.336929) (xy 145.156859 -388.358741) (xy 145.204465 -388.387795)
			(xy 145.247333 -388.42347) (xy 145.28455 -388.465007) (xy 145.315323 -388.51152) (xy 145.338995 -388.562017)
			(xy 145.355063 -388.615424) (xy 145.363183 -388.6706) (xy 145.363692 -388.698486) (xy 145.363183 -388.726372)
			(xy 145.355063 -388.781548) (xy 145.338995 -388.834955) (xy 145.315323 -388.885452) (xy 145.28455 -388.931965)
			(xy 145.247333 -388.973502) (xy 145.204465 -389.009177) (xy 145.156859 -389.038231) (xy 145.10553 -389.060043)
			(xy 145.051573 -389.074149) (xy 144.996136 -389.080249) (xy 144.940402 -389.078212) (xy 144.885559 -389.068082)
			(xy 144.832775 -389.050075) (xy 144.783175 -389.024574) (xy 144.737817 -388.992123) (xy 144.697668 -388.953414)
			(xy 144.663582 -388.909271) (xy 144.636286 -388.860636) (xy 144.616363 -388.808545) (xy 144.604237 -388.754108)
			(xy 144.600166 -388.698486) (xy 144.04709 -388.698486) (xy 144.036288 -388.727696) (xy 144.035018 -388.741158)
			(xy 144.036542 -388.74827) (xy 144.039972 -388.76662) (xy 144.043657 -388.803771) (xy 144.043908 -388.822438)
			(xy 144.043908 -388.8232) (xy 144.043469 -388.849182) (xy 144.036413 -388.900665) (xy 144.022434 -388.950714)
			(xy 144.001789 -388.998401) (xy 143.97486 -389.042844) (xy 143.942147 -389.083219) (xy 143.923512 -389.10133)
			(xy 143.916245 -389.108829) (xy 143.907983 -389.127982) (xy 143.90751 -389.138414) (xy 143.90751 -389.268462)
			(xy 143.907076 -389.278527) (xy 143.899347 -389.297117) (xy 143.892524 -389.30453) (xy 143.837406 -389.359648)
			(xy 145.873468 -389.359648) (xy 145.877539 -389.304026) (xy 145.889665 -389.249589) (xy 145.909588 -389.197498)
			(xy 145.936884 -389.148863) (xy 145.97097 -389.10472) (xy 146.011119 -389.066011) (xy 146.056477 -389.03356)
			(xy 146.106077 -389.008059) (xy 146.158861 -388.990052) (xy 146.213704 -388.979922) (xy 146.269438 -388.977885)
			(xy 146.324875 -388.983985) (xy 146.378832 -388.998091) (xy 146.430161 -389.019903) (xy 146.477767 -389.048957)
			(xy 146.520635 -389.084632) (xy 146.557852 -389.126169) (xy 146.588625 -389.172682) (xy 146.612297 -389.223179)
			(xy 146.628365 -389.276586) (xy 146.636485 -389.331762) (xy 146.636994 -389.359648) (xy 146.636485 -389.387534)
			(xy 146.636365 -389.38835) (xy 147.905468 -389.38835) (xy 147.909539 -389.332728) (xy 147.921665 -389.278291)
			(xy 147.941588 -389.2262) (xy 147.968884 -389.177565) (xy 148.00297 -389.133422) (xy 148.043119 -389.094713)
			(xy 148.088477 -389.062262) (xy 148.138077 -389.036761) (xy 148.190861 -389.018754) (xy 148.245704 -389.008624)
			(xy 148.301438 -389.006587) (xy 148.356875 -389.012687) (xy 148.410832 -389.026793) (xy 148.462161 -389.048605)
			(xy 148.509767 -389.077659) (xy 148.552635 -389.113334) (xy 148.589852 -389.154871) (xy 148.594424 -389.161782)
			(xy 150.953468 -389.161782) (xy 150.957539 -389.10616) (xy 150.969665 -389.051723) (xy 150.989588 -388.999632)
			(xy 151.016884 -388.950997) (xy 151.05097 -388.906854) (xy 151.091119 -388.868145) (xy 151.136477 -388.835694)
			(xy 151.186077 -388.810193) (xy 151.238861 -388.792186) (xy 151.293704 -388.782056) (xy 151.349438 -388.780019)
			(xy 151.404875 -388.786119) (xy 151.458832 -388.800225) (xy 151.510161 -388.822037) (xy 151.557767 -388.851091)
			(xy 151.600635 -388.886766) (xy 151.637852 -388.928303) (xy 151.668625 -388.974816) (xy 151.692297 -389.025313)
			(xy 151.708365 -389.07872) (xy 151.716485 -389.133896) (xy 151.716994 -389.161782) (xy 151.716485 -389.189668)
			(xy 151.708365 -389.244844) (xy 151.692297 -389.298251) (xy 151.668625 -389.348748) (xy 151.637852 -389.395261)
			(xy 151.600635 -389.436798) (xy 151.557767 -389.472473) (xy 151.510161 -389.501527) (xy 151.458832 -389.523339)
			(xy 151.404875 -389.537445) (xy 151.349438 -389.543545) (xy 151.293704 -389.541508) (xy 151.238861 -389.531378)
			(xy 151.186077 -389.513371) (xy 151.136477 -389.48787) (xy 151.091119 -389.455419) (xy 151.05097 -389.41671)
			(xy 151.016884 -389.372567) (xy 150.989588 -389.323932) (xy 150.969665 -389.271841) (xy 150.957539 -389.217404)
			(xy 150.953468 -389.161782) (xy 148.594424 -389.161782) (xy 148.620625 -389.201384) (xy 148.644297 -389.251881)
			(xy 148.660365 -389.305288) (xy 148.668485 -389.360464) (xy 148.668994 -389.38835) (xy 148.668485 -389.416236)
			(xy 148.660365 -389.471412) (xy 148.644297 -389.524819) (xy 148.620625 -389.575316) (xy 148.589852 -389.621829)
			(xy 148.552635 -389.663366) (xy 148.509767 -389.699041) (xy 148.462161 -389.728095) (xy 148.410832 -389.749907)
			(xy 148.356875 -389.764013) (xy 148.301438 -389.770113) (xy 148.245704 -389.768076) (xy 148.190861 -389.757946)
			(xy 148.138077 -389.739939) (xy 148.088477 -389.714438) (xy 148.043119 -389.681987) (xy 148.00297 -389.643278)
			(xy 147.968884 -389.599135) (xy 147.941588 -389.5505) (xy 147.921665 -389.498409) (xy 147.909539 -389.443972)
			(xy 147.905468 -389.38835) (xy 146.636365 -389.38835) (xy 146.628365 -389.44271) (xy 146.612297 -389.496117)
			(xy 146.588625 -389.546614) (xy 146.557852 -389.593127) (xy 146.520635 -389.634664) (xy 146.477767 -389.670339)
			(xy 146.430161 -389.699393) (xy 146.378832 -389.721205) (xy 146.324875 -389.735311) (xy 146.269438 -389.741411)
			(xy 146.213704 -389.739374) (xy 146.158861 -389.729244) (xy 146.106077 -389.711237) (xy 146.056477 -389.685736)
			(xy 146.011119 -389.653285) (xy 145.97097 -389.614576) (xy 145.936884 -389.570433) (xy 145.909588 -389.521798)
			(xy 145.889665 -389.469707) (xy 145.877539 -389.41527) (xy 145.873468 -389.359648) (xy 143.837406 -389.359648)
			(xy 143.779748 -389.417306) (xy 143.775938 -389.426704) (xy 143.762984 -389.456168) (xy 143.75892 -389.465058)
			(xy 143.757904 -389.483346) (xy 143.781272 -389.55726) (xy 143.784506 -389.566108) (xy 143.796232 -389.58083)
			(xy 143.804132 -389.585962) (xy 143.828386 -389.600761) (xy 143.872627 -389.636406) (xy 143.9111 -389.678211)
			(xy 143.942956 -389.725255) (xy 143.967492 -389.776498) (xy 143.984166 -389.83081) (xy 143.992612 -389.886993)
			(xy 143.993108 -389.9154) (xy 143.992622 -389.942651) (xy 143.984866 -389.996599) (xy 143.969511 -390.048894)
			(xy 143.946869 -390.098471) (xy 143.917403 -390.144321) (xy 143.881712 -390.185512) (xy 143.840521 -390.221203)
			(xy 143.794671 -390.250669) (xy 143.745094 -390.273311) (xy 143.692799 -390.288666) (xy 143.638851 -390.296422)
			(xy 143.6116 -390.296908) (xy 143.585955 -390.296491) (xy 143.535128 -390.289612) (xy 143.485684 -390.275978)
			(xy 143.438514 -390.255836) (xy 143.416274 -390.24306) (xy 143.407384 -390.237726) (xy 143.387826 -390.234932)
			(xy 143.308324 -390.254998) (xy 143.298704 -390.257819) (xy 143.282613 -390.269748) (xy 143.277082 -390.278112)
			(xy 142.986031 -390.763252) (xy 143.960848 -390.763252) (xy 143.964919 -390.70763) (xy 143.977045 -390.653193)
			(xy 143.996968 -390.601102) (xy 144.024264 -390.552467) (xy 144.05835 -390.508324) (xy 144.098499 -390.469615)
			(xy 144.143857 -390.437164) (xy 144.193457 -390.411663) (xy 144.246241 -390.393656) (xy 144.301084 -390.383526)
			(xy 144.356818 -390.381489) (xy 144.412255 -390.387589) (xy 144.466212 -390.401695) (xy 144.517541 -390.423507)
			(xy 144.565147 -390.452561) (xy 144.608015 -390.488236) (xy 144.645232 -390.529773) (xy 144.676005 -390.576286)
			(xy 144.699677 -390.626783) (xy 144.715745 -390.68019) (xy 144.723865 -390.735366) (xy 144.724374 -390.763252)
			(xy 144.723865 -390.791138) (xy 144.715745 -390.846314) (xy 144.699677 -390.899721) (xy 144.676005 -390.950218)
			(xy 144.645232 -390.996731) (xy 144.608015 -391.038268) (xy 144.565147 -391.073943) (xy 144.517541 -391.102997)
			(xy 144.466212 -391.124809) (xy 144.412255 -391.138915) (xy 144.356818 -391.145015) (xy 144.301084 -391.142978)
			(xy 144.246241 -391.132848) (xy 144.193457 -391.114841) (xy 144.143857 -391.08934) (xy 144.098499 -391.056889)
			(xy 144.05835 -391.01818) (xy 144.024264 -390.974037) (xy 143.996968 -390.925402) (xy 143.977045 -390.873311)
			(xy 143.964919 -390.818874) (xy 143.960848 -390.763252) (xy 142.986031 -390.763252) (xy 142.527817 -391.52703)
			(xy 142.865854 -391.52703) (xy 142.869925 -391.471408) (xy 142.882051 -391.416971) (xy 142.901974 -391.36488)
			(xy 142.92927 -391.316245) (xy 142.963356 -391.272102) (xy 143.003505 -391.233393) (xy 143.048863 -391.200942)
			(xy 143.098463 -391.175441) (xy 143.151247 -391.157434) (xy 143.20609 -391.147304) (xy 143.261824 -391.145267)
			(xy 143.317261 -391.151367) (xy 143.371218 -391.165473) (xy 143.422547 -391.187285) (xy 143.470153 -391.216339)
			(xy 143.513021 -391.252014) (xy 143.550238 -391.293551) (xy 143.581011 -391.340064) (xy 143.604683 -391.390561)
			(xy 143.620751 -391.443968) (xy 143.628871 -391.499144) (xy 143.629055 -391.50925) (xy 145.03476 -391.50925)
			(xy 145.038831 -391.453628) (xy 145.050957 -391.399191) (xy 145.07088 -391.3471) (xy 145.098176 -391.298465)
			(xy 145.132262 -391.254322) (xy 145.172411 -391.215613) (xy 145.217769 -391.183162) (xy 145.267369 -391.157661)
			(xy 145.320153 -391.139654) (xy 145.374996 -391.129524) (xy 145.43073 -391.127487) (xy 145.486167 -391.133587)
			(xy 145.540124 -391.147693) (xy 145.591453 -391.169505) (xy 145.639059 -391.198559) (xy 145.681927 -391.234234)
			(xy 145.719144 -391.275771) (xy 145.749917 -391.322284) (xy 145.773589 -391.372781) (xy 145.789657 -391.426188)
			(xy 145.797777 -391.481364) (xy 145.798286 -391.50925) (xy 145.797777 -391.537136) (xy 145.793209 -391.568178)
			(xy 147.905468 -391.568178) (xy 147.909539 -391.512556) (xy 147.921665 -391.458119) (xy 147.941588 -391.406028)
			(xy 147.968884 -391.357393) (xy 148.00297 -391.31325) (xy 148.043119 -391.274541) (xy 148.088477 -391.24209)
			(xy 148.138077 -391.216589) (xy 148.190861 -391.198582) (xy 148.245704 -391.188452) (xy 148.301438 -391.186415)
			(xy 148.356875 -391.192515) (xy 148.410832 -391.206621) (xy 148.462161 -391.228433) (xy 148.509767 -391.257487)
			(xy 148.552635 -391.293162) (xy 148.589852 -391.334699) (xy 148.620625 -391.381212) (xy 148.644297 -391.431709)
			(xy 148.660365 -391.485116) (xy 148.668485 -391.540292) (xy 148.668994 -391.568178) (xy 148.668485 -391.596064)
			(xy 148.660365 -391.65124) (xy 148.644297 -391.704647) (xy 148.620625 -391.755144) (xy 148.609885 -391.771378)
			(xy 149.937468 -391.771378) (xy 149.941539 -391.715756) (xy 149.953665 -391.661319) (xy 149.973588 -391.609228)
			(xy 150.000884 -391.560593) (xy 150.03497 -391.51645) (xy 150.075119 -391.477741) (xy 150.120477 -391.44529)
			(xy 150.170077 -391.419789) (xy 150.222861 -391.401782) (xy 150.277704 -391.391652) (xy 150.333438 -391.389615)
			(xy 150.388875 -391.395715) (xy 150.442832 -391.409821) (xy 150.494161 -391.431633) (xy 150.541767 -391.460687)
			(xy 150.584635 -391.496362) (xy 150.621852 -391.537899) (xy 150.652625 -391.584412) (xy 150.676297 -391.634909)
			(xy 150.692365 -391.688316) (xy 150.700485 -391.743492) (xy 150.700994 -391.771378) (xy 150.700485 -391.799264)
			(xy 150.692365 -391.85444) (xy 150.676297 -391.907847) (xy 150.652625 -391.958344) (xy 150.621852 -392.004857)
			(xy 150.584635 -392.046394) (xy 150.541767 -392.082069) (xy 150.494161 -392.111123) (xy 150.442832 -392.132935)
			(xy 150.388875 -392.147041) (xy 150.333438 -392.153141) (xy 150.277704 -392.151104) (xy 150.222861 -392.140974)
			(xy 150.170077 -392.122967) (xy 150.120477 -392.097466) (xy 150.075119 -392.065015) (xy 150.03497 -392.026306)
			(xy 150.000884 -391.982163) (xy 149.973588 -391.933528) (xy 149.953665 -391.881437) (xy 149.941539 -391.827)
			(xy 149.937468 -391.771378) (xy 148.609885 -391.771378) (xy 148.589852 -391.801657) (xy 148.552635 -391.843194)
			(xy 148.509767 -391.878869) (xy 148.462161 -391.907923) (xy 148.410832 -391.929735) (xy 148.356875 -391.943841)
			(xy 148.301438 -391.949941) (xy 148.245704 -391.947904) (xy 148.190861 -391.937774) (xy 148.138077 -391.919767)
			(xy 148.088477 -391.894266) (xy 148.043119 -391.861815) (xy 148.00297 -391.823106) (xy 147.968884 -391.778963)
			(xy 147.941588 -391.730328) (xy 147.921665 -391.678237) (xy 147.909539 -391.6238) (xy 147.905468 -391.568178)
			(xy 145.793209 -391.568178) (xy 145.789657 -391.592312) (xy 145.773589 -391.645719) (xy 145.749917 -391.696216)
			(xy 145.719144 -391.742729) (xy 145.681927 -391.784266) (xy 145.639059 -391.819941) (xy 145.591453 -391.848995)
			(xy 145.540124 -391.870807) (xy 145.486167 -391.884913) (xy 145.43073 -391.891013) (xy 145.374996 -391.888976)
			(xy 145.320153 -391.878846) (xy 145.267369 -391.860839) (xy 145.217769 -391.835338) (xy 145.172411 -391.802887)
			(xy 145.132262 -391.764178) (xy 145.098176 -391.720035) (xy 145.07088 -391.6714) (xy 145.050957 -391.619309)
			(xy 145.038831 -391.564872) (xy 145.03476 -391.50925) (xy 143.629055 -391.50925) (xy 143.62938 -391.52703)
			(xy 143.628871 -391.554916) (xy 143.620751 -391.610092) (xy 143.604683 -391.663499) (xy 143.581011 -391.713996)
			(xy 143.550238 -391.760509) (xy 143.513021 -391.802046) (xy 143.470153 -391.837721) (xy 143.422547 -391.866775)
			(xy 143.371218 -391.888587) (xy 143.317261 -391.902693) (xy 143.261824 -391.908793) (xy 143.20609 -391.906756)
			(xy 143.151247 -391.896626) (xy 143.098463 -391.878619) (xy 143.048863 -391.853118) (xy 143.003505 -391.820667)
			(xy 142.963356 -391.781958) (xy 142.92927 -391.737815) (xy 142.901974 -391.68918) (xy 142.882051 -391.637089)
			(xy 142.869925 -391.582652) (xy 142.865854 -391.52703) (xy 142.527817 -391.52703) (xy 142.388082 -391.759948)
			(xy 142.36633 -391.795378) (xy 142.317771 -391.862868) (xy 142.263758 -391.926077) (xy 142.204666 -391.984567)
			(xy 142.140907 -392.037931) (xy 142.107158 -392.062208) (xy 141.995652 -392.140694) (xy 141.986254 -392.152886)
			(xy 141.983714 -392.159998) (xy 141.976103 -392.179302) (xy 146.321016 -392.179302) (xy 146.325087 -392.12368)
			(xy 146.337213 -392.069243) (xy 146.357136 -392.017152) (xy 146.384432 -391.968517) (xy 146.418518 -391.924374)
			(xy 146.458667 -391.885665) (xy 146.504025 -391.853214) (xy 146.553625 -391.827713) (xy 146.606409 -391.809706)
			(xy 146.661252 -391.799576) (xy 146.716986 -391.797539) (xy 146.772423 -391.803639) (xy 146.82638 -391.817745)
			(xy 146.877709 -391.839557) (xy 146.925315 -391.868611) (xy 146.968183 -391.904286) (xy 147.0054 -391.945823)
			(xy 147.036173 -391.992336) (xy 147.059845 -392.042833) (xy 147.075913 -392.09624) (xy 147.084033 -392.151416)
			(xy 147.084542 -392.179302) (xy 147.084033 -392.207188) (xy 147.075913 -392.262364) (xy 147.059845 -392.315771)
			(xy 147.036173 -392.366268) (xy 147.0054 -392.412781) (xy 146.968183 -392.454318) (xy 146.925315 -392.489993)
			(xy 146.877709 -392.519047) (xy 146.82638 -392.540859) (xy 146.772423 -392.554965) (xy 146.716986 -392.561065)
			(xy 146.661252 -392.559028) (xy 146.606409 -392.548898) (xy 146.553625 -392.530891) (xy 146.504025 -392.50539)
			(xy 146.458667 -392.472939) (xy 146.418518 -392.43423) (xy 146.384432 -392.390087) (xy 146.357136 -392.341452)
			(xy 146.337213 -392.289361) (xy 146.325087 -392.234924) (xy 146.321016 -392.179302) (xy 141.976103 -392.179302)
			(xy 141.973225 -392.186603) (xy 141.945433 -392.236582) (xy 141.910493 -392.281854) (xy 141.869188 -392.321404)
			(xy 141.822444 -392.354348) (xy 141.771306 -392.379947) (xy 141.716921 -392.397627) (xy 141.660507 -392.406994)
			(xy 141.631924 -392.407902) (xy 141.624335 -392.408298) (xy 141.609872 -392.412942) (xy 141.603476 -392.417046)
			(xy 141.277067 -392.646916) (xy 148.921468 -392.646916) (xy 148.925539 -392.591294) (xy 148.937665 -392.536857)
			(xy 148.957588 -392.484766) (xy 148.984884 -392.436131) (xy 149.01897 -392.391988) (xy 149.059119 -392.353279)
			(xy 149.104477 -392.320828) (xy 149.154077 -392.295327) (xy 149.206861 -392.27732) (xy 149.261704 -392.26719)
			(xy 149.317438 -392.265153) (xy 149.372875 -392.271253) (xy 149.426832 -392.285359) (xy 149.478161 -392.307171)
			(xy 149.525767 -392.336225) (xy 149.568635 -392.3719) (xy 149.605852 -392.413437) (xy 149.636625 -392.45995)
			(xy 149.660297 -392.510447) (xy 149.676365 -392.563854) (xy 149.684485 -392.61903) (xy 149.684994 -392.646916)
			(xy 149.684485 -392.674802) (xy 149.676365 -392.729978) (xy 149.673844 -392.738356) (xy 150.953468 -392.738356)
			(xy 150.957539 -392.682734) (xy 150.969665 -392.628297) (xy 150.989588 -392.576206) (xy 151.016884 -392.527571)
			(xy 151.05097 -392.483428) (xy 151.091119 -392.444719) (xy 151.136477 -392.412268) (xy 151.186077 -392.386767)
			(xy 151.238861 -392.36876) (xy 151.293704 -392.35863) (xy 151.349438 -392.356593) (xy 151.404875 -392.362693)
			(xy 151.458832 -392.376799) (xy 151.510161 -392.398611) (xy 151.557767 -392.427665) (xy 151.600635 -392.46334)
			(xy 151.637852 -392.504877) (xy 151.668625 -392.55139) (xy 151.692297 -392.601887) (xy 151.708365 -392.655294)
			(xy 151.716485 -392.71047) (xy 151.716994 -392.738356) (xy 151.716485 -392.766242) (xy 151.708365 -392.821418)
			(xy 151.692297 -392.874825) (xy 151.668625 -392.925322) (xy 151.637852 -392.971835) (xy 151.600635 -393.013372)
			(xy 151.557767 -393.049047) (xy 151.510161 -393.078101) (xy 151.458832 -393.099913) (xy 151.404875 -393.114019)
			(xy 151.349438 -393.120119) (xy 151.293704 -393.118082) (xy 151.238861 -393.107952) (xy 151.186077 -393.089945)
			(xy 151.136477 -393.064444) (xy 151.091119 -393.031993) (xy 151.05097 -392.993284) (xy 151.016884 -392.949141)
			(xy 150.989588 -392.900506) (xy 150.969665 -392.848415) (xy 150.957539 -392.793978) (xy 150.953468 -392.738356)
			(xy 149.673844 -392.738356) (xy 149.660297 -392.783385) (xy 149.636625 -392.833882) (xy 149.605852 -392.880395)
			(xy 149.568635 -392.921932) (xy 149.525767 -392.957607) (xy 149.478161 -392.986661) (xy 149.426832 -393.008473)
			(xy 149.372875 -393.022579) (xy 149.317438 -393.028679) (xy 149.261704 -393.026642) (xy 149.206861 -393.016512)
			(xy 149.154077 -392.998505) (xy 149.104477 -392.973004) (xy 149.059119 -392.940553) (xy 149.01897 -392.901844)
			(xy 148.984884 -392.857701) (xy 148.957588 -392.809066) (xy 148.937665 -392.756975) (xy 148.925539 -392.702538)
			(xy 148.921468 -392.646916) (xy 141.277067 -392.646916) (xy 138.86561 -394.34516) (xy 138.859006 -394.350748)
			(xy 136.079484 -397.13027) (xy 136.072955 -397.13734) (xy 136.065267 -397.154966) (xy 136.064498 -397.16456)
			(xy 136.061958 -397.243808) (xy 136.068562 -397.262096) (xy 136.074912 -397.269208) (xy 136.093847 -397.29142)
			(xy 136.126838 -397.33957) (xy 136.153826 -397.391325) (xy 136.174421 -397.445939) (xy 136.188328 -397.502627)
			(xy 136.195347 -397.560572) (xy 136.195816 -397.589756) (xy 136.195816 -397.59001) (xy 136.195318 -397.621807)
			(xy 136.187016 -397.684858) (xy 136.170554 -397.746285) (xy 136.146216 -397.805038) (xy 136.114417 -397.860111)
			(xy 136.075701 -397.910562) (xy 136.030731 -397.955529) (xy 135.980276 -397.99424) (xy 135.9252 -398.026035)
			(xy 135.866445 -398.050368) (xy 135.805016 -398.066824) (xy 135.741965 -398.075121) (xy 135.710168 -398.075658)
			(xy 135.709914 -398.075658) (xy 135.680726 -398.07523) (xy 135.62277 -398.068239) (xy 135.566071 -398.054344)
			(xy 135.51145 -398.033745) (xy 135.459695 -398.006741) (xy 135.411555 -397.973722) (xy 135.389366 -397.954754)
			(xy 135.382254 -397.948404) (xy 135.363966 -397.9418) (xy 135.284718 -397.94434) (xy 135.275122 -397.945089)
			(xy 135.257501 -397.952797) (xy 135.250428 -397.959326) (xy 134.319518 -398.890236) (xy 135.22402 -398.890236)
			(xy 135.228011 -398.828069) (xy 135.23992 -398.766922) (xy 135.259549 -398.707801) (xy 135.286578 -398.651675)
			(xy 135.320562 -398.599466) (xy 135.360944 -398.552031) (xy 135.40706 -398.51015) (xy 135.458152 -398.47451)
			(xy 135.513383 -398.445696) (xy 135.571845 -398.424182) (xy 135.632579 -398.41032) (xy 135.694586 -398.404338)
			(xy 135.756849 -398.406334) (xy 135.818346 -398.416277) (xy 135.878067 -398.434001) (xy 135.93503 -398.459218)
			(xy 135.988301 -398.491511) (xy 136.037006 -398.530351) (xy 136.080343 -398.575101) (xy 136.117603 -398.625025)
			(xy 136.148172 -398.679304) (xy 136.17155 -398.737047) (xy 136.187351 -398.797305) (xy 136.195317 -398.859088)
			(xy 136.195816 -398.890236) (xy 136.195317 -398.921384) (xy 136.187351 -398.983167) (xy 136.17155 -399.043425)
			(xy 136.148172 -399.101168) (xy 136.117603 -399.155447) (xy 136.080343 -399.205371) (xy 136.037006 -399.250121)
			(xy 135.988301 -399.288961) (xy 135.93503 -399.321254) (xy 135.878067 -399.346471) (xy 135.818346 -399.364195)
			(xy 135.756849 -399.374138) (xy 135.694586 -399.376134) (xy 135.632579 -399.370152) (xy 135.571845 -399.35629)
			(xy 135.513383 -399.334776) (xy 135.458152 -399.305962) (xy 135.40706 -399.270322) (xy 135.360944 -399.228441)
			(xy 135.320562 -399.181006) (xy 135.286578 -399.128797) (xy 135.259549 -399.072671) (xy 135.23992 -399.01355)
			(xy 135.228011 -398.952403) (xy 135.22402 -398.890236) (xy 134.319518 -398.890236) (xy 134.09676 -399.112994)
			(xy 134.089394 -399.128996) (xy 134.088632 -399.13814) (xy 134.085335 -399.171988) (xy 134.071829 -399.238643)
			(xy 134.050627 -399.303264) (xy 134.022021 -399.364965) (xy 133.986403 -399.422902) (xy 133.94426 -399.47628)
			(xy 133.896169 -399.52437) (xy 133.842789 -399.566511) (xy 133.784852 -399.602128) (xy 133.72315 -399.630733)
			(xy 133.658529 -399.651932) (xy 133.591873 -399.665438) (xy 133.558026 -399.668746) (xy 133.548882 -399.669508)
			(xy 133.53288 -399.676874) (xy 133.452108 -399.757646) (xy 133.444713 -399.7645) (xy 133.426114 -399.772245)
			(xy 133.41604 -399.772632) (xy 131.787392 -399.772632) (xy 131.781381 -399.772795) (xy 131.769695 -399.775611)
			(xy 131.764278 -399.77822) (xy 131.722039 -399.799197) (xy 131.634381 -399.834004) (xy 131.543826 -399.860369)
			(xy 131.451183 -399.878056) (xy 131.357284 -399.886908) (xy 131.310126 -399.88744) (xy 131.265322 -399.886962)
			(xy 131.176075 -399.878945) (xy 131.087905 -399.862956) (xy 131.001526 -399.839123) (xy 130.917632 -399.807639)
			(xy 130.877056 -399.788634) (xy 130.86865 -399.784995) (xy 130.850425 -399.783291) (xy 130.841496 -399.785332)
			(xy 130.818513 -399.791232) (xy 130.771494 -399.797603) (xy 130.74777 -399.798032) (xy 130.716093 -399.797325)
			(xy 130.653743 -399.78609) (xy 130.623818 -399.77568) (xy 130.615436 -399.772632) (xy 129.570226 -399.772632)
			(xy 129.560204 -399.773048) (xy 129.541683 -399.780714) (xy 129.527511 -399.794888) (xy 129.519847 -399.81341)
			(xy 129.519426 -399.823432) (xy 129.519426 -399.825972) (xy 129.51968 -399.828766) (xy 129.51968 -400.11477)
			(xy 129.519876 -400.121642) (xy 129.523488 -400.134902) (xy 129.526792 -400.140932) (xy 129.543113 -400.169294)
			(xy 129.568828 -400.229465) (xy 129.586234 -400.292543) (xy 129.595016 -400.357387) (xy 129.595016 -400.390106)
			(xy 133.023872 -400.390106) (xy 133.027863 -400.327939) (xy 133.039772 -400.266792) (xy 133.059401 -400.207671)
			(xy 133.08643 -400.151545) (xy 133.120414 -400.099336) (xy 133.160796 -400.051901) (xy 133.206912 -400.01002)
			(xy 133.258004 -399.97438) (xy 133.313235 -399.945566) (xy 133.371697 -399.924052) (xy 133.432431 -399.91019)
			(xy 133.494438 -399.904208) (xy 133.556701 -399.906204) (xy 133.618198 -399.916147) (xy 133.677919 -399.933871)
			(xy 133.734882 -399.959088) (xy 133.788153 -399.991381) (xy 133.836858 -400.030221) (xy 133.880195 -400.074971)
			(xy 133.917455 -400.124895) (xy 133.948024 -400.179174) (xy 133.971402 -400.236917) (xy 133.987203 -400.297175)
			(xy 133.995169 -400.358958) (xy 133.995668 -400.390106) (xy 133.995169 -400.421254) (xy 133.987203 -400.483037)
			(xy 133.971402 -400.543295) (xy 133.948024 -400.601038) (xy 133.917455 -400.655317) (xy 133.880195 -400.705241)
			(xy 133.836858 -400.749991) (xy 133.788153 -400.788831) (xy 133.734882 -400.821124) (xy 133.677919 -400.846341)
			(xy 133.618198 -400.864065) (xy 133.556701 -400.874008) (xy 133.494438 -400.876004) (xy 133.432431 -400.870022)
			(xy 133.371697 -400.85616) (xy 133.313235 -400.834646) (xy 133.258004 -400.805832) (xy 133.206912 -400.770192)
			(xy 133.160796 -400.728311) (xy 133.120414 -400.680876) (xy 133.08643 -400.628667) (xy 133.059401 -400.572541)
			(xy 133.039772 -400.51342) (xy 133.027863 -400.452273) (xy 133.023872 -400.390106) (xy 129.595016 -400.390106)
			(xy 129.595016 -400.422823) (xy 129.586232 -400.487667) (xy 129.568825 -400.550745) (xy 129.543108 -400.610916)
			(xy 129.526792 -400.63928) (xy 129.523486 -400.645307) (xy 129.51989 -400.65857) (xy 129.51968 -400.665442)
			(xy 129.51968 -401.414742) (xy 129.519872 -401.421616) (xy 129.523478 -401.434879) (xy 129.526792 -401.440904)
			(xy 129.543115 -401.469266) (xy 129.568834 -401.529437) (xy 129.586243 -401.592517) (xy 129.595029 -401.657362)
			(xy 129.595032 -401.7228) (xy 129.586251 -401.787646) (xy 129.568846 -401.850727) (xy 129.543132 -401.910901)
			(xy 129.526792 -401.939252) (xy 129.523483 -401.945279) (xy 129.51988 -401.958541) (xy 129.51968 -401.965414)
			(xy 129.51968 -402.251418) (xy 129.519182 -402.261575) (xy 129.511405 -402.280341) (xy 129.497041 -402.294705)
			(xy 129.478275 -402.302482) (xy 129.468118 -402.30298) (xy 128.751838 -402.30298) (xy 128.74166 -402.302561)
			(xy 128.722849 -402.294783) (xy 128.708448 -402.280398) (xy 128.70065 -402.261595) (xy 128.700276 -402.251418)
			(xy 128.700276 -401.965414) (xy 128.70009 -401.958539) (xy 128.696494 -401.945269) (xy 128.693164 -401.939252)
			(xy 128.676842 -401.910891) (xy 128.651126 -401.85072) (xy 128.63372 -401.787643) (xy 128.624939 -401.722799)
			(xy 128.624942 -401.657363) (xy 128.633728 -401.59252) (xy 128.651139 -401.529444) (xy 128.67686 -401.469275)
			(xy 128.693164 -401.440904) (xy 128.69647 -401.434877) (xy 128.700065 -401.421614) (xy 128.700276 -401.414742)
			(xy 128.700276 -400.665442) (xy 128.700081 -400.658569) (xy 128.696469 -400.64531) (xy 128.693164 -400.63928)
			(xy 128.676841 -400.610919) (xy 128.651121 -400.550748) (xy 128.633711 -400.487669) (xy 128.624926 -400.422824)
			(xy 128.624926 -400.357386) (xy 128.633709 -400.292541) (xy 128.651117 -400.229462) (xy 128.676836 -400.16929)
			(xy 128.693164 -400.140932) (xy 128.696473 -400.134906) (xy 128.700075 -400.121643) (xy 128.700276 -400.11477)
			(xy 128.700276 -399.828766) (xy 128.70053 -399.825972) (xy 128.70053 -399.823432) (xy 128.700117 -399.813404)
			(xy 128.692453 -399.794871) (xy 128.678281 -399.780681) (xy 128.659757 -399.772996) (xy 128.64973 -399.772632)
			(xy 127.38735 -399.772632) (xy 127.381341 -399.772799) (xy 127.369659 -399.775625) (xy 127.364236 -399.77822)
			(xy 127.321998 -399.7992) (xy 127.23434 -399.834011) (xy 127.143785 -399.860382) (xy 127.051143 -399.878074)
			(xy 126.957243 -399.886931) (xy 126.910084 -399.88744) (xy 126.865281 -399.88696) (xy 126.776034 -399.878939)
			(xy 126.687867 -399.862947) (xy 126.601489 -399.839111) (xy 126.517597 -399.807624) (xy 126.477014 -399.788634)
			(xy 126.468607 -399.785003) (xy 126.450386 -399.783313) (xy 126.441454 -399.785332) (xy 126.418471 -399.791229)
			(xy 126.371452 -399.797594) (xy 126.347728 -399.798032) (xy 126.316052 -399.797321) (xy 126.253704 -399.78608)
			(xy 126.223776 -399.77568) (xy 126.215394 -399.772632) (xy 125.170438 -399.772632) (xy 125.160414 -399.773046)
			(xy 125.14189 -399.78071) (xy 125.127713 -399.794885) (xy 125.120047 -399.813408) (xy 125.119638 -399.823432)
			(xy 125.119638 -399.825972) (xy 125.119892 -399.828766) (xy 125.119892 -400.11477) (xy 125.120088 -400.121642)
			(xy 125.123701 -400.134902) (xy 125.127004 -400.140932) (xy 125.143324 -400.169294) (xy 125.169039 -400.229465)
			(xy 125.186445 -400.292543) (xy 125.195227 -400.357387) (xy 125.195226 -400.422823) (xy 125.186443 -400.487667)
			(xy 125.169036 -400.550745) (xy 125.14332 -400.610915) (xy 125.127004 -400.63928) (xy 125.123698 -400.645307)
			(xy 125.120101 -400.65857) (xy 125.119892 -400.665442) (xy 125.119892 -401.414742) (xy 125.120084 -401.421615)
			(xy 125.123691 -401.434879) (xy 125.127004 -401.440904) (xy 125.143326 -401.469266) (xy 125.169045 -401.529438)
			(xy 125.186454 -401.592517) (xy 125.195239 -401.657362) (xy 125.195242 -401.7228) (xy 125.186462 -401.787646)
			(xy 125.169057 -401.850727) (xy 125.143344 -401.910901) (xy 125.127004 -401.939252) (xy 125.123694 -401.945278)
			(xy 125.12009 -401.958541) (xy 125.119892 -401.965414) (xy 125.119892 -402.251418) (xy 125.119394 -402.261576)
			(xy 125.111617 -402.280344) (xy 125.097254 -402.294711) (xy 125.078487 -402.302492) (xy 125.06833 -402.30298)
			(xy 124.35205 -402.30298) (xy 124.34187 -402.302563) (xy 124.323056 -402.294787) (xy 124.308651 -402.280402)
			(xy 124.30085 -402.261597) (xy 124.300488 -402.251418) (xy 124.300488 -401.965414) (xy 124.300303 -401.958538)
			(xy 124.296708 -401.945268) (xy 124.293376 -401.939252) (xy 124.277054 -401.910891) (xy 124.251337 -401.850721)
			(xy 124.233931 -401.787643) (xy 124.225149 -401.722799) (xy 124.225152 -401.657363) (xy 124.233938 -401.59252)
			(xy 124.25135 -401.529444) (xy 124.277071 -401.469275) (xy 124.293376 -401.440904) (xy 124.296681 -401.434877)
			(xy 124.300275 -401.421614) (xy 124.300488 -401.414742) (xy 124.300488 -400.665442) (xy 124.300294 -400.658569)
			(xy 124.296682 -400.645309) (xy 124.293376 -400.63928) (xy 124.277052 -400.610919) (xy 124.251332 -400.550748)
			(xy 124.233922 -400.487669) (xy 124.225137 -400.422824) (xy 124.225136 -400.357386) (xy 124.23392 -400.292541)
			(xy 124.251328 -400.229462) (xy 124.277048 -400.16929) (xy 124.293376 -400.140932) (xy 124.296685 -400.134905)
			(xy 124.300286 -400.121642) (xy 124.300488 -400.11477) (xy 124.300488 -399.828766) (xy 124.300742 -399.825972)
			(xy 124.300742 -399.823432) (xy 124.30026 -399.813417) (xy 124.292608 -399.794907) (xy 124.278455 -399.780734)
			(xy 124.259956 -399.773055) (xy 124.249942 -399.772632) (xy 122.987308 -399.772632) (xy 122.9813 -399.772804)
			(xy 122.969623 -399.775638) (xy 122.964194 -399.77822) (xy 122.921955 -399.799198) (xy 122.834298 -399.834006)
			(xy 122.743742 -399.860372) (xy 122.6511 -399.878061) (xy 122.5572 -399.886914) (xy 122.510042 -399.88744)
			(xy 122.465238 -399.886962) (xy 122.37599 -399.878947) (xy 122.28782 -399.862959) (xy 122.20144 -399.839128)
			(xy 122.117545 -399.807645) (xy 122.076972 -399.788634) (xy 122.068565 -399.78501) (xy 122.050348 -399.783335)
			(xy 122.041412 -399.785332) (xy 122.01843 -399.791233) (xy 121.97141 -399.797606) (xy 121.947686 -399.798032)
			(xy 121.916011 -399.797317) (xy 121.853666 -399.786069) (xy 121.823734 -399.77568) (xy 121.815352 -399.772632)
			(xy 120.770396 -399.772632) (xy 120.760378 -399.773053) (xy 120.741868 -399.780725) (xy 120.727704 -399.794898)
			(xy 120.720046 -399.813413) (xy 120.719596 -399.823432) (xy 120.719596 -400.11477) (xy 120.719792 -400.121642)
			(xy 120.723405 -400.134902) (xy 120.726708 -400.140932) (xy 120.74308 -400.169279) (xy 120.768893 -400.229436)
			(xy 120.786389 -400.292517) (xy 120.795251 -400.357376) (xy 120.795796 -400.390106) (xy 120.795227 -400.422835)
			(xy 120.786369 -400.487693) (xy 120.768882 -400.550774) (xy 120.743082 -400.610936) (xy 120.726708 -400.63928)
			(xy 120.723402 -400.645307) (xy 120.719805 -400.65857) (xy 120.719596 -400.665442) (xy 120.719596 -401.414742)
			(xy 120.719788 -401.421615) (xy 120.723395 -401.434878) (xy 120.726708 -401.440904) (xy 120.743075 -401.469252)
			(xy 120.768879 -401.529411) (xy 120.786366 -401.592491) (xy 120.795218 -401.657349) (xy 120.795796 -401.690078)
			(xy 120.795229 -401.722808) (xy 120.786374 -401.787667) (xy 120.76889 -401.85075) (xy 120.743093 -401.910914)
			(xy 120.726708 -401.939252) (xy 120.723398 -401.945278) (xy 120.719794 -401.958541) (xy 120.719596 -401.965414)
			(xy 120.719596 -402.251418) (xy 120.719104 -402.261544) (xy 120.711375 -402.280265) (xy 120.697091 -402.294623)
			(xy 120.678412 -402.302451) (xy 120.668288 -402.30298) (xy 119.952008 -402.30298) (xy 119.941856 -402.302551)
			(xy 119.923107 -402.294758) (xy 119.908789 -402.280362) (xy 119.901095 -402.261572) (xy 119.9007 -402.251418)
			(xy 119.9007 -401.965414) (xy 119.900515 -401.958538) (xy 119.89692 -401.945268) (xy 119.893588 -401.939252)
			(xy 119.877218 -401.910904) (xy 119.851407 -401.850747) (xy 119.833913 -401.787667) (xy 119.825053 -401.722808)
			(xy 119.8245 -401.690078) (xy 119.82507 -401.657349) (xy 119.83393 -401.592492) (xy 119.851419 -401.529412)
			(xy 119.87722 -401.469252) (xy 119.893588 -401.440904) (xy 119.896893 -401.434876) (xy 119.900486 -401.421614)
			(xy 119.9007 -401.414742) (xy 119.9007 -400.665442) (xy 119.900506 -400.658569) (xy 119.896895 -400.645309)
			(xy 119.893588 -400.63928) (xy 119.877222 -400.610931) (xy 119.85142 -400.550773) (xy 119.833935 -400.487692)
			(xy 119.825086 -400.422835) (xy 119.8245 -400.390106) (xy 119.825068 -400.357376) (xy 119.833925 -400.292518)
			(xy 119.85141 -400.229436) (xy 119.877209 -400.169274) (xy 119.893588 -400.140932) (xy 119.896896 -400.134905)
			(xy 119.900496 -400.121642) (xy 119.9007 -400.11477) (xy 119.9007 -399.823432) (xy 119.900286 -399.813406)
			(xy 119.892622 -399.794879) (xy 119.878448 -399.780696) (xy 119.859925 -399.77302) (xy 119.8499 -399.772632)
			(xy 118.587266 -399.772632) (xy 118.581256 -399.772798) (xy 118.569573 -399.77562) (xy 118.564152 -399.77822)
			(xy 118.521914 -399.7992) (xy 118.434257 -399.834014) (xy 118.343702 -399.860385) (xy 118.251059 -399.878079)
			(xy 118.157159 -399.886938) (xy 118.11 -399.88744) (xy 118.065197 -399.88696) (xy 117.97595 -399.878941)
			(xy 117.887781 -399.86295) (xy 117.801403 -399.839115) (xy 117.71751 -399.80763) (xy 117.67693 -399.788634)
			(xy 117.668524 -399.785) (xy 117.650301 -399.783304) (xy 117.64137 -399.785332) (xy 117.618387 -399.79123)
			(xy 117.571368 -399.797597) (xy 117.547644 -399.798032) (xy 117.515968 -399.797322) (xy 117.453619 -399.786084)
			(xy 117.423692 -399.77568) (xy 117.41531 -399.772632) (xy 117.149626 -399.772632) (xy 117.139575 -399.772128)
			(xy 117.121012 -399.764408) (xy 117.113558 -399.757646) (xy 116.13134 -398.775428) (xy 116.10721 -398.768062)
			(xy 116.094764 -398.770348) (xy 116.049029 -398.778437) (xy 115.956548 -398.787091) (xy 115.910106 -398.78762)
			(xy 115.865296 -398.787121) (xy 115.77604 -398.779062) (xy 115.687867 -398.763024) (xy 115.601489 -398.739139)
			(xy 115.517603 -398.707598) (xy 115.477036 -398.68856) (xy 115.46863 -398.684923) (xy 115.450406 -398.683225)
			(xy 115.441476 -398.685258) (xy 115.418493 -398.691158) (xy 115.371474 -398.697527) (xy 115.34775 -398.697958)
			(xy 115.319768 -398.697405) (xy 115.264494 -398.688644) (xy 115.21127 -398.671346) (xy 115.161408 -398.645936)
			(xy 115.116133 -398.61304) (xy 115.07656 -398.573467) (xy 115.043664 -398.528192) (xy 115.018254 -398.47833)
			(xy 115.000956 -398.425106) (xy 114.992195 -398.369832) (xy 114.991642 -398.34185) (xy 114.991642 -398.341342)
			(xy 114.992066 -398.316038) (xy 114.999203 -398.265935) (xy 115.005866 -398.24152) (xy 115.008048 -398.232711)
			(xy 115.006744 -398.214622) (xy 115.003326 -398.206214) (xy 114.985886 -398.167052) (xy 114.956992 -398.086332)
			(xy 114.935134 -398.003429) (xy 114.920472 -397.918957) (xy 114.913116 -397.833538) (xy 114.912648 -397.79067)
			(xy 114.912648 -397.578072) (xy 114.912195 -397.568047) (xy 114.904596 -397.549496) (xy 114.897916 -397.542004)
			(xy 114.780568 -397.424656) (xy 114.773872 -397.417246) (xy 114.766254 -397.398805) (xy 114.766242 -397.378854)
			(xy 114.773839 -397.360405) (xy 114.780568 -397.353028) (xy 114.92484 -397.208756) (xy 114.929655 -397.203579)
			(xy 114.936485 -397.191205) (xy 114.938302 -397.184372) (xy 114.945922 -397.15313) (xy 114.947396 -397.146736)
			(xy 114.94739 -397.133618) (xy 114.945922 -397.127222) (xy 114.935335 -397.08551) (xy 114.920537 -397.000727)
			(xy 114.913104 -396.914984) (xy 114.912648 -396.871952) (xy 114.912648 -396.49019) (xy 114.913264 -396.441103)
			(xy 114.922964 -396.343409) (xy 114.942211 -396.247139) (xy 114.970817 -396.153225) (xy 114.989102 -396.107666)
			(xy 114.992407 -396.098719) (xy 114.992785 -396.079663) (xy 114.989864 -396.070582) (xy 114.978862 -396.038676)
			(xy 114.966986 -395.972244) (xy 114.966242 -395.938502) (xy 114.966656 -395.913154) (xy 114.973366 -395.862903)
			(xy 114.986668 -395.813983) (xy 115.006328 -395.767253) (xy 115.032 -395.723537) (xy 115.047268 -395.703298)
			(xy 115.05226 -395.696469) (xy 115.057829 -395.680508) (xy 115.05819 -395.672056) (xy 115.05819 -384.264916)
			(xy 115.057937 -384.257504) (xy 115.053676 -384.243304) (xy 115.049808 -384.236976) (xy 115.036052 -384.215124)
			(xy 115.014306 -384.168293) (xy 114.99955 -384.118813) (xy 114.992094 -384.06772) (xy 114.992093 -384.016086)
			(xy 114.999549 -383.964994) (xy 115.014304 -383.915513) (xy 115.036049 -383.868681) (xy 115.049808 -383.846832)
			(xy 115.053667 -383.840501) (xy 115.057913 -383.826302) (xy 115.05819 -383.818892) (xy 115.05819 -383.063242)
			(xy 115.057941 -383.055828) (xy 115.053686 -383.041625) (xy 115.049808 -383.035302) (xy 115.03605 -383.01345)
			(xy 115.0143 -382.966619) (xy 114.999541 -382.917137) (xy 114.992081 -382.866043) (xy 114.992078 -382.814407)
			(xy 114.99953 -382.763312) (xy 115.014283 -382.713828) (xy 115.036026 -382.666994) (xy 115.049808 -382.645158)
			(xy 115.05367 -382.638828) (xy 115.057923 -382.624629) (xy 115.05819 -382.617218) (xy 115.05819 -381.905002)
			(xy 115.057794 -381.896558) (xy 115.052218 -381.880612) (xy 115.047268 -381.87376) (xy 115.030306 -381.851264)
			(xy 115.002488 -381.80227) (xy 114.982176 -381.749719) (xy 114.969812 -381.694752) (xy 114.965663 -381.638565)
			(xy 114.969822 -381.582379) (xy 114.982196 -381.527415) (xy 115.002518 -381.474867) (xy 115.030344 -381.425879)
			(xy 115.047268 -381.403352) (xy 115.052267 -381.396526) (xy 115.057853 -381.380564) (xy 115.05819 -381.37211)
			(xy 115.05819 -380.364746) (xy 115.057941 -380.357332) (xy 115.053687 -380.343128) (xy 115.049808 -380.336806)
			(xy 115.03605 -380.314954) (xy 115.014299 -380.268123) (xy 114.99954 -380.218641) (xy 114.992079 -380.167546)
			(xy 114.992075 -380.11591) (xy 114.999527 -380.064815) (xy 115.014279 -380.015331) (xy 115.036022 -379.968495)
			(xy 115.049808 -379.946662) (xy 115.05367 -379.940332) (xy 115.057925 -379.926133) (xy 115.05819 -379.918722)
			(xy 115.05819 -379.163072) (xy 115.057931 -379.155662) (xy 115.05366 -379.141469) (xy 115.049808 -379.135132)
			(xy 115.036055 -379.11328) (xy 115.014315 -379.06645) (xy 114.999566 -379.016972) (xy 114.992115 -378.965882)
			(xy 114.99212 -378.914251) (xy 114.99958 -378.863163) (xy 115.014339 -378.813687) (xy 115.036088 -378.766861)
			(xy 115.049808 -378.744988) (xy 115.053674 -378.738659) (xy 115.057936 -378.72446) (xy 115.05819 -378.717048)
			(xy 115.05819 -378.004832) (xy 115.057798 -377.996386) (xy 115.05223 -377.980435) (xy 115.047268 -377.97359)
			(xy 115.030304 -377.951093) (xy 115.002481 -377.902099) (xy 114.982165 -377.849547) (xy 114.969797 -377.794579)
			(xy 114.965645 -377.738389) (xy 114.9698 -377.6822) (xy 114.982172 -377.627232) (xy 115.002491 -377.574681)
			(xy 115.030316 -377.525688) (xy 115.047268 -377.503182) (xy 115.052257 -377.496353) (xy 115.057821 -377.480391)
			(xy 115.05819 -377.47194) (xy 115.05819 -376.46483) (xy 115.057939 -376.457417) (xy 115.053681 -376.443215)
			(xy 115.049808 -376.43689) (xy 115.036051 -376.415039) (xy 115.014304 -376.368209) (xy 114.999552 -376.318728)
			(xy 114.992103 -376.267635) (xy 114.991642 -376.241818) (xy 114.992102 -376.216316) (xy 114.99937 -376.165831)
			(xy 115.00612 -376.141234) (xy 115.008361 -376.132365) (xy 115.007064 -376.114132) (xy 115.00358 -376.105674)
			(xy 114.986116 -376.066516) (xy 114.957173 -375.985802) (xy 114.935263 -375.902903) (xy 114.920548 -375.818428)
			(xy 114.913136 -375.733003) (xy 114.912648 -375.69013) (xy 114.912648 -375.308114) (xy 114.913123 -375.265125)
			(xy 114.920569 -375.179469) (xy 114.935356 -375.094771) (xy 114.945922 -375.053098) (xy 114.947405 -375.046703)
			(xy 114.947416 -375.033581) (xy 114.945922 -375.02719) (xy 114.935346 -374.985519) (xy 114.92056 -374.900821)
			(xy 114.913123 -374.815164) (xy 114.912648 -374.772174) (xy 114.912648 -374.390158) (xy 114.913261 -374.34107)
			(xy 114.922955 -374.243374) (xy 114.942195 -374.147102) (xy 114.970796 -374.053185) (xy 114.989102 -374.007634)
			(xy 114.99242 -373.998686) (xy 114.992822 -373.979622) (xy 114.989864 -373.97055) (xy 114.978856 -373.938645)
			(xy 114.966968 -373.872213) (xy 114.966242 -373.83847) (xy 114.966652 -373.81312) (xy 114.973354 -373.762865)
			(xy 114.986648 -373.71394) (xy 115.006302 -373.667205) (xy 115.031969 -373.623482) (xy 115.047268 -373.603266)
			(xy 115.052269 -373.59644) (xy 115.05786 -373.580479) (xy 115.05819 -373.572024) (xy 115.05819 -372.564914)
			(xy 115.057937 -372.557502) (xy 115.053675 -372.543303) (xy 115.049808 -372.536974) (xy 115.036052 -372.515122)
			(xy 115.014306 -372.468291) (xy 114.999551 -372.418811) (xy 114.992095 -372.367718) (xy 114.992095 -372.316085)
			(xy 114.99955 -372.264992) (xy 115.014305 -372.215512) (xy 115.03605 -372.168681) (xy 115.049808 -372.14683)
			(xy 115.053666 -372.140499) (xy 115.057912 -372.1263) (xy 115.05819 -372.11889) (xy 115.05819 -371.567202)
			(xy 115.058612 -371.557131) (xy 115.066325 -371.538525) (xy 115.073176 -371.531134) (xy 115.485418 -371.118892)
			(xy 115.492272 -371.111497) (xy 115.500016 -371.092898) (xy 115.500404 -371.082824) (xy 115.500404 -370.765324)
			(xy 115.500207 -370.758452) (xy 115.496593 -370.745194) (xy 115.493292 -370.739162) (xy 115.476972 -370.7108)
			(xy 115.451259 -370.650629) (xy 115.433854 -370.587551) (xy 115.425072 -370.522707) (xy 115.425074 -370.457272)
			(xy 115.433858 -370.392429) (xy 115.451265 -370.329352) (xy 115.476981 -370.269181) (xy 115.493292 -370.240814)
			(xy 115.496598 -370.234787) (xy 115.500193 -370.221524) (xy 115.500404 -370.214652) (xy 115.500404 -369.928902)
			(xy 115.500898 -369.918741) (xy 115.508671 -369.899966) (xy 115.523035 -369.885592) (xy 115.541806 -369.877806)
			(xy 115.551966 -369.87734) (xy 115.724178 -369.87734) (xy 115.735176 -369.876731) (xy 115.755118 -369.867432)
			(xy 115.769387 -369.850682) (xy 115.772946 -369.840256) (xy 116.228876 -368.224562) (xy 116.241769 -368.180709)
			(xy 116.274508 -368.095359) (xy 116.314911 -368.01336) (xy 116.33835 -367.974118) (xy 116.40312 -367.868454)
			(xy 116.406628 -367.86235) (xy 116.410503 -367.84882) (xy 116.41074 -367.841784) (xy 116.41074 -337.350608)
			(xy 116.411163 -337.340538) (xy 116.41888 -337.321935) (xy 116.425726 -337.31454) (xy 122.503184 -331.237082)
			(xy 122.509866 -331.229681) (xy 122.517464 -331.211269) (xy 122.517468 -331.19135) (xy 122.514106 -331.181964)
			(xy 122.508264 -331.167486) (xy 122.48261 -331.150468) (xy 117.5258 -331.150468) (xy 117.51579 -331.150956)
			(xy 117.497293 -331.158614) (xy 117.483132 -331.172766) (xy 117.475462 -331.191258) (xy 117.475 -331.201268)
			(xy 117.475 -332.896718) (xy 117.474573 -332.906787) (xy 117.466854 -332.925386) (xy 117.460014 -332.932786)
			(xy 116.118386 -334.274414) (xy 116.111532 -334.281809) (xy 116.10379 -334.300408) (xy 116.1034 -334.310482)
			(xy 116.1034 -334.979518) (xy 116.102973 -334.989587) (xy 116.095254 -335.008186) (xy 116.088414 -335.015586)
			(xy 111.292386 -339.811614) (xy 111.284991 -339.818468) (xy 111.266392 -339.82621) (xy 111.256318 -339.8266)
			(xy 108.733082 -339.8266) (xy 108.723013 -339.827027) (xy 108.704414 -339.834746) (xy 108.697014 -339.841586)
			(xy 106.071828 -342.466772) (xy 111.4808 -342.466772) (xy 111.4808 -342.412228) (xy 111.488562 -342.358241)
			(xy 111.503929 -342.305907) (xy 111.526587 -342.256293) (xy 111.556075 -342.210409) (xy 111.591794 -342.169188)
			(xy 111.633015 -342.133471) (xy 111.6789 -342.103983) (xy 111.728515 -342.081326) (xy 111.780848 -342.06596)
			(xy 111.834836 -342.058199) (xy 111.862108 -342.057736) (xy 112.725708 -342.057736) (xy 112.752977 -342.058227)
			(xy 112.806959 -342.06599) (xy 112.859288 -342.081355) (xy 112.908897 -342.104012) (xy 112.954776 -342.133498)
			(xy 112.995993 -342.169213) (xy 113.031707 -342.21043) (xy 113.061192 -342.256311) (xy 113.083847 -342.30592)
			(xy 113.099212 -342.358249) (xy 113.106974 -342.412231) (xy 113.106974 -342.466768) (xy 114.589822 -342.466768)
			(xy 114.589822 -342.412232) (xy 114.597583 -342.358251) (xy 114.612947 -342.305924) (xy 114.635601 -342.256315)
			(xy 114.665084 -342.210436) (xy 114.700796 -342.169219) (xy 114.74201 -342.133503) (xy 114.787887 -342.104016)
			(xy 114.837494 -342.081358) (xy 114.88982 -342.06599) (xy 114.9438 -342.058225) (xy 114.971068 -342.057736)
			(xy 115.834668 -342.057736) (xy 115.86194 -342.058201) (xy 115.91593 -342.06596) (xy 115.968267 -342.081323)
			(xy 116.017884 -342.103979) (xy 116.063771 -342.133465) (xy 116.104995 -342.169183) (xy 116.140715 -342.210403)
			(xy 116.170206 -342.256288) (xy 116.192866 -342.305903) (xy 116.208233 -342.358238) (xy 116.215996 -342.412228)
			(xy 116.215996 -342.466772) (xy 116.208233 -342.520762) (xy 116.192866 -342.573097) (xy 116.170206 -342.622712)
			(xy 116.140715 -342.668597) (xy 116.104995 -342.709817) (xy 116.063771 -342.745535) (xy 116.017884 -342.775021)
			(xy 115.968267 -342.797677) (xy 115.91593 -342.81304) (xy 115.86194 -342.820799) (xy 115.834668 -342.82126)
			(xy 114.971068 -342.82126) (xy 114.9438 -342.820775) (xy 114.88982 -342.81301) (xy 114.837494 -342.797642)
			(xy 114.787887 -342.774984) (xy 114.74201 -342.745497) (xy 114.700796 -342.709781) (xy 114.665084 -342.668564)
			(xy 114.635601 -342.622685) (xy 114.612947 -342.573076) (xy 114.597583 -342.520749) (xy 114.589822 -342.466768)
			(xy 113.106974 -342.466768) (xy 113.106974 -342.466769) (xy 113.099212 -342.520751) (xy 113.083847 -342.57308)
			(xy 113.061192 -342.622689) (xy 113.031707 -342.66857) (xy 112.995993 -342.709787) (xy 112.954776 -342.745502)
			(xy 112.908897 -342.774988) (xy 112.859288 -342.797645) (xy 112.806959 -342.81301) (xy 112.752977 -342.820773)
			(xy 112.725708 -342.82126) (xy 111.862108 -342.82126) (xy 111.834836 -342.820801) (xy 111.780848 -342.81304)
			(xy 111.728515 -342.797674) (xy 111.6789 -342.775017) (xy 111.633015 -342.745529) (xy 111.591794 -342.709812)
			(xy 111.556075 -342.668591) (xy 111.526587 -342.622707) (xy 111.503929 -342.573093) (xy 111.488562 -342.520759)
			(xy 111.4808 -342.466772) (xy 106.071828 -342.466772) (xy 105.907586 -342.631014) (xy 105.900732 -342.638409)
			(xy 105.89299 -342.657008) (xy 105.8926 -342.667082) (xy 105.8926 -344.021918) (xy 105.892173 -344.031987)
			(xy 105.884454 -344.050586) (xy 105.877614 -344.057986) (xy 104.706674 -345.228926) (xy 105.613452 -345.228926)
			(xy 105.617523 -345.173304) (xy 105.629649 -345.118867) (xy 105.649572 -345.066776) (xy 105.676868 -345.018141)
			(xy 105.710954 -344.973998) (xy 105.751103 -344.935289) (xy 105.796461 -344.902838) (xy 105.846061 -344.877337)
			(xy 105.898845 -344.85933) (xy 105.953688 -344.8492) (xy 106.009422 -344.847163) (xy 106.064859 -344.853263)
			(xy 106.118816 -344.867369) (xy 106.170145 -344.889181) (xy 106.217751 -344.918235) (xy 106.260619 -344.95391)
			(xy 106.297836 -344.995447) (xy 106.328609 -345.04196) (xy 106.352281 -345.092457) (xy 106.368349 -345.145864)
			(xy 106.376469 -345.20104) (xy 106.376978 -345.228926) (xy 106.376469 -345.256812) (xy 106.368349 -345.311988)
			(xy 106.352281 -345.365395) (xy 106.328609 -345.415892) (xy 106.297836 -345.462405) (xy 106.260619 -345.503942)
			(xy 106.217751 -345.539617) (xy 106.174964 -345.56573) (xy 107.785662 -345.56573) (xy 107.786148 -345.539579)
			(xy 107.793301 -345.487769) (xy 107.807463 -345.437422) (xy 107.828368 -345.38948) (xy 107.855624 -345.344842)
			(xy 107.888722 -345.304345) (xy 107.927041 -345.268749) (xy 107.969862 -345.238719) (xy 107.992926 -345.226386)
			(xy 108.004967 -345.21971) (xy 108.025252 -345.201113) (xy 108.039828 -345.177771) (xy 108.047635 -345.151382)
			(xy 108.048105 -345.123867) (xy 108.041203 -345.097227) (xy 108.027431 -345.073401) (xy 108.007792 -345.054123)
			(xy 107.995974 -345.047062) (xy 107.970936 -345.032486) (xy 107.925169 -344.996967) (xy 107.885299 -344.954935)
			(xy 107.852244 -344.907358) (xy 107.826763 -344.85533) (xy 107.809442 -344.800047) (xy 107.800679 -344.74278)
			(xy 107.80014 -344.713814) (xy 107.800626 -344.686563) (xy 107.808382 -344.632615) (xy 107.823737 -344.58032)
			(xy 107.846379 -344.530743) (xy 107.875845 -344.484893) (xy 107.911536 -344.443702) (xy 107.952727 -344.408011)
			(xy 107.998577 -344.378545) (xy 108.048154 -344.355903) (xy 108.100449 -344.340548) (xy 108.154397 -344.332792)
			(xy 108.208899 -344.332792) (xy 108.262847 -344.340548) (xy 108.315142 -344.355903) (xy 108.364719 -344.378545)
			(xy 108.410569 -344.408011) (xy 108.45176 -344.443702) (xy 108.487451 -344.484893) (xy 108.516917 -344.530743)
			(xy 108.539559 -344.58032) (xy 108.554914 -344.632615) (xy 108.56267 -344.686563) (xy 108.563156 -344.713814)
			(xy 108.562696 -344.739965) (xy 108.555538 -344.791776) (xy 108.541371 -344.842124) (xy 108.520462 -344.890066)
			(xy 108.493202 -344.934703) (xy 108.460101 -344.975199) (xy 108.42178 -345.010796) (xy 108.378957 -345.040825)
			(xy 108.355892 -345.053158) (xy 108.343811 -345.059769) (xy 108.323518 -345.078376) (xy 108.308939 -345.10173)
			(xy 108.301132 -345.128132) (xy 108.300668 -345.155659) (xy 108.30758 -345.182309) (xy 108.321364 -345.206141)
			(xy 108.341018 -345.225421) (xy 108.352844 -345.232482) (xy 108.377882 -345.247058) (xy 108.423653 -345.282574)
			(xy 108.463526 -345.324604) (xy 108.496584 -345.372181) (xy 108.522065 -345.42421) (xy 108.539383 -345.479495)
			(xy 108.541352 -345.492368) (xy 111.480847 -345.492368) (xy 111.480847 -345.437832) (xy 111.488609 -345.383851)
			(xy 111.503974 -345.331524) (xy 111.526629 -345.281916) (xy 111.556114 -345.236038) (xy 111.591828 -345.194822)
			(xy 111.633044 -345.159109) (xy 111.678923 -345.129625) (xy 111.728531 -345.106971) (xy 111.780859 -345.091607)
			(xy 111.83484 -345.083847) (xy 111.862108 -345.083384) (xy 112.725708 -345.083384) (xy 112.75298 -345.083779)
			(xy 112.80697 -345.091543) (xy 112.859304 -345.106911) (xy 112.90892 -345.12957) (xy 112.954805 -345.15906)
			(xy 112.996027 -345.194779) (xy 113.031745 -345.236001) (xy 113.061234 -345.281888) (xy 113.083892 -345.331503)
			(xy 113.099259 -345.383838) (xy 113.107021 -345.437828) (xy 113.107021 -345.492365) (xy 114.58987 -345.492365)
			(xy 114.58987 -345.437835) (xy 114.59763 -345.383861) (xy 114.612992 -345.33154) (xy 114.635643 -345.281938)
			(xy 114.665122 -345.236064) (xy 114.70083 -345.194853) (xy 114.742039 -345.159142) (xy 114.78791 -345.129658)
			(xy 114.83751 -345.107003) (xy 114.88983 -345.091637) (xy 114.943803 -345.083872) (xy 114.971068 -345.083384)
			(xy 115.834668 -345.083384) (xy 115.861944 -345.083753) (xy 115.915941 -345.091513) (xy 115.968283 -345.106878)
			(xy 116.017907 -345.129537) (xy 116.0638 -345.159027) (xy 116.105029 -345.194749) (xy 116.140754 -345.235975)
			(xy 116.170248 -345.281865) (xy 116.192911 -345.331487) (xy 116.20828 -345.383828) (xy 116.216044 -345.437824)
			(xy 116.216044 -345.492376) (xy 116.20828 -345.546372) (xy 116.192911 -345.598713) (xy 116.170248 -345.648335)
			(xy 116.140754 -345.694225) (xy 116.105029 -345.735451) (xy 116.0638 -345.771173) (xy 116.017907 -345.800663)
			(xy 115.968283 -345.823322) (xy 115.915941 -345.838687) (xy 115.861944 -345.846447) (xy 115.834668 -345.846908)
			(xy 114.971068 -345.846908) (xy 114.943803 -345.846328) (xy 114.88983 -345.838563) (xy 114.83751 -345.823197)
			(xy 114.78791 -345.800542) (xy 114.742039 -345.771058) (xy 114.70083 -345.735347) (xy 114.665122 -345.694136)
			(xy 114.635643 -345.648262) (xy 114.612992 -345.59866) (xy 114.59763 -345.546339) (xy 114.58987 -345.492365)
			(xy 113.107021 -345.492365) (xy 113.107021 -345.492372) (xy 113.099259 -345.546362) (xy 113.083892 -345.598697)
			(xy 113.061234 -345.648312) (xy 113.031745 -345.694199) (xy 112.996027 -345.735421) (xy 112.954805 -345.77114)
			(xy 112.90892 -345.80063) (xy 112.859304 -345.82329) (xy 112.80697 -345.838657) (xy 112.75298 -345.846421)
			(xy 112.725708 -345.846908) (xy 111.862108 -345.846908) (xy 111.83484 -345.846353) (xy 111.780859 -345.838593)
			(xy 111.728531 -345.823229) (xy 111.678923 -345.800575) (xy 111.633044 -345.771091) (xy 111.591828 -345.735378)
			(xy 111.556114 -345.694162) (xy 111.526629 -345.648284) (xy 111.503974 -345.598676) (xy 111.488609 -345.546349)
			(xy 111.480847 -345.492368) (xy 108.541352 -345.492368) (xy 108.548141 -345.536763) (xy 108.548678 -345.56573)
			(xy 108.548192 -345.592981) (xy 108.540436 -345.646929) (xy 108.525081 -345.699224) (xy 108.502439 -345.748801)
			(xy 108.472973 -345.794651) (xy 108.437282 -345.835842) (xy 108.396091 -345.871533) (xy 108.350241 -345.900999)
			(xy 108.300664 -345.923641) (xy 108.248369 -345.938996) (xy 108.194421 -345.946752) (xy 108.139919 -345.946752)
			(xy 108.085971 -345.938996) (xy 108.033676 -345.923641) (xy 107.984099 -345.900999) (xy 107.938249 -345.871533)
			(xy 107.897058 -345.835842) (xy 107.861367 -345.794651) (xy 107.831901 -345.748801) (xy 107.809259 -345.699224)
			(xy 107.793904 -345.646929) (xy 107.786148 -345.592981) (xy 107.785662 -345.56573) (xy 106.174964 -345.56573)
			(xy 106.170145 -345.568671) (xy 106.118816 -345.590483) (xy 106.064859 -345.604589) (xy 106.009422 -345.610689)
			(xy 105.953688 -345.608652) (xy 105.898845 -345.598522) (xy 105.846061 -345.580515) (xy 105.796461 -345.555014)
			(xy 105.751103 -345.522563) (xy 105.710954 -345.483854) (xy 105.676868 -345.439711) (xy 105.649572 -345.391076)
			(xy 105.629649 -345.338985) (xy 105.617523 -345.284548) (xy 105.613452 -345.228926) (xy 104.706674 -345.228926)
			(xy 104.586786 -345.348814) (xy 104.579391 -345.355668) (xy 104.560792 -345.36341) (xy 104.550718 -345.3638)
			(xy 104.091486 -345.3638) (xy 104.082293 -345.364186) (xy 104.065098 -345.370696) (xy 104.057958 -345.3765)
			(xy 104.030949 -345.399439) (xy 103.972423 -345.439394) (xy 103.909541 -345.472066) (xy 103.843204 -345.496989)
			(xy 103.774364 -345.513804) (xy 103.704008 -345.522271) (xy 103.668576 -345.522804) (xy 101.563678 -345.522804)
			(xy 101.55361 -345.523231) (xy 101.535011 -345.530952) (xy 101.52761 -345.53779) (xy 100.603558 -346.461842)
			(xy 107.639864 -346.461842) (xy 107.643935 -346.40622) (xy 107.656061 -346.351783) (xy 107.675984 -346.299692)
			(xy 107.70328 -346.251057) (xy 107.737366 -346.206914) (xy 107.777515 -346.168205) (xy 107.822873 -346.135754)
			(xy 107.872473 -346.110253) (xy 107.925257 -346.092246) (xy 107.9801 -346.082116) (xy 108.035834 -346.080079)
			(xy 108.091271 -346.086179) (xy 108.145228 -346.100285) (xy 108.196557 -346.122097) (xy 108.244163 -346.151151)
			(xy 108.287031 -346.186826) (xy 108.324248 -346.228363) (xy 108.355021 -346.274876) (xy 108.378693 -346.325373)
			(xy 108.394761 -346.37878) (xy 108.402881 -346.433956) (xy 108.40339 -346.461842) (xy 108.402881 -346.489728)
			(xy 108.394761 -346.544904) (xy 108.378693 -346.598311) (xy 108.355021 -346.648808) (xy 108.324248 -346.695321)
			(xy 108.287031 -346.736858) (xy 108.244163 -346.772533) (xy 108.196557 -346.801587) (xy 108.145228 -346.823399)
			(xy 108.091271 -346.837505) (xy 108.035834 -346.843605) (xy 107.9801 -346.841568) (xy 107.925257 -346.831438)
			(xy 107.872473 -346.813431) (xy 107.822873 -346.78793) (xy 107.777515 -346.755479) (xy 107.737366 -346.71677)
			(xy 107.70328 -346.672627) (xy 107.675984 -346.623992) (xy 107.656061 -346.571901) (xy 107.643935 -346.517464)
			(xy 107.639864 -346.461842) (xy 100.603558 -346.461842) (xy 99.718876 -347.346524) (xy 99.71303 -347.352768)
			(xy 99.705538 -347.368132) (xy 99.703566 -347.385112) (xy 99.70516 -347.393514) (xy 99.723956 -347.47708)
			(xy 99.726126 -347.485382) (xy 99.735152 -347.499962) (xy 99.748499 -347.510728) (xy 99.756468 -347.51391)
			(xy 99.783797 -347.524343) (xy 99.835167 -347.552321) (xy 99.881669 -347.587806) (xy 99.922216 -347.629968)
			(xy 99.955858 -347.67782) (xy 99.981809 -347.730244) (xy 99.999461 -347.786011) (xy 100.008403 -347.843819)
			(xy 100.008944 -347.873066) (xy 100.008461 -347.90032) (xy 100.000708 -347.954273) (xy 99.985356 -348.006574)
			(xy 99.962718 -348.056158) (xy 99.933253 -348.102015) (xy 99.897562 -348.143212) (xy 99.856371 -348.178911)
			(xy 99.810519 -348.208384) (xy 99.76094 -348.231032) (xy 99.708642 -348.246393) (xy 99.65469 -348.254156)
			(xy 99.627436 -348.254574) (xy 99.600533 -348.254116) (xy 99.547259 -348.246562) (xy 99.495575 -348.231599)
			(xy 99.446505 -348.209523) (xy 99.401023 -348.180774) (xy 99.360031 -348.145919) (xy 99.324342 -348.105652)
			(xy 99.294664 -348.060771) (xy 99.282758 -348.036642) (xy 99.277424 -348.025466) (xy 99.25812 -348.010734)
			(xy 99.152202 -347.991684) (xy 99.128834 -347.99905) (xy 99.120198 -348.007432) (xy 99.099673 -348.02675)
			(xy 99.053983 -348.059753) (xy 99.003941 -348.08569) (xy 98.97745 -348.095316) (xy 98.966274 -348.099126)
			(xy 98.846386 -348.219014) (xy 98.839532 -348.226409) (xy 98.83179 -348.245008) (xy 98.8314 -348.255082)
			(xy 98.8314 -348.406551) (xy 105.290366 -348.406551) (xy 105.290366 -348.352049) (xy 105.298122 -348.298103)
			(xy 105.313475 -348.245809) (xy 105.336115 -348.196233) (xy 105.365579 -348.150383) (xy 105.401268 -348.109192)
			(xy 105.442455 -348.073499) (xy 105.488303 -348.044031) (xy 105.537877 -348.021387) (xy 105.59017 -348.006029)
			(xy 105.644115 -347.998268) (xy 105.671366 -347.99778) (xy 105.700106 -347.998269) (xy 105.756935 -348.006901)
			(xy 105.811826 -348.023959) (xy 105.863537 -348.049058) (xy 105.910898 -348.08163) (xy 105.932224 -348.100904)
			(xy 105.93945 -348.107046) (xy 105.957045 -348.114079) (xy 105.966514 -348.11462) (xy 106.045254 -348.115128)
			(xy 106.063034 -348.10827) (xy 106.069892 -348.102174) (xy 106.0704 -348.101666) (xy 106.091557 -348.08308)
			(xy 106.138336 -348.051728) (xy 106.189214 -348.027589) (xy 106.243086 -348.011186) (xy 106.298783 -348.002875)
			(xy 106.32694 -348.002352) (xy 106.354186 -348.002921) (xy 106.408124 -348.010681) (xy 106.460409 -348.026038)
			(xy 106.509976 -348.048679) (xy 106.555816 -348.078143) (xy 106.596997 -348.113831) (xy 106.632681 -348.155016)
			(xy 106.66214 -348.20086) (xy 106.684776 -348.250429) (xy 106.700127 -348.302715) (xy 106.707882 -348.356653)
			(xy 106.707882 -348.411147) (xy 106.700127 -348.465085) (xy 106.684776 -348.517371) (xy 106.66214 -348.56694)
			(xy 106.632681 -348.612784) (xy 106.632431 -348.613072) (xy 111.480792 -348.613072) (xy 111.480792 -348.558528)
			(xy 111.488554 -348.504539) (xy 111.503921 -348.452204) (xy 111.52658 -348.402589) (xy 111.556069 -348.356704)
			(xy 111.591788 -348.315483) (xy 111.63301 -348.279764) (xy 111.678896 -348.250276) (xy 111.728512 -348.227618)
			(xy 111.780847 -348.212252) (xy 111.834836 -348.204491) (xy 111.862108 -348.204028) (xy 112.725708 -348.204028)
			(xy 112.752976 -348.204535) (xy 112.806958 -348.212297) (xy 112.859285 -348.227663) (xy 112.908893 -348.250319)
			(xy 112.954771 -348.279804) (xy 112.995987 -348.315519) (xy 113.0317 -348.356735) (xy 113.061185 -348.402614)
			(xy 113.08384 -348.452223) (xy 113.099204 -348.50455) (xy 113.106966 -348.558532) (xy 113.106966 -348.613068)
			(xy 113.106966 -348.613069) (xy 114.589814 -348.613069) (xy 114.589814 -348.558531) (xy 114.597575 -348.504549)
			(xy 114.61294 -348.452221) (xy 114.635594 -348.402611) (xy 114.665078 -348.356731) (xy 114.70079 -348.315513)
			(xy 114.742005 -348.279797) (xy 114.787883 -348.250309) (xy 114.837491 -348.227651) (xy 114.889818 -348.212282)
			(xy 114.943799 -348.204517) (xy 114.971068 -348.204028) (xy 115.834668 -348.204028) (xy 115.86194 -348.204509)
			(xy 115.915929 -348.212268) (xy 115.968264 -348.227631) (xy 116.01788 -348.250286) (xy 116.063766 -348.279772)
			(xy 116.104989 -348.315488) (xy 116.140709 -348.356708) (xy 116.170199 -348.402592) (xy 116.192858 -348.452206)
			(xy 116.208226 -348.50454) (xy 116.215988 -348.558528) (xy 116.215988 -348.613072) (xy 116.208226 -348.66706)
			(xy 116.192858 -348.719394) (xy 116.170199 -348.769008) (xy 116.140709 -348.814892) (xy 116.104989 -348.856112)
			(xy 116.063766 -348.891828) (xy 116.01788 -348.921314) (xy 115.968264 -348.943969) (xy 115.915929 -348.959332)
			(xy 115.86194 -348.967091) (xy 115.834668 -348.967552) (xy 114.971068 -348.967552) (xy 114.943799 -348.967083)
			(xy 114.889818 -348.959318) (xy 114.837491 -348.943949) (xy 114.787883 -348.921291) (xy 114.742005 -348.891803)
			(xy 114.70079 -348.856087) (xy 114.665078 -348.814869) (xy 114.635594 -348.768989) (xy 114.61294 -348.719379)
			(xy 114.597575 -348.667051) (xy 114.589814 -348.613069) (xy 113.106966 -348.613069) (xy 113.099204 -348.66705)
			(xy 113.08384 -348.719377) (xy 113.061185 -348.768986) (xy 113.0317 -348.814865) (xy 112.995987 -348.856081)
			(xy 112.954771 -348.891796) (xy 112.908893 -348.921281) (xy 112.859285 -348.943937) (xy 112.806958 -348.959303)
			(xy 112.752976 -348.967065) (xy 112.725708 -348.967552) (xy 111.862108 -348.967552) (xy 111.834836 -348.967109)
			(xy 111.780847 -348.959348) (xy 111.728512 -348.943982) (xy 111.678896 -348.921324) (xy 111.63301 -348.891836)
			(xy 111.591788 -348.856117) (xy 111.556069 -348.814896) (xy 111.52658 -348.769011) (xy 111.503921 -348.719396)
			(xy 111.488554 -348.667061) (xy 111.480792 -348.613072) (xy 106.632431 -348.613072) (xy 106.596997 -348.653969)
			(xy 106.555816 -348.689657) (xy 106.509976 -348.719121) (xy 106.460409 -348.741762) (xy 106.408124 -348.757119)
			(xy 106.354186 -348.764879) (xy 106.32694 -348.765368) (xy 106.298201 -348.764863) (xy 106.241373 -348.756233)
			(xy 106.186483 -348.739177) (xy 106.134772 -348.714082) (xy 106.087409 -348.681515) (xy 106.066082 -348.662244)
			(xy 106.058849 -348.656111) (xy 106.041259 -348.649071) (xy 106.031792 -348.648528) (xy 105.953052 -348.64802)
			(xy 105.935272 -348.654878) (xy 105.928414 -348.660974) (xy 105.927906 -348.661482) (xy 105.906753 -348.680073)
			(xy 105.859972 -348.711423) (xy 105.809093 -348.73556) (xy 105.75522 -348.751963) (xy 105.699523 -348.760274)
			(xy 105.671366 -348.760796) (xy 105.644115 -348.760332) (xy 105.59017 -348.752571) (xy 105.537877 -348.737213)
			(xy 105.488303 -348.714569) (xy 105.442455 -348.685101) (xy 105.401268 -348.649408) (xy 105.365579 -348.608217)
			(xy 105.336115 -348.562367) (xy 105.313475 -348.512791) (xy 105.298122 -348.460497) (xy 105.290366 -348.406551)
			(xy 98.8314 -348.406551) (xy 98.8314 -351.40392) (xy 99.12426 -351.40392) (xy 99.128331 -351.348298)
			(xy 99.140457 -351.293861) (xy 99.16038 -351.24177) (xy 99.187676 -351.193135) (xy 99.221762 -351.148992)
			(xy 99.261911 -351.110283) (xy 99.307269 -351.077832) (xy 99.356869 -351.052331) (xy 99.409653 -351.034324)
			(xy 99.464496 -351.024194) (xy 99.52023 -351.022157) (xy 99.575667 -351.028257) (xy 99.629624 -351.042363)
			(xy 99.680953 -351.064175) (xy 99.728559 -351.093229) (xy 99.771427 -351.128904) (xy 99.808644 -351.170441)
			(xy 99.839417 -351.216954) (xy 99.863089 -351.267451) (xy 99.879157 -351.320858) (xy 99.887277 -351.376034)
			(xy 99.887786 -351.40392) (xy 99.887277 -351.431806) (xy 99.879157 -351.486982) (xy 99.871134 -351.513648)
			(xy 106.459526 -351.513648) (xy 106.463597 -351.458026) (xy 106.475723 -351.403589) (xy 106.495646 -351.351498)
			(xy 106.522942 -351.302863) (xy 106.557028 -351.25872) (xy 106.597177 -351.220011) (xy 106.642535 -351.18756)
			(xy 106.692135 -351.162059) (xy 106.744919 -351.144052) (xy 106.799762 -351.133922) (xy 106.855496 -351.131885)
			(xy 106.910933 -351.137985) (xy 106.96489 -351.152091) (xy 107.016219 -351.173903) (xy 107.063825 -351.202957)
			(xy 107.106693 -351.238632) (xy 107.14391 -351.280169) (xy 107.174683 -351.326682) (xy 107.198355 -351.377179)
			(xy 107.214423 -351.430586) (xy 107.222543 -351.485762) (xy 107.223052 -351.513648) (xy 107.222543 -351.541534)
			(xy 107.214423 -351.59671) (xy 107.201799 -351.638669) (xy 111.480839 -351.638669) (xy 111.480839 -351.584131)
			(xy 111.488601 -351.530149) (xy 111.503966 -351.477821) (xy 111.526622 -351.428212) (xy 111.556107 -351.382333)
			(xy 111.591822 -351.341117) (xy 111.633039 -351.305403) (xy 111.678919 -351.275918) (xy 111.728529 -351.253263)
			(xy 111.780857 -351.237899) (xy 111.834839 -351.230139) (xy 111.862108 -351.229676) (xy 112.725708 -351.229676)
			(xy 112.75298 -351.230087) (xy 112.806968 -351.23785) (xy 112.859302 -351.253218) (xy 112.908916 -351.275877)
			(xy 112.9548 -351.305366) (xy 112.996021 -351.341085) (xy 113.031739 -351.382306) (xy 113.061227 -351.428191)
			(xy 113.083885 -351.477806) (xy 113.099251 -351.53014) (xy 113.107014 -351.584128) (xy 113.107014 -351.638665)
			(xy 114.589862 -351.638665) (xy 114.589862 -351.584135) (xy 114.597622 -351.530159) (xy 114.612984 -351.477838)
			(xy 114.635636 -351.428234) (xy 114.665116 -351.38236) (xy 114.700824 -351.341147) (xy 114.742034 -351.305435)
			(xy 114.787906 -351.275951) (xy 114.837508 -351.253296) (xy 114.889828 -351.237929) (xy 114.943803 -351.230165)
			(xy 114.971068 -351.229676) (xy 115.834668 -351.229676) (xy 115.861943 -351.230061) (xy 115.915939 -351.237821)
			(xy 115.968281 -351.253186) (xy 116.017903 -351.275844) (xy 116.063795 -351.305333) (xy 116.105023 -351.341054)
			(xy 116.140747 -351.382279) (xy 116.170241 -351.428169) (xy 116.192903 -351.477789) (xy 116.208273 -351.53013)
			(xy 116.216036 -351.584125) (xy 116.216036 -351.638675) (xy 116.208273 -351.69267) (xy 116.192903 -351.745011)
			(xy 116.170241 -351.794631) (xy 116.140747 -351.840521) (xy 116.105023 -351.881746) (xy 116.063795 -351.917467)
			(xy 116.017903 -351.946956) (xy 115.968281 -351.969614) (xy 115.915939 -351.984979) (xy 115.861943 -351.992739)
			(xy 115.834668 -351.9932) (xy 114.971068 -351.9932) (xy 114.943803 -351.992635) (xy 114.889828 -351.984871)
			(xy 114.837508 -351.969504) (xy 114.787906 -351.946849) (xy 114.742034 -351.917365) (xy 114.700824 -351.881653)
			(xy 114.665116 -351.84044) (xy 114.635636 -351.794566) (xy 114.612984 -351.744962) (xy 114.597622 -351.692641)
			(xy 114.589862 -351.638665) (xy 113.107014 -351.638665) (xy 113.107014 -351.638672) (xy 113.099251 -351.69266)
			(xy 113.083885 -351.744994) (xy 113.061227 -351.794609) (xy 113.031739 -351.840494) (xy 112.996021 -351.881715)
			(xy 112.9548 -351.917434) (xy 112.908916 -351.946923) (xy 112.859302 -351.969582) (xy 112.806968 -351.98495)
			(xy 112.75298 -351.992713) (xy 112.725708 -351.9932) (xy 111.862108 -351.9932) (xy 111.834839 -351.992661)
			(xy 111.780857 -351.984901) (xy 111.728529 -351.969537) (xy 111.678919 -351.946882) (xy 111.633039 -351.917397)
			(xy 111.591822 -351.881683) (xy 111.556107 -351.840467) (xy 111.526622 -351.794588) (xy 111.503966 -351.744979)
			(xy 111.488601 -351.692651) (xy 111.480839 -351.638669) (xy 107.201799 -351.638669) (xy 107.198355 -351.650117)
			(xy 107.174683 -351.700614) (xy 107.14391 -351.747127) (xy 107.106693 -351.788664) (xy 107.063825 -351.824339)
			(xy 107.016219 -351.853393) (xy 106.96489 -351.875205) (xy 106.910933 -351.889311) (xy 106.855496 -351.895411)
			(xy 106.799762 -351.893374) (xy 106.744919 -351.883244) (xy 106.692135 -351.865237) (xy 106.642535 -351.839736)
			(xy 106.597177 -351.807285) (xy 106.557028 -351.768576) (xy 106.522942 -351.724433) (xy 106.495646 -351.675798)
			(xy 106.475723 -351.623707) (xy 106.463597 -351.56927) (xy 106.459526 -351.513648) (xy 99.871134 -351.513648)
			(xy 99.863089 -351.540389) (xy 99.839417 -351.590886) (xy 99.808644 -351.637399) (xy 99.771427 -351.678936)
			(xy 99.728559 -351.714611) (xy 99.680953 -351.743665) (xy 99.629624 -351.765477) (xy 99.575667 -351.779583)
			(xy 99.52023 -351.785683) (xy 99.464496 -351.783646) (xy 99.409653 -351.773516) (xy 99.356869 -351.755509)
			(xy 99.307269 -351.730008) (xy 99.261911 -351.697557) (xy 99.221762 -351.658848) (xy 99.187676 -351.614705)
			(xy 99.16038 -351.56607) (xy 99.140457 -351.513979) (xy 99.128331 -351.459542) (xy 99.12426 -351.40392)
			(xy 98.8314 -351.40392) (xy 98.8314 -353.26955) (xy 98.831897 -353.279551) (xy 98.839565 -353.298026)
			(xy 98.853716 -353.312163) (xy 98.872199 -353.319813) (xy 98.8822 -353.32035) (xy 99.080574 -353.32035)
			(xy 99.093052 -353.319771) (xy 99.115143 -353.308172) (xy 99.122738 -353.298252) (xy 99.169982 -353.228656)
			(xy 99.176289 -353.218011) (xy 99.179058 -353.193463) (xy 99.175316 -353.181666) (xy 99.166972 -353.159418)
			(xy 99.155231 -353.113375) (xy 99.149292 -353.066232) (xy 99.1489 -353.042474) (xy 99.149386 -353.015223)
			(xy 99.157142 -352.961275) (xy 99.172497 -352.90898) (xy 99.195139 -352.859403) (xy 99.224605 -352.813553)
			(xy 99.260296 -352.772362) (xy 99.301487 -352.736671) (xy 99.347337 -352.707205) (xy 99.396914 -352.684563)
			(xy 99.449209 -352.669208) (xy 99.503157 -352.661452) (xy 99.557659 -352.661452) (xy 99.611607 -352.669208)
			(xy 99.663902 -352.684563) (xy 99.713479 -352.707205) (xy 99.759329 -352.736671) (xy 99.80052 -352.772362)
			(xy 99.836211 -352.813553) (xy 99.865677 -352.859403) (xy 99.888319 -352.90898) (xy 99.903674 -352.961275)
			(xy 99.91143 -353.015223) (xy 99.911916 -353.042474) (xy 99.911541 -353.066233) (xy 99.90561 -353.11338)
			(xy 99.893863 -353.159424) (xy 99.8855 -353.181666) (xy 99.880928 -353.193604) (xy 99.883722 -353.217988)
			(xy 99.938078 -353.298252) (xy 99.945655 -353.308185) (xy 99.967762 -353.319762) (xy 99.980242 -353.32035)
			(xy 100.088192 -353.32035) (xy 100.09674 -353.320025) (xy 100.112886 -353.314404) (xy 100.126283 -353.303784)
			(xy 100.131118 -353.296728) (xy 100.177092 -353.224592) (xy 100.181387 -353.217176) (xy 100.185272 -353.200495)
			(xy 100.18348 -353.183462) (xy 100.18014 -353.17557) (xy 100.168739 -353.150139) (xy 100.152668 -353.096775)
			(xy 100.144556 -353.041638) (xy 100.144072 -353.013772) (xy 100.144072 -353.013518) (xy 100.144558 -352.986267)
			(xy 100.152314 -352.932319) (xy 100.167669 -352.880024) (xy 100.190311 -352.830447) (xy 100.219777 -352.784597)
			(xy 100.255468 -352.743406) (xy 100.296659 -352.707715) (xy 100.342509 -352.678249) (xy 100.392086 -352.655607)
			(xy 100.444381 -352.640252) (xy 100.498329 -352.632496) (xy 100.552831 -352.632496) (xy 100.606779 -352.640252)
			(xy 100.659074 -352.655607) (xy 100.708651 -352.678249) (xy 100.754501 -352.707715) (xy 100.795692 -352.743406)
			(xy 100.831383 -352.784597) (xy 100.860849 -352.830447) (xy 100.883491 -352.880024) (xy 100.898846 -352.932319)
			(xy 100.906602 -352.986267) (xy 100.907088 -353.013518) (xy 100.906639 -353.040029) (xy 100.89931 -353.092541)
			(xy 100.884781 -353.143532) (xy 100.884654 -353.14382) (xy 106.532932 -353.14382) (xy 106.537003 -353.088198)
			(xy 106.549129 -353.033761) (xy 106.569052 -352.98167) (xy 106.596348 -352.933035) (xy 106.630434 -352.888892)
			(xy 106.670583 -352.850183) (xy 106.715941 -352.817732) (xy 106.765541 -352.792231) (xy 106.818325 -352.774224)
			(xy 106.873168 -352.764094) (xy 106.928902 -352.762057) (xy 106.984339 -352.768157) (xy 107.038296 -352.782263)
			(xy 107.089625 -352.804075) (xy 107.137231 -352.833129) (xy 107.180099 -352.868804) (xy 107.217316 -352.910341)
			(xy 107.248089 -352.956854) (xy 107.271761 -353.007351) (xy 107.287829 -353.060758) (xy 107.295949 -353.115934)
			(xy 107.296458 -353.14382) (xy 107.295949 -353.171706) (xy 107.287829 -353.226882) (xy 107.271761 -353.280289)
			(xy 107.248089 -353.330786) (xy 107.217316 -353.377299) (xy 107.180099 -353.418836) (xy 107.137231 -353.454511)
			(xy 107.089625 -353.483565) (xy 107.038296 -353.505377) (xy 106.984339 -353.519483) (xy 106.928902 -353.525583)
			(xy 106.873168 -353.523546) (xy 106.818325 -353.513416) (xy 106.765541 -353.495409) (xy 106.715941 -353.469908)
			(xy 106.670583 -353.437457) (xy 106.630434 -353.398748) (xy 106.596348 -353.354605) (xy 106.569052 -353.30597)
			(xy 106.549129 -353.253879) (xy 106.537003 -353.199442) (xy 106.532932 -353.14382) (xy 100.884654 -353.14382)
			(xy 100.863333 -353.192022) (xy 100.835378 -353.237075) (xy 100.801455 -353.277824) (xy 100.78212 -353.295966)
			(xy 100.7745 -353.302824) (xy 100.765864 -353.32162) (xy 100.763832 -353.405694) (xy 100.764056 -353.416091)
			(xy 100.77178 -353.435378) (xy 100.778818 -353.443032) (xy 100.952808 -353.617022) (xy 100.952808 -353.659186)
			(xy 100.947982 -353.664012) (xy 100.940362 -353.682554) (xy 100.940362 -354.136198) (xy 105.899202 -354.136198)
			(xy 105.903273 -354.080576) (xy 105.915399 -354.026139) (xy 105.935322 -353.974048) (xy 105.962618 -353.925413)
			(xy 105.996704 -353.88127) (xy 106.036853 -353.842561) (xy 106.082211 -353.81011) (xy 106.131811 -353.784609)
			(xy 106.184595 -353.766602) (xy 106.239438 -353.756472) (xy 106.295172 -353.754435) (xy 106.350609 -353.760535)
			(xy 106.404566 -353.774641) (xy 106.455895 -353.796453) (xy 106.503501 -353.825507) (xy 106.546369 -353.861182)
			(xy 106.583586 -353.902719) (xy 106.614359 -353.949232) (xy 106.638031 -353.999729) (xy 106.654099 -354.053136)
			(xy 106.662219 -354.108312) (xy 106.662728 -354.136198) (xy 106.662219 -354.164084) (xy 106.654099 -354.21926)
			(xy 106.638031 -354.272667) (xy 106.614359 -354.323164) (xy 106.583586 -354.369677) (xy 106.546369 -354.411214)
			(xy 106.503501 -354.446889) (xy 106.455895 -354.475943) (xy 106.404566 -354.497755) (xy 106.350609 -354.511861)
			(xy 106.295172 -354.517961) (xy 106.239438 -354.515924) (xy 106.184595 -354.505794) (xy 106.131811 -354.487787)
			(xy 106.082211 -354.462286) (xy 106.036853 -354.429835) (xy 105.996704 -354.391126) (xy 105.962618 -354.346983)
			(xy 105.935322 -354.298348) (xy 105.915399 -354.246257) (xy 105.903273 -354.19182) (xy 105.899202 -354.136198)
			(xy 100.940362 -354.136198) (xy 100.940362 -355.08057) (xy 100.940974 -355.092421) (xy 100.951557 -355.113627)
			(xy 100.960682 -355.12121) (xy 101.02596 -355.169724) (xy 101.035809 -355.176329) (xy 101.059115 -355.180551)
			(xy 101.070664 -355.177852) (xy 101.096931 -355.170607) (xy 101.150862 -355.162836) (xy 101.178106 -355.162358)
			(xy 101.17836 -355.162358) (xy 101.205617 -355.162818) (xy 101.259577 -355.170571) (xy 101.311885 -355.185925)
			(xy 101.361474 -355.208567) (xy 101.407337 -355.238037) (xy 101.448538 -355.273734) (xy 101.483429 -355.313996)
			(xy 106.055922 -355.313996) (xy 106.056408 -355.286745) (xy 106.064164 -355.232797) (xy 106.079519 -355.180502)
			(xy 106.102161 -355.130925) (xy 106.131627 -355.085075) (xy 106.167318 -355.043884) (xy 106.208509 -355.008193)
			(xy 106.254359 -354.978727) (xy 106.303936 -354.956085) (xy 106.356231 -354.94073) (xy 106.410179 -354.932974)
			(xy 106.464681 -354.932974) (xy 106.518629 -354.94073) (xy 106.570924 -354.956085) (xy 106.620501 -354.978727)
			(xy 106.666351 -355.008193) (xy 106.707542 -355.043884) (xy 106.743233 -355.085075) (xy 106.772699 -355.130925)
			(xy 106.795341 -355.180502) (xy 106.810696 -355.232797) (xy 106.818452 -355.286745) (xy 106.818938 -355.313996)
			(xy 106.818455 -355.342566) (xy 106.809941 -355.399069) (xy 106.793088 -355.453667) (xy 106.768274 -355.505138)
			(xy 106.736054 -355.552329) (xy 106.697152 -355.594181) (xy 106.652438 -355.629757) (xy 106.62793 -355.64445)
			(xy 106.616417 -355.651599) (xy 106.59736 -355.670853) (xy 106.58403 -355.694437) (xy 106.577363 -355.720694)
			(xy 106.577428 -355.72446) (xy 106.991658 -355.72446) (xy 106.992258 -355.695119) (xy 107.001235 -355.637129)
			(xy 107.018987 -355.581197) (xy 107.045094 -355.528644) (xy 107.078941 -355.480708) (xy 107.11973 -355.438521)
			(xy 107.166498 -355.403077) (xy 107.192064 -355.388672) (xy 107.202143 -355.382558) (xy 107.215788 -355.363374)
			(xy 107.218226 -355.351842) (xy 107.230926 -355.272086) (xy 107.232114 -355.260326) (xy 107.224966 -355.237825)
			(xy 107.21721 -355.228906) (xy 107.197458 -355.207456) (xy 107.164022 -355.159689) (xy 107.13824 -355.107392)
			(xy 107.120711 -355.051782) (xy 107.111844 -354.994153) (xy 107.111292 -354.965) (xy 107.111733 -354.93833)
			(xy 107.119151 -354.885508) (xy 107.133856 -354.834235) (xy 107.155563 -354.785511) (xy 107.183846 -354.740286)
			(xy 107.218155 -354.699444) (xy 107.257819 -354.66378) (xy 107.279694 -354.648516) (xy 107.288969 -354.64155)
			(xy 107.300474 -354.621434) (xy 107.301792 -354.609908) (xy 107.308142 -354.517706) (xy 107.299252 -354.496116)
			(xy 107.290362 -354.488242) (xy 107.270564 -354.470073) (xy 107.235771 -354.429123) (xy 107.207072 -354.383695)
			(xy 107.185034 -354.334687) (xy 107.170096 -354.28307) (xy 107.162552 -354.229867) (xy 107.162092 -354.203)
			(xy 107.162578 -354.175749) (xy 107.170334 -354.121801) (xy 107.185689 -354.069506) (xy 107.208331 -354.019929)
			(xy 107.237797 -353.974079) (xy 107.273488 -353.932888) (xy 107.314679 -353.897197) (xy 107.360529 -353.867731)
			(xy 107.410106 -353.845089) (xy 107.462401 -353.829734) (xy 107.516349 -353.821978) (xy 107.570851 -353.821978)
			(xy 107.624799 -353.829734) (xy 107.677094 -353.845089) (xy 107.726671 -353.867731) (xy 107.772521 -353.897197)
			(xy 107.813712 -353.932888) (xy 107.849403 -353.974079) (xy 107.878869 -354.019929) (xy 107.901511 -354.069506)
			(xy 107.916866 -354.121801) (xy 107.924622 -354.175749) (xy 107.925108 -354.203) (xy 107.924667 -354.22967)
			(xy 107.917249 -354.282492) (xy 107.902544 -354.333765) (xy 107.880837 -354.382489) (xy 107.852554 -354.427714)
			(xy 107.818245 -354.468556) (xy 107.778581 -354.50422) (xy 107.756706 -354.519484) (xy 107.747431 -354.52645)
			(xy 107.735926 -354.546566) (xy 107.734608 -354.558092) (xy 107.728258 -354.650294) (xy 107.737148 -354.671884)
			(xy 107.746038 -354.679758) (xy 107.765836 -354.697927) (xy 107.800629 -354.738877) (xy 107.813575 -354.759369)
			(xy 114.589806 -354.759369) (xy 114.589806 -354.704831) (xy 114.597568 -354.650847) (xy 114.612932 -354.598518)
			(xy 114.635587 -354.548908) (xy 114.665071 -354.503026) (xy 114.700785 -354.461807) (xy 114.742 -354.42609)
			(xy 114.78788 -354.396602) (xy 114.837488 -354.373943) (xy 114.889816 -354.358574) (xy 114.943799 -354.350809)
			(xy 114.971068 -354.35032) (xy 115.834668 -354.35032) (xy 115.861939 -354.350817) (xy 115.915927 -354.358575)
			(xy 115.968261 -354.373938) (xy 116.017876 -354.396593) (xy 116.063761 -354.426078) (xy 116.104983 -354.461794)
			(xy 116.140703 -354.503013) (xy 116.170192 -354.548896) (xy 116.192851 -354.598509) (xy 116.208218 -354.650842)
			(xy 116.21598 -354.704829) (xy 116.21598 -354.759371) (xy 116.208218 -354.813358) (xy 116.192851 -354.865691)
			(xy 116.170192 -354.915304) (xy 116.140703 -354.961187) (xy 116.104983 -355.002406) (xy 116.063761 -355.038122)
			(xy 116.017876 -355.067607) (xy 115.968261 -355.090262) (xy 115.915927 -355.105625) (xy 115.861939 -355.113383)
			(xy 115.834668 -355.113844) (xy 114.971068 -355.113844) (xy 114.943799 -355.113391) (xy 114.889816 -355.105626)
			(xy 114.837488 -355.090257) (xy 114.78788 -355.067598) (xy 114.742 -355.03811) (xy 114.700785 -355.002393)
			(xy 114.665071 -354.961174) (xy 114.635587 -354.915292) (xy 114.612932 -354.865682) (xy 114.597568 -354.813353)
			(xy 114.589806 -354.759369) (xy 107.813575 -354.759369) (xy 107.829328 -354.784305) (xy 107.851366 -354.833313)
			(xy 107.866304 -354.88493) (xy 107.873848 -354.938133) (xy 107.874308 -354.965) (xy 107.873774 -354.994343)
			(xy 107.864787 -355.052338) (xy 107.847025 -355.108272) (xy 107.820907 -355.160826) (xy 107.787049 -355.208761)
			(xy 107.746251 -355.250946) (xy 107.699473 -355.286385) (xy 107.673902 -355.300788) (xy 107.663795 -355.306864)
			(xy 107.650165 -355.326076) (xy 107.64774 -355.337618) (xy 107.63504 -355.417374) (xy 107.63386 -355.429134)
			(xy 107.641 -355.451636) (xy 107.648756 -355.460554) (xy 107.668531 -355.481984) (xy 107.701965 -355.529756)
			(xy 107.727743 -355.582058) (xy 107.745266 -355.637672) (xy 107.754127 -355.695305) (xy 107.754674 -355.72446)
			(xy 107.754188 -355.751711) (xy 107.746432 -355.805659) (xy 107.731077 -355.857954) (xy 107.708435 -355.907531)
			(xy 107.678969 -355.953381) (xy 107.643278 -355.994572) (xy 107.602087 -356.030263) (xy 107.556237 -356.059729)
			(xy 107.50666 -356.082371) (xy 107.454365 -356.097726) (xy 107.400417 -356.105482) (xy 107.345915 -356.105482)
			(xy 107.291967 -356.097726) (xy 107.239672 -356.082371) (xy 107.190095 -356.059729) (xy 107.144245 -356.030263)
			(xy 107.103054 -355.994572) (xy 107.067363 -355.953381) (xy 107.037897 -355.907531) (xy 107.015255 -355.857954)
			(xy 106.9999 -355.805659) (xy 106.992144 -355.751711) (xy 106.991658 -355.72446) (xy 106.577428 -355.72446)
			(xy 106.577827 -355.747781) (xy 106.585391 -355.773795) (xy 106.599522 -355.796908) (xy 106.619228 -355.815497)
			(xy 106.630978 -355.82225) (xy 106.65669 -355.836645) (xy 106.703806 -355.872029) (xy 106.744919 -355.914239)
			(xy 106.779048 -355.962272) (xy 106.805383 -356.014982) (xy 106.823295 -356.071117) (xy 106.832359 -356.129338)
			(xy 106.832908 -356.1588) (xy 106.832422 -356.186051) (xy 106.824666 -356.239999) (xy 106.809311 -356.292294)
			(xy 106.786669 -356.341871) (xy 106.757203 -356.387721) (xy 106.721512 -356.428912) (xy 106.680321 -356.464603)
			(xy 106.634471 -356.494069) (xy 106.584894 -356.516711) (xy 106.532599 -356.532066) (xy 106.478651 -356.539822)
			(xy 106.424149 -356.539822) (xy 106.370201 -356.532066) (xy 106.317906 -356.516711) (xy 106.268329 -356.494069)
			(xy 106.222479 -356.464603) (xy 106.181288 -356.428912) (xy 106.145597 -356.387721) (xy 106.116131 -356.341871)
			(xy 106.093489 -356.292294) (xy 106.078134 -356.239999) (xy 106.070378 -356.186051) (xy 106.069892 -356.1588)
			(xy 106.070357 -356.130229) (xy 106.078872 -356.073725) (xy 106.095727 -356.019125) (xy 106.120544 -355.967654)
			(xy 106.152767 -355.920463) (xy 106.191673 -355.878612) (xy 106.236391 -355.843038) (xy 106.2609 -355.828346)
			(xy 106.272424 -355.821209) (xy 106.291495 -355.801958) (xy 106.304835 -355.778371) (xy 106.311507 -355.752107)
			(xy 106.311041 -355.725013) (xy 106.303471 -355.698994) (xy 106.289329 -355.67588) (xy 106.269608 -355.657295)
			(xy 106.257852 -355.650546) (xy 106.232122 -355.636182) (xy 106.185009 -355.60079) (xy 106.1439 -355.558573)
			(xy 106.109774 -355.510535) (xy 106.083443 -355.45782) (xy 106.065533 -355.401683) (xy 106.05647 -355.343459)
			(xy 106.055922 -355.313996) (xy 101.483429 -355.313996) (xy 101.484239 -355.314931) (xy 101.513713 -355.360791)
			(xy 101.536361 -355.410378) (xy 101.55172 -355.462684) (xy 101.559479 -355.516643) (xy 101.559479 -355.571157)
			(xy 101.55172 -355.625116) (xy 101.536361 -355.677422) (xy 101.513713 -355.727009) (xy 101.484239 -355.772869)
			(xy 101.448538 -355.814066) (xy 101.407337 -355.849763) (xy 101.361474 -355.879233) (xy 101.311885 -355.901875)
			(xy 101.259577 -355.917229) (xy 101.205617 -355.924982) (xy 101.17836 -355.925374) (xy 101.150984 -355.924899)
			(xy 101.096796 -355.917063) (xy 101.044286 -355.901559) (xy 100.994532 -355.878706) (xy 100.948557 -355.848972)
			(xy 100.907308 -355.812969) (xy 100.87163 -355.771437) (xy 100.856542 -355.74859) (xy 100.856542 -355.748336)
			(xy 100.849838 -355.739134) (xy 100.830448 -355.727263) (xy 100.819204 -355.725476) (xy 100.74021 -355.716586)
			(xy 100.728799 -355.716018) (xy 100.707308 -355.72368) (xy 100.698808 -355.731318) (xy 100.51796 -355.912166)
			(xy 100.511117 -355.919565) (xy 100.503397 -355.938164) (xy 100.502974 -355.948234) (xy 100.502974 -356.221284)
			(xy 103.80167 -356.221284) (xy 103.805741 -356.165662) (xy 103.817867 -356.111225) (xy 103.83779 -356.059134)
			(xy 103.865086 -356.010499) (xy 103.899172 -355.966356) (xy 103.939321 -355.927647) (xy 103.984679 -355.895196)
			(xy 104.034279 -355.869695) (xy 104.087063 -355.851688) (xy 104.141906 -355.841558) (xy 104.19764 -355.839521)
			(xy 104.253077 -355.845621) (xy 104.307034 -355.859727) (xy 104.358363 -355.881539) (xy 104.405969 -355.910593)
			(xy 104.448837 -355.946268) (xy 104.486054 -355.987805) (xy 104.516827 -356.034318) (xy 104.540499 -356.084815)
			(xy 104.556567 -356.138222) (xy 104.564687 -356.193398) (xy 104.565196 -356.221284) (xy 104.564687 -356.24917)
			(xy 104.556567 -356.304346) (xy 104.540499 -356.357753) (xy 104.516827 -356.40825) (xy 104.486054 -356.454763)
			(xy 104.448837 -356.4963) (xy 104.405969 -356.531975) (xy 104.358363 -356.561029) (xy 104.307034 -356.582841)
			(xy 104.253077 -356.596947) (xy 104.19764 -356.603047) (xy 104.141906 -356.60101) (xy 104.087063 -356.59088)
			(xy 104.034279 -356.572873) (xy 103.984679 -356.547372) (xy 103.939321 -356.514921) (xy 103.899172 -356.476212)
			(xy 103.865086 -356.432069) (xy 103.83779 -356.383434) (xy 103.817867 -356.331343) (xy 103.805741 -356.276906)
			(xy 103.80167 -356.221284) (xy 100.502974 -356.221284) (xy 100.502974 -356.343204) (xy 100.503397 -356.353274)
			(xy 100.51111 -356.37188) (xy 100.51796 -356.379272) (xy 100.518722 -356.380034) (xy 100.526342 -356.398576)
			(xy 100.526342 -357.784966) (xy 114.589854 -357.784966) (xy 114.589854 -357.730434) (xy 114.597614 -357.676458)
			(xy 114.612977 -357.624135) (xy 114.635629 -357.574531) (xy 114.66511 -357.528655) (xy 114.700819 -357.487441)
			(xy 114.742029 -357.451729) (xy 114.787903 -357.422244) (xy 114.837505 -357.399588) (xy 114.889826 -357.384221)
			(xy 114.943802 -357.376457) (xy 114.971068 -357.375968) (xy 115.834668 -357.375968) (xy 115.861943 -357.376369)
			(xy 115.915937 -357.384128) (xy 115.968278 -357.399493) (xy 116.017899 -357.422151) (xy 116.06379 -357.45164)
			(xy 116.105017 -357.48736) (xy 116.140741 -357.528584) (xy 116.170234 -357.574473) (xy 116.192896 -357.624092)
			(xy 116.208265 -357.676431) (xy 116.216028 -357.730425) (xy 116.216028 -357.784975) (xy 116.208265 -357.838969)
			(xy 116.192896 -357.891308) (xy 116.170234 -357.940927) (xy 116.140741 -357.986816) (xy 116.105017 -358.02804)
			(xy 116.06379 -358.06376) (xy 116.017899 -358.093249) (xy 115.968278 -358.115907) (xy 115.915937 -358.131272)
			(xy 115.861943 -358.139031) (xy 115.834668 -358.139492) (xy 114.971068 -358.139492) (xy 114.943802 -358.138943)
			(xy 114.889826 -358.131179) (xy 114.837505 -358.115812) (xy 114.787903 -358.093156) (xy 114.742029 -358.063671)
			(xy 114.700819 -358.027959) (xy 114.66511 -357.986745) (xy 114.635629 -357.940869) (xy 114.612977 -357.891265)
			(xy 114.597614 -357.838942) (xy 114.589854 -357.784966) (xy 100.526342 -357.784966) (xy 100.526342 -360.017783)
			(xy 101.774757 -360.017783) (xy 101.774757 -359.957817) (xy 101.782584 -359.898365) (xy 101.798104 -359.840443)
			(xy 101.821052 -359.785042) (xy 101.851035 -359.733111) (xy 101.88754 -359.685538) (xy 101.929942 -359.643136)
			(xy 101.977516 -359.606632) (xy 102.029448 -359.57665) (xy 102.084849 -359.553703) (xy 102.142771 -359.538183)
			(xy 102.202223 -359.530357) (xy 102.232206 -359.529888) (xy 103.095806 -359.529888) (xy 103.125793 -359.530279)
			(xy 103.185255 -359.538108) (xy 103.243186 -359.553631) (xy 103.298595 -359.576583) (xy 103.350534 -359.60657)
			(xy 103.398115 -359.643081) (xy 103.440523 -359.68549) (xy 103.477033 -359.733071) (xy 103.50702 -359.785011)
			(xy 103.529971 -359.84042) (xy 103.545494 -359.898351) (xy 103.553322 -359.957813) (xy 103.553322 -360.017787)
			(xy 103.545494 -360.077249) (xy 103.529971 -360.13518) (xy 103.525241 -360.1466) (xy 106.603292 -360.1466)
			(xy 106.603805 -360.117682) (xy 106.612541 -360.060509) (xy 106.629813 -360.005313) (xy 106.655224 -359.953358)
			(xy 106.688191 -359.905838) (xy 106.707686 -359.884472) (xy 106.713736 -359.877544) (xy 106.720898 -359.860618)
			(xy 106.721656 -359.851452) (xy 106.724704 -359.775252) (xy 106.718862 -359.75798) (xy 106.71302 -359.750868)
			(xy 106.69712 -359.730454) (xy 106.670426 -359.686126) (xy 106.649966 -359.638599) (xy 106.636113 -359.588743)
			(xy 106.629123 -359.537472) (xy 106.628692 -359.5116) (xy 106.629178 -359.484349) (xy 106.636934 -359.430401)
			(xy 106.652289 -359.378106) (xy 106.674931 -359.328529) (xy 106.704397 -359.282679) (xy 106.740088 -359.241488)
			(xy 106.781279 -359.205797) (xy 106.827129 -359.176331) (xy 106.876706 -359.153689) (xy 106.929001 -359.138334)
			(xy 106.982949 -359.130578) (xy 107.037451 -359.130578) (xy 107.091399 -359.138334) (xy 107.143694 -359.153689)
			(xy 107.193271 -359.176331) (xy 107.239121 -359.205797) (xy 107.280312 -359.241488) (xy 107.316003 -359.282679)
			(xy 107.345469 -359.328529) (xy 107.368111 -359.378106) (xy 107.383466 -359.430401) (xy 107.391222 -359.484349)
			(xy 107.391708 -359.5116) (xy 107.391195 -359.540518) (xy 107.382459 -359.597691) (xy 107.365187 -359.652887)
			(xy 107.339776 -359.704842) (xy 107.306809 -359.752362) (xy 107.287314 -359.773728) (xy 107.281264 -359.780656)
			(xy 107.274102 -359.797582) (xy 107.273344 -359.806748) (xy 107.270296 -359.882948) (xy 107.276138 -359.90022)
			(xy 107.28198 -359.907332) (xy 107.29788 -359.927746) (xy 107.324574 -359.972074) (xy 107.345034 -360.019601)
			(xy 107.358887 -360.069457) (xy 107.365877 -360.120728) (xy 107.366308 -360.1466) (xy 107.365822 -360.173851)
			(xy 107.358066 -360.227799) (xy 107.342711 -360.280094) (xy 107.320069 -360.329671) (xy 107.290603 -360.375521)
			(xy 107.254912 -360.416712) (xy 107.213721 -360.452403) (xy 107.167871 -360.481869) (xy 107.118294 -360.504511)
			(xy 107.065999 -360.519866) (xy 107.012051 -360.527622) (xy 106.957549 -360.527622) (xy 106.903601 -360.519866)
			(xy 106.851306 -360.504511) (xy 106.801729 -360.481869) (xy 106.755879 -360.452403) (xy 106.714688 -360.416712)
			(xy 106.678997 -360.375521) (xy 106.649531 -360.329671) (xy 106.626889 -360.280094) (xy 106.611534 -360.227799)
			(xy 106.603778 -360.173851) (xy 106.603292 -360.1466) (xy 103.525241 -360.1466) (xy 103.50702 -360.190589)
			(xy 103.477033 -360.242529) (xy 103.440523 -360.29011) (xy 103.398115 -360.332519) (xy 103.350534 -360.36903)
			(xy 103.298595 -360.399017) (xy 103.243186 -360.421969) (xy 103.185255 -360.437492) (xy 103.125793 -360.445321)
			(xy 103.095806 -360.445812) (xy 102.232206 -360.445812) (xy 102.202223 -360.445243) (xy 102.142771 -360.437417)
			(xy 102.084849 -360.421897) (xy 102.029448 -360.39895) (xy 101.977516 -360.368968) (xy 101.929942 -360.332464)
			(xy 101.88754 -360.290062) (xy 101.851035 -360.242489) (xy 101.821052 -360.190558) (xy 101.798104 -360.135157)
			(xy 101.782584 -360.077235) (xy 101.774757 -360.017783) (xy 100.526342 -360.017783) (xy 100.526342 -360.69778)
			(xy 100.526759 -360.707801) (xy 100.534427 -360.726317) (xy 100.548601 -360.740486) (xy 100.567121 -360.748146)
			(xy 100.577142 -360.74858) (xy 100.772976 -360.74858) (xy 100.783041 -360.749016) (xy 100.801627 -360.756748)
			(xy 100.809044 -360.763566) (xy 101.22789 -361.182412) (xy 101.234735 -361.189811) (xy 101.242467 -361.208409)
			(xy 101.242876 -361.21848) (xy 101.242876 -361.755944) (xy 101.242444 -361.76601) (xy 101.234716 -361.784601)
			(xy 101.22789 -361.792012) (xy 100.541328 -362.478574) (xy 100.53449 -362.485975) (xy 100.526778 -362.504574)
			(xy 100.526342 -362.514642) (xy 100.526342 -363.027976) (xy 100.525903 -363.038039) (xy 100.518163 -363.056618)
			(xy 100.511356 -363.064044) (xy 99.25685 -364.318804) (xy 99.249999 -364.3262) (xy 99.242258 -364.344799)
			(xy 99.241864 -364.354872) (xy 99.241864 -366.731042) (xy 99.241336 -366.740936) (xy 99.233741 -366.759217)
			(xy 99.227132 -366.766602) (xy 99.221036 -366.772952) (xy 99.214376 -366.780304) (xy 99.206773 -366.798605)
			(xy 99.206304 -366.808512) (xy 99.206304 -367.680826) (xy 99.682623 -367.680826) (xy 99.682626 -367.626333)
			(xy 99.690383 -367.572394) (xy 99.705738 -367.520109) (xy 99.728377 -367.47054) (xy 99.75784 -367.424698)
			(xy 99.793527 -367.383516) (xy 99.834711 -367.347831) (xy 99.880554 -367.31837) (xy 99.930124 -367.295733)
			(xy 99.98241 -367.28038) (xy 100.036349 -367.272624) (xy 100.090842 -367.272624) (xy 100.144781 -367.280378)
			(xy 100.197068 -367.295729) (xy 100.246637 -367.318365) (xy 100.292481 -367.347825) (xy 100.333666 -367.383509)
			(xy 100.369354 -367.424691) (xy 100.398818 -367.470532) (xy 100.421459 -367.5201) (xy 100.436815 -367.572385)
			(xy 100.444574 -367.626323) (xy 100.445062 -367.65357) (xy 100.444303 -367.687997) (xy 100.431907 -367.755726)
			(xy 100.420424 -367.78819) (xy 100.415625 -367.80207) (xy 100.413449 -367.83135) (xy 100.419694 -367.860038)
			(xy 100.433846 -367.885763) (xy 100.454732 -367.906397) (xy 100.480627 -367.920234) (xy 100.509389 -367.926131)
			(xy 100.524056 -367.92535) (xy 100.555552 -367.92408) (xy 100.582809 -367.924504) (xy 100.63677 -367.932255)
			(xy 100.689078 -367.947608) (xy 100.738668 -367.970248) (xy 100.784532 -367.999716) (xy 100.825735 -368.035411)
			(xy 100.861438 -368.076607) (xy 100.890915 -368.122465) (xy 100.913566 -368.172051) (xy 100.928929 -368.224356)
			(xy 100.93464 -368.264054) (xy 103.243332 -368.264054) (xy 103.243332 -368.209546) (xy 103.251089 -368.155594)
			(xy 103.266445 -368.103294) (xy 103.289087 -368.053713) (xy 103.318555 -368.007858) (xy 103.354249 -367.966663)
			(xy 103.395442 -367.930967) (xy 103.441295 -367.901497) (xy 103.490876 -367.878852) (xy 103.543174 -367.863493)
			(xy 103.597126 -367.855733) (xy 103.62438 -367.855246) (xy 103.651658 -367.855674) (xy 103.705657 -367.863443)
			(xy 103.757999 -367.878824) (xy 103.807616 -367.901505) (xy 103.853496 -367.931023) (xy 103.894704 -367.966775)
			(xy 103.930398 -368.008032) (xy 103.959852 -368.053954) (xy 103.982463 -368.103603) (xy 103.997771 -368.155966)
			(xy 104.002078 -368.182906) (xy 104.004785 -368.197766) (xy 104.017581 -368.225105) (xy 104.037808 -368.247511)
			(xy 104.063699 -368.263029) (xy 104.092995 -368.270304) (xy 104.123138 -368.268701) (xy 104.151497 -368.25836)
			(xy 104.163876 -368.249708) (xy 104.188882 -368.23155) (xy 104.243532 -368.202707) (xy 104.302116 -368.183048)
			(xy 104.363103 -368.173089) (xy 104.394 -368.172492) (xy 104.421251 -368.172978) (xy 104.475199 -368.180734)
			(xy 104.527494 -368.196089) (xy 104.577071 -368.218731) (xy 104.622921 -368.248197) (xy 104.664112 -368.283888)
			(xy 104.699803 -368.325079) (xy 104.729269 -368.370929) (xy 104.751911 -368.420506) (xy 104.767266 -368.472801)
			(xy 104.775022 -368.526749) (xy 104.775022 -368.581251) (xy 104.767266 -368.635199) (xy 104.751911 -368.687494)
			(xy 104.729269 -368.737071) (xy 104.699803 -368.782921) (xy 104.664112 -368.824112) (xy 104.622921 -368.859803)
			(xy 104.577071 -368.889269) (xy 104.527494 -368.911911) (xy 104.475199 -368.927266) (xy 104.421251 -368.935022)
			(xy 104.394 -368.935508) (xy 104.366724 -368.935053) (xy 104.312728 -368.927283) (xy 104.260389 -368.911901)
			(xy 104.210775 -368.889222) (xy 104.164896 -368.859707) (xy 104.12369 -368.823958) (xy 104.087995 -368.782705)
			(xy 104.05854 -368.736788) (xy 104.035925 -368.687144) (xy 104.020612 -368.634786) (xy 104.016302 -368.607848)
			(xy 104.013597 -368.592985) (xy 104.000809 -368.565637) (xy 103.980584 -368.543223) (xy 103.95469 -368.5277)
			(xy 103.925389 -368.520426) (xy 103.895241 -368.522035) (xy 103.866881 -368.532388) (xy 103.854504 -368.541046)
			(xy 103.829509 -368.55922) (xy 103.774855 -368.588058) (xy 103.716267 -368.607711) (xy 103.655278 -368.617667)
			(xy 103.62438 -368.618262) (xy 103.597126 -368.617867) (xy 103.543174 -368.610107) (xy 103.490876 -368.594748)
			(xy 103.441295 -368.572103) (xy 103.395442 -368.542633) (xy 103.354249 -368.506937) (xy 103.318555 -368.465742)
			(xy 103.289087 -368.419887) (xy 103.266445 -368.370306) (xy 103.251089 -368.318006) (xy 103.243332 -368.264054)
			(xy 100.93464 -368.264054) (xy 100.936691 -368.278315) (xy 100.936695 -368.332829) (xy 100.92894 -368.386789)
			(xy 100.913585 -368.439097) (xy 100.890942 -368.488686) (xy 100.861472 -368.534548) (xy 100.825775 -368.575749)
			(xy 100.784577 -368.61145) (xy 100.738718 -368.640925) (xy 100.68913 -368.663573) (xy 100.636825 -368.678933)
			(xy 100.582865 -368.686692) (xy 100.528351 -368.686694) (xy 100.474391 -368.678936) (xy 100.422085 -368.663578)
			(xy 100.372496 -368.640933) (xy 100.326636 -368.61146) (xy 100.285437 -368.57576) (xy 100.249738 -368.534561)
			(xy 100.220266 -368.4887) (xy 100.19762 -368.439112) (xy 100.182263 -368.386805) (xy 100.174506 -368.332845)
			(xy 100.174044 -368.305588) (xy 100.174792 -368.271161) (xy 100.187196 -368.203431) (xy 100.198682 -368.170968)
			(xy 100.203407 -368.157064) (xy 100.205595 -368.127796) (xy 100.199362 -368.099115) (xy 100.185224 -368.073394)
			(xy 100.164349 -368.052762) (xy 100.138465 -368.038925) (xy 100.109713 -368.033028) (xy 100.09505 -368.033808)
			(xy 100.063554 -368.035078) (xy 100.036307 -368.034573) (xy 99.982369 -368.026811) (xy 99.930085 -368.011453)
			(xy 99.880518 -367.98881) (xy 99.834678 -367.959345) (xy 99.793498 -367.923655) (xy 99.757815 -367.882469)
			(xy 99.728358 -367.836623) (xy 99.705724 -367.787053) (xy 99.690375 -367.734766) (xy 99.682623 -367.680826)
			(xy 99.206304 -367.680826) (xy 99.206304 -368.935) (xy 102.360982 -368.935) (xy 102.365053 -368.879378)
			(xy 102.377179 -368.824941) (xy 102.397102 -368.77285) (xy 102.424398 -368.724215) (xy 102.458484 -368.680072)
			(xy 102.498633 -368.641363) (xy 102.543991 -368.608912) (xy 102.593591 -368.583411) (xy 102.646375 -368.565404)
			(xy 102.701218 -368.555274) (xy 102.756952 -368.553237) (xy 102.812389 -368.559337) (xy 102.866346 -368.573443)
			(xy 102.917675 -368.595255) (xy 102.965281 -368.624309) (xy 103.008149 -368.659984) (xy 103.045366 -368.701521)
			(xy 103.076139 -368.748034) (xy 103.099811 -368.798531) (xy 103.115879 -368.851938) (xy 103.123999 -368.907114)
			(xy 103.124508 -368.935) (xy 103.123999 -368.962886) (xy 103.115879 -369.018062) (xy 103.099811 -369.071469)
			(xy 103.076139 -369.121966) (xy 103.045366 -369.168479) (xy 103.008149 -369.210016) (xy 102.965281 -369.245691)
			(xy 102.917675 -369.274745) (xy 102.866346 -369.296557) (xy 102.812389 -369.310663) (xy 102.756952 -369.316763)
			(xy 102.701218 -369.314726) (xy 102.646375 -369.304596) (xy 102.593591 -369.286589) (xy 102.543991 -369.261088)
			(xy 102.498633 -369.228637) (xy 102.458484 -369.189928) (xy 102.424398 -369.145785) (xy 102.397102 -369.09715)
			(xy 102.377179 -369.045059) (xy 102.365053 -368.990622) (xy 102.360982 -368.935) (xy 99.206304 -368.935)
			(xy 99.206304 -370.967) (xy 104.011992 -370.967) (xy 104.015722 -370.913749) (xy 104.026838 -370.861537)
			(xy 104.045124 -370.811385) (xy 104.070223 -370.764271) (xy 104.101645 -370.721117) (xy 104.138775 -370.682763)
			(xy 104.159558 -370.66601) (xy 104.16836 -370.658399) (xy 104.178544 -370.637501) (xy 104.179116 -370.625878)
			(xy 104.179116 -370.546122) (xy 104.178544 -370.534494) (xy 104.168378 -370.513585) (xy 104.159558 -370.50599)
			(xy 104.138775 -370.489237) (xy 104.101645 -370.450883) (xy 104.070223 -370.407729) (xy 104.045124 -370.360615)
			(xy 104.026838 -370.310463) (xy 104.015722 -370.258251) (xy 104.011992 -370.205) (xy 104.015722 -370.151749)
			(xy 104.026838 -370.099537) (xy 104.045124 -370.049385) (xy 104.070223 -370.002271) (xy 104.101645 -369.959117)
			(xy 104.138775 -369.920763) (xy 104.159558 -369.90401) (xy 104.16836 -369.896399) (xy 104.178544 -369.875501)
			(xy 104.179116 -369.863878) (xy 104.179116 -369.784122) (xy 104.178544 -369.772494) (xy 104.168378 -369.751585)
			(xy 104.159558 -369.74399) (xy 104.137061 -369.725815) (xy 104.097329 -369.683791) (xy 104.064392 -369.636252)
			(xy 104.039007 -369.584288) (xy 104.021753 -369.529088) (xy 104.013026 -369.471917) (xy 104.012492 -369.443)
			(xy 104.012978 -369.415749) (xy 104.020734 -369.361801) (xy 104.036089 -369.309506) (xy 104.058731 -369.259929)
			(xy 104.088197 -369.214079) (xy 104.123888 -369.172888) (xy 104.165079 -369.137197) (xy 104.210929 -369.107731)
			(xy 104.260506 -369.085089) (xy 104.312801 -369.069734) (xy 104.366749 -369.061978) (xy 104.421251 -369.061978)
			(xy 104.475199 -369.069734) (xy 104.527494 -369.085089) (xy 104.577071 -369.107731) (xy 104.622921 -369.137197)
			(xy 104.664112 -369.172888) (xy 104.699803 -369.214079) (xy 104.729269 -369.259929) (xy 104.751911 -369.309506)
			(xy 104.767266 -369.361801) (xy 104.775022 -369.415749) (xy 104.775508 -369.443) (xy 104.775025 -369.471919)
			(xy 104.766293 -369.529093) (xy 104.749031 -369.584294) (xy 104.723633 -369.636256) (xy 104.690681 -369.683789)
			(xy 104.650932 -369.725803) (xy 104.628442 -369.74399) (xy 104.61964 -369.751601) (xy 104.609456 -369.772499)
			(xy 104.608884 -369.784122) (xy 104.608884 -369.863878) (xy 104.609456 -369.875506) (xy 104.619622 -369.896415)
			(xy 104.628442 -369.90401) (xy 104.649225 -369.920763) (xy 104.686355 -369.959117) (xy 104.717777 -370.002271)
			(xy 104.742876 -370.049385) (xy 104.761162 -370.099537) (xy 104.772278 -370.151749) (xy 104.776008 -370.205)
			(xy 104.772278 -370.258251) (xy 104.761162 -370.310463) (xy 104.742876 -370.360615) (xy 104.717777 -370.407729)
			(xy 104.686355 -370.450883) (xy 104.649225 -370.489237) (xy 104.628442 -370.50599) (xy 104.61964 -370.513601)
			(xy 104.609456 -370.534499) (xy 104.608884 -370.546122) (xy 104.608884 -370.625878) (xy 104.609456 -370.637506)
			(xy 104.619622 -370.658415) (xy 104.628442 -370.66601) (xy 104.649225 -370.682763) (xy 104.686355 -370.721117)
			(xy 104.717777 -370.764271) (xy 104.742876 -370.811385) (xy 104.761162 -370.861537) (xy 104.772278 -370.913749)
			(xy 104.776008 -370.967) (xy 104.772278 -371.020251) (xy 104.761162 -371.072463) (xy 104.742876 -371.122615)
			(xy 104.717777 -371.169729) (xy 104.686355 -371.212883) (xy 104.649225 -371.251237) (xy 104.628442 -371.26799)
			(xy 104.61964 -371.275601) (xy 104.609456 -371.296499) (xy 104.608884 -371.308122) (xy 104.608884 -371.387878)
			(xy 104.609456 -371.399506) (xy 104.619622 -371.420415) (xy 104.628442 -371.42801) (xy 104.650939 -371.446185)
			(xy 104.690671 -371.488209) (xy 104.723608 -371.535748) (xy 104.748993 -371.587712) (xy 104.766247 -371.642912)
			(xy 104.774974 -371.700083) (xy 104.775508 -371.729) (xy 104.775022 -371.756251) (xy 104.767266 -371.810199)
			(xy 104.751911 -371.862494) (xy 104.729269 -371.912071) (xy 104.699803 -371.957921) (xy 104.664112 -371.999112)
			(xy 104.622921 -372.034803) (xy 104.577071 -372.064269) (xy 104.527494 -372.086911) (xy 104.475199 -372.102266)
			(xy 104.421251 -372.110022) (xy 104.366749 -372.110022) (xy 104.312801 -372.102266) (xy 104.260506 -372.086911)
			(xy 104.210929 -372.064269) (xy 104.165079 -372.034803) (xy 104.123888 -371.999112) (xy 104.088197 -371.957921)
			(xy 104.058731 -371.912071) (xy 104.036089 -371.862494) (xy 104.020734 -371.810199) (xy 104.012978 -371.756251)
			(xy 104.012492 -371.729) (xy 104.012975 -371.700081) (xy 104.021707 -371.642907) (xy 104.038969 -371.587706)
			(xy 104.064367 -371.535744) (xy 104.097319 -371.488211) (xy 104.137068 -371.446197) (xy 104.159558 -371.42801)
			(xy 104.16836 -371.420399) (xy 104.178544 -371.399501) (xy 104.179116 -371.387878) (xy 104.179116 -371.308122)
			(xy 104.178544 -371.296494) (xy 104.168378 -371.275585) (xy 104.159558 -371.26799) (xy 104.138775 -371.251237)
			(xy 104.101645 -371.212883) (xy 104.070223 -371.169729) (xy 104.045124 -371.122615) (xy 104.026838 -371.072463)
			(xy 104.015722 -371.020251) (xy 104.011992 -370.967) (xy 99.206304 -370.967) (xy 99.206304 -375.213371)
			(xy 104.681961 -375.213371) (xy 104.681961 -375.153429) (xy 104.689785 -375.094001) (xy 104.7053 -375.036103)
			(xy 104.72824 -374.980725) (xy 104.758212 -374.928815) (xy 104.794703 -374.881262) (xy 104.837089 -374.838879)
			(xy 104.884645 -374.802391) (xy 104.936557 -374.772424) (xy 104.991937 -374.749489) (xy 105.049837 -374.733978)
			(xy 105.109265 -374.726159) (xy 105.139236 -374.725692) (xy 106.002836 -374.725692) (xy 106.032802 -374.726184)
			(xy 106.092221 -374.734011) (xy 106.15011 -374.749527) (xy 106.205479 -374.772465) (xy 106.25738 -374.802434)
			(xy 106.304926 -374.838921) (xy 106.347303 -374.881301) (xy 106.383786 -374.92885) (xy 106.413751 -374.980753)
			(xy 106.436685 -375.036124) (xy 106.452196 -375.094014) (xy 106.460018 -375.153434) (xy 106.460018 -375.213366)
			(xy 106.452196 -375.272786) (xy 106.436685 -375.330676) (xy 106.413751 -375.386047) (xy 106.383786 -375.43795)
			(xy 106.347303 -375.485499) (xy 106.304926 -375.527879) (xy 106.25738 -375.564366) (xy 106.205479 -375.594335)
			(xy 106.15011 -375.617273) (xy 106.092221 -375.632789) (xy 106.032802 -375.640616) (xy 106.002836 -375.641108)
			(xy 105.139236 -375.641108) (xy 105.109265 -375.640641) (xy 105.049837 -375.632822) (xy 104.991937 -375.617311)
			(xy 104.936557 -375.594376) (xy 104.884645 -375.564409) (xy 104.837089 -375.527921) (xy 104.794703 -375.485538)
			(xy 104.758212 -375.437985) (xy 104.72824 -375.386075) (xy 104.7053 -375.330697) (xy 104.689785 -375.272799)
			(xy 104.681961 -375.213371) (xy 99.206304 -375.213371) (xy 99.206304 -376.484642) (xy 99.998528 -376.484642)
			(xy 100.002599 -376.42902) (xy 100.014725 -376.374583) (xy 100.034648 -376.322492) (xy 100.061944 -376.273857)
			(xy 100.09603 -376.229714) (xy 100.136179 -376.191005) (xy 100.181537 -376.158554) (xy 100.231137 -376.133053)
			(xy 100.283921 -376.115046) (xy 100.338764 -376.104916) (xy 100.394498 -376.102879) (xy 100.449935 -376.108979)
			(xy 100.503892 -376.123085) (xy 100.555221 -376.144897) (xy 100.602827 -376.173951) (xy 100.645695 -376.209626)
			(xy 100.682912 -376.251163) (xy 100.713685 -376.297676) (xy 100.737357 -376.348173) (xy 100.753425 -376.40158)
			(xy 100.761545 -376.456756) (xy 100.762054 -376.484642) (xy 100.761545 -376.512528) (xy 100.753425 -376.567704)
			(xy 100.737357 -376.621111) (xy 100.713685 -376.671608) (xy 100.682912 -376.718121) (xy 100.645695 -376.759658)
			(xy 100.602827 -376.795333) (xy 100.555221 -376.824387) (xy 100.503892 -376.846199) (xy 100.449935 -376.860305)
			(xy 100.394498 -376.866405) (xy 100.338764 -376.864368) (xy 100.283921 -376.854238) (xy 100.231137 -376.836231)
			(xy 100.181537 -376.81073) (xy 100.136179 -376.778279) (xy 100.09603 -376.73957) (xy 100.061944 -376.695427)
			(xy 100.034648 -376.646792) (xy 100.014725 -376.594701) (xy 100.002599 -376.540264) (xy 99.998528 -376.484642)
			(xy 99.206304 -376.484642) (xy 99.206304 -377.387612) (xy 100.044502 -377.387612) (xy 100.048573 -377.33199)
			(xy 100.060699 -377.277553) (xy 100.080622 -377.225462) (xy 100.107918 -377.176827) (xy 100.142004 -377.132684)
			(xy 100.182153 -377.093975) (xy 100.227511 -377.061524) (xy 100.277111 -377.036023) (xy 100.329895 -377.018016)
			(xy 100.384738 -377.007886) (xy 100.440472 -377.005849) (xy 100.495909 -377.011949) (xy 100.549866 -377.026055)
			(xy 100.601195 -377.047867) (xy 100.648801 -377.076921) (xy 100.691669 -377.112596) (xy 100.728886 -377.154133)
			(xy 100.759659 -377.200646) (xy 100.783331 -377.251143) (xy 100.799399 -377.30455) (xy 100.807519 -377.359726)
			(xy 100.808028 -377.387612) (xy 100.807519 -377.415498) (xy 100.799399 -377.470674) (xy 100.783331 -377.524081)
			(xy 100.759659 -377.574578) (xy 100.728886 -377.621091) (xy 100.691669 -377.662628) (xy 100.648801 -377.698303)
			(xy 100.601195 -377.727357) (xy 100.549866 -377.749169) (xy 100.495909 -377.763275) (xy 100.440472 -377.769375)
			(xy 100.384738 -377.767338) (xy 100.329895 -377.757208) (xy 100.277111 -377.739201) (xy 100.227511 -377.7137)
			(xy 100.182153 -377.681249) (xy 100.142004 -377.64254) (xy 100.107918 -377.598397) (xy 100.080622 -377.549762)
			(xy 100.060699 -377.497671) (xy 100.048573 -377.443234) (xy 100.044502 -377.387612) (xy 99.206304 -377.387612)
			(xy 99.206304 -381.286851) (xy 100.042966 -381.286851) (xy 100.042966 -381.232349) (xy 100.050722 -381.178401)
			(xy 100.066077 -381.126106) (xy 100.088717 -381.076529) (xy 100.118182 -381.030678) (xy 100.153873 -380.989487)
			(xy 100.195062 -380.953794) (xy 100.240911 -380.924327) (xy 100.290488 -380.901684) (xy 100.342782 -380.886326)
			(xy 100.396729 -380.878567) (xy 100.42398 -380.87808) (xy 100.453271 -380.878598) (xy 100.511167 -380.887545)
			(xy 100.567016 -380.905232) (xy 100.619507 -380.931244) (xy 100.667407 -380.96497) (xy 100.709593 -381.005618)
			(xy 100.745074 -381.052234) (xy 100.759514 -381.077724) (xy 100.766512 -381.089738) (xy 100.78586 -381.109691)
			(xy 100.809873 -381.123686) (xy 100.83677 -381.130687) (xy 100.864559 -381.130175) (xy 100.89118 -381.122187)
			(xy 100.91466 -381.107316) (xy 100.93326 -381.086664) (xy 100.939854 -381.074422) (xy 100.952016 -381.050864)
			(xy 100.981867 -381.007049) (xy 101.017499 -380.967792) (xy 101.058226 -380.93385) (xy 101.103263 -380.905877)
			(xy 101.15174 -380.884412) (xy 101.202723 -380.86987) (xy 101.25523 -380.862531) (xy 101.281738 -380.862078)
			(xy 101.308986 -380.862595) (xy 101.362928 -380.870355) (xy 101.387499 -380.877572) (xy 105.0036 -380.877572)
			(xy 105.0036 -380.013972) (xy 105.00409 -379.983988) (xy 105.011918 -379.924532) (xy 105.027439 -379.866607)
			(xy 105.050388 -379.811203) (xy 105.080372 -379.759269) (xy 105.116878 -379.711693) (xy 105.159283 -379.669288)
			(xy 105.206859 -379.632782) (xy 105.258793 -379.602798) (xy 105.314197 -379.579849) (xy 105.372122 -379.564328)
			(xy 105.431578 -379.5565) (xy 105.491546 -379.5565) (xy 105.551002 -379.564328) (xy 105.608927 -379.579849)
			(xy 105.664331 -379.602798) (xy 105.716265 -379.632782) (xy 105.763841 -379.669288) (xy 105.806246 -379.711693)
			(xy 105.842752 -379.759269) (xy 105.872736 -379.811203) (xy 105.895685 -379.866607) (xy 105.911206 -379.924532)
			(xy 105.919034 -379.983988) (xy 105.919524 -380.013972) (xy 105.919524 -380.877572) (xy 105.919034 -380.907556)
			(xy 105.911206 -380.967012) (xy 105.895685 -381.024937) (xy 105.872736 -381.080341) (xy 105.842752 -381.132275)
			(xy 105.806246 -381.179851) (xy 105.763841 -381.222256) (xy 105.716265 -381.258762) (xy 105.664331 -381.288746)
			(xy 105.608927 -381.311695) (xy 105.551002 -381.327216) (xy 105.491546 -381.335044) (xy 105.431578 -381.335044)
			(xy 105.372122 -381.327216) (xy 105.314197 -381.311695) (xy 105.258793 -381.288746) (xy 105.206859 -381.258762)
			(xy 105.159283 -381.222256) (xy 105.116878 -381.179851) (xy 105.080372 -381.132275) (xy 105.050388 -381.080341)
			(xy 105.027439 -381.024937) (xy 105.011918 -380.967012) (xy 105.00409 -380.907556) (xy 105.0036 -380.877572)
			(xy 101.387499 -380.877572) (xy 101.415216 -380.885713) (xy 101.464787 -380.908356) (xy 101.510631 -380.937822)
			(xy 101.551815 -380.973512) (xy 101.587501 -381.0147) (xy 101.616963 -381.060547) (xy 101.6396 -381.110119)
			(xy 101.654953 -381.162409) (xy 101.662708 -381.216352) (xy 101.662708 -381.270848) (xy 101.654953 -381.324791)
			(xy 101.6396 -381.377081) (xy 101.616963 -381.426653) (xy 101.587501 -381.4725) (xy 101.551815 -381.513688)
			(xy 101.510631 -381.549378) (xy 101.464787 -381.578844) (xy 101.415216 -381.601487) (xy 101.362928 -381.616845)
			(xy 101.308986 -381.624605) (xy 101.281738 -381.625094) (xy 101.252446 -381.624576) (xy 101.194551 -381.61563)
			(xy 101.138701 -381.597945) (xy 101.086209 -381.571933) (xy 101.038308 -381.538207) (xy 100.996123 -381.497558)
			(xy 100.960643 -381.450941) (xy 100.946204 -381.42545) (xy 100.939178 -381.413456) (xy 100.919833 -381.393509)
			(xy 100.895826 -381.379518) (xy 100.868935 -381.372518) (xy 100.841153 -381.373028) (xy 100.814538 -381.38101)
			(xy 100.79106 -381.395872) (xy 100.77246 -381.416515) (xy 100.765864 -381.428752) (xy 100.753677 -381.452297)
			(xy 100.723831 -381.496112) (xy 100.688202 -381.53537) (xy 100.647479 -381.569314) (xy 100.602446 -381.597289)
			(xy 100.553972 -381.618756) (xy 100.502991 -381.6333) (xy 100.450487 -381.640642) (xy 100.42398 -381.641096)
			(xy 100.396729 -381.640633) (xy 100.342782 -381.632874) (xy 100.290488 -381.617516) (xy 100.240911 -381.594873)
			(xy 100.195062 -381.565406) (xy 100.153873 -381.529713) (xy 100.118182 -381.488522) (xy 100.088717 -381.442671)
			(xy 100.066077 -381.393094) (xy 100.050722 -381.340799) (xy 100.042966 -381.286851) (xy 99.206304 -381.286851)
			(xy 99.206304 -385.583938) (xy 100.447856 -385.583938) (xy 100.447856 -384.720338) (xy 100.448346 -384.690354)
			(xy 100.456174 -384.630898) (xy 100.471695 -384.572973) (xy 100.494644 -384.517569) (xy 100.524628 -384.465635)
			(xy 100.561134 -384.418059) (xy 100.603539 -384.375654) (xy 100.651115 -384.339148) (xy 100.703049 -384.309164)
			(xy 100.758453 -384.286215) (xy 100.816378 -384.270694) (xy 100.875834 -384.262866) (xy 100.935802 -384.262866)
			(xy 100.995258 -384.270694) (xy 101.053183 -384.286215) (xy 101.108587 -384.309164) (xy 101.160521 -384.339148)
			(xy 101.208097 -384.375654) (xy 101.250502 -384.418059) (xy 101.287008 -384.465635) (xy 101.316992 -384.517569)
			(xy 101.339941 -384.572973) (xy 101.355462 -384.630898) (xy 101.36329 -384.690354) (xy 101.36378 -384.720338)
			(xy 101.36378 -385.319283) (xy 104.635826 -385.319283) (xy 104.635826 -385.259317) (xy 104.643653 -385.199864)
			(xy 104.659172 -385.141942) (xy 104.682119 -385.08654) (xy 104.7121 -385.034608) (xy 104.748603 -384.987032)
			(xy 104.791004 -384.944628) (xy 104.838576 -384.908121) (xy 104.890506 -384.878136) (xy 104.945906 -384.855184)
			(xy 105.003827 -384.83966) (xy 105.063279 -384.831828) (xy 105.093262 -384.831336) (xy 105.956862 -384.831336)
			(xy 105.986849 -384.831807) (xy 106.046311 -384.83963) (xy 106.104243 -384.855149) (xy 106.159653 -384.878097)
			(xy 106.211594 -384.908081) (xy 106.259176 -384.944589) (xy 106.301586 -384.986995) (xy 106.338098 -385.034574)
			(xy 106.368087 -385.086513) (xy 106.391039 -385.141921) (xy 106.406562 -385.199852) (xy 106.414391 -385.259313)
			(xy 106.414391 -385.319287) (xy 106.406562 -385.378748) (xy 106.391039 -385.436679) (xy 106.368087 -385.492087)
			(xy 106.338098 -385.544026) (xy 106.301586 -385.591605) (xy 106.259176 -385.634011) (xy 106.211594 -385.670519)
			(xy 106.159653 -385.700503) (xy 106.104243 -385.723451) (xy 106.046311 -385.73897) (xy 105.986849 -385.746793)
			(xy 105.956862 -385.74726) (xy 105.093262 -385.74726) (xy 105.063279 -385.746772) (xy 105.003827 -385.73894)
			(xy 104.945906 -385.723416) (xy 104.890506 -385.700464) (xy 104.838576 -385.670479) (xy 104.791004 -385.633972)
			(xy 104.748603 -385.591568) (xy 104.7121 -385.543992) (xy 104.682119 -385.49206) (xy 104.659172 -385.436658)
			(xy 104.643653 -385.378736) (xy 104.635826 -385.319283) (xy 101.36378 -385.319283) (xy 101.36378 -385.583938)
			(xy 101.36329 -385.613922) (xy 101.355462 -385.673378) (xy 101.339941 -385.731303) (xy 101.316992 -385.786707)
			(xy 101.287008 -385.838641) (xy 101.250502 -385.886217) (xy 101.208097 -385.928622) (xy 101.160521 -385.965128)
			(xy 101.108587 -385.995112) (xy 101.053183 -386.018061) (xy 100.995258 -386.033582) (xy 100.935802 -386.04141)
			(xy 100.875834 -386.04141) (xy 100.816378 -386.033582) (xy 100.758453 -386.018061) (xy 100.703049 -385.995112)
			(xy 100.651115 -385.965128) (xy 100.603539 -385.928622) (xy 100.561134 -385.886217) (xy 100.524628 -385.838641)
			(xy 100.494644 -385.786707) (xy 100.471695 -385.731303) (xy 100.456174 -385.673378) (xy 100.448346 -385.613922)
			(xy 100.447856 -385.583938) (xy 99.206304 -385.583938) (xy 99.206304 -388.911846) (xy 103.494838 -388.911846)
			(xy 103.498909 -388.856224) (xy 103.511035 -388.801787) (xy 103.530958 -388.749696) (xy 103.558254 -388.701061)
			(xy 103.59234 -388.656918) (xy 103.632489 -388.618209) (xy 103.677847 -388.585758) (xy 103.727447 -388.560257)
			(xy 103.780231 -388.54225) (xy 103.835074 -388.53212) (xy 103.890808 -388.530083) (xy 103.946245 -388.536183)
			(xy 104.000202 -388.550289) (xy 104.051531 -388.572101) (xy 104.099137 -388.601155) (xy 104.142005 -388.63683)
			(xy 104.179222 -388.678367) (xy 104.209995 -388.72488) (xy 104.233667 -388.775377) (xy 104.249735 -388.828784)
			(xy 104.257855 -388.88396) (xy 104.258364 -388.911846) (xy 104.257855 -388.939732) (xy 104.249735 -388.994908)
			(xy 104.233667 -389.048315) (xy 104.209995 -389.098812) (xy 104.179222 -389.145325) (xy 104.142005 -389.186862)
			(xy 104.099137 -389.222537) (xy 104.051531 -389.251591) (xy 104.000202 -389.273403) (xy 103.946245 -389.287509)
			(xy 103.890808 -389.293609) (xy 103.835074 -389.291572) (xy 103.780231 -389.281442) (xy 103.727447 -389.263435)
			(xy 103.677847 -389.237934) (xy 103.632489 -389.205483) (xy 103.59234 -389.166774) (xy 103.558254 -389.122631)
			(xy 103.530958 -389.073996) (xy 103.511035 -389.021905) (xy 103.498909 -388.967468) (xy 103.494838 -388.911846)
			(xy 99.206304 -388.911846) (xy 99.206304 -390.037574) (xy 99.206918 -390.048899) (xy 99.216689 -390.069333)
			(xy 99.2251 -390.076944) (xy 99.246627 -390.095167) (xy 99.284596 -390.13687) (xy 99.316015 -390.183708)
			(xy 99.340198 -390.23466) (xy 99.356618 -390.288615) (xy 99.364919 -390.3444) (xy 99.364919 -390.4008)
			(xy 99.356618 -390.456585) (xy 99.340198 -390.51054) (xy 99.316015 -390.561492) (xy 99.291764 -390.597644)
			(xy 99.793806 -390.597644) (xy 99.794296 -390.570275) (xy 99.802108 -390.516097) (xy 99.817591 -390.463594)
			(xy 99.840428 -390.413846) (xy 99.870147 -390.367878) (xy 99.887786 -390.346946) (xy 99.88804 -390.346692)
			(xy 99.893641 -390.339615) (xy 99.899878 -390.322691) (xy 99.900232 -390.313672) (xy 99.900232 -390.246616)
			(xy 99.89986 -390.237601) (xy 99.893622 -390.220684) (xy 99.88804 -390.213596) (xy 99.887786 -390.213596)
			(xy 99.887786 -390.213342) (xy 99.870151 -390.192407) (xy 99.840439 -390.146435) (xy 99.817602 -390.096688)
			(xy 99.80211 -390.044188) (xy 99.794281 -389.990013) (xy 99.793806 -389.962644) (xy 99.794292 -389.935393)
			(xy 99.802048 -389.881445) (xy 99.817403 -389.82915) (xy 99.840045 -389.779573) (xy 99.869511 -389.733723)
			(xy 99.905202 -389.692532) (xy 99.946393 -389.656841) (xy 99.992243 -389.627375) (xy 100.04182 -389.604733)
			(xy 100.094115 -389.589378) (xy 100.148063 -389.581622) (xy 100.202565 -389.581622) (xy 100.256513 -389.589378)
			(xy 100.308808 -389.604733) (xy 100.358385 -389.627375) (xy 100.404235 -389.656841) (xy 100.445426 -389.692532)
			(xy 100.475893 -389.727694) (xy 106.942888 -389.727694) (xy 106.946959 -389.672072) (xy 106.959085 -389.617635)
			(xy 106.979008 -389.565544) (xy 107.006304 -389.516909) (xy 107.04039 -389.472766) (xy 107.080539 -389.434057)
			(xy 107.125897 -389.401606) (xy 107.175497 -389.376105) (xy 107.228281 -389.358098) (xy 107.283124 -389.347968)
			(xy 107.338858 -389.345931) (xy 107.394295 -389.352031) (xy 107.448252 -389.366137) (xy 107.499581 -389.387949)
			(xy 107.547187 -389.417003) (xy 107.590055 -389.452678) (xy 107.627272 -389.494215) (xy 107.658045 -389.540728)
			(xy 107.681717 -389.591225) (xy 107.697785 -389.644632) (xy 107.705905 -389.699808) (xy 107.706414 -389.727694)
			(xy 107.705905 -389.75558) (xy 107.697785 -389.810756) (xy 107.681717 -389.864163) (xy 107.658045 -389.91466)
			(xy 107.627272 -389.961173) (xy 107.590055 -390.00271) (xy 107.547187 -390.038385) (xy 107.499581 -390.067439)
			(xy 107.448252 -390.089251) (xy 107.394295 -390.103357) (xy 107.338858 -390.109457) (xy 107.283124 -390.10742)
			(xy 107.228281 -390.09729) (xy 107.175497 -390.079283) (xy 107.125897 -390.053782) (xy 107.080539 -390.021331)
			(xy 107.04039 -389.982622) (xy 107.006304 -389.938479) (xy 106.979008 -389.889844) (xy 106.959085 -389.837753)
			(xy 106.946959 -389.783316) (xy 106.942888 -389.727694) (xy 100.475893 -389.727694) (xy 100.481117 -389.733723)
			(xy 100.510583 -389.779573) (xy 100.533225 -389.82915) (xy 100.54858 -389.881445) (xy 100.556336 -389.935393)
			(xy 100.556822 -389.962644) (xy 100.556342 -389.990014) (xy 100.548531 -390.044193) (xy 100.533046 -390.096697)
			(xy 100.510207 -390.146444) (xy 100.480483 -390.192411) (xy 100.462842 -390.213342) (xy 100.462588 -390.213596)
			(xy 100.456996 -390.220679) (xy 100.450753 -390.237598) (xy 100.450396 -390.246616) (xy 100.450396 -390.313672)
			(xy 100.450767 -390.322687) (xy 100.457005 -390.339604) (xy 100.462588 -390.346692) (xy 100.462842 -390.346692)
			(xy 100.462842 -390.346946) (xy 100.480476 -390.367882) (xy 100.510187 -390.413854) (xy 100.533024 -390.463601)
			(xy 100.548516 -390.5161) (xy 100.556347 -390.570275) (xy 100.556822 -390.597644) (xy 100.556336 -390.624895)
			(xy 100.54858 -390.678843) (xy 100.533225 -390.731138) (xy 100.510583 -390.780715) (xy 100.481117 -390.826565)
			(xy 100.445426 -390.867756) (xy 100.404235 -390.903447) (xy 100.358385 -390.932913) (xy 100.308808 -390.955555)
			(xy 100.256513 -390.97091) (xy 100.202565 -390.978666) (xy 100.148063 -390.978666) (xy 100.094115 -390.97091)
			(xy 100.04182 -390.955555) (xy 99.992243 -390.932913) (xy 99.946393 -390.903447) (xy 99.905202 -390.867756)
			(xy 99.869511 -390.826565) (xy 99.840045 -390.780715) (xy 99.817403 -390.731138) (xy 99.802048 -390.678843)
			(xy 99.794292 -390.624895) (xy 99.793806 -390.597644) (xy 99.291764 -390.597644) (xy 99.284596 -390.60833)
			(xy 99.246627 -390.650033) (xy 99.2251 -390.668256) (xy 99.216713 -390.675878) (xy 99.206977 -390.696311)
			(xy 99.206304 -390.707626) (xy 99.206304 -390.852152) (xy 99.207057 -390.864817) (xy 99.219187 -390.887065)
			(xy 99.229418 -390.89457) (xy 99.300538 -390.941052) (xy 99.311495 -390.947377) (xy 99.336673 -390.949494)
			(xy 99.348544 -390.945116) (xy 99.372827 -390.934937) (xy 99.423486 -390.920586) (xy 99.475634 -390.913319)
			(xy 99.50196 -390.912858) (xy 99.529217 -390.913318) (xy 99.583177 -390.921071) (xy 99.635485 -390.936425)
			(xy 99.685074 -390.959067) (xy 99.730937 -390.988537) (xy 99.772138 -391.024234) (xy 99.807839 -391.065431)
			(xy 99.837313 -391.111291) (xy 99.857008 -391.154412) (xy 106.201208 -391.154412) (xy 106.205279 -391.09879)
			(xy 106.217405 -391.044353) (xy 106.237328 -390.992262) (xy 106.264624 -390.943627) (xy 106.29871 -390.899484)
			(xy 106.338859 -390.860775) (xy 106.384217 -390.828324) (xy 106.433817 -390.802823) (xy 106.486601 -390.784816)
			(xy 106.541444 -390.774686) (xy 106.597178 -390.772649) (xy 106.652615 -390.778749) (xy 106.706572 -390.792855)
			(xy 106.757901 -390.814667) (xy 106.805507 -390.843721) (xy 106.848375 -390.879396) (xy 106.885592 -390.920933)
			(xy 106.916365 -390.967446) (xy 106.940037 -391.017943) (xy 106.956105 -391.07135) (xy 106.964225 -391.126526)
			(xy 106.964734 -391.154412) (xy 106.964225 -391.182298) (xy 106.956105 -391.237474) (xy 106.940037 -391.290881)
			(xy 106.916365 -391.341378) (xy 106.885592 -391.387891) (xy 106.848375 -391.429428) (xy 106.805507 -391.465103)
			(xy 106.757901 -391.494157) (xy 106.706572 -391.515969) (xy 106.652615 -391.530075) (xy 106.597178 -391.536175)
			(xy 106.541444 -391.534138) (xy 106.486601 -391.524008) (xy 106.433817 -391.506001) (xy 106.384217 -391.4805)
			(xy 106.338859 -391.448049) (xy 106.29871 -391.40934) (xy 106.264624 -391.365197) (xy 106.237328 -391.316562)
			(xy 106.217405 -391.264471) (xy 106.205279 -391.210034) (xy 106.201208 -391.154412) (xy 99.857008 -391.154412)
			(xy 99.859961 -391.160878) (xy 99.87532 -391.213184) (xy 99.883079 -391.267143) (xy 99.883079 -391.321657)
			(xy 99.87532 -391.375616) (xy 99.859961 -391.427922) (xy 99.837313 -391.477509) (xy 99.807839 -391.523369)
			(xy 99.772138 -391.564566) (xy 99.730937 -391.600263) (xy 99.685074 -391.629733) (xy 99.635485 -391.652375)
			(xy 99.628116 -391.654538) (xy 108.000036 -391.654538) (xy 108.004107 -391.598916) (xy 108.016233 -391.544479)
			(xy 108.036156 -391.492388) (xy 108.063452 -391.443753) (xy 108.097538 -391.39961) (xy 108.137687 -391.360901)
			(xy 108.183045 -391.32845) (xy 108.232645 -391.302949) (xy 108.285429 -391.284942) (xy 108.340272 -391.274812)
			(xy 108.396006 -391.272775) (xy 108.451443 -391.278875) (xy 108.5054 -391.292981) (xy 108.556729 -391.314793)
			(xy 108.604335 -391.343847) (xy 108.647203 -391.379522) (xy 108.68442 -391.421059) (xy 108.715193 -391.467572)
			(xy 108.738865 -391.518069) (xy 108.754933 -391.571476) (xy 108.763053 -391.626652) (xy 108.763562 -391.654538)
			(xy 108.763053 -391.682424) (xy 108.754933 -391.7376) (xy 108.738865 -391.791007) (xy 108.715193 -391.841504)
			(xy 108.68442 -391.888017) (xy 108.647203 -391.929554) (xy 108.604335 -391.965229) (xy 108.556729 -391.994283)
			(xy 108.5054 -392.016095) (xy 108.451443 -392.030201) (xy 108.396006 -392.036301) (xy 108.340272 -392.034264)
			(xy 108.285429 -392.024134) (xy 108.232645 -392.006127) (xy 108.183045 -391.980626) (xy 108.137687 -391.948175)
			(xy 108.097538 -391.909466) (xy 108.063452 -391.865323) (xy 108.036156 -391.816688) (xy 108.016233 -391.764597)
			(xy 108.004107 -391.71016) (xy 108.000036 -391.654538) (xy 99.628116 -391.654538) (xy 99.583177 -391.667729)
			(xy 99.529217 -391.675482) (xy 99.50196 -391.675874) (xy 99.475631 -391.675438) (xy 99.423474 -391.668197)
			(xy 99.372814 -391.65383) (xy 99.348544 -391.643616) (xy 99.336606 -391.638536) (xy 99.311206 -391.640568)
			(xy 99.229418 -391.694162) (xy 99.219155 -391.701635) (xy 99.20704 -391.723904) (xy 99.206304 -391.73658)
			(xy 99.206304 -392.147552) (xy 99.207057 -392.160217) (xy 99.219187 -392.182465) (xy 99.229418 -392.18997)
			(xy 99.300538 -392.236452) (xy 99.311495 -392.242777) (xy 99.336673 -392.244894) (xy 99.348544 -392.240516)
			(xy 99.372827 -392.230337) (xy 99.423486 -392.215986) (xy 99.475634 -392.208719) (xy 99.50196 -392.208258)
			(xy 99.529217 -392.208718) (xy 99.583177 -392.216471) (xy 99.635485 -392.231825) (xy 99.685074 -392.254467)
			(xy 99.730937 -392.283937) (xy 99.772138 -392.319634) (xy 99.785237 -392.33475) (xy 106.667298 -392.33475)
			(xy 106.671369 -392.279128) (xy 106.683495 -392.224691) (xy 106.703418 -392.1726) (xy 106.730714 -392.123965)
			(xy 106.7648 -392.079822) (xy 106.804949 -392.041113) (xy 106.850307 -392.008662) (xy 106.899907 -391.983161)
			(xy 106.952691 -391.965154) (xy 107.007534 -391.955024) (xy 107.063268 -391.952987) (xy 107.118705 -391.959087)
			(xy 107.172662 -391.973193) (xy 107.223991 -391.995005) (xy 107.271597 -392.024059) (xy 107.314465 -392.059734)
			(xy 107.351682 -392.101271) (xy 107.382455 -392.147784) (xy 107.406127 -392.198281) (xy 107.422195 -392.251688)
			(xy 107.430315 -392.306864) (xy 107.430824 -392.33475) (xy 107.430315 -392.362636) (xy 107.422195 -392.417812)
			(xy 107.406127 -392.471219) (xy 107.382455 -392.521716) (xy 107.351682 -392.568229) (xy 107.314465 -392.609766)
			(xy 107.271597 -392.645441) (xy 107.223991 -392.674495) (xy 107.172662 -392.696307) (xy 107.118705 -392.710413)
			(xy 107.063268 -392.716513) (xy 107.007534 -392.714476) (xy 106.952691 -392.704346) (xy 106.899907 -392.686339)
			(xy 106.850307 -392.660838) (xy 106.804949 -392.628387) (xy 106.7648 -392.589678) (xy 106.730714 -392.545535)
			(xy 106.703418 -392.4969) (xy 106.683495 -392.444809) (xy 106.671369 -392.390372) (xy 106.667298 -392.33475)
			(xy 99.785237 -392.33475) (xy 99.807839 -392.360831) (xy 99.837313 -392.406691) (xy 99.859961 -392.456278)
			(xy 99.87532 -392.508584) (xy 99.883079 -392.562543) (xy 99.883079 -392.617057) (xy 99.87532 -392.671016)
			(xy 99.859961 -392.723322) (xy 99.837313 -392.772909) (xy 99.807839 -392.818769) (xy 99.772138 -392.859966)
			(xy 99.730937 -392.895663) (xy 99.685074 -392.925133) (xy 99.635485 -392.947775) (xy 99.583177 -392.963129)
			(xy 99.529217 -392.970882) (xy 99.50196 -392.971274) (xy 99.475631 -392.970838) (xy 99.423474 -392.963597)
			(xy 99.372814 -392.94923) (xy 99.348544 -392.939016) (xy 99.336606 -392.933936) (xy 99.311206 -392.935968)
			(xy 99.229418 -392.989562) (xy 99.219155 -392.997035) (xy 99.20704 -393.019304) (xy 99.206304 -393.03198)
			(xy 99.206304 -393.442952) (xy 99.207057 -393.455617) (xy 99.219187 -393.477865) (xy 99.229418 -393.48537)
			(xy 99.300538 -393.531852) (xy 99.311495 -393.538177) (xy 99.336673 -393.540294) (xy 99.348544 -393.535916)
			(xy 99.372827 -393.525737) (xy 99.423486 -393.511386) (xy 99.475634 -393.504119) (xy 99.50196 -393.503658)
			(xy 99.529217 -393.504118) (xy 99.583177 -393.511871) (xy 99.635485 -393.527225) (xy 99.685074 -393.549867)
			(xy 99.730937 -393.579337) (xy 99.772138 -393.615034) (xy 99.807839 -393.656231) (xy 99.837313 -393.702091)
			(xy 99.859961 -393.751678) (xy 99.87532 -393.803984) (xy 99.883079 -393.857943) (xy 99.883079 -393.912457)
			(xy 99.87532 -393.966416) (xy 99.859961 -394.018722) (xy 99.837313 -394.068309) (xy 99.807839 -394.114169)
			(xy 99.772138 -394.155366) (xy 99.730937 -394.191063) (xy 99.685074 -394.220533) (xy 99.635485 -394.243175)
			(xy 99.583177 -394.258529) (xy 99.529217 -394.266282) (xy 99.50196 -394.266674) (xy 99.475631 -394.266238)
			(xy 99.423474 -394.258997) (xy 99.372814 -394.24463) (xy 99.348544 -394.234416) (xy 99.336606 -394.229336)
			(xy 99.311206 -394.231368) (xy 99.229418 -394.284962) (xy 99.219155 -394.292435) (xy 99.20704 -394.314704)
			(xy 99.206304 -394.32738) (xy 105.828336 -394.32738) (xy 105.832407 -394.271758) (xy 105.844533 -394.217321)
			(xy 105.864456 -394.16523) (xy 105.891752 -394.116595) (xy 105.925838 -394.072452) (xy 105.965987 -394.033743)
			(xy 106.011345 -394.001292) (xy 106.060945 -393.975791) (xy 106.113729 -393.957784) (xy 106.168572 -393.947654)
			(xy 106.224306 -393.945617) (xy 106.279743 -393.951717) (xy 106.3337 -393.965823) (xy 106.385029 -393.987635)
			(xy 106.432635 -394.016689) (xy 106.475503 -394.052364) (xy 106.51272 -394.093901) (xy 106.543493 -394.140414)
			(xy 106.567165 -394.190911) (xy 106.583233 -394.244318) (xy 106.591353 -394.299494) (xy 106.591862 -394.32738)
			(xy 106.591353 -394.355266) (xy 106.583233 -394.410442) (xy 106.567165 -394.463849) (xy 106.543493 -394.514346)
			(xy 106.51272 -394.560859) (xy 106.475503 -394.602396) (xy 106.432635 -394.638071) (xy 106.385029 -394.667125)
			(xy 106.3337 -394.688937) (xy 106.279743 -394.703043) (xy 106.224306 -394.709143) (xy 106.168572 -394.707106)
			(xy 106.113729 -394.696976) (xy 106.060945 -394.678969) (xy 106.011345 -394.653468) (xy 105.965987 -394.621017)
			(xy 105.925838 -394.582308) (xy 105.891752 -394.538165) (xy 105.864456 -394.48953) (xy 105.844533 -394.437439)
			(xy 105.832407 -394.383002) (xy 105.828336 -394.32738) (xy 99.206304 -394.32738) (xy 99.206304 -394.738352)
			(xy 99.207057 -394.751017) (xy 99.219187 -394.773265) (xy 99.229418 -394.78077) (xy 99.300538 -394.827252)
			(xy 99.311495 -394.833577) (xy 99.336673 -394.835694) (xy 99.348544 -394.831316) (xy 99.372827 -394.821137)
			(xy 99.423486 -394.806786) (xy 99.475634 -394.799519) (xy 99.50196 -394.799058) (xy 99.529216 -394.799518)
			(xy 99.583173 -394.80727) (xy 99.635477 -394.822622) (xy 99.685065 -394.845262) (xy 99.730925 -394.874729)
			(xy 99.772126 -394.910422) (xy 99.807827 -394.951615) (xy 99.837302 -394.99747) (xy 99.859952 -395.047053)
			(xy 99.875314 -395.099355) (xy 99.883077 -395.15331) (xy 99.883468 -395.180566) (xy 99.883355 -395.18717)
			(xy 101.058724 -395.18717) (xy 101.062795 -395.131548) (xy 101.074921 -395.077111) (xy 101.094844 -395.02502)
			(xy 101.12214 -394.976385) (xy 101.156226 -394.932242) (xy 101.196375 -394.893533) (xy 101.241733 -394.861082)
			(xy 101.291333 -394.835581) (xy 101.344117 -394.817574) (xy 101.39896 -394.807444) (xy 101.454694 -394.805407)
			(xy 101.510131 -394.811507) (xy 101.564088 -394.825613) (xy 101.615417 -394.847425) (xy 101.663023 -394.876479)
			(xy 101.705891 -394.912154) (xy 101.743108 -394.953691) (xy 101.773881 -395.000204) (xy 101.797553 -395.050701)
			(xy 101.813621 -395.104108) (xy 101.821741 -395.159284) (xy 101.82225 -395.18717) (xy 101.821741 -395.215056)
			(xy 101.813621 -395.270232) (xy 101.797553 -395.323639) (xy 101.773881 -395.374136) (xy 101.743108 -395.420649)
			(xy 101.705891 -395.462186) (xy 101.663023 -395.497861) (xy 101.615417 -395.526915) (xy 101.564088 -395.548727)
			(xy 101.510131 -395.562833) (xy 101.454694 -395.568933) (xy 101.39896 -395.566896) (xy 101.344117 -395.556766)
			(xy 101.291333 -395.538759) (xy 101.241733 -395.513258) (xy 101.196375 -395.480807) (xy 101.156226 -395.442098)
			(xy 101.12214 -395.397955) (xy 101.094844 -395.34932) (xy 101.074921 -395.297229) (xy 101.062795 -395.242792)
			(xy 101.058724 -395.18717) (xy 99.883355 -395.18717) (xy 99.883008 -395.20747) (xy 99.87545 -395.260745)
			(xy 99.860478 -395.312428) (xy 99.83839 -395.361493) (xy 99.809625 -395.406967) (xy 99.774753 -395.447946)
			(xy 99.734467 -395.483616) (xy 99.712272 -395.498828) (xy 99.702874 -395.505178) (xy 99.690936 -395.524736)
			(xy 99.681792 -395.614398) (xy 99.681318 -395.625682) (xy 99.688961 -395.646905) (xy 99.696524 -395.655292)
			(xy 100.197158 -396.15618) (xy 100.228654 -396.161514) (xy 100.243132 -396.154656) (xy 100.268563 -396.143254)
			(xy 100.321927 -396.127183) (xy 100.377064 -396.119071) (xy 100.40493 -396.118588) (xy 100.405184 -396.118588)
			(xy 100.434173 -396.119127) (xy 100.491484 -396.127897) (xy 100.546808 -396.145238) (xy 100.598871 -396.17075)
			(xy 100.646475 -396.203846) (xy 100.688523 -396.243764) (xy 100.724047 -396.289584) (xy 100.752229 -396.340252)
			(xy 100.772419 -396.394601) (xy 100.778818 -396.42288) (xy 100.78172 -396.434194) (xy 100.79599 -396.452654)
			(xy 100.816936 -396.462936) (xy 100.828602 -396.46352) (xy 101.277166 -396.46352) (xy 101.288839 -396.46295)
			(xy 101.309799 -396.452673) (xy 101.324083 -396.434207) (xy 101.32695 -396.42288) (xy 101.332976 -396.396082)
			(xy 101.351691 -396.344442) (xy 101.377617 -396.29602) (xy 101.410219 -396.251816) (xy 101.448823 -396.212744)
			(xy 101.492631 -396.179612) (xy 101.540738 -396.153104) (xy 101.592148 -396.133768) (xy 101.6458 -396.122005)
			(xy 101.700584 -396.118056) (xy 101.755368 -396.122005) (xy 101.80902 -396.133768) (xy 101.86043 -396.153104)
			(xy 101.908537 -396.179612) (xy 101.952345 -396.212744) (xy 101.990949 -396.251816) (xy 102.023551 -396.29602)
			(xy 102.049477 -396.344442) (xy 102.068192 -396.396082) (xy 102.074218 -396.42288) (xy 102.07712 -396.434194)
			(xy 102.09139 -396.452654) (xy 102.112336 -396.462936) (xy 102.124002 -396.46352) (xy 102.572566 -396.46352)
			(xy 102.584239 -396.46295) (xy 102.605199 -396.452673) (xy 102.619483 -396.434207) (xy 102.62235 -396.42288)
			(xy 102.628376 -396.396082) (xy 102.647091 -396.344442) (xy 102.673017 -396.29602) (xy 102.705619 -396.251816)
			(xy 102.744223 -396.212744) (xy 102.788031 -396.179612) (xy 102.836138 -396.153104) (xy 102.887548 -396.133768)
			(xy 102.9412 -396.122005) (xy 102.995984 -396.118056) (xy 103.050768 -396.122005) (xy 103.10442 -396.133768)
			(xy 103.15583 -396.153104) (xy 103.203937 -396.179612) (xy 103.247745 -396.212744) (xy 103.286349 -396.251816)
			(xy 103.318951 -396.29602) (xy 103.344877 -396.344442) (xy 103.363592 -396.396082) (xy 103.369618 -396.42288)
			(xy 103.37252 -396.434194) (xy 103.38679 -396.452654) (xy 103.407736 -396.462936) (xy 103.419402 -396.46352)
			(xy 103.867966 -396.46352) (xy 103.879639 -396.46295) (xy 103.900599 -396.452673) (xy 103.914883 -396.434207)
			(xy 103.91775 -396.42288) (xy 103.923776 -396.396082) (xy 103.942491 -396.344442) (xy 103.968417 -396.29602)
			(xy 104.001019 -396.251816) (xy 104.039623 -396.212744) (xy 104.083431 -396.179612) (xy 104.131538 -396.153104)
			(xy 104.182948 -396.133768) (xy 104.2366 -396.122005) (xy 104.291384 -396.118056) (xy 104.346168 -396.122005)
			(xy 104.39982 -396.133768) (xy 104.45123 -396.153104) (xy 104.499337 -396.179612) (xy 104.543145 -396.212744)
			(xy 104.581749 -396.251816) (xy 104.614351 -396.29602) (xy 104.640277 -396.344442) (xy 104.658992 -396.396082)
			(xy 104.665018 -396.42288) (xy 104.66792 -396.434194) (xy 104.68219 -396.452654) (xy 104.703136 -396.462936)
			(xy 104.714802 -396.46352) (xy 106.641646 -396.46352) (xy 106.651712 -396.463952) (xy 106.670303 -396.47168)
			(xy 106.677714 -396.478506) (xy 107.733338 -397.53413) (xy 107.740186 -397.541527) (xy 107.74792 -397.560126)
			(xy 107.748324 -397.570198) (xy 107.748324 -399.299684) (xy 107.747818 -399.309734) (xy 107.740095 -399.328294)
			(xy 107.733338 -399.335752) (xy 107.245658 -399.823686) (xy 107.238258 -399.830527) (xy 107.21966 -399.838249)
			(xy 107.20959 -399.838672) (xy 98.394774 -399.838672) (xy 98.384706 -399.838244) (xy 98.366111 -399.830519)
			(xy 98.358706 -399.823686) (xy 94.720918 -396.185898) (xy 94.71407 -396.1785) (xy 94.706334 -396.159902)
			(xy 94.705932 -396.14983) (xy 94.705932 -368.991896) (xy 94.705528 -368.981911) (xy 94.697895 -368.963459)
			(xy 94.683762 -368.949352) (xy 94.67469 -368.94516) (xy 94.660466 -368.939064) (xy 94.63024 -368.94516)
			(xy 93.79839 -369.77701) (xy 93.791535 -369.784405) (xy 93.78379 -369.803004) (xy 93.783404 -369.813078)
			(xy 93.783404 -383.285746) (xy 93.782938 -383.3189) (xy 93.775513 -383.384791) (xy 93.760763 -383.449438)
			(xy 93.738871 -383.512028) (xy 93.710113 -383.571775) (xy 93.674851 -383.62793) (xy 93.633527 -383.679786)
			(xy 93.61043 -383.703576) (xy 92.811346 -384.50266) (xy 92.78557 -384.527717) (xy 92.72897 -384.572037)
			(xy 92.667405 -384.609153) (xy 92.634816 -384.624326) (xy 92.62618 -384.628136) (xy 92.61729 -384.637026)
			(xy 92.610438 -384.644421) (xy 92.602699 -384.663021) (xy 92.602304 -384.673094) (xy 92.602304 -384.94843)
			(xy 92.601875 -384.958498) (xy 92.594154 -384.977095) (xy 92.587318 -384.984498) (xy 92.579952 -384.991864)
			(xy 92.579952 -393.283186) (xy 92.579512 -393.293248) (xy 92.57177 -393.311825) (xy 92.564966 -393.319254)
			(xy 89.934542 -395.949932) (xy 89.927696 -395.95733) (xy 89.919967 -395.975929) (xy 89.919556 -395.986)
			(xy 89.919556 -396.214854) (xy 89.919749 -396.221727) (xy 89.923357 -396.23499) (xy 89.926668 -396.241016)
			(xy 89.942991 -396.269377) (xy 89.968709 -396.329549) (xy 89.986118 -396.392628) (xy 89.994903 -396.457473)
			(xy 89.994904 -396.52291) (xy 89.986122 -396.587755) (xy 89.968715 -396.650835) (xy 89.942998 -396.711007)
			(xy 89.926668 -396.739364) (xy 89.923356 -396.74539) (xy 89.919751 -396.758653) (xy 89.919556 -396.765526)
			(xy 89.919556 -397.514826) (xy 89.919746 -397.5217) (xy 89.923347 -397.534967) (xy 89.926668 -397.540988)
			(xy 89.936052 -397.557291) (xy 91.224968 -397.557291) (xy 91.233749 -397.492447) (xy 91.251154 -397.429369)
			(xy 91.276868 -397.369198) (xy 91.293188 -397.340836) (xy 91.296489 -397.334805) (xy 91.300104 -397.321546)
			(xy 91.3003 -397.314674) (xy 91.3003 -397.028924) (xy 91.300741 -397.018771) (xy 91.308529 -397.000019)
			(xy 91.32292 -396.985695) (xy 91.341708 -396.977995) (xy 91.351862 -396.977616) (xy 92.068142 -396.977616)
			(xy 92.078268 -396.978091) (xy 92.096986 -396.985829) (xy 92.11134 -397.000118) (xy 92.119162 -397.0188)
			(xy 92.119704 -397.028924) (xy 92.119704 -397.314674) (xy 92.119906 -397.321547) (xy 92.123507 -397.334809)
			(xy 92.126816 -397.340836) (xy 92.143148 -397.369192) (xy 92.168867 -397.429364) (xy 92.186276 -397.492444)
			(xy 92.195059 -397.55729) (xy 92.195058 -397.622728) (xy 92.186273 -397.687573) (xy 92.168862 -397.750652)
			(xy 92.14314 -397.810823) (xy 92.126816 -397.839184) (xy 92.123508 -397.845212) (xy 92.119898 -397.858473)
			(xy 92.119704 -397.865346) (xy 92.119704 -398.6149) (xy 92.119895 -398.621773) (xy 92.123504 -398.635036)
			(xy 92.126816 -398.641062) (xy 92.14317 -398.669406) (xy 92.168887 -398.729581) (xy 92.186294 -398.792663)
			(xy 92.195074 -398.857511) (xy 92.19507 -398.922951) (xy 92.186281 -398.987798) (xy 92.168867 -399.050878)
			(xy 92.143142 -399.111049) (xy 92.126816 -399.13941) (xy 92.123499 -399.145433) (xy 92.119894 -399.158698)
			(xy 92.119704 -399.165572) (xy 92.119704 -399.451576) (xy 92.119259 -399.461728) (xy 92.111472 -399.480479)
			(xy 92.097082 -399.494803) (xy 92.078296 -399.502505) (xy 92.068142 -399.502884) (xy 91.351862 -399.502884)
			(xy 91.341736 -399.502405) (xy 91.323018 -399.494669) (xy 91.308664 -399.480381) (xy 91.300842 -399.4617)
			(xy 91.3003 -399.451576) (xy 91.3003 -399.165572) (xy 91.300119 -399.158698) (xy 91.296503 -399.145435)
			(xy 91.293188 -399.13941) (xy 91.276898 -399.111031) (xy 91.25118 -399.050864) (xy 91.23377 -398.987789)
			(xy 91.224984 -398.922948) (xy 91.22498 -398.857514) (xy 91.233758 -398.792672) (xy 91.25116 -398.729595)
			(xy 91.27687 -398.669424) (xy 91.293188 -398.641062) (xy 91.296515 -398.635044) (xy 91.300113 -398.621775)
			(xy 91.3003 -398.6149) (xy 91.3003 -397.865346) (xy 91.30009 -397.858474) (xy 91.296494 -397.845211)
			(xy 91.293188 -397.839184) (xy 91.276876 -397.810818) (xy 91.25116 -397.750647) (xy 91.233753 -397.687569)
			(xy 91.224969 -397.622726) (xy 91.224968 -397.557291) (xy 89.936052 -397.557291) (xy 89.942993 -397.569349)
			(xy 89.968715 -397.629521) (xy 89.986128 -397.692601) (xy 89.994916 -397.757448) (xy 89.99492 -397.822887)
			(xy 89.986141 -397.887735) (xy 89.968736 -397.950817) (xy 89.943022 -398.010992) (xy 89.926668 -398.039336)
			(xy 89.923353 -398.045361) (xy 89.91974 -398.058624) (xy 89.919556 -398.065498) (xy 89.919556 -398.351502)
			(xy 89.91913 -398.361673) (xy 89.911344 -398.380466) (xy 89.896959 -398.394849) (xy 89.878165 -398.402631)
			(xy 89.867994 -398.403064) (xy 89.53246 -398.403064) (xy 89.522455 -398.403558) (xy 89.503971 -398.411224)
			(xy 89.489822 -398.425374) (xy 89.482158 -398.443859) (xy 89.48166 -398.453864) (xy 89.48166 -399.833846)
			(xy 89.482087 -399.843546) (xy 89.489262 -399.86157) (xy 89.49563 -399.868898) (xy 89.516458 -399.890488)
			(xy 89.523089 -399.896976) (xy 89.539768 -399.905059) (xy 89.54897 -399.906236) (xy 89.580292 -399.909265)
			(xy 89.641837 -399.922393) (xy 89.701169 -399.943364) (xy 89.757293 -399.971826) (xy 89.80927 -400.007301)
			(xy 89.856226 -400.049196) (xy 89.897375 -400.096808) (xy 89.932026 -400.149337) (xy 89.959599 -400.205904)
			(xy 89.97963 -400.26556) (xy 89.991785 -400.327304) (xy 89.99586 -400.3901) (xy 89.991785 -400.452897)
			(xy 89.97963 -400.514641) (xy 89.959598 -400.574297) (xy 89.932025 -400.630864) (xy 89.897374 -400.683393)
			(xy 89.856225 -400.731004) (xy 89.809269 -400.772899) (xy 89.757293 -400.808375) (xy 89.701168 -400.836837)
			(xy 89.641836 -400.857807) (xy 89.580291 -400.870935) (xy 89.54897 -400.873976) (xy 89.539792 -400.875225)
			(xy 89.523138 -400.883305) (xy 89.516458 -400.889724) (xy 89.49563 -400.911314) (xy 89.489248 -400.918635)
			(xy 89.482063 -400.936662) (xy 89.48166 -400.946366) (xy 89.48166 -401.133818) (xy 89.482082 -401.14352)
			(xy 89.489249 -401.161551) (xy 89.49563 -401.16887) (xy 89.516458 -401.19046) (xy 89.523088 -401.196951)
			(xy 89.539767 -401.205038) (xy 89.54897 -401.206208) (xy 89.578995 -401.209079) (xy 89.638056 -401.221322)
			(xy 89.695145 -401.24079) (xy 89.749382 -401.267181) (xy 89.799931 -401.30009) (xy 89.846012 -401.339009)
			(xy 89.886915 -401.383337) (xy 89.922011 -401.432393) (xy 89.950757 -401.485419) (xy 89.952618 -401.49018)
			(xy 91.223854 -401.49018) (xy 91.227845 -401.428013) (xy 91.239754 -401.366866) (xy 91.259383 -401.307745)
			(xy 91.286412 -401.251619) (xy 91.320396 -401.19941) (xy 91.360778 -401.151975) (xy 91.406894 -401.110094)
			(xy 91.457986 -401.074454) (xy 91.513217 -401.04564) (xy 91.571679 -401.024126) (xy 91.632413 -401.010264)
			(xy 91.69442 -401.004282) (xy 91.756683 -401.006278) (xy 91.81818 -401.016221) (xy 91.877901 -401.033945)
			(xy 91.934864 -401.059162) (xy 91.988135 -401.091455) (xy 92.03684 -401.130295) (xy 92.080177 -401.175045)
			(xy 92.117437 -401.224969) (xy 92.148006 -401.279248) (xy 92.171384 -401.336991) (xy 92.187185 -401.397249)
			(xy 92.195151 -401.459032) (xy 92.19565 -401.49018) (xy 92.195151 -401.521328) (xy 92.187185 -401.583111)
			(xy 92.171384 -401.643369) (xy 92.148006 -401.701112) (xy 92.135792 -401.7228) (xy 115.425055 -401.7228)
			(xy 115.425057 -401.657362) (xy 115.433842 -401.592517) (xy 115.451252 -401.529438) (xy 115.47697 -401.469266)
			(xy 115.493292 -401.440904) (xy 115.496605 -401.434878) (xy 115.500212 -401.421615) (xy 115.500404 -401.414742)
			(xy 115.500404 -400.665442) (xy 115.500195 -400.65857) (xy 115.496598 -400.645307) (xy 115.493292 -400.63928)
			(xy 115.476976 -400.610915) (xy 115.451261 -400.550745) (xy 115.433854 -400.487667) (xy 115.42507 -400.422823)
			(xy 115.42507 -400.357387) (xy 115.433852 -400.292544) (xy 115.451257 -400.229465) (xy 115.476972 -400.169294)
			(xy 115.493292 -400.140932) (xy 115.496595 -400.134902) (xy 115.500208 -400.121642) (xy 115.500404 -400.11477)
			(xy 115.500404 -399.828766) (xy 115.500905 -399.81861) (xy 115.508684 -399.799847) (xy 115.523047 -399.785484)
			(xy 115.54181 -399.777705) (xy 115.551966 -399.777204) (xy 116.268246 -399.777204) (xy 116.278403 -399.777695)
			(xy 116.297166 -399.785478) (xy 116.311529 -399.799844) (xy 116.319307 -399.818609) (xy 116.319808 -399.828766)
			(xy 116.319808 -400.11477) (xy 116.320011 -400.121642) (xy 116.323612 -400.134905) (xy 116.32692 -400.140932)
			(xy 116.343249 -400.16929) (xy 116.368968 -400.229461) (xy 116.386377 -400.292541) (xy 116.395161 -400.357386)
			(xy 116.39516 -400.422824) (xy 116.386375 -400.487669) (xy 116.368964 -400.550748) (xy 116.343244 -400.610919)
			(xy 116.32692 -400.63928) (xy 116.323614 -400.645309) (xy 116.320002 -400.658569) (xy 116.319808 -400.665442)
			(xy 116.319808 -401.414742) (xy 116.320021 -401.421614) (xy 116.323615 -401.434876) (xy 116.32692 -401.440904)
			(xy 116.343225 -401.469275) (xy 116.368946 -401.529444) (xy 116.386358 -401.59252) (xy 116.395145 -401.657363)
			(xy 116.395147 -401.722799) (xy 116.386366 -401.787643) (xy 116.368959 -401.850721) (xy 116.343242 -401.910891)
			(xy 116.32692 -401.939252) (xy 116.323588 -401.945268) (xy 116.319993 -401.958538) (xy 116.319808 -401.965414)
			(xy 116.319808 -402.251418) (xy 116.319283 -402.261571) (xy 116.311511 -402.280332) (xy 116.297156 -402.294695)
			(xy 116.278399 -402.302477) (xy 116.268246 -402.30298) (xy 115.551966 -402.30298) (xy 115.541808 -402.302495)
			(xy 115.523042 -402.294713) (xy 115.508678 -402.280345) (xy 115.500902 -402.261576) (xy 115.500404 -402.251418)
			(xy 115.500404 -401.965414) (xy 115.500206 -401.958541) (xy 115.496602 -401.945278) (xy 115.493292 -401.939252)
			(xy 115.476953 -401.910901) (xy 115.451239 -401.850727) (xy 115.433835 -401.787646) (xy 115.425055 -401.7228)
			(xy 92.135792 -401.7228) (xy 92.117437 -401.755391) (xy 92.080177 -401.805315) (xy 92.03684 -401.850065)
			(xy 91.988135 -401.888905) (xy 91.934864 -401.921198) (xy 91.877901 -401.946415) (xy 91.81818 -401.964139)
			(xy 91.756683 -401.974082) (xy 91.69442 -401.976078) (xy 91.632413 -401.970096) (xy 91.571679 -401.956234)
			(xy 91.513217 -401.93472) (xy 91.457986 -401.905906) (xy 91.406894 -401.870266) (xy 91.360778 -401.828385)
			(xy 91.320396 -401.78095) (xy 91.286412 -401.728741) (xy 91.259383 -401.672615) (xy 91.239754 -401.613494)
			(xy 91.227845 -401.552347) (xy 91.223854 -401.49018) (xy 89.952618 -401.49018) (xy 89.972711 -401.541599)
			(xy 89.987534 -401.600066) (xy 89.994999 -401.659919) (xy 89.995502 -401.690078) (xy 89.995006 -401.721876)
			(xy 89.986707 -401.784929) (xy 89.970248 -401.846359) (xy 89.945912 -401.905115) (xy 89.914113 -401.960191)
			(xy 89.875397 -402.010645) (xy 89.830427 -402.055613) (xy 89.779971 -402.094327) (xy 89.724893 -402.126122)
			(xy 89.666136 -402.150456) (xy 89.604705 -402.166912) (xy 89.541652 -402.175207) (xy 89.509854 -402.175726)
			(xy 89.509346 -402.175726) (xy 89.497132 -402.175632) (xy 89.472736 -402.174364) (xy 89.460578 -402.173186)
			(xy 89.449618 -402.172632) (xy 89.428869 -402.179713) (xy 89.412905 -402.194741) (xy 89.408254 -402.204682)
			(xy 89.391343 -402.245026) (xy 89.351412 -402.322864) (xy 89.3048 -402.396897) (xy 89.278714 -402.432012)
			(xy 89.275412 -402.436838) (xy 89.26283 -402.457305) (xy 89.233292 -402.495198) (xy 89.199219 -402.529071)
			(xy 89.180416 -402.544026) (xy 89.17559 -402.548344) (xy 88.933782 -402.790152) (xy 91.223854 -402.790152)
			(xy 91.227845 -402.727985) (xy 91.239754 -402.666838) (xy 91.259383 -402.607717) (xy 91.286412 -402.551591)
			(xy 91.320396 -402.499382) (xy 91.360778 -402.451947) (xy 91.406894 -402.410066) (xy 91.457986 -402.374426)
			(xy 91.513217 -402.345612) (xy 91.571679 -402.324098) (xy 91.632413 -402.310236) (xy 91.69442 -402.304254)
			(xy 91.756683 -402.30625) (xy 91.81818 -402.316193) (xy 91.877901 -402.333917) (xy 91.934864 -402.359134)
			(xy 91.988135 -402.391427) (xy 92.03684 -402.430267) (xy 92.080177 -402.475017) (xy 92.117437 -402.524941)
			(xy 92.148006 -402.57922) (xy 92.171384 -402.636963) (xy 92.187185 -402.697221) (xy 92.195151 -402.759004)
			(xy 92.19565 -402.790152) (xy 117.624352 -402.790152) (xy 117.624925 -402.757423) (xy 117.63378 -402.692565)
			(xy 117.651268 -402.629485) (xy 117.677073 -402.569326) (xy 117.69344 -402.540978) (xy 117.696758 -402.534955)
			(xy 117.700362 -402.52169) (xy 117.700552 -402.514816) (xy 117.700552 -401.765516) (xy 117.70036 -401.758643)
			(xy 117.696752 -401.74538) (xy 117.69344 -401.739354) (xy 117.67706 -401.711013) (xy 117.651261 -401.650851)
			(xy 117.633775 -401.587769) (xy 117.62492 -401.52291) (xy 117.624352 -401.49018) (xy 117.624937 -401.457451)
			(xy 117.633788 -401.392594) (xy 117.651273 -401.329514) (xy 117.677074 -401.269355) (xy 117.69344 -401.241006)
			(xy 117.696748 -401.234978) (xy 117.700359 -401.221717) (xy 117.700552 -401.214844) (xy 117.700552 -400.92884)
			(xy 117.701117 -400.91874) (xy 117.708832 -400.900072) (xy 117.723105 -400.885777) (xy 117.741761 -400.878033)
			(xy 117.75186 -400.877532) (xy 118.46814 -400.877532) (xy 118.478255 -400.877953) (xy 118.49694 -400.88571)
			(xy 118.511235 -400.900027) (xy 118.518963 -400.918724) (xy 118.519448 -400.92884) (xy 118.519448 -401.214844)
			(xy 118.519655 -401.221716) (xy 118.523252 -401.234979) (xy 118.52656 -401.241006) (xy 118.542924 -401.269356)
			(xy 118.568727 -401.329515) (xy 118.586217 -401.392594) (xy 118.595078 -401.457451) (xy 118.595648 -401.49018)
			(xy 118.595089 -401.52291) (xy 118.58623 -401.587768) (xy 118.568738 -401.650848) (xy 118.542929 -401.711006)
			(xy 118.52656 -401.739354) (xy 118.523266 -401.745389) (xy 118.519647 -401.758645) (xy 118.519448 -401.765516)
			(xy 118.519448 -402.514816) (xy 118.519628 -402.52169) (xy 118.523244 -402.534953) (xy 118.52656 -402.540978)
			(xy 118.542913 -402.569334) (xy 118.568719 -402.629491) (xy 118.586212 -402.692568) (xy 118.595076 -402.757424)
			(xy 118.595648 -402.790152) (xy 118.595077 -402.822879) (xy 122.024971 -402.822879) (xy 122.024976 -402.757439)
			(xy 122.033766 -402.692592) (xy 122.051179 -402.629512) (xy 122.076903 -402.569339) (xy 122.093228 -402.540978)
			(xy 122.096553 -402.534958) (xy 122.100151 -402.521691) (xy 122.10034 -402.514816) (xy 122.10034 -401.765516)
			(xy 122.100137 -401.758644) (xy 122.096536 -401.745381) (xy 122.093228 -401.739354) (xy 122.076889 -401.711002)
			(xy 122.051174 -401.650829) (xy 122.033768 -401.587748) (xy 122.024987 -401.522902) (xy 122.024989 -401.457464)
			(xy 122.033775 -401.392618) (xy 122.051185 -401.329539) (xy 122.076905 -401.269367) (xy 122.093228 -401.241006)
			(xy 122.096543 -401.234981) (xy 122.100148 -401.221718) (xy 122.10034 -401.214844) (xy 122.10034 -400.92884)
			(xy 122.100755 -400.918684) (xy 122.108545 -400.899924) (xy 122.122945 -400.885598) (xy 122.141743 -400.877904)
			(xy 122.151902 -400.877532) (xy 122.868182 -400.877532) (xy 122.878307 -400.878041) (xy 122.897026 -400.885761)
			(xy 122.911383 -400.900041) (xy 122.919204 -400.918718) (xy 122.919744 -400.92884) (xy 122.919744 -401.214844)
			(xy 122.919952 -401.221716) (xy 122.923549 -401.234979) (xy 122.926856 -401.241006) (xy 122.943161 -401.269377)
			(xy 122.968881 -401.329545) (xy 122.986291 -401.392622) (xy 122.995077 -401.457465) (xy 122.995079 -401.522901)
			(xy 122.986298 -401.587744) (xy 122.968892 -401.650822) (xy 122.943177 -401.710993) (xy 122.926856 -401.739354)
			(xy 122.923562 -401.745389) (xy 122.919943 -401.758645) (xy 122.919744 -401.765516) (xy 122.919744 -402.514816)
			(xy 122.919924 -402.52169) (xy 122.92354 -402.534953) (xy 122.926856 -402.540978) (xy 122.943138 -402.569362)
			(xy 122.968859 -402.629528) (xy 122.986272 -402.692602) (xy 122.995061 -402.757442) (xy 122.995063 -402.790152)
			(xy 126.424436 -402.790152) (xy 126.425011 -402.757423) (xy 126.433866 -402.692565) (xy 126.451353 -402.629485)
			(xy 126.477157 -402.569327) (xy 126.493524 -402.540978) (xy 126.496848 -402.534958) (xy 126.500447 -402.521691)
			(xy 126.500636 -402.514816) (xy 126.500636 -401.765516) (xy 126.500433 -401.758644) (xy 126.496832 -401.745381)
			(xy 126.493524 -401.739354) (xy 126.477142 -401.711014) (xy 126.451344 -401.650851) (xy 126.433859 -401.587769)
			(xy 126.425003 -401.52291) (xy 126.424436 -401.49018) (xy 126.425024 -401.457451) (xy 126.433874 -401.392594)
			(xy 126.451358 -401.329514) (xy 126.477159 -401.269355) (xy 126.493524 -401.241006) (xy 126.496838 -401.234981)
			(xy 126.500444 -401.221718) (xy 126.500636 -401.214844) (xy 126.500636 -400.92884) (xy 126.50105 -400.918716)
			(xy 126.508791 -400.900006) (xy 126.523109 -400.885689) (xy 126.54182 -400.877949) (xy 126.551944 -400.877532)
			(xy 127.268224 -400.877532) (xy 127.278352 -400.877897) (xy 127.297062 -400.885659) (xy 127.311377 -400.899991)
			(xy 127.319116 -400.918711) (xy 127.319532 -400.92884) (xy 127.319532 -401.214844) (xy 127.319741 -401.221716)
			(xy 127.323337 -401.234979) (xy 127.326644 -401.241006) (xy 127.343007 -401.269357) (xy 127.36881 -401.329515)
			(xy 127.386301 -401.392594) (xy 127.395162 -401.457451) (xy 127.395732 -401.49018) (xy 127.395176 -401.52291)
			(xy 127.386316 -401.587768) (xy 127.368823 -401.650848) (xy 127.343014 -401.711006) (xy 127.326644 -401.739354)
			(xy 127.323349 -401.745388) (xy 127.31973 -401.758645) (xy 127.319532 -401.765516) (xy 127.319532 -402.514816)
			(xy 127.319714 -402.52169) (xy 127.323329 -402.534953) (xy 127.326644 -402.540978) (xy 127.342995 -402.569335)
			(xy 127.368802 -402.629491) (xy 127.386296 -402.692568) (xy 127.39516 -402.757424) (xy 127.395732 -402.790152)
			(xy 127.395163 -402.822879) (xy 130.825057 -402.822879) (xy 130.825062 -402.757439) (xy 130.833851 -402.692592)
			(xy 130.851265 -402.629512) (xy 130.876987 -402.56934) (xy 130.893312 -402.540978) (xy 130.896635 -402.534958)
			(xy 130.900235 -402.521691) (xy 130.900424 -402.514816) (xy 130.900424 -401.765516) (xy 130.900223 -401.758643)
			(xy 130.896621 -401.745381) (xy 130.893312 -401.739354) (xy 130.876974 -401.711002) (xy 130.851259 -401.650828)
			(xy 130.833854 -401.587748) (xy 130.825073 -401.522902) (xy 130.825075 -401.457464) (xy 130.833861 -401.392619)
			(xy 130.85127 -401.329539) (xy 130.876989 -401.269368) (xy 130.893312 -401.241006) (xy 130.896625 -401.234981)
			(xy 130.900232 -401.221717) (xy 130.900424 -401.214844) (xy 130.900424 -400.92884) (xy 130.900855 -400.918686)
			(xy 130.908642 -400.899929) (xy 130.923036 -400.885604) (xy 130.94183 -400.877907) (xy 130.951986 -400.877532)
			(xy 131.668266 -400.877532) (xy 131.67839 -400.878054) (xy 131.697108 -400.88577) (xy 131.711465 -400.900045)
			(xy 131.719287 -400.918719) (xy 131.719828 -400.92884) (xy 131.719828 -401.214844) (xy 131.720038 -401.221716)
			(xy 131.723634 -401.234979) (xy 131.72694 -401.241006) (xy 131.743246 -401.269376) (xy 131.768966 -401.329545)
			(xy 131.786377 -401.392622) (xy 131.795163 -401.457465) (xy 131.795165 -401.522901) (xy 131.786384 -401.587744)
			(xy 131.768978 -401.650822) (xy 131.752201 -401.690078) (xy 133.023872 -401.690078) (xy 133.027863 -401.627911)
			(xy 133.039772 -401.566764) (xy 133.059401 -401.507643) (xy 133.08643 -401.451517) (xy 133.120414 -401.399308)
			(xy 133.160796 -401.351873) (xy 133.206912 -401.309992) (xy 133.258004 -401.274352) (xy 133.313235 -401.245538)
			(xy 133.371697 -401.224024) (xy 133.432431 -401.210162) (xy 133.494438 -401.20418) (xy 133.556701 -401.206176)
			(xy 133.618198 -401.216119) (xy 133.677919 -401.233843) (xy 133.734882 -401.25906) (xy 133.788153 -401.291353)
			(xy 133.836858 -401.330193) (xy 133.880195 -401.374943) (xy 133.917455 -401.424867) (xy 133.948024 -401.479146)
			(xy 133.952491 -401.49018) (xy 135.22402 -401.49018) (xy 135.228011 -401.428013) (xy 135.23992 -401.366866)
			(xy 135.259549 -401.307745) (xy 135.286578 -401.251619) (xy 135.320562 -401.19941) (xy 135.360944 -401.151975)
			(xy 135.40706 -401.110094) (xy 135.458152 -401.074454) (xy 135.513383 -401.04564) (xy 135.571845 -401.024126)
			(xy 135.632579 -401.010264) (xy 135.694586 -401.004282) (xy 135.756849 -401.006278) (xy 135.818346 -401.016221)
			(xy 135.878067 -401.033945) (xy 135.93503 -401.059162) (xy 135.988301 -401.091455) (xy 136.037006 -401.130295)
			(xy 136.080343 -401.175045) (xy 136.117603 -401.224969) (xy 136.148172 -401.279248) (xy 136.17155 -401.336991)
			(xy 136.187351 -401.397249) (xy 136.195317 -401.459032) (xy 136.195816 -401.49018) (xy 136.195317 -401.521328)
			(xy 136.187351 -401.583111) (xy 136.17155 -401.643369) (xy 136.148172 -401.701112) (xy 136.117603 -401.755391)
			(xy 136.080343 -401.805315) (xy 136.037006 -401.850065) (xy 135.988301 -401.888905) (xy 135.93503 -401.921198)
			(xy 135.878067 -401.946415) (xy 135.818346 -401.964139) (xy 135.756849 -401.974082) (xy 135.694586 -401.976078)
			(xy 135.632579 -401.970096) (xy 135.571845 -401.956234) (xy 135.513383 -401.93472) (xy 135.458152 -401.905906)
			(xy 135.40706 -401.870266) (xy 135.360944 -401.828385) (xy 135.320562 -401.78095) (xy 135.286578 -401.728741)
			(xy 135.259549 -401.672615) (xy 135.23992 -401.613494) (xy 135.228011 -401.552347) (xy 135.22402 -401.49018)
			(xy 133.952491 -401.49018) (xy 133.971402 -401.536889) (xy 133.987203 -401.597147) (xy 133.995169 -401.65893)
			(xy 133.995668 -401.690078) (xy 133.995169 -401.721226) (xy 133.987203 -401.783009) (xy 133.971402 -401.843267)
			(xy 133.948024 -401.90101) (xy 133.917455 -401.955289) (xy 133.880195 -402.005213) (xy 133.836858 -402.049963)
			(xy 133.788153 -402.088803) (xy 133.734882 -402.121096) (xy 133.677919 -402.146313) (xy 133.618198 -402.164037)
			(xy 133.556701 -402.17398) (xy 133.494438 -402.175976) (xy 133.432431 -402.169994) (xy 133.371697 -402.156132)
			(xy 133.313235 -402.134618) (xy 133.258004 -402.105804) (xy 133.206912 -402.070164) (xy 133.160796 -402.028283)
			(xy 133.120414 -401.980848) (xy 133.08643 -401.928639) (xy 133.059401 -401.872513) (xy 133.039772 -401.813392)
			(xy 133.027863 -401.752245) (xy 133.023872 -401.690078) (xy 131.752201 -401.690078) (xy 131.743262 -401.710993)
			(xy 131.72694 -401.739354) (xy 131.723645 -401.745388) (xy 131.720026 -401.758645) (xy 131.719828 -401.765516)
			(xy 131.719828 -402.514816) (xy 131.720011 -402.52169) (xy 131.723625 -402.534953) (xy 131.72694 -402.540978)
			(xy 131.743222 -402.569361) (xy 131.768945 -402.629527) (xy 131.786358 -402.692601) (xy 131.795147 -402.757442)
			(xy 131.79515 -402.790152) (xy 135.22402 -402.790152) (xy 135.228011 -402.727985) (xy 135.23992 -402.666838)
			(xy 135.259549 -402.607717) (xy 135.286578 -402.551591) (xy 135.320562 -402.499382) (xy 135.360944 -402.451947)
			(xy 135.40706 -402.410066) (xy 135.458152 -402.374426) (xy 135.513383 -402.345612) (xy 135.571845 -402.324098)
			(xy 135.632579 -402.310236) (xy 135.694586 -402.304254) (xy 135.756849 -402.30625) (xy 135.818346 -402.316193)
			(xy 135.878067 -402.333917) (xy 135.93503 -402.359134) (xy 135.988301 -402.391427) (xy 136.037006 -402.430267)
			(xy 136.080343 -402.475017) (xy 136.117603 -402.524941) (xy 136.148172 -402.57922) (xy 136.17155 -402.636963)
			(xy 136.187351 -402.697221) (xy 136.195317 -402.759004) (xy 136.195816 -402.790152) (xy 136.195317 -402.8213)
			(xy 136.187351 -402.883083) (xy 136.17155 -402.943341) (xy 136.148172 -403.001084) (xy 136.117603 -403.055363)
			(xy 136.080343 -403.105287) (xy 136.037006 -403.150037) (xy 135.988301 -403.188877) (xy 135.93503 -403.22117)
			(xy 135.878067 -403.246387) (xy 135.818346 -403.264111) (xy 135.756849 -403.274054) (xy 135.694586 -403.27605)
			(xy 135.632579 -403.270068) (xy 135.571845 -403.256206) (xy 135.513383 -403.234692) (xy 135.458152 -403.205878)
			(xy 135.40706 -403.170238) (xy 135.360944 -403.128357) (xy 135.320562 -403.080922) (xy 135.286578 -403.028713)
			(xy 135.259549 -402.972587) (xy 135.23992 -402.913466) (xy 135.228011 -402.852319) (xy 135.22402 -402.790152)
			(xy 131.79515 -402.790152) (xy 131.795153 -402.822876) (xy 131.786375 -402.887718) (xy 131.768972 -402.950795)
			(xy 131.74326 -403.010965) (xy 131.72694 -403.039326) (xy 131.723619 -403.045348) (xy 131.720017 -403.058614)
			(xy 131.719828 -403.065488) (xy 131.719828 -403.351492) (xy 131.719372 -403.361642) (xy 131.711585 -403.380389)
			(xy 131.697199 -403.394712) (xy 131.678418 -403.402417) (xy 131.668266 -403.4028) (xy 130.951986 -403.4028)
			(xy 130.941863 -403.402286) (xy 130.92315 -403.394561) (xy 130.908795 -403.380284) (xy 130.90097 -403.361612)
			(xy 130.900424 -403.351492) (xy 130.900424 -403.065488) (xy 130.900234 -403.058615) (xy 130.896624 -403.045352)
			(xy 130.893312 -403.039326) (xy 130.87695 -403.010987) (xy 130.851238 -402.95081) (xy 130.833835 -402.887727)
			(xy 130.825057 -402.822879) (xy 127.395163 -402.822879) (xy 127.395163 -402.822881) (xy 127.386308 -402.887739)
			(xy 127.368818 -402.95082) (xy 127.343012 -403.010978) (xy 127.326644 -403.039326) (xy 127.323324 -403.045348)
			(xy 127.319721 -403.058614) (xy 127.319532 -403.065488) (xy 127.319532 -403.351492) (xy 127.319009 -403.361596)
			(xy 127.31128 -403.380268) (xy 127.296995 -403.394562) (xy 127.278328 -403.402303) (xy 127.268224 -403.4028)
			(xy 126.551944 -403.4028) (xy 126.541824 -403.402348) (xy 126.523122 -403.394614) (xy 126.508806 -403.380308)
			(xy 126.501059 -403.361611) (xy 126.500636 -403.351492) (xy 126.500636 -403.065488) (xy 126.500444 -403.058615)
			(xy 126.496835 -403.045352) (xy 126.493524 -403.039326) (xy 126.477171 -403.01097) (xy 126.451366 -402.950813)
			(xy 126.433872 -402.887736) (xy 126.425008 -402.82288) (xy 126.424436 -402.790152) (xy 122.995063 -402.790152)
			(xy 122.995066 -402.822876) (xy 122.986289 -402.887718) (xy 122.968887 -402.950795) (xy 122.943175 -403.010965)
			(xy 122.926856 -403.039326) (xy 122.923536 -403.045348) (xy 122.919933 -403.058614) (xy 122.919744 -403.065488)
			(xy 122.919744 -403.351492) (xy 122.919273 -403.36164) (xy 122.911488 -403.380384) (xy 122.897107 -403.394706)
			(xy 122.878332 -403.402414) (xy 122.868182 -403.4028) (xy 122.151902 -403.4028) (xy 122.14178 -403.402273)
			(xy 122.123067 -403.394553) (xy 122.108712 -403.38028) (xy 122.100886 -403.361611) (xy 122.10034 -403.351492)
			(xy 122.10034 -403.065488) (xy 122.100148 -403.058615) (xy 122.096539 -403.045352) (xy 122.093228 -403.039326)
			(xy 122.076865 -403.010987) (xy 122.051152 -402.950811) (xy 122.033749 -402.887727) (xy 122.024971 -402.822879)
			(xy 118.595077 -402.822879) (xy 118.595077 -402.822881) (xy 118.586222 -402.887739) (xy 118.568733 -402.950819)
			(xy 118.542928 -403.010978) (xy 118.52656 -403.039326) (xy 118.523241 -403.045348) (xy 118.519637 -403.058614)
			(xy 118.519448 -403.065488) (xy 118.519448 -403.351492) (xy 118.51891 -403.361594) (xy 118.511183 -403.380263)
			(xy 118.496903 -403.394557) (xy 118.478242 -403.4023) (xy 118.46814 -403.4028) (xy 117.75186 -403.4028)
			(xy 117.741749 -403.402348) (xy 117.72307 -403.394597) (xy 117.708776 -403.38029) (xy 117.701043 -403.361604)
			(xy 117.700552 -403.351492) (xy 117.700552 -403.065488) (xy 117.700371 -403.058614) (xy 117.696756 -403.045351)
			(xy 117.69344 -403.039326) (xy 117.677089 -403.010969) (xy 117.651282 -402.950813) (xy 117.633789 -402.887735)
			(xy 117.624924 -402.82288) (xy 117.624352 -402.790152) (xy 92.19565 -402.790152) (xy 92.195151 -402.8213)
			(xy 92.187185 -402.883083) (xy 92.171384 -402.943341) (xy 92.148006 -403.001084) (xy 92.117437 -403.055363)
			(xy 92.080177 -403.105287) (xy 92.03684 -403.150037) (xy 91.988135 -403.188877) (xy 91.934864 -403.22117)
			(xy 91.877901 -403.246387) (xy 91.81818 -403.264111) (xy 91.756683 -403.274054) (xy 91.69442 -403.27605)
			(xy 91.632413 -403.270068) (xy 91.571679 -403.256206) (xy 91.513217 -403.234692) (xy 91.457986 -403.205878)
			(xy 91.406894 -403.170238) (xy 91.360778 -403.128357) (xy 91.320396 -403.080922) (xy 91.286412 -403.028713)
			(xy 91.259383 -402.972587) (xy 91.239754 -402.913466) (xy 91.227845 -402.852319) (xy 91.223854 -402.790152)
			(xy 88.933782 -402.790152) (xy 88.737694 -402.98624) (xy 88.706798 -403.016493) (xy 88.640593 -403.07213)
			(xy 88.569819 -403.121825) (xy 88.495007 -403.165204) (xy 88.416721 -403.201942) (xy 88.335547 -403.231763)
			(xy 88.252095 -403.254443) (xy 88.209628 -403.262592) (xy 88.198758 -403.26515) (xy 88.180571 -403.278063)
			(xy 88.174576 -403.287484) (xy 88.152435 -403.32501) (xy 88.102535 -403.396443) (xy 88.046596 -403.463253)
			(xy 87.985044 -403.52493) (xy 87.918347 -403.581005) (xy 87.847015 -403.631049) (xy 87.77159 -403.674683)
			(xy 87.692648 -403.711572) (xy 87.61079 -403.741437) (xy 87.526638 -403.76405) (xy 87.440836 -403.779239)
			(xy 87.354036 -403.786887) (xy 87.310468 -403.787356) (xy 87.30996 -403.787356) (xy 87.268794 -403.786955)
			(xy 87.186738 -403.780208) (xy 87.105519 -403.766715) (xy 87.02569 -403.746567) (xy 86.947795 -403.719901)
			(xy 86.90991 -403.70379) (xy 86.901081 -403.700346) (xy 86.882159 -403.699552) (xy 86.87308 -403.702266)
			(xy 86.842838 -403.71208) (xy 86.780153 -403.72268) (xy 86.748366 -403.723348) (xy 86.747858 -403.723348)
			(xy 86.720608 -403.722859) (xy 86.666662 -403.715098) (xy 86.61437 -403.69974) (xy 86.564796 -403.677097)
			(xy 86.518948 -403.64763) (xy 86.477759 -403.611939) (xy 86.442069 -403.570751) (xy 86.412602 -403.524902)
			(xy 86.389959 -403.475328) (xy 86.374601 -403.423036) (xy 86.36684 -403.36909) (xy 86.36635 -403.34184)
			(xy 86.36635 -403.341586) (xy 86.367062 -403.307982) (xy 86.378817 -403.241809) (xy 86.389718 -403.210014)
			(xy 86.39265 -403.200935) (xy 86.392273 -403.181874) (xy 86.388956 -403.17293) (xy 86.370694 -403.127403)
			(xy 86.342164 -403.033542) (xy 86.322984 -402.937335) (xy 86.31334 -402.83971) (xy 86.312756 -402.79066)
			(xy 86.312756 -402.40712) (xy 86.313212 -402.365454) (xy 86.32021 -402.282414) (xy 86.326726 -402.241258)
			(xy 86.327861 -402.232545) (xy 86.324835 -402.215249) (xy 86.31615 -402.199989) (xy 86.309708 -402.194014)
			(xy 86.243414 -402.137372) (xy 86.236589 -402.131993) (xy 86.220373 -402.125778) (xy 86.203012 -402.125365)
			(xy 86.194646 -402.12772) (xy 86.148765 -402.142325) (xy 86.054876 -402.163702) (xy 86.007194 -402.170392)
			(xy 85.9957 -402.172424) (xy 85.976235 -402.185257) (xy 85.969856 -402.19503) (xy 85.947581 -402.232075)
			(xy 85.897537 -402.302563) (xy 85.841579 -402.368456) (xy 85.780128 -402.429257) (xy 85.713643 -402.48451)
			(xy 85.642626 -402.533801) (xy 85.567608 -402.576758) (xy 85.489153 -402.613061) (xy 85.40785 -402.642436)
			(xy 85.324309 -402.664662) (xy 85.239158 -402.679574) (xy 85.153035 -402.687058) (xy 85.109812 -402.687536)
			(xy 85.063469 -402.687009) (xy 84.971182 -402.678413) (xy 84.880091 -402.661294) (xy 84.79098 -402.6358)
			(xy 84.747608 -402.619464) (xy 84.738286 -402.616288) (xy 84.718614 -402.616543) (xy 84.700506 -402.624234)
			(xy 84.693252 -402.630894) (xy 84.337652 -402.98624) (xy 84.306757 -403.016495) (xy 84.240553 -403.072135)
			(xy 84.16978 -403.121834) (xy 84.09497 -403.165218) (xy 84.016684 -403.20196) (xy 83.93551 -403.231786)
			(xy 83.852059 -403.254471) (xy 83.809586 -403.262592) (xy 83.798721 -403.265157) (xy 83.780548 -403.278077)
			(xy 83.774534 -403.287484) (xy 83.752393 -403.325009) (xy 83.702492 -403.39644) (xy 83.646552 -403.463247)
			(xy 83.584999 -403.524922) (xy 83.518302 -403.580993) (xy 83.44697 -403.631035) (xy 83.371545 -403.674665)
			(xy 83.292603 -403.711552) (xy 83.210744 -403.741414) (xy 83.126594 -403.764023) (xy 83.040792 -403.779208)
			(xy 82.953993 -403.786852) (xy 82.910426 -403.787356) (xy 82.909918 -403.787356) (xy 82.868753 -403.78694)
			(xy 82.786702 -403.780171) (xy 82.705486 -403.766671) (xy 82.625658 -403.74653) (xy 82.547758 -403.719885)
			(xy 82.509868 -403.70379) (xy 82.501039 -403.700354) (xy 82.482122 -403.699575) (xy 82.473038 -403.702266)
			(xy 82.442796 -403.712076) (xy 82.38011 -403.722669) (xy 82.348324 -403.723348) (xy 82.347816 -403.723348)
			(xy 82.320563 -403.722863) (xy 82.266611 -403.715109) (xy 82.214312 -403.699756) (xy 82.164731 -403.677116)
			(xy 82.118875 -403.647651) (xy 82.07768 -403.61196) (xy 82.041983 -403.57077) (xy 82.012511 -403.524919)
			(xy 81.989864 -403.47534) (xy 81.974503 -403.423043) (xy 81.966741 -403.369093) (xy 81.966308 -403.34184)
			(xy 81.966308 -403.341586) (xy 81.96702 -403.307982) (xy 81.978774 -403.241809) (xy 81.989676 -403.210014)
			(xy 81.992605 -403.200935) (xy 81.99223 -403.181874) (xy 81.988914 -403.17293) (xy 81.970596 -403.12735)
			(xy 81.941976 -403.033372) (xy 81.922738 -402.937034) (xy 81.91307 -402.839272) (xy 81.91246 -402.790152)
			(xy 81.91246 -402.408136) (xy 81.912934 -402.36621) (xy 81.920056 -402.28266) (xy 81.926684 -402.241258)
			(xy 81.92897 -402.22805) (xy 81.919826 -402.203158) (xy 81.833466 -402.128736) (xy 81.807304 -402.123656)
			(xy 81.794604 -402.127974) (xy 81.748782 -402.142512) (xy 81.65502 -402.163762) (xy 81.607406 -402.170392)
			(xy 81.595911 -402.172421) (xy 81.576442 -402.185252) (xy 81.570068 -402.19503) (xy 81.547793 -402.232075)
			(xy 81.497749 -402.302564) (xy 81.441792 -402.368457) (xy 81.38034 -402.429259) (xy 81.313856 -402.484513)
			(xy 81.242839 -402.533805) (xy 81.167821 -402.576763) (xy 81.089366 -402.613067) (xy 81.008063 -402.642443)
			(xy 80.924522 -402.66467) (xy 80.83937 -402.679583) (xy 80.753248 -402.687068) (xy 80.710024 -402.687536)
			(xy 80.663674 -402.686988) (xy 80.571379 -402.678343) (xy 80.480285 -402.661161) (xy 80.391181 -402.635593)
			(xy 80.34782 -402.61921) (xy 80.347566 -402.61921) (xy 80.33828 -402.616102) (xy 80.318717 -402.616414)
			(xy 80.300701 -402.624042) (xy 80.293464 -402.63064) (xy 79.93761 -402.98624) (xy 79.906714 -403.016494)
			(xy 79.840509 -403.072131) (xy 79.769736 -403.121827) (xy 79.694925 -403.165208) (xy 79.616638 -403.201947)
			(xy 79.535464 -403.23177) (xy 79.452013 -403.254451) (xy 79.409544 -403.262592) (xy 79.398684 -403.265164)
			(xy 79.380525 -403.278092) (xy 79.374492 -403.287484) (xy 79.352351 -403.32501) (xy 79.302452 -403.396444)
			(xy 79.246513 -403.463255) (xy 79.184961 -403.524933) (xy 79.118264 -403.581009) (xy 79.046932 -403.631055)
			(xy 78.971508 -403.674689) (xy 78.892565 -403.71158) (xy 78.810707 -403.741447) (xy 78.726555 -403.764061)
			(xy 78.640753 -403.779251) (xy 78.553952 -403.7869) (xy 78.510384 -403.787356) (xy 78.509876 -403.787356)
			(xy 78.468709 -403.786956) (xy 78.386653 -403.78021) (xy 78.305434 -403.766718) (xy 78.225604 -403.746571)
			(xy 78.147709 -403.719906) (xy 78.109826 -403.70379) (xy 78.100997 -403.700343) (xy 78.082073 -403.699544)
			(xy 78.072996 -403.702266) (xy 78.042755 -403.712081) (xy 77.980069 -403.722683) (xy 77.948282 -403.723348)
			(xy 77.947774 -403.723348) (xy 77.920523 -403.72286) (xy 77.866576 -403.715101) (xy 77.814282 -403.699744)
			(xy 77.764705 -403.677102) (xy 77.718855 -403.647636) (xy 77.677665 -403.611945) (xy 77.641973 -403.570756)
			(xy 77.612505 -403.524907) (xy 77.589861 -403.475331) (xy 77.574502 -403.423038) (xy 77.566741 -403.369091)
			(xy 77.566266 -403.34184) (xy 77.566266 -403.341586) (xy 77.566978 -403.307982) (xy 77.578734 -403.241809)
			(xy 77.589634 -403.210014) (xy 77.592565 -403.200935) (xy 77.592189 -403.181874) (xy 77.588872 -403.17293)
			(xy 77.570609 -403.127403) (xy 77.542079 -403.033543) (xy 77.522899 -402.937335) (xy 77.513254 -402.83971)
			(xy 77.512672 -402.79066) (xy 77.512672 -402.40712) (xy 77.513128 -402.365454) (xy 77.520126 -402.282414)
			(xy 77.526642 -402.241258) (xy 77.528928 -402.22805) (xy 77.519784 -402.203158) (xy 77.433424 -402.128736)
			(xy 77.407262 -402.123656) (xy 77.394562 -402.127974) (xy 77.348739 -402.14251) (xy 77.254977 -402.163756)
			(xy 77.207364 -402.170392) (xy 77.195874 -402.172429) (xy 77.176419 -402.185268) (xy 77.170026 -402.19503)
			(xy 77.14775 -402.232074) (xy 77.097706 -402.302561) (xy 77.041748 -402.368452) (xy 76.980296 -402.429251)
			(xy 76.913811 -402.484502) (xy 76.842793 -402.53379) (xy 76.767775 -402.576746) (xy 76.68932 -402.613046)
			(xy 76.608017 -402.642419) (xy 76.524477 -402.664643) (xy 76.439327 -402.679552) (xy 76.353205 -402.687034)
			(xy 76.309982 -402.687536) (xy 76.263633 -402.686986) (xy 76.171338 -402.678337) (xy 76.080246 -402.661152)
			(xy 75.991144 -402.63558) (xy 75.947778 -402.61921) (xy 75.947524 -402.61921) (xy 75.93824 -402.61611)
			(xy 75.918686 -402.616436) (xy 75.900683 -402.624073) (xy 75.893422 -402.63064) (xy 75.537568 -402.98624)
			(xy 75.506671 -403.016493) (xy 75.440466 -403.072128) (xy 75.369691 -403.12182) (xy 75.294879 -403.165198)
			(xy 75.216592 -403.201934) (xy 75.135418 -403.231753) (xy 75.051967 -403.254431) (xy 75.009502 -403.262592)
			(xy 74.998635 -403.265154) (xy 74.980457 -403.278072) (xy 74.97445 -403.287484) (xy 74.952309 -403.325009)
			(xy 74.902408 -403.396441) (xy 74.846469 -403.463249) (xy 74.784916 -403.524925) (xy 74.718219 -403.580998)
			(xy 74.646887 -403.63104) (xy 74.571462 -403.674672) (xy 74.49252 -403.71156) (xy 74.410662 -403.741423)
			(xy 74.326511 -403.764033) (xy 74.240709 -403.77922) (xy 74.153909 -403.786866) (xy 74.110342 -403.787356)
			(xy 74.109834 -403.787356) (xy 74.068669 -403.78694) (xy 73.986617 -403.780173) (xy 73.905401 -403.766674)
			(xy 73.825572 -403.746534) (xy 73.747672 -403.719891) (xy 73.709784 -403.70379) (xy 73.700955 -403.700351)
			(xy 73.682036 -403.699567) (xy 73.672954 -403.702266) (xy 73.642712 -403.712077) (xy 73.580026 -403.722673)
			(xy 73.54824 -403.723348) (xy 73.547732 -403.723348) (xy 73.520478 -403.722864) (xy 73.466525 -403.715112)
			(xy 73.414224 -403.69976) (xy 73.36464 -403.677121) (xy 73.318783 -403.647656) (xy 73.277586 -403.611965)
			(xy 73.241887 -403.570775) (xy 73.212413 -403.524923) (xy 73.189765 -403.475344) (xy 73.174403 -403.423046)
			(xy 73.166641 -403.369094) (xy 73.166224 -403.34184) (xy 73.166224 -403.341586) (xy 73.166936 -403.307982)
			(xy 73.17869 -403.241809) (xy 73.189592 -403.210014) (xy 73.192521 -403.200935) (xy 73.192145 -403.181874)
			(xy 73.18883 -403.17293) (xy 73.170512 -403.12735) (xy 73.141891 -403.033372) (xy 73.122653 -402.937034)
			(xy 73.112985 -402.839272) (xy 73.112376 -402.790152) (xy 73.112376 -402.408136) (xy 73.11285 -402.36621)
			(xy 73.119972 -402.28266) (xy 73.1266 -402.241258) (xy 73.128886 -402.22805) (xy 73.119742 -402.203158)
			(xy 73.033382 -402.128736) (xy 73.00722 -402.123656) (xy 72.99452 -402.127974) (xy 72.948697 -402.142508)
			(xy 72.854934 -402.16375) (xy 72.807322 -402.170392) (xy 72.795825 -402.172418) (xy 72.77635 -402.185246)
			(xy 72.769984 -402.19503) (xy 72.747709 -402.232075) (xy 72.697666 -402.302566) (xy 72.641709 -402.36846)
			(xy 72.580257 -402.429262) (xy 72.513773 -402.484517) (xy 72.442756 -402.53381) (xy 72.367738 -402.57677)
			(xy 72.289283 -402.613075) (xy 72.20798 -402.642452) (xy 72.124439 -402.664681) (xy 72.039287 -402.679594)
			(xy 71.953164 -402.687081) (xy 71.90994 -402.687536) (xy 71.868744 -402.68711) (xy 71.786633 -402.68031)
			(xy 71.705363 -402.666763) (xy 71.625487 -402.64656) (xy 71.547549 -402.619838) (xy 71.509636 -402.603716)
			(xy 71.500794 -402.600345) (xy 71.481903 -402.59958) (xy 71.472806 -402.602192) (xy 71.442506 -402.612034)
			(xy 71.37969 -402.622633) (xy 71.347838 -402.623274) (xy 71.320584 -402.622813) (xy 71.266631 -402.61506)
			(xy 71.214331 -402.599707) (xy 71.164748 -402.577067) (xy 71.118892 -402.547599) (xy 71.077698 -402.511905)
			(xy 71.042003 -402.470711) (xy 71.012535 -402.424856) (xy 70.989894 -402.375273) (xy 70.97454 -402.322973)
			(xy 70.966787 -402.26902) (xy 70.96633 -402.241766) (xy 70.96633 -402.241512) (xy 70.96704 -402.207907)
			(xy 70.97879 -402.141733) (xy 70.989698 -402.10994) (xy 70.992616 -402.100862) (xy 70.992214 -402.081811)
			(xy 70.988936 -402.072856) (xy 70.970673 -402.027329) (xy 70.942141 -401.933469) (xy 70.922959 -401.837262)
			(xy 70.913312 -401.739636) (xy 70.912736 -401.690586) (xy 70.912736 -401.3073) (xy 70.913208 -401.264444)
			(xy 70.920588 -401.179049) (xy 70.93527 -401.094603) (xy 70.945756 -401.053046) (xy 70.947232 -401.046652)
			(xy 70.94723 -401.033533) (xy 70.945756 -401.027138) (xy 70.935261 -400.985583) (xy 70.920581 -400.901136)
			(xy 70.913205 -400.815741) (xy 70.912736 -400.772884) (xy 70.912736 -400.389852) (xy 70.913307 -400.340769)
			(xy 70.922926 -400.243077) (xy 70.942104 -400.146804) (xy 70.970656 -400.052883) (xy 70.988936 -400.007328)
			(xy 70.992256 -399.998381) (xy 70.992656 -399.979316) (xy 70.989698 -399.970244) (xy 70.978774 -399.938455)
			(xy 70.967025 -399.872278) (xy 70.96633 -399.838672) (xy 70.96633 -399.838418) (xy 70.966792 -399.811165)
			(xy 70.974547 -399.757214) (xy 70.989902 -399.704917) (xy 71.012544 -399.655337) (xy 71.042012 -399.609484)
			(xy 71.077706 -399.568292) (xy 71.1189 -399.5326) (xy 71.164754 -399.503134) (xy 71.214335 -399.480495)
			(xy 71.266634 -399.465143) (xy 71.320585 -399.457391) (xy 71.347838 -399.45691) (xy 71.348092 -399.45691)
			(xy 71.361554 -399.457164) (xy 71.372455 -399.457048) (xy 71.392596 -399.448765) (xy 71.407506 -399.432891)
			(xy 71.414514 -399.412271) (xy 71.412364 -399.3906) (xy 71.407274 -399.380964) (xy 71.388786 -399.347733)
			(xy 71.35965 -399.277492) (xy 71.339924 -399.204051) (xy 71.329948 -399.128664) (xy 71.329296 -399.090642)
			(xy 71.329296 -399.090134) (xy 71.329811 -399.055256) (xy 71.338165 -398.986003) (xy 71.354756 -398.91825)
			(xy 71.379346 -398.852973) (xy 71.411579 -398.791112) (xy 71.450993 -398.733559) (xy 71.497018 -398.681143)
			(xy 71.548993 -398.634619) (xy 71.606167 -398.594657) (xy 71.667717 -398.561834) (xy 71.732756 -398.536622)
			(xy 71.76643 -398.527524) (xy 71.777201 -398.524191) (xy 71.794585 -398.509877) (xy 71.804186 -398.489508)
			(xy 71.804784 -398.478248) (xy 71.804784 -398.453864) (xy 71.80429 -398.443862) (xy 71.796623 -398.425386)
			(xy 71.782471 -398.411248) (xy 71.763986 -398.4036) (xy 71.753984 -398.403064) (xy 71.5518 -398.403064)
			(xy 71.54165 -398.402633) (xy 71.522907 -398.394838) (xy 71.508595 -398.380442) (xy 71.500909 -398.361654)
			(xy 71.500492 -398.351502) (xy 71.500492 -398.065498) (xy 71.500305 -398.058623) (xy 71.496706 -398.045355)
			(xy 71.49338 -398.039336) (xy 71.477011 -398.010988) (xy 71.451202 -397.95083) (xy 71.433711 -397.88775)
			(xy 71.424854 -397.822892) (xy 71.424292 -397.790162) (xy 71.424863 -397.757433) (xy 71.433725 -397.692577)
			(xy 71.451215 -397.629498) (xy 71.477017 -397.569339) (xy 71.49338 -397.540988) (xy 71.496696 -397.534963)
			(xy 71.500311 -397.5217) (xy 71.500492 -397.514826) (xy 71.500492 -396.765526) (xy 71.500296 -396.758654)
			(xy 71.496681 -396.745396) (xy 71.49338 -396.739364) (xy 71.477009 -396.711017) (xy 71.451197 -396.650859)
			(xy 71.433702 -396.587779) (xy 71.424841 -396.52292) (xy 71.424292 -396.49019) (xy 71.424861 -396.457461)
			(xy 71.43372 -396.392603) (xy 71.451207 -396.329522) (xy 71.477006 -396.269361) (xy 71.49338 -396.241016)
			(xy 71.496687 -396.234989) (xy 71.500283 -396.221726) (xy 71.500492 -396.214854) (xy 71.500492 -395.92885)
			(xy 71.500972 -395.918714) (xy 71.508689 -395.899968) (xy 71.522974 -395.885585) (xy 71.541667 -395.877742)
			(xy 71.5518 -395.877288) (xy 71.753984 -395.877288) (xy 71.764007 -395.876871) (xy 71.782527 -395.869204)
			(xy 71.796701 -395.85503) (xy 71.80437 -395.836511) (xy 71.804784 -395.826488) (xy 71.804784 -395.821154)
			(xy 71.804692 -395.816135) (xy 71.802772 -395.806283) (xy 71.800974 -395.801596) (xy 71.794878 -395.787118)
			(xy 71.792869 -395.782555) (xy 71.787368 -395.774243) (xy 71.783956 -395.770608) (xy 71.775574 -395.762226)
			(xy 71.770945 -395.757891) (xy 71.760025 -395.751453) (xy 71.753984 -395.749526) (xy 71.753476 -395.749272)
			(xy 71.721772 -395.739909) (xy 71.660549 -395.714968) (xy 71.602554 -395.683237) (xy 71.548537 -395.645126)
			(xy 71.499196 -395.601127) (xy 71.455171 -395.551811) (xy 71.41703 -395.497815) (xy 71.385267 -395.439837)
			(xy 71.360293 -395.378627) (xy 71.350886 -395.346936) (xy 71.350886 -395.346428) (xy 71.350632 -395.346174)
			(xy 71.348671 -395.340147) (xy 71.342248 -395.329226) (xy 71.337932 -395.324584) (xy 70.709536 -394.696188)
			(xy 70.701916 -394.689838) (xy 67.10553 -392.286998) (xy 67.065132 -392.259271) (xy 66.989427 -392.197055)
			(xy 66.9544 -392.162792) (xy 64.337438 -389.54583) (xy 64.31431 -389.522405) (xy 64.270839 -389.472962)
			(xy 64.25057 -389.447024) (xy 64.242442 -389.436102) (xy 64.217296 -389.425688) (xy 64.11595 -389.439404)
			(xy 64.10722 -389.440991) (xy 64.091532 -389.449251) (xy 64.079596 -389.462361) (xy 64.075818 -389.470392)
			(xy 64.064693 -389.496362) (xy 64.035907 -389.544975) (xy 64.000267 -389.588812) (xy 63.958553 -389.626915)
			(xy 63.911678 -389.658451) (xy 63.860665 -389.682731) (xy 63.806629 -389.699224) (xy 63.750752 -389.707569)
			(xy 63.722504 -389.708136) (xy 63.695249 -389.707673) (xy 63.641294 -389.699916) (xy 63.588991 -389.684559)
			(xy 63.539407 -389.661915) (xy 63.49355 -389.632445) (xy 63.452354 -389.596749) (xy 63.416657 -389.555553)
			(xy 63.387186 -389.509697) (xy 63.364542 -389.460112) (xy 63.349185 -389.40781) (xy 63.341427 -389.353855)
			(xy 63.341427 -389.299345) (xy 63.349185 -389.24539) (xy 63.364542 -389.193088) (xy 63.387186 -389.143503)
			(xy 63.416657 -389.097647) (xy 63.452354 -389.056451) (xy 63.49355 -389.020755) (xy 63.539407 -388.991285)
			(xy 63.588991 -388.968641) (xy 63.641294 -388.953284) (xy 63.695249 -388.945527) (xy 63.722504 -388.94512)
			(xy 63.750611 -388.945637) (xy 63.806213 -388.953923) (xy 63.833248 -388.96163) (xy 63.833502 -388.96163)
			(xy 63.842789 -388.964017) (xy 63.861886 -388.962441) (xy 63.879065 -388.953955) (xy 63.885826 -388.947152)
			(xy 63.947548 -388.87908) (xy 63.95373 -388.871709) (xy 63.960554 -388.853738) (xy 63.960258 -388.834518)
			(xy 63.956946 -388.825486) (xy 63.336678 -387.328918) (xy 63.334669 -387.324355) (xy 63.329168 -387.316043)
			(xy 63.325756 -387.312408) (xy 62.963552 -386.950204) (xy 62.956699 -386.942808) (xy 62.948955 -386.92421)
			(xy 62.948566 -386.914136) (xy 62.948566 -386.402072) (xy 62.948476 -386.397053) (xy 62.946559 -386.387199)
			(xy 62.944756 -386.382514) (xy 62.791086 -386.012182) (xy 62.772895 -385.96666) (xy 62.744459 -385.872838)
			(xy 62.725355 -385.776681) (xy 62.719966 -385.727956) (xy 62.719458 -385.722622) (xy 62.718244 -385.714039)
			(xy 62.710852 -385.698374) (xy 62.698651 -385.686077) (xy 62.69101 -385.681982) (xy 62.601094 -385.638294)
			(xy 62.574678 -385.640072) (xy 62.563502 -385.647184) (xy 62.540304 -385.661561) (xy 62.49067 -385.684254)
			(xy 62.438308 -385.699641) (xy 62.384288 -385.707407) (xy 62.357 -385.70789) (xy 62.32975 -385.707404)
			(xy 62.275805 -385.699648) (xy 62.223513 -385.684293) (xy 62.173938 -385.661653) (xy 62.12809 -385.632188)
			(xy 62.086901 -385.596499) (xy 62.051212 -385.55531) (xy 62.021747 -385.509462) (xy 61.999107 -385.459887)
			(xy 61.983752 -385.407595) (xy 61.975996 -385.35365) (xy 61.975996 -385.29915) (xy 61.983752 -385.245205)
			(xy 61.999107 -385.192913) (xy 62.021747 -385.143338) (xy 62.051212 -385.09749) (xy 62.086901 -385.056301)
			(xy 62.12809 -385.020612) (xy 62.173938 -384.991147) (xy 62.223513 -384.968507) (xy 62.275805 -384.953152)
			(xy 62.32975 -384.945396) (xy 62.357 -384.944874) (xy 62.380893 -384.945262) (xy 62.428302 -384.951256)
			(xy 62.474595 -384.963113) (xy 62.496954 -384.971544) (xy 62.5094 -384.97637) (xy 62.535308 -384.972814)
			(xy 62.615318 -384.912616) (xy 62.622076 -384.907093) (xy 62.631693 -384.892544) (xy 62.635868 -384.875611)
			(xy 62.635384 -384.866896) (xy 61.957204 -377.975114) (xy 61.955956 -377.966425) (xy 61.948417 -377.950586)
			(xy 61.942472 -377.944126) (xy 61.24194 -377.243594) (xy 61.23509 -377.236197) (xy 61.227352 -377.217599)
			(xy 61.226954 -377.207526) (xy 61.226954 -370.556028) (xy 61.2267 -370.550948) (xy 61.033406 -368.58448)
			(xy 61.030104 -368.571272) (xy 56.321706 -356.36708) (xy 56.317624 -356.357712) (xy 56.303454 -356.343014)
			(xy 56.28467 -356.335016) (xy 56.274462 -356.334568) (xy 53.597556 -356.334568) (xy 53.587552 -356.335063)
			(xy 53.56907 -356.342729) (xy 53.554923 -356.35688) (xy 53.547261 -356.375364) (xy 53.546756 -356.385368)
			(xy 53.546756 -357.896668) (xy 53.546143 -357.945615) (xy 53.536528 -358.043037) (xy 53.517415 -358.139048)
			(xy 53.488989 -358.232726) (xy 53.47081 -358.278176) (xy 53.256942 -358.794812) (xy 53.237657 -358.83984)
			(xy 53.191469 -358.926229) (xy 53.16474 -358.967278) (xy 52.893976 -359.372662) (xy 52.880226 -359.392968)
			(xy 52.851002 -359.432355) (xy 52.835556 -359.451402) (xy 49.648403 -363.334808) (xy 54.890416 -363.334808)
			(xy 54.890416 -362.471208) (xy 54.890906 -362.441224) (xy 54.898734 -362.381768) (xy 54.914255 -362.323843)
			(xy 54.937204 -362.268439) (xy 54.967188 -362.216505) (xy 55.003694 -362.168929) (xy 55.046099 -362.126524)
			(xy 55.093675 -362.090018) (xy 55.145609 -362.060034) (xy 55.201013 -362.037085) (xy 55.258938 -362.021564)
			(xy 55.318394 -362.013736) (xy 55.378362 -362.013736) (xy 55.437818 -362.021564) (xy 55.495743 -362.037085)
			(xy 55.551147 -362.060034) (xy 55.603081 -362.090018) (xy 55.650657 -362.126524) (xy 55.693062 -362.168929)
			(xy 55.729568 -362.216505) (xy 55.759552 -362.268439) (xy 55.782501 -362.323843) (xy 55.798022 -362.381768)
			(xy 55.80585 -362.441224) (xy 55.80634 -362.471208) (xy 55.80634 -363.334808) (xy 55.80585 -363.364792)
			(xy 55.798022 -363.424248) (xy 55.782501 -363.482173) (xy 55.759552 -363.537577) (xy 55.729568 -363.589511)
			(xy 55.693062 -363.637087) (xy 55.650657 -363.679492) (xy 55.603081 -363.715998) (xy 55.551147 -363.745982)
			(xy 55.495743 -363.768931) (xy 55.437818 -363.784452) (xy 55.378362 -363.79228) (xy 55.318394 -363.79228)
			(xy 55.258938 -363.784452) (xy 55.201013 -363.768931) (xy 55.145609 -363.745982) (xy 55.093675 -363.715998)
			(xy 55.046099 -363.679492) (xy 55.003694 -363.637087) (xy 54.967188 -363.589511) (xy 54.937204 -363.537577)
			(xy 54.914255 -363.482173) (xy 54.898734 -363.424248) (xy 54.890906 -363.364792) (xy 54.890416 -363.334808)
			(xy 49.648403 -363.334808) (xy 47.62734 -365.797384) (xy 54.438294 -365.797384) (xy 54.438294 -365.737416)
			(xy 54.446121 -365.67796) (xy 54.461641 -365.620034) (xy 54.484589 -365.564629) (xy 54.514571 -365.512694)
			(xy 54.551076 -365.465115) (xy 54.593478 -365.422709) (xy 54.641052 -365.386199) (xy 54.692984 -365.356211)
			(xy 54.748387 -365.333257) (xy 54.806311 -365.317731) (xy 54.865766 -365.309897) (xy 54.89575 -365.309404)
			(xy 55.75935 -365.309404) (xy 55.789336 -365.309938) (xy 55.848794 -365.31776) (xy 55.906723 -365.333276)
			(xy 55.962131 -365.356222) (xy 56.01407 -365.386203) (xy 56.06165 -365.422708) (xy 56.104059 -365.465112)
			(xy 56.140569 -365.512689) (xy 56.170556 -365.564624) (xy 56.193508 -365.620029) (xy 56.20903 -365.677957)
			(xy 56.216859 -365.737414) (xy 56.216859 -365.797386) (xy 56.20903 -365.856843) (xy 56.193508 -365.914771)
			(xy 56.170556 -365.970176) (xy 56.140569 -366.022112) (xy 56.104059 -366.069688) (xy 56.06165 -366.112092)
			(xy 56.01407 -366.148597) (xy 55.962131 -366.178578) (xy 55.906723 -366.201524) (xy 55.848794 -366.21704)
			(xy 55.789336 -366.224862) (xy 55.75935 -366.225328) (xy 54.89575 -366.225328) (xy 54.865766 -366.224903)
			(xy 54.806311 -366.217069) (xy 54.748386 -366.201543) (xy 54.692984 -366.178589) (xy 54.641052 -366.148601)
			(xy 54.593478 -366.112091) (xy 54.551076 -366.069685) (xy 54.514571 -366.022106) (xy 54.484589 -365.970171)
			(xy 54.461641 -365.914766) (xy 54.446121 -365.85684) (xy 54.438294 -365.797384) (xy 47.62734 -365.797384)
			(xy 46.601126 -367.04778) (xy 46.595888 -367.054797) (xy 46.590033 -367.071289) (xy 46.589696 -367.080038)
			(xy 46.589696 -368.990118) (xy 47.223942 -368.990118) (xy 47.227933 -368.927951) (xy 47.239842 -368.866804)
			(xy 47.259471 -368.807683) (xy 47.2865 -368.751557) (xy 47.320484 -368.699348) (xy 47.360866 -368.651913)
			(xy 47.406982 -368.610032) (xy 47.458074 -368.574392) (xy 47.513305 -368.545578) (xy 47.571767 -368.524064)
			(xy 47.632501 -368.510202) (xy 47.694508 -368.50422) (xy 47.756771 -368.506216) (xy 47.818268 -368.516159)
			(xy 47.819963 -368.516662) (xy 53.966364 -368.516662) (xy 53.966364 -367.653062) (xy 53.96685 -367.625793)
			(xy 53.974612 -367.571809) (xy 53.989977 -367.519479) (xy 54.012634 -367.469869) (xy 54.04212 -367.423988)
			(xy 54.077835 -367.382771) (xy 54.119052 -367.347056) (xy 54.164933 -367.31757) (xy 54.214543 -367.294913)
			(xy 54.266873 -367.279548) (xy 54.320857 -367.271786) (xy 54.375395 -367.271786) (xy 54.429379 -367.279548)
			(xy 54.481709 -367.294913) (xy 54.531319 -367.31757) (xy 54.5772 -367.347056) (xy 54.618417 -367.382771)
			(xy 54.654132 -367.423988) (xy 54.683618 -367.469869) (xy 54.706275 -367.519479) (xy 54.72164 -367.571809)
			(xy 54.729402 -367.625793) (xy 54.729888 -367.653062) (xy 54.729888 -368.516662) (xy 57.339484 -368.516662)
			(xy 57.339484 -367.653062) (xy 57.33997 -367.625793) (xy 57.347732 -367.571809) (xy 57.363097 -367.519479)
			(xy 57.385754 -367.469869) (xy 57.41524 -367.423988) (xy 57.450955 -367.382771) (xy 57.492172 -367.347056)
			(xy 57.538053 -367.31757) (xy 57.587663 -367.294913) (xy 57.639993 -367.279548) (xy 57.693977 -367.271786)
			(xy 57.748515 -367.271786) (xy 57.802499 -367.279548) (xy 57.854829 -367.294913) (xy 57.904439 -367.31757)
			(xy 57.95032 -367.347056) (xy 57.991537 -367.382771) (xy 58.027252 -367.423988) (xy 58.056738 -367.469869)
			(xy 58.079395 -367.519479) (xy 58.09476 -367.571809) (xy 58.102522 -367.625793) (xy 58.103008 -367.653062)
			(xy 58.103008 -368.516662) (xy 58.102522 -368.543931) (xy 58.09476 -368.597915) (xy 58.079395 -368.650245)
			(xy 58.056738 -368.699855) (xy 58.027252 -368.745736) (xy 57.991537 -368.786953) (xy 57.95032 -368.822668)
			(xy 57.904439 -368.852154) (xy 57.854829 -368.874811) (xy 57.802499 -368.890176) (xy 57.748515 -368.897938)
			(xy 57.693977 -368.897938) (xy 57.639993 -368.890176) (xy 57.587663 -368.874811) (xy 57.538053 -368.852154)
			(xy 57.492172 -368.822668) (xy 57.450955 -368.786953) (xy 57.41524 -368.745736) (xy 57.385754 -368.699855)
			(xy 57.363097 -368.650245) (xy 57.347732 -368.597915) (xy 57.33997 -368.543931) (xy 57.339484 -368.516662)
			(xy 54.729888 -368.516662) (xy 54.729402 -368.543931) (xy 54.72164 -368.597915) (xy 54.706275 -368.650245)
			(xy 54.683618 -368.699855) (xy 54.654132 -368.745736) (xy 54.618417 -368.786953) (xy 54.5772 -368.822668)
			(xy 54.531319 -368.852154) (xy 54.481709 -368.874811) (xy 54.429379 -368.890176) (xy 54.375395 -368.897938)
			(xy 54.320857 -368.897938) (xy 54.266873 -368.890176) (xy 54.214543 -368.874811) (xy 54.164933 -368.852154)
			(xy 54.119052 -368.822668) (xy 54.077835 -368.786953) (xy 54.04212 -368.745736) (xy 54.012634 -368.699855)
			(xy 53.989977 -368.650245) (xy 53.974612 -368.597915) (xy 53.96685 -368.543931) (xy 53.966364 -368.516662)
			(xy 47.819963 -368.516662) (xy 47.877989 -368.533883) (xy 47.934952 -368.5591) (xy 47.988223 -368.591393)
			(xy 48.036928 -368.630233) (xy 48.080265 -368.674983) (xy 48.117525 -368.724907) (xy 48.148094 -368.779186)
			(xy 48.171472 -368.836929) (xy 48.187273 -368.897187) (xy 48.195239 -368.95897) (xy 48.195738 -368.990118)
			(xy 48.195239 -369.021266) (xy 48.187273 -369.083049) (xy 48.171472 -369.143307) (xy 48.148094 -369.20105)
			(xy 48.117525 -369.255329) (xy 48.080265 -369.305253) (xy 48.036928 -369.350003) (xy 47.988223 -369.388843)
			(xy 47.934952 -369.421136) (xy 47.877989 -369.446353) (xy 47.818268 -369.464077) (xy 47.756771 -369.47402)
			(xy 47.694508 -369.476016) (xy 47.632501 -369.470034) (xy 47.571767 -369.456172) (xy 47.513305 -369.434658)
			(xy 47.458074 -369.405844) (xy 47.406982 -369.370204) (xy 47.360866 -369.328323) (xy 47.320484 -369.280888)
			(xy 47.2865 -369.228679) (xy 47.259471 -369.172553) (xy 47.239842 -369.113432) (xy 47.227933 -369.052285)
			(xy 47.223942 -368.990118) (xy 46.589696 -368.990118) (xy 46.589696 -371.622787) (xy 47.225018 -371.622787)
			(xy 47.225022 -371.557348) (xy 47.233811 -371.492501) (xy 47.251225 -371.42942) (xy 47.27695 -371.369249)
			(xy 47.293276 -371.340888) (xy 47.296593 -371.334865) (xy 47.300198 -371.3216) (xy 47.300388 -371.314726)
			(xy 47.300388 -371.028722) (xy 47.300783 -371.018546) (xy 47.30857 -370.999742) (xy 47.322966 -370.985355)
			(xy 47.341773 -370.977578) (xy 47.35195 -370.97716) (xy 48.06823 -370.97716) (xy 48.078392 -370.977609)
			(xy 48.097167 -370.985398) (xy 48.111532 -370.999777) (xy 48.119301 -371.018559) (xy 48.119792 -371.028722)
			(xy 48.119792 -371.310662) (xy 53.966364 -371.310662) (xy 53.966364 -370.447062) (xy 53.96685 -370.419793)
			(xy 53.974612 -370.365809) (xy 53.989977 -370.313479) (xy 54.012634 -370.263869) (xy 54.04212 -370.217988)
			(xy 54.077835 -370.176771) (xy 54.119052 -370.141056) (xy 54.164933 -370.11157) (xy 54.214543 -370.088913)
			(xy 54.266873 -370.073548) (xy 54.320857 -370.065786) (xy 54.375395 -370.065786) (xy 54.429379 -370.073548)
			(xy 54.481709 -370.088913) (xy 54.531319 -370.11157) (xy 54.5772 -370.141056) (xy 54.618417 -370.176771)
			(xy 54.654132 -370.217988) (xy 54.683618 -370.263869) (xy 54.706275 -370.313479) (xy 54.72164 -370.365809)
			(xy 54.729402 -370.419793) (xy 54.729888 -370.447062) (xy 54.729888 -371.310662) (xy 57.339484 -371.310662)
			(xy 57.339484 -370.447062) (xy 57.33997 -370.419793) (xy 57.347732 -370.365809) (xy 57.363097 -370.313479)
			(xy 57.385754 -370.263869) (xy 57.41524 -370.217988) (xy 57.450955 -370.176771) (xy 57.492172 -370.141056)
			(xy 57.538053 -370.11157) (xy 57.587663 -370.088913) (xy 57.639993 -370.073548) (xy 57.693977 -370.065786)
			(xy 57.748515 -370.065786) (xy 57.802499 -370.073548) (xy 57.854829 -370.088913) (xy 57.904439 -370.11157)
			(xy 57.95032 -370.141056) (xy 57.991537 -370.176771) (xy 58.027252 -370.217988) (xy 58.056738 -370.263869)
			(xy 58.079395 -370.313479) (xy 58.09476 -370.365809) (xy 58.102522 -370.419793) (xy 58.103008 -370.447062)
			(xy 58.103008 -371.310662) (xy 58.102522 -371.337931) (xy 58.09476 -371.391915) (xy 58.079395 -371.444245)
			(xy 58.056738 -371.493855) (xy 58.027252 -371.539736) (xy 57.991537 -371.580953) (xy 57.95032 -371.616668)
			(xy 57.904439 -371.646154) (xy 57.854829 -371.668811) (xy 57.802499 -371.684176) (xy 57.748515 -371.691938)
			(xy 57.693977 -371.691938) (xy 57.639993 -371.684176) (xy 57.587663 -371.668811) (xy 57.538053 -371.646154)
			(xy 57.492172 -371.616668) (xy 57.450955 -371.580953) (xy 57.41524 -371.539736) (xy 57.385754 -371.493855)
			(xy 57.363097 -371.444245) (xy 57.347732 -371.391915) (xy 57.33997 -371.337931) (xy 57.339484 -371.310662)
			(xy 54.729888 -371.310662) (xy 54.729402 -371.337931) (xy 54.72164 -371.391915) (xy 54.706275 -371.444245)
			(xy 54.683618 -371.493855) (xy 54.654132 -371.539736) (xy 54.618417 -371.580953) (xy 54.5772 -371.616668)
			(xy 54.531319 -371.646154) (xy 54.481709 -371.668811) (xy 54.429379 -371.684176) (xy 54.375395 -371.691938)
			(xy 54.320857 -371.691938) (xy 54.266873 -371.684176) (xy 54.214543 -371.668811) (xy 54.164933 -371.646154)
			(xy 54.119052 -371.616668) (xy 54.077835 -371.580953) (xy 54.04212 -371.539736) (xy 54.012634 -371.493855)
			(xy 53.989977 -371.444245) (xy 53.974612 -371.391915) (xy 53.96685 -371.337931) (xy 53.966364 -371.310662)
			(xy 48.119792 -371.310662) (xy 48.119792 -371.314726) (xy 48.119975 -371.3216) (xy 48.123589 -371.334863)
			(xy 48.126904 -371.340888) (xy 48.143193 -371.369267) (xy 48.168911 -371.429435) (xy 48.186321 -371.49251)
			(xy 48.195108 -371.557351) (xy 48.195112 -371.622784) (xy 48.186334 -371.687626) (xy 48.168933 -371.750703)
			(xy 48.143222 -371.810874) (xy 48.126904 -371.839236) (xy 48.123577 -371.845255) (xy 48.119979 -371.858523)
			(xy 48.119792 -371.865398) (xy 48.119792 -372.614698) (xy 48.119986 -372.621571) (xy 48.123593 -372.634834)
			(xy 48.126904 -372.64086) (xy 48.143254 -372.669206) (xy 48.168966 -372.729381) (xy 48.18637 -372.792463)
			(xy 48.195149 -372.85731) (xy 48.195145 -372.922748) (xy 48.186358 -372.987594) (xy 48.168947 -373.050674)
			(xy 48.143227 -373.110846) (xy 48.126904 -373.139208) (xy 48.123587 -373.145231) (xy 48.119983 -373.158496)
			(xy 48.119792 -373.16537) (xy 48.119792 -373.451374) (xy 48.119246 -373.461526) (xy 48.111486 -373.480289)
			(xy 48.097136 -373.494655) (xy 48.078382 -373.502435) (xy 48.06823 -373.502936) (xy 47.35195 -373.502936)
			(xy 47.341778 -373.502495) (xy 47.32298 -373.494721) (xy 47.308592 -373.48034) (xy 47.30081 -373.461545)
			(xy 47.300388 -373.451374) (xy 47.300388 -373.16537) (xy 47.300209 -373.158496) (xy 47.296592 -373.145233)
			(xy 47.293276 -373.139208) (xy 47.276981 -373.110831) (xy 47.251259 -373.050664) (xy 47.233847 -372.987589)
			(xy 47.225059 -372.922747) (xy 47.225055 -372.857312) (xy 47.233835 -372.792469) (xy 47.25124 -372.729391)
			(xy 47.276955 -372.669221) (xy 47.293276 -372.64086) (xy 47.296603 -372.634841) (xy 47.300201 -372.621573)
			(xy 47.300388 -372.614698) (xy 47.300388 -371.865398) (xy 47.300199 -371.858525) (xy 47.296589 -371.845262)
			(xy 47.293276 -371.839236) (xy 47.27692 -371.810893) (xy 47.251204 -371.750718) (xy 47.233798 -371.687635)
			(xy 47.225018 -371.622787) (xy 46.589696 -371.622787) (xy 46.589696 -373.88419) (xy 56.962292 -373.88419)
			(xy 56.966363 -373.828568) (xy 56.978489 -373.774131) (xy 56.998412 -373.72204) (xy 57.025708 -373.673405)
			(xy 57.059794 -373.629262) (xy 57.099943 -373.590553) (xy 57.145301 -373.558102) (xy 57.194901 -373.532601)
			(xy 57.247685 -373.514594) (xy 57.302528 -373.504464) (xy 57.358262 -373.502427) (xy 57.413699 -373.508527)
			(xy 57.467656 -373.522633) (xy 57.518985 -373.544445) (xy 57.566591 -373.573499) (xy 57.609459 -373.609174)
			(xy 57.646676 -373.650711) (xy 57.677449 -373.697224) (xy 57.701121 -373.747721) (xy 57.717189 -373.801128)
			(xy 57.725309 -373.856304) (xy 57.725818 -373.88419) (xy 57.725309 -373.912076) (xy 57.717189 -373.967252)
			(xy 57.701121 -374.020659) (xy 57.677449 -374.071156) (xy 57.646676 -374.117669) (xy 57.609459 -374.159206)
			(xy 57.566591 -374.194881) (xy 57.518985 -374.223935) (xy 57.467656 -374.245747) (xy 57.413699 -374.259853)
			(xy 57.358262 -374.265953) (xy 57.302528 -374.263916) (xy 57.247685 -374.253786) (xy 57.194901 -374.235779)
			(xy 57.145301 -374.210278) (xy 57.099943 -374.177827) (xy 57.059794 -374.139118) (xy 57.025708 -374.094975)
			(xy 56.998412 -374.04634) (xy 56.978489 -373.994249) (xy 56.966363 -373.939812) (xy 56.962292 -373.88419)
			(xy 46.589696 -373.88419) (xy 46.589696 -376.757485) (xy 47.225041 -376.757485) (xy 47.233825 -376.69264)
			(xy 47.251234 -376.629562) (xy 47.276953 -376.569391) (xy 47.293276 -376.54103) (xy 47.296578 -376.534999)
			(xy 47.300192 -376.52174) (xy 47.300388 -376.514868) (xy 47.300388 -375.765568) (xy 47.30021 -375.758694)
			(xy 47.296592 -375.745431) (xy 47.293276 -375.739406) (xy 47.27698 -375.71103) (xy 47.251258 -375.650863)
			(xy 47.233845 -375.587787) (xy 47.225058 -375.522945) (xy 47.225054 -375.45751) (xy 47.233834 -375.392667)
			(xy 47.251239 -375.329589) (xy 47.276955 -375.269419) (xy 47.293276 -375.241058) (xy 47.296604 -375.23504)
			(xy 47.300202 -375.221771) (xy 47.300388 -375.214896) (xy 47.300388 -374.928892) (xy 47.300815 -374.918739)
			(xy 47.308611 -374.899989) (xy 47.323006 -374.885666) (xy 47.341795 -374.877965) (xy 47.35195 -374.877584)
			(xy 48.06823 -374.877584) (xy 48.078364 -374.878003) (xy 48.097094 -374.885749) (xy 48.111451 -374.900056)
			(xy 48.119261 -374.91876) (xy 48.119792 -374.928892) (xy 48.119792 -375.214896) (xy 48.119986 -375.221769)
			(xy 48.123593 -375.235032) (xy 48.126904 -375.241058) (xy 48.143252 -375.269405) (xy 48.168965 -375.32958)
			(xy 48.186368 -375.392661) (xy 48.194111 -375.449846) (xy 56.712102 -375.449846) (xy 56.716173 -375.394224)
			(xy 56.728299 -375.339787) (xy 56.748222 -375.287696) (xy 56.775518 -375.239061) (xy 56.809604 -375.194918)
			(xy 56.849753 -375.156209) (xy 56.895111 -375.123758) (xy 56.944711 -375.098257) (xy 56.997495 -375.08025)
			(xy 57.052338 -375.07012) (xy 57.108072 -375.068083) (xy 57.163509 -375.074183) (xy 57.191673 -375.081546)
			(xy 58.879484 -375.081546) (xy 58.883555 -375.025924) (xy 58.895681 -374.971487) (xy 58.915604 -374.919396)
			(xy 58.9429 -374.870761) (xy 58.976986 -374.826618) (xy 59.017135 -374.787909) (xy 59.062493 -374.755458)
			(xy 59.112093 -374.729957) (xy 59.164877 -374.71195) (xy 59.21972 -374.70182) (xy 59.275454 -374.699783)
			(xy 59.330891 -374.705883) (xy 59.384848 -374.719989) (xy 59.436177 -374.741801) (xy 59.483783 -374.770855)
			(xy 59.526651 -374.80653) (xy 59.563868 -374.848067) (xy 59.594641 -374.89458) (xy 59.618313 -374.945077)
			(xy 59.634381 -374.998484) (xy 59.642501 -375.05366) (xy 59.64301 -375.081546) (xy 59.642501 -375.109432)
			(xy 59.634381 -375.164608) (xy 59.618313 -375.218015) (xy 59.594641 -375.268512) (xy 59.563868 -375.315025)
			(xy 59.526651 -375.356562) (xy 59.483783 -375.392237) (xy 59.436177 -375.421291) (xy 59.384848 -375.443103)
			(xy 59.330891 -375.457209) (xy 59.275454 -375.463309) (xy 59.21972 -375.461272) (xy 59.164877 -375.451142)
			(xy 59.112093 -375.433135) (xy 59.062493 -375.407634) (xy 59.017135 -375.375183) (xy 58.976986 -375.336474)
			(xy 58.9429 -375.292331) (xy 58.915604 -375.243696) (xy 58.895681 -375.191605) (xy 58.883555 -375.137168)
			(xy 58.879484 -375.081546) (xy 57.191673 -375.081546) (xy 57.217466 -375.088289) (xy 57.268795 -375.110101)
			(xy 57.316401 -375.139155) (xy 57.359269 -375.17483) (xy 57.396486 -375.216367) (xy 57.427259 -375.26288)
			(xy 57.450931 -375.313377) (xy 57.466999 -375.366784) (xy 57.475119 -375.42196) (xy 57.475628 -375.449846)
			(xy 57.475119 -375.477732) (xy 57.466999 -375.532908) (xy 57.450931 -375.586315) (xy 57.427259 -375.636812)
			(xy 57.396486 -375.683325) (xy 57.359269 -375.724862) (xy 57.316401 -375.760537) (xy 57.268795 -375.789591)
			(xy 57.217466 -375.811403) (xy 57.163509 -375.825509) (xy 57.108072 -375.831609) (xy 57.052338 -375.829572)
			(xy 56.997495 -375.819442) (xy 56.944711 -375.801435) (xy 56.895111 -375.775934) (xy 56.849753 -375.743483)
			(xy 56.809604 -375.704774) (xy 56.775518 -375.660631) (xy 56.748222 -375.611996) (xy 56.728299 -375.559905)
			(xy 56.716173 -375.505468) (xy 56.712102 -375.449846) (xy 48.194111 -375.449846) (xy 48.195148 -375.457508)
			(xy 48.195144 -375.522947) (xy 48.186357 -375.587792) (xy 48.168947 -375.650872) (xy 48.143227 -375.711044)
			(xy 48.126904 -375.739406) (xy 48.123587 -375.74543) (xy 48.119983 -375.758694) (xy 48.119792 -375.765568)
			(xy 48.119792 -376.514868) (xy 48.119997 -376.52174) (xy 48.123596 -376.535003) (xy 48.126904 -376.54103)
			(xy 48.143228 -376.56939) (xy 48.168943 -376.629562) (xy 48.186349 -376.692641) (xy 48.1868 -376.69597)
			(xy 54.986172 -376.69597) (xy 54.990243 -376.640348) (xy 55.002369 -376.585911) (xy 55.022292 -376.53382)
			(xy 55.049588 -376.485185) (xy 55.083674 -376.441042) (xy 55.123823 -376.402333) (xy 55.169181 -376.369882)
			(xy 55.218781 -376.344381) (xy 55.271565 -376.326374) (xy 55.326408 -376.316244) (xy 55.382142 -376.314207)
			(xy 55.437579 -376.320307) (xy 55.491536 -376.334413) (xy 55.518106 -376.345704) (xy 59.301886 -376.345704)
			(xy 59.305957 -376.290082) (xy 59.318083 -376.235645) (xy 59.338006 -376.183554) (xy 59.365302 -376.134919)
			(xy 59.399388 -376.090776) (xy 59.439537 -376.052067) (xy 59.484895 -376.019616) (xy 59.534495 -375.994115)
			(xy 59.587279 -375.976108) (xy 59.642122 -375.965978) (xy 59.697856 -375.963941) (xy 59.753293 -375.970041)
			(xy 59.80725 -375.984147) (xy 59.858579 -376.005959) (xy 59.906185 -376.035013) (xy 59.949053 -376.070688)
			(xy 59.98627 -376.112225) (xy 60.017043 -376.158738) (xy 60.040715 -376.209235) (xy 60.056783 -376.262642)
			(xy 60.064903 -376.317818) (xy 60.065412 -376.345704) (xy 60.064903 -376.37359) (xy 60.056783 -376.428766)
			(xy 60.040715 -376.482173) (xy 60.017043 -376.53267) (xy 59.98627 -376.579183) (xy 59.949053 -376.62072)
			(xy 59.906185 -376.656395) (xy 59.858579 -376.685449) (xy 59.80725 -376.707261) (xy 59.753293 -376.721367)
			(xy 59.697856 -376.727467) (xy 59.642122 -376.72543) (xy 59.587279 -376.7153) (xy 59.534495 -376.697293)
			(xy 59.484895 -376.671792) (xy 59.439537 -376.639341) (xy 59.399388 -376.600632) (xy 59.365302 -376.556489)
			(xy 59.338006 -376.507854) (xy 59.318083 -376.455763) (xy 59.305957 -376.401326) (xy 59.301886 -376.345704)
			(xy 55.518106 -376.345704) (xy 55.542865 -376.356225) (xy 55.590471 -376.385279) (xy 55.633339 -376.420954)
			(xy 55.670556 -376.462491) (xy 55.701329 -376.509004) (xy 55.725001 -376.559501) (xy 55.741069 -376.612908)
			(xy 55.749189 -376.668084) (xy 55.749698 -376.69597) (xy 55.749189 -376.723856) (xy 55.741069 -376.779032)
			(xy 55.725001 -376.832439) (xy 55.701329 -376.882936) (xy 55.670556 -376.929449) (xy 55.633339 -376.970986)
			(xy 55.590471 -377.006661) (xy 55.542865 -377.035715) (xy 55.491536 -377.057527) (xy 55.437579 -377.071633)
			(xy 55.382142 -377.077733) (xy 55.326408 -377.075696) (xy 55.271565 -377.065566) (xy 55.218781 -377.047559)
			(xy 55.169181 -377.022058) (xy 55.123823 -376.989607) (xy 55.083674 -376.950898) (xy 55.049588 -376.906755)
			(xy 55.022292 -376.85812) (xy 55.002369 -376.806029) (xy 54.990243 -376.751592) (xy 54.986172 -376.69597)
			(xy 48.1868 -376.69597) (xy 48.195132 -376.757485) (xy 48.195131 -376.822922) (xy 48.186348 -376.887766)
			(xy 48.168941 -376.950845) (xy 48.143225 -377.011016) (xy 48.126904 -377.039378) (xy 48.123597 -377.045407)
			(xy 48.119987 -377.058667) (xy 48.119792 -377.06554) (xy 48.119792 -377.351544) (xy 48.119414 -377.361702)
			(xy 48.111603 -377.380457) (xy 48.097193 -377.394779) (xy 48.07839 -377.402476) (xy 48.06823 -377.402852)
			(xy 47.35195 -377.402852) (xy 47.341825 -377.402332) (xy 47.323104 -377.394619) (xy 47.308746 -377.380343)
			(xy 47.300926 -377.361666) (xy 47.300388 -377.351544) (xy 47.300388 -377.06554) (xy 47.300182 -377.058668)
			(xy 47.296583 -377.045405) (xy 47.293276 -377.039378) (xy 47.276956 -377.011015) (xy 47.251236 -376.950845)
			(xy 47.233826 -376.887766) (xy 47.225042 -376.822922) (xy 47.225041 -376.757485) (xy 46.589696 -376.757485)
			(xy 46.589696 -377.556268) (xy 58.845702 -377.556268) (xy 58.849773 -377.500646) (xy 58.861899 -377.446209)
			(xy 58.881822 -377.394118) (xy 58.909118 -377.345483) (xy 58.943204 -377.30134) (xy 58.983353 -377.262631)
			(xy 59.028711 -377.23018) (xy 59.078311 -377.204679) (xy 59.131095 -377.186672) (xy 59.185938 -377.176542)
			(xy 59.241672 -377.174505) (xy 59.297109 -377.180605) (xy 59.351066 -377.194711) (xy 59.402395 -377.216523)
			(xy 59.450001 -377.245577) (xy 59.492869 -377.281252) (xy 59.530086 -377.322789) (xy 59.560859 -377.369302)
			(xy 59.584531 -377.419799) (xy 59.600599 -377.473206) (xy 59.608719 -377.528382) (xy 59.609228 -377.556268)
			(xy 59.608719 -377.584154) (xy 59.600599 -377.63933) (xy 59.584531 -377.692737) (xy 59.560859 -377.743234)
			(xy 59.530086 -377.789747) (xy 59.492869 -377.831284) (xy 59.450001 -377.866959) (xy 59.402395 -377.896013)
			(xy 59.351066 -377.917825) (xy 59.297109 -377.931931) (xy 59.241672 -377.938031) (xy 59.185938 -377.935994)
			(xy 59.131095 -377.925864) (xy 59.078311 -377.907857) (xy 59.028711 -377.882356) (xy 58.983353 -377.849905)
			(xy 58.943204 -377.811196) (xy 58.909118 -377.767053) (xy 58.881822 -377.718418) (xy 58.861899 -377.666327)
			(xy 58.849773 -377.61189) (xy 58.845702 -377.556268) (xy 46.589696 -377.556268) (xy 46.589696 -378.376434)
			(xy 54.891938 -378.376434) (xy 54.896009 -378.320812) (xy 54.908135 -378.266375) (xy 54.928058 -378.214284)
			(xy 54.955354 -378.165649) (xy 54.98944 -378.121506) (xy 55.029589 -378.082797) (xy 55.074947 -378.050346)
			(xy 55.124547 -378.024845) (xy 55.177331 -378.006838) (xy 55.232174 -377.996708) (xy 55.287908 -377.994671)
			(xy 55.343345 -378.000771) (xy 55.397302 -378.014877) (xy 55.448631 -378.036689) (xy 55.496237 -378.065743)
			(xy 55.539105 -378.101418) (xy 55.576322 -378.142955) (xy 55.584423 -378.1552) (xy 55.980328 -378.1552)
			(xy 55.984399 -378.099578) (xy 55.996525 -378.045141) (xy 56.016448 -377.99305) (xy 56.043744 -377.944415)
			(xy 56.07783 -377.900272) (xy 56.117979 -377.861563) (xy 56.163337 -377.829112) (xy 56.212937 -377.803611)
			(xy 56.265721 -377.785604) (xy 56.320564 -377.775474) (xy 56.376298 -377.773437) (xy 56.431735 -377.779537)
			(xy 56.485692 -377.793643) (xy 56.537021 -377.815455) (xy 56.584627 -377.844509) (xy 56.627495 -377.880184)
			(xy 56.664712 -377.921721) (xy 56.695485 -377.968234) (xy 56.719157 -378.018731) (xy 56.735225 -378.072138)
			(xy 56.743345 -378.127314) (xy 56.743854 -378.1552) (xy 56.743345 -378.183086) (xy 56.735225 -378.238262)
			(xy 56.719157 -378.291669) (xy 56.695485 -378.342166) (xy 56.664712 -378.388679) (xy 56.627495 -378.430216)
			(xy 56.584627 -378.465891) (xy 56.537021 -378.494945) (xy 56.485692 -378.516757) (xy 56.431735 -378.530863)
			(xy 56.376298 -378.536963) (xy 56.320564 -378.534926) (xy 56.265721 -378.524796) (xy 56.212937 -378.506789)
			(xy 56.163337 -378.481288) (xy 56.117979 -378.448837) (xy 56.07783 -378.410128) (xy 56.043744 -378.365985)
			(xy 56.016448 -378.31735) (xy 55.996525 -378.265259) (xy 55.984399 -378.210822) (xy 55.980328 -378.1552)
			(xy 55.584423 -378.1552) (xy 55.607095 -378.189468) (xy 55.630767 -378.239965) (xy 55.646835 -378.293372)
			(xy 55.654955 -378.348548) (xy 55.655464 -378.376434) (xy 55.654955 -378.40432) (xy 55.646835 -378.459496)
			(xy 55.630767 -378.512903) (xy 55.607095 -378.5634) (xy 55.576322 -378.609913) (xy 55.539105 -378.65145)
			(xy 55.496237 -378.687125) (xy 55.448631 -378.716179) (xy 55.397302 -378.737991) (xy 55.343345 -378.752097)
			(xy 55.287908 -378.758197) (xy 55.232174 -378.75616) (xy 55.177331 -378.74603) (xy 55.124547 -378.728023)
			(xy 55.074947 -378.702522) (xy 55.029589 -378.670071) (xy 54.98944 -378.631362) (xy 54.955354 -378.587219)
			(xy 54.928058 -378.538584) (xy 54.908135 -378.486493) (xy 54.896009 -378.432056) (xy 54.891938 -378.376434)
			(xy 46.589696 -378.376434) (xy 46.589696 -378.829316) (xy 58.842146 -378.829316) (xy 58.846217 -378.773694)
			(xy 58.858343 -378.719257) (xy 58.878266 -378.667166) (xy 58.905562 -378.618531) (xy 58.939648 -378.574388)
			(xy 58.979797 -378.535679) (xy 59.025155 -378.503228) (xy 59.074755 -378.477727) (xy 59.127539 -378.45972)
			(xy 59.182382 -378.44959) (xy 59.238116 -378.447553) (xy 59.293553 -378.453653) (xy 59.34751 -378.467759)
			(xy 59.398839 -378.489571) (xy 59.446445 -378.518625) (xy 59.489313 -378.5543) (xy 59.52653 -378.595837)
			(xy 59.557303 -378.64235) (xy 59.580975 -378.692847) (xy 59.597043 -378.746254) (xy 59.605163 -378.80143)
			(xy 59.605672 -378.829316) (xy 59.605163 -378.857202) (xy 59.597043 -378.912378) (xy 59.580975 -378.965785)
			(xy 59.557303 -379.016282) (xy 59.52653 -379.062795) (xy 59.489313 -379.104332) (xy 59.446445 -379.140007)
			(xy 59.398839 -379.169061) (xy 59.34751 -379.190873) (xy 59.293553 -379.204979) (xy 59.238116 -379.211079)
			(xy 59.182382 -379.209042) (xy 59.127539 -379.198912) (xy 59.074755 -379.180905) (xy 59.025155 -379.155404)
			(xy 58.979797 -379.122953) (xy 58.939648 -379.084244) (xy 58.905562 -379.040101) (xy 58.878266 -378.991466)
			(xy 58.858343 -378.939375) (xy 58.846217 -378.884938) (xy 58.842146 -378.829316) (xy 46.589696 -378.829316)
			(xy 46.589696 -379.390148) (xy 47.223942 -379.390148) (xy 47.227933 -379.327981) (xy 47.239842 -379.266834)
			(xy 47.259471 -379.207713) (xy 47.2865 -379.151587) (xy 47.320484 -379.099378) (xy 47.360866 -379.051943)
			(xy 47.406982 -379.010062) (xy 47.458074 -378.974422) (xy 47.513305 -378.945608) (xy 47.571767 -378.924094)
			(xy 47.632501 -378.910232) (xy 47.694508 -378.90425) (xy 47.756771 -378.906246) (xy 47.818268 -378.916189)
			(xy 47.877989 -378.933913) (xy 47.934952 -378.95913) (xy 47.988223 -378.991423) (xy 48.036928 -379.030263)
			(xy 48.080265 -379.075013) (xy 48.117525 -379.124937) (xy 48.148094 -379.179216) (xy 48.171472 -379.236959)
			(xy 48.187273 -379.297217) (xy 48.195239 -379.359) (xy 48.195738 -379.390148) (xy 48.195239 -379.421296)
			(xy 48.187273 -379.483079) (xy 48.171472 -379.543337) (xy 48.148094 -379.60108) (xy 48.117525 -379.655359)
			(xy 48.114139 -379.659896) (xy 54.995316 -379.659896) (xy 54.999387 -379.604274) (xy 55.011513 -379.549837)
			(xy 55.031436 -379.497746) (xy 55.058732 -379.449111) (xy 55.092818 -379.404968) (xy 55.132967 -379.366259)
			(xy 55.178325 -379.333808) (xy 55.227925 -379.308307) (xy 55.280709 -379.2903) (xy 55.335552 -379.28017)
			(xy 55.391286 -379.278133) (xy 55.446723 -379.284233) (xy 55.50068 -379.298339) (xy 55.552009 -379.320151)
			(xy 55.599615 -379.349205) (xy 55.642483 -379.38488) (xy 55.6797 -379.426417) (xy 55.710473 -379.47293)
			(xy 55.734145 -379.523427) (xy 55.750213 -379.576834) (xy 55.758333 -379.63201) (xy 55.758842 -379.659896)
			(xy 55.758333 -379.687782) (xy 55.750213 -379.742958) (xy 55.734145 -379.796365) (xy 55.710473 -379.846862)
			(xy 55.6797 -379.893375) (xy 55.642483 -379.934912) (xy 55.599615 -379.970587) (xy 55.552009 -379.999641)
			(xy 55.50068 -380.021453) (xy 55.446723 -380.035559) (xy 55.391286 -380.041659) (xy 55.335552 -380.039622)
			(xy 55.280709 -380.029492) (xy 55.227925 -380.011485) (xy 55.178325 -379.985984) (xy 55.132967 -379.953533)
			(xy 55.092818 -379.914824) (xy 55.058732 -379.870681) (xy 55.031436 -379.822046) (xy 55.011513 -379.769955)
			(xy 54.999387 -379.715518) (xy 54.995316 -379.659896) (xy 48.114139 -379.659896) (xy 48.080265 -379.705283)
			(xy 48.036928 -379.750033) (xy 47.988223 -379.788873) (xy 47.934952 -379.821166) (xy 47.877989 -379.846383)
			(xy 47.818268 -379.864107) (xy 47.756771 -379.87405) (xy 47.694508 -379.876046) (xy 47.632501 -379.870064)
			(xy 47.571767 -379.856202) (xy 47.513305 -379.834688) (xy 47.458074 -379.805874) (xy 47.406982 -379.770234)
			(xy 47.360866 -379.728353) (xy 47.320484 -379.680918) (xy 47.2865 -379.628709) (xy 47.259471 -379.572583)
			(xy 47.239842 -379.513462) (xy 47.227933 -379.452315) (xy 47.223942 -379.390148) (xy 46.589696 -379.390148)
			(xy 46.589696 -380.69012) (xy 47.223942 -380.69012) (xy 47.227933 -380.627953) (xy 47.239842 -380.566806)
			(xy 47.259471 -380.507685) (xy 47.2865 -380.451559) (xy 47.320484 -380.39935) (xy 47.360866 -380.351915)
			(xy 47.406982 -380.310034) (xy 47.458074 -380.274394) (xy 47.513305 -380.24558) (xy 47.571767 -380.224066)
			(xy 47.632501 -380.210204) (xy 47.694508 -380.204222) (xy 47.756771 -380.206218) (xy 47.818268 -380.216161)
			(xy 47.877989 -380.233885) (xy 47.934952 -380.259102) (xy 47.988223 -380.291395) (xy 48.036928 -380.330235)
			(xy 48.080265 -380.374985) (xy 48.117525 -380.424909) (xy 48.148094 -380.479188) (xy 48.171472 -380.536931)
			(xy 48.187273 -380.597189) (xy 48.188186 -380.604268) (xy 56.220104 -380.604268) (xy 56.224175 -380.548646)
			(xy 56.236301 -380.494209) (xy 56.256224 -380.442118) (xy 56.28352 -380.393483) (xy 56.317606 -380.34934)
			(xy 56.357755 -380.310631) (xy 56.403113 -380.27818) (xy 56.452713 -380.252679) (xy 56.505497 -380.234672)
			(xy 56.56034 -380.224542) (xy 56.616074 -380.222505) (xy 56.671511 -380.228605) (xy 56.725468 -380.242711)
			(xy 56.776797 -380.264523) (xy 56.824403 -380.293577) (xy 56.867271 -380.329252) (xy 56.904488 -380.370789)
			(xy 56.935261 -380.417302) (xy 56.958933 -380.467799) (xy 56.975001 -380.521206) (xy 56.983121 -380.576382)
			(xy 56.98363 -380.604268) (xy 56.983121 -380.632154) (xy 56.975001 -380.68733) (xy 56.958933 -380.740737)
			(xy 56.935261 -380.791234) (xy 56.904488 -380.837747) (xy 56.867271 -380.879284) (xy 56.824403 -380.914959)
			(xy 56.776797 -380.944013) (xy 56.725468 -380.965825) (xy 56.671511 -380.979931) (xy 56.616074 -380.986031)
			(xy 56.56034 -380.983994) (xy 56.505497 -380.973864) (xy 56.452713 -380.955857) (xy 56.403113 -380.930356)
			(xy 56.357755 -380.897905) (xy 56.317606 -380.859196) (xy 56.28352 -380.815053) (xy 56.256224 -380.766418)
			(xy 56.236301 -380.714327) (xy 56.224175 -380.65989) (xy 56.220104 -380.604268) (xy 48.188186 -380.604268)
			(xy 48.195239 -380.658972) (xy 48.195738 -380.69012) (xy 48.195239 -380.721268) (xy 48.187273 -380.783051)
			(xy 48.171472 -380.843309) (xy 48.148094 -380.901052) (xy 48.117525 -380.955331) (xy 48.080265 -381.005255)
			(xy 48.036928 -381.050005) (xy 47.988223 -381.088845) (xy 47.934952 -381.121138) (xy 47.877989 -381.146355)
			(xy 47.818268 -381.164079) (xy 47.756771 -381.174022) (xy 47.694508 -381.176018) (xy 47.632501 -381.170036)
			(xy 47.571767 -381.156174) (xy 47.513305 -381.13466) (xy 47.458074 -381.105846) (xy 47.406982 -381.070206)
			(xy 47.360866 -381.028325) (xy 47.320484 -380.98089) (xy 47.2865 -380.928681) (xy 47.259471 -380.872555)
			(xy 47.239842 -380.813434) (xy 47.227933 -380.752287) (xy 47.223942 -380.69012) (xy 46.589696 -380.69012)
			(xy 46.589696 -381.620268) (xy 57.056272 -381.620268) (xy 57.060343 -381.564646) (xy 57.072469 -381.510209)
			(xy 57.092392 -381.458118) (xy 57.119688 -381.409483) (xy 57.153774 -381.36534) (xy 57.193923 -381.326631)
			(xy 57.239281 -381.29418) (xy 57.288881 -381.268679) (xy 57.341665 -381.250672) (xy 57.396508 -381.240542)
			(xy 57.452242 -381.238505) (xy 57.507679 -381.244605) (xy 57.561636 -381.258711) (xy 57.612965 -381.280523)
			(xy 57.660571 -381.309577) (xy 57.703439 -381.345252) (xy 57.740656 -381.386789) (xy 57.771429 -381.433302)
			(xy 57.795101 -381.483799) (xy 57.811169 -381.537206) (xy 57.819289 -381.592382) (xy 57.819798 -381.620268)
			(xy 57.819289 -381.648154) (xy 57.811169 -381.70333) (xy 57.795101 -381.756737) (xy 57.771429 -381.807234)
			(xy 57.740656 -381.853747) (xy 57.703439 -381.895284) (xy 57.660571 -381.930959) (xy 57.612965 -381.960013)
			(xy 57.561636 -381.981825) (xy 57.507679 -381.995931) (xy 57.452242 -382.002031) (xy 57.396508 -381.999994)
			(xy 57.341665 -381.989864) (xy 57.288881 -381.971857) (xy 57.239281 -381.946356) (xy 57.193923 -381.913905)
			(xy 57.153774 -381.875196) (xy 57.119688 -381.831053) (xy 57.092392 -381.782418) (xy 57.072469 -381.730327)
			(xy 57.060343 -381.67589) (xy 57.056272 -381.620268) (xy 46.589696 -381.620268) (xy 46.589696 -382.281684)
			(xy 58.230514 -382.281684) (xy 58.234585 -382.226062) (xy 58.246711 -382.171625) (xy 58.266634 -382.119534)
			(xy 58.29393 -382.070899) (xy 58.328016 -382.026756) (xy 58.368165 -381.988047) (xy 58.413523 -381.955596)
			(xy 58.463123 -381.930095) (xy 58.515907 -381.912088) (xy 58.57075 -381.901958) (xy 58.626484 -381.899921)
			(xy 58.681921 -381.906021) (xy 58.735878 -381.920127) (xy 58.787207 -381.941939) (xy 58.834813 -381.970993)
			(xy 58.877681 -382.006668) (xy 58.914898 -382.048205) (xy 58.945671 -382.094718) (xy 58.969343 -382.145215)
			(xy 58.985411 -382.198622) (xy 58.993531 -382.253798) (xy 58.99404 -382.281684) (xy 58.993531 -382.30957)
			(xy 58.985411 -382.364746) (xy 58.969343 -382.418153) (xy 58.945671 -382.46865) (xy 58.914898 -382.515163)
			(xy 58.877681 -382.5567) (xy 58.834813 -382.592375) (xy 58.787207 -382.621429) (xy 58.735878 -382.643241)
			(xy 58.681921 -382.657347) (xy 58.626484 -382.663447) (xy 58.57075 -382.66141) (xy 58.515907 -382.65128)
			(xy 58.463123 -382.633273) (xy 58.413523 -382.607772) (xy 58.368165 -382.575321) (xy 58.328016 -382.536612)
			(xy 58.29393 -382.492469) (xy 58.266634 -382.443834) (xy 58.246711 -382.391743) (xy 58.234585 -382.337306)
			(xy 58.230514 -382.281684) (xy 46.589696 -382.281684) (xy 46.589696 -383.322789) (xy 47.225019 -383.322789)
			(xy 47.225023 -383.257349) (xy 47.233812 -383.192502) (xy 47.251226 -383.129422) (xy 47.27695 -383.069251)
			(xy 47.293276 -383.04089) (xy 47.296593 -383.034866) (xy 47.300198 -383.021602) (xy 47.300388 -383.014728)
			(xy 47.300388 -382.728724) (xy 47.300841 -382.718573) (xy 47.308626 -382.699823) (xy 47.323013 -382.685499)
			(xy 47.341797 -382.677797) (xy 47.35195 -382.677416) (xy 48.06823 -382.677416) (xy 48.078356 -382.677901)
			(xy 48.097073 -382.685634) (xy 48.111427 -382.699921) (xy 48.11925 -382.718601) (xy 48.119792 -382.728724)
			(xy 48.119792 -383.014728) (xy 48.119974 -383.021602) (xy 48.123589 -383.034865) (xy 48.126904 -383.04089)
			(xy 48.143194 -383.069269) (xy 48.168913 -383.129436) (xy 48.186322 -383.192511) (xy 48.195109 -383.257352)
			(xy 48.195113 -383.322786) (xy 48.186335 -383.387628) (xy 48.168933 -383.450705) (xy 48.143222 -383.510876)
			(xy 48.126904 -383.539238) (xy 48.123576 -383.545256) (xy 48.119979 -383.558525) (xy 48.119792 -383.5654)
			(xy 48.119792 -384.024886) (xy 59.976764 -384.024886) (xy 59.980835 -383.969264) (xy 59.992961 -383.914827)
			(xy 60.012884 -383.862736) (xy 60.04018 -383.814101) (xy 60.074266 -383.769958) (xy 60.114415 -383.731249)
			(xy 60.159773 -383.698798) (xy 60.209373 -383.673297) (xy 60.262157 -383.65529) (xy 60.317 -383.64516)
			(xy 60.372734 -383.643123) (xy 60.428171 -383.649223) (xy 60.482128 -383.663329) (xy 60.533457 -383.685141)
			(xy 60.581063 -383.714195) (xy 60.623931 -383.74987) (xy 60.661148 -383.791407) (xy 60.691921 -383.83792)
			(xy 60.715593 -383.888417) (xy 60.723333 -383.914142) (xy 61.475872 -383.914142) (xy 61.479943 -383.85852)
			(xy 61.492069 -383.804083) (xy 61.511992 -383.751992) (xy 61.539288 -383.703357) (xy 61.573374 -383.659214)
			(xy 61.613523 -383.620505) (xy 61.658881 -383.588054) (xy 61.708481 -383.562553) (xy 61.761265 -383.544546)
			(xy 61.816108 -383.534416) (xy 61.871842 -383.532379) (xy 61.927279 -383.538479) (xy 61.981236 -383.552585)
			(xy 62.032565 -383.574397) (xy 62.080171 -383.603451) (xy 62.123039 -383.639126) (xy 62.160256 -383.680663)
			(xy 62.191029 -383.727176) (xy 62.214701 -383.777673) (xy 62.230769 -383.83108) (xy 62.238889 -383.886256)
			(xy 62.239398 -383.914142) (xy 62.238889 -383.942028) (xy 62.230769 -383.997204) (xy 62.214701 -384.050611)
			(xy 62.191029 -384.101108) (xy 62.160256 -384.147621) (xy 62.123039 -384.189158) (xy 62.080171 -384.224833)
			(xy 62.032565 -384.253887) (xy 61.981236 -384.275699) (xy 61.927279 -384.289805) (xy 61.871842 -384.295905)
			(xy 61.816108 -384.293868) (xy 61.761265 -384.283738) (xy 61.708481 -384.265731) (xy 61.658881 -384.24023)
			(xy 61.613523 -384.207779) (xy 61.573374 -384.16907) (xy 61.539288 -384.124927) (xy 61.511992 -384.076292)
			(xy 61.492069 -384.024201) (xy 61.479943 -383.969764) (xy 61.475872 -383.914142) (xy 60.723333 -383.914142)
			(xy 60.731661 -383.941824) (xy 60.739781 -383.997) (xy 60.74029 -384.024886) (xy 60.739781 -384.052772)
			(xy 60.731661 -384.107948) (xy 60.715593 -384.161355) (xy 60.691921 -384.211852) (xy 60.661148 -384.258365)
			(xy 60.623931 -384.299902) (xy 60.581063 -384.335577) (xy 60.533457 -384.364631) (xy 60.482128 -384.386443)
			(xy 60.428171 -384.400549) (xy 60.372734 -384.406649) (xy 60.317 -384.404612) (xy 60.262157 -384.394482)
			(xy 60.209373 -384.376475) (xy 60.159773 -384.350974) (xy 60.114415 -384.318523) (xy 60.074266 -384.279814)
			(xy 60.04018 -384.235671) (xy 60.012884 -384.187036) (xy 59.992961 -384.134945) (xy 59.980835 -384.080508)
			(xy 59.976764 -384.024886) (xy 48.119792 -384.024886) (xy 48.119792 -384.3147) (xy 48.119985 -384.321573)
			(xy 48.123592 -384.334836) (xy 48.126904 -384.340862) (xy 48.143255 -384.369207) (xy 48.168968 -384.429382)
			(xy 48.186371 -384.492464) (xy 48.19515 -384.557312) (xy 48.195146 -384.62275) (xy 48.186359 -384.687596)
			(xy 48.182159 -384.702812) (xy 57.268616 -384.702812) (xy 57.272687 -384.64719) (xy 57.284813 -384.592753)
			(xy 57.304736 -384.540662) (xy 57.332032 -384.492027) (xy 57.366118 -384.447884) (xy 57.406267 -384.409175)
			(xy 57.451625 -384.376724) (xy 57.501225 -384.351223) (xy 57.554009 -384.333216) (xy 57.608852 -384.323086)
			(xy 57.664586 -384.321049) (xy 57.720023 -384.327149) (xy 57.77398 -384.341255) (xy 57.825309 -384.363067)
			(xy 57.872915 -384.392121) (xy 57.915783 -384.427796) (xy 57.953 -384.469333) (xy 57.983773 -384.515846)
			(xy 58.007445 -384.566343) (xy 58.023513 -384.61975) (xy 58.031633 -384.674926) (xy 58.032142 -384.702812)
			(xy 58.031633 -384.730698) (xy 58.023513 -384.785874) (xy 58.007445 -384.839281) (xy 57.983773 -384.889778)
			(xy 57.953 -384.936291) (xy 57.915783 -384.977828) (xy 57.872915 -385.013503) (xy 57.825309 -385.042557)
			(xy 57.77398 -385.064369) (xy 57.720023 -385.078475) (xy 57.664586 -385.084575) (xy 57.608852 -385.082538)
			(xy 57.554009 -385.072408) (xy 57.501225 -385.054401) (xy 57.451625 -385.0289) (xy 57.406267 -384.996449)
			(xy 57.366118 -384.95774) (xy 57.332032 -384.913597) (xy 57.304736 -384.864962) (xy 57.284813 -384.812871)
			(xy 57.272687 -384.758434) (xy 57.268616 -384.702812) (xy 48.182159 -384.702812) (xy 48.168947 -384.750676)
			(xy 48.143227 -384.810848) (xy 48.126904 -384.83921) (xy 48.123586 -384.845233) (xy 48.119982 -384.858498)
			(xy 48.119792 -384.865372) (xy 48.119792 -385.151376) (xy 48.119359 -385.16153) (xy 48.11157 -385.180283)
			(xy 48.097176 -385.194608) (xy 48.078386 -385.202307) (xy 48.06823 -385.202684) (xy 47.35195 -385.202684)
			(xy 47.341829 -385.202133) (xy 47.323114 -385.194426) (xy 47.308757 -385.18016) (xy 47.300932 -385.161493)
			(xy 47.300388 -385.151376) (xy 47.300388 -384.865372) (xy 47.300208 -384.858498) (xy 47.296592 -384.845235)
			(xy 47.293276 -384.83921) (xy 47.276983 -384.810832) (xy 47.251261 -384.750665) (xy 47.233848 -384.68759)
			(xy 47.22506 -384.622748) (xy 47.225056 -384.557314) (xy 47.233835 -384.492471) (xy 47.25124 -384.429393)
			(xy 47.276955 -384.369223) (xy 47.293276 -384.340862) (xy 47.296603 -384.334843) (xy 47.300201 -384.321575)
			(xy 47.300388 -384.3147) (xy 47.300388 -383.5654) (xy 47.300197 -383.558527) (xy 47.296588 -383.545264)
			(xy 47.293276 -383.539238) (xy 47.276922 -383.510894) (xy 47.251205 -383.450719) (xy 47.233799 -383.387637)
			(xy 47.225019 -383.322789) (xy 46.589696 -383.322789) (xy 46.589696 -384.344672) (xy 46.590132 -384.354736)
			(xy 46.597865 -384.373322) (xy 46.604682 -384.38074) (xy 46.66742 -384.443478) (xy 46.674263 -384.450877)
			(xy 46.681981 -384.469476) (xy 46.682406 -384.479546) (xy 46.682406 -385.718812) (xy 56.34177 -385.718812)
			(xy 56.345841 -385.66319) (xy 56.357967 -385.608753) (xy 56.37789 -385.556662) (xy 56.405186 -385.508027)
			(xy 56.439272 -385.463884) (xy 56.479421 -385.425175) (xy 56.524779 -385.392724) (xy 56.574379 -385.367223)
			(xy 56.627163 -385.349216) (xy 56.682006 -385.339086) (xy 56.73774 -385.337049) (xy 56.793177 -385.343149)
			(xy 56.847134 -385.357255) (xy 56.898463 -385.379067) (xy 56.946069 -385.408121) (xy 56.988937 -385.443796)
			(xy 57.026154 -385.485333) (xy 57.056927 -385.531846) (xy 57.080599 -385.582343) (xy 57.096667 -385.63575)
			(xy 57.104787 -385.690926) (xy 57.105296 -385.718812) (xy 57.104787 -385.746698) (xy 57.096667 -385.801874)
			(xy 57.080599 -385.855281) (xy 57.056927 -385.905778) (xy 57.026154 -385.952291) (xy 56.988937 -385.993828)
			(xy 56.946069 -386.029503) (xy 56.898463 -386.058557) (xy 56.88267 -386.065268) (xy 60.783214 -386.065268)
			(xy 60.787285 -386.009646) (xy 60.799411 -385.955209) (xy 60.819334 -385.903118) (xy 60.84663 -385.854483)
			(xy 60.880716 -385.81034) (xy 60.920865 -385.771631) (xy 60.966223 -385.73918) (xy 61.015823 -385.713679)
			(xy 61.068607 -385.695672) (xy 61.12345 -385.685542) (xy 61.179184 -385.683505) (xy 61.234621 -385.689605)
			(xy 61.288578 -385.703711) (xy 61.339907 -385.725523) (xy 61.387513 -385.754577) (xy 61.430381 -385.790252)
			(xy 61.467598 -385.831789) (xy 61.498371 -385.878302) (xy 61.522043 -385.928799) (xy 61.538111 -385.982206)
			(xy 61.546231 -386.037382) (xy 61.54674 -386.065268) (xy 61.546231 -386.093154) (xy 61.538111 -386.14833)
			(xy 61.522043 -386.201737) (xy 61.498371 -386.252234) (xy 61.467598 -386.298747) (xy 61.430381 -386.340284)
			(xy 61.387513 -386.375959) (xy 61.339907 -386.405013) (xy 61.288578 -386.426825) (xy 61.234621 -386.440931)
			(xy 61.179184 -386.447031) (xy 61.12345 -386.444994) (xy 61.068607 -386.434864) (xy 61.015823 -386.416857)
			(xy 60.966223 -386.391356) (xy 60.920865 -386.358905) (xy 60.880716 -386.320196) (xy 60.84663 -386.276053)
			(xy 60.819334 -386.227418) (xy 60.799411 -386.175327) (xy 60.787285 -386.12089) (xy 60.783214 -386.065268)
			(xy 56.88267 -386.065268) (xy 56.847134 -386.080369) (xy 56.793177 -386.094475) (xy 56.73774 -386.100575)
			(xy 56.682006 -386.098538) (xy 56.627163 -386.088408) (xy 56.574379 -386.070401) (xy 56.524779 -386.0449)
			(xy 56.479421 -386.012449) (xy 56.439272 -385.97374) (xy 56.405186 -385.929597) (xy 56.37789 -385.880962)
			(xy 56.357967 -385.828871) (xy 56.345841 -385.774434) (xy 56.34177 -385.718812) (xy 46.682406 -385.718812)
			(xy 46.682406 -386.734812) (xy 57.268616 -386.734812) (xy 57.272687 -386.67919) (xy 57.284813 -386.624753)
			(xy 57.304736 -386.572662) (xy 57.332032 -386.524027) (xy 57.366118 -386.479884) (xy 57.406267 -386.441175)
			(xy 57.451625 -386.408724) (xy 57.501225 -386.383223) (xy 57.554009 -386.365216) (xy 57.608852 -386.355086)
			(xy 57.664586 -386.353049) (xy 57.720023 -386.359149) (xy 57.77398 -386.373255) (xy 57.825309 -386.395067)
			(xy 57.872915 -386.424121) (xy 57.915783 -386.459796) (xy 57.953 -386.501333) (xy 57.983773 -386.547846)
			(xy 58.007445 -386.598343) (xy 58.023513 -386.65175) (xy 58.031633 -386.706926) (xy 58.032142 -386.734812)
			(xy 59.48248 -386.734812) (xy 59.486551 -386.67919) (xy 59.498677 -386.624753) (xy 59.5186 -386.572662)
			(xy 59.545896 -386.524027) (xy 59.579982 -386.479884) (xy 59.620131 -386.441175) (xy 59.665489 -386.408724)
			(xy 59.715089 -386.383223) (xy 59.767873 -386.365216) (xy 59.822716 -386.355086) (xy 59.87845 -386.353049)
			(xy 59.933887 -386.359149) (xy 59.987844 -386.373255) (xy 60.039173 -386.395067) (xy 60.086779 -386.424121)
			(xy 60.129647 -386.459796) (xy 60.166864 -386.501333) (xy 60.197637 -386.547846) (xy 60.221309 -386.598343)
			(xy 60.237377 -386.65175) (xy 60.245497 -386.706926) (xy 60.246006 -386.734812) (xy 60.245497 -386.762698)
			(xy 60.237377 -386.817874) (xy 60.221309 -386.871281) (xy 60.197637 -386.921778) (xy 60.166864 -386.968291)
			(xy 60.129647 -387.009828) (xy 60.086779 -387.045503) (xy 60.039173 -387.074557) (xy 59.987844 -387.096369)
			(xy 59.933887 -387.110475) (xy 59.87845 -387.116575) (xy 59.822716 -387.114538) (xy 59.767873 -387.104408)
			(xy 59.715089 -387.086401) (xy 59.665489 -387.0609) (xy 59.620131 -387.028449) (xy 59.579982 -386.98974)
			(xy 59.545896 -386.945597) (xy 59.5186 -386.896962) (xy 59.498677 -386.844871) (xy 59.486551 -386.790434)
			(xy 59.48248 -386.734812) (xy 58.032142 -386.734812) (xy 58.031633 -386.762698) (xy 58.023513 -386.817874)
			(xy 58.007445 -386.871281) (xy 57.983773 -386.921778) (xy 57.953 -386.968291) (xy 57.915783 -387.009828)
			(xy 57.872915 -387.045503) (xy 57.825309 -387.074557) (xy 57.77398 -387.096369) (xy 57.720023 -387.110475)
			(xy 57.664586 -387.116575) (xy 57.608852 -387.114538) (xy 57.554009 -387.104408) (xy 57.501225 -387.086401)
			(xy 57.451625 -387.0609) (xy 57.406267 -387.028449) (xy 57.366118 -386.98974) (xy 57.332032 -386.945597)
			(xy 57.304736 -386.896962) (xy 57.284813 -386.844871) (xy 57.272687 -386.790434) (xy 57.268616 -386.734812)
			(xy 46.682406 -386.734812) (xy 46.682406 -387.156198) (xy 62.08598 -387.156198) (xy 62.090051 -387.100576)
			(xy 62.102177 -387.046139) (xy 62.1221 -386.994048) (xy 62.149396 -386.945413) (xy 62.183482 -386.90127)
			(xy 62.223631 -386.862561) (xy 62.268989 -386.83011) (xy 62.318589 -386.804609) (xy 62.371373 -386.786602)
			(xy 62.426216 -386.776472) (xy 62.48195 -386.774435) (xy 62.537387 -386.780535) (xy 62.591344 -386.794641)
			(xy 62.642673 -386.816453) (xy 62.690279 -386.845507) (xy 62.733147 -386.881182) (xy 62.770364 -386.922719)
			(xy 62.801137 -386.969232) (xy 62.824809 -387.019729) (xy 62.840877 -387.073136) (xy 62.848997 -387.128312)
			(xy 62.849506 -387.156198) (xy 62.848997 -387.184084) (xy 62.840877 -387.23926) (xy 62.824809 -387.292667)
			(xy 62.801137 -387.343164) (xy 62.770364 -387.389677) (xy 62.733147 -387.431214) (xy 62.690279 -387.466889)
			(xy 62.642673 -387.495943) (xy 62.591344 -387.517755) (xy 62.537387 -387.531861) (xy 62.48195 -387.537961)
			(xy 62.426216 -387.535924) (xy 62.371373 -387.525794) (xy 62.318589 -387.507787) (xy 62.268989 -387.482286)
			(xy 62.223631 -387.449835) (xy 62.183482 -387.411126) (xy 62.149396 -387.366983) (xy 62.1221 -387.318348)
			(xy 62.102177 -387.266257) (xy 62.090051 -387.21182) (xy 62.08598 -387.156198) (xy 46.682406 -387.156198)
			(xy 46.682406 -388.265416) (xy 59.963302 -388.265416) (xy 59.967373 -388.209794) (xy 59.979499 -388.155357)
			(xy 59.999422 -388.103266) (xy 60.026718 -388.054631) (xy 60.060804 -388.010488) (xy 60.100953 -387.971779)
			(xy 60.146311 -387.939328) (xy 60.195911 -387.913827) (xy 60.248695 -387.89582) (xy 60.303538 -387.88569)
			(xy 60.359272 -387.883653) (xy 60.414709 -387.889753) (xy 60.468666 -387.903859) (xy 60.519995 -387.925671)
			(xy 60.567601 -387.954725) (xy 60.610469 -387.9904) (xy 60.647686 -388.031937) (xy 60.678459 -388.07845)
			(xy 60.702131 -388.128947) (xy 60.718199 -388.182354) (xy 60.726319 -388.23753) (xy 60.726828 -388.265416)
			(xy 60.726319 -388.293302) (xy 60.718199 -388.348478) (xy 60.702131 -388.401885) (xy 60.678459 -388.452382)
			(xy 60.647686 -388.498895) (xy 60.610469 -388.540432) (xy 60.567601 -388.576107) (xy 60.519995 -388.605161)
			(xy 60.468666 -388.626973) (xy 60.414709 -388.641079) (xy 60.359272 -388.647179) (xy 60.303538 -388.645142)
			(xy 60.248695 -388.635012) (xy 60.195911 -388.617005) (xy 60.146311 -388.591504) (xy 60.100953 -388.559053)
			(xy 60.060804 -388.520344) (xy 60.026718 -388.476201) (xy 59.999422 -388.427566) (xy 59.979499 -388.375475)
			(xy 59.967373 -388.321038) (xy 59.963302 -388.265416) (xy 46.682406 -388.265416) (xy 46.682406 -388.822438)
			(xy 55.493156 -388.822438) (xy 55.497227 -388.766816) (xy 55.509353 -388.712379) (xy 55.529276 -388.660288)
			(xy 55.556572 -388.611653) (xy 55.590658 -388.56751) (xy 55.630807 -388.528801) (xy 55.676165 -388.49635)
			(xy 55.725765 -388.470849) (xy 55.778549 -388.452842) (xy 55.833392 -388.442712) (xy 55.889126 -388.440675)
			(xy 55.944563 -388.446775) (xy 55.99852 -388.460881) (xy 56.049849 -388.482693) (xy 56.097455 -388.511747)
			(xy 56.140323 -388.547422) (xy 56.17754 -388.588959) (xy 56.208313 -388.635472) (xy 56.231985 -388.685969)
			(xy 56.248053 -388.739376) (xy 56.255716 -388.79145) (xy 57.41619 -388.79145) (xy 57.420261 -388.735828)
			(xy 57.432387 -388.681391) (xy 57.45231 -388.6293) (xy 57.479606 -388.580665) (xy 57.513692 -388.536522)
			(xy 57.553841 -388.497813) (xy 57.599199 -388.465362) (xy 57.648799 -388.439861) (xy 57.701583 -388.421854)
			(xy 57.756426 -388.411724) (xy 57.81216 -388.409687) (xy 57.867597 -388.415787) (xy 57.921554 -388.429893)
			(xy 57.972883 -388.451705) (xy 58.020489 -388.480759) (xy 58.063357 -388.516434) (xy 58.100574 -388.557971)
			(xy 58.131347 -388.604484) (xy 58.155019 -388.654981) (xy 58.171087 -388.708388) (xy 58.179207 -388.763564)
			(xy 58.179716 -388.79145) (xy 58.179207 -388.819336) (xy 58.171087 -388.874512) (xy 58.163294 -388.900416)
			(xy 58.70397 -388.900416) (xy 58.708041 -388.844794) (xy 58.720167 -388.790357) (xy 58.74009 -388.738266)
			(xy 58.767386 -388.689631) (xy 58.801472 -388.645488) (xy 58.841621 -388.606779) (xy 58.886979 -388.574328)
			(xy 58.936579 -388.548827) (xy 58.989363 -388.53082) (xy 59.044206 -388.52069) (xy 59.09994 -388.518653)
			(xy 59.155377 -388.524753) (xy 59.209334 -388.538859) (xy 59.260663 -388.560671) (xy 59.308269 -388.589725)
			(xy 59.351137 -388.6254) (xy 59.388354 -388.666937) (xy 59.419127 -388.71345) (xy 59.442799 -388.763947)
			(xy 59.458867 -388.817354) (xy 59.466987 -388.87253) (xy 59.467496 -388.900416) (xy 59.466987 -388.928302)
			(xy 59.458867 -388.983478) (xy 59.442799 -389.036885) (xy 59.435807 -389.0518) (xy 61.746382 -389.0518)
			(xy 61.750453 -388.996178) (xy 61.762579 -388.941741) (xy 61.782502 -388.88965) (xy 61.809798 -388.841015)
			(xy 61.843884 -388.796872) (xy 61.884033 -388.758163) (xy 61.929391 -388.725712) (xy 61.978991 -388.700211)
			(xy 62.031775 -388.682204) (xy 62.086618 -388.672074) (xy 62.142352 -388.670037) (xy 62.197789 -388.676137)
			(xy 62.251746 -388.690243) (xy 62.303075 -388.712055) (xy 62.350681 -388.741109) (xy 62.393549 -388.776784)
			(xy 62.430766 -388.818321) (xy 62.461539 -388.864834) (xy 62.485211 -388.915331) (xy 62.501279 -388.968738)
			(xy 62.509399 -389.023914) (xy 62.509908 -389.0518) (xy 62.509399 -389.079686) (xy 62.501279 -389.134862)
			(xy 62.485211 -389.188269) (xy 62.461539 -389.238766) (xy 62.430766 -389.285279) (xy 62.393549 -389.326816)
			(xy 62.350681 -389.362491) (xy 62.303075 -389.391545) (xy 62.251746 -389.413357) (xy 62.197789 -389.427463)
			(xy 62.142352 -389.433563) (xy 62.086618 -389.431526) (xy 62.031775 -389.421396) (xy 61.978991 -389.403389)
			(xy 61.929391 -389.377888) (xy 61.884033 -389.345437) (xy 61.843884 -389.306728) (xy 61.809798 -389.262585)
			(xy 61.782502 -389.21395) (xy 61.762579 -389.161859) (xy 61.750453 -389.107422) (xy 61.746382 -389.0518)
			(xy 59.435807 -389.0518) (xy 59.419127 -389.087382) (xy 59.388354 -389.133895) (xy 59.351137 -389.175432)
			(xy 59.308269 -389.211107) (xy 59.260663 -389.240161) (xy 59.209334 -389.261973) (xy 59.155377 -389.276079)
			(xy 59.09994 -389.282179) (xy 59.044206 -389.280142) (xy 58.989363 -389.270012) (xy 58.936579 -389.252005)
			(xy 58.886979 -389.226504) (xy 58.841621 -389.194053) (xy 58.801472 -389.155344) (xy 58.767386 -389.111201)
			(xy 58.74009 -389.062566) (xy 58.720167 -389.010475) (xy 58.708041 -388.956038) (xy 58.70397 -388.900416)
			(xy 58.163294 -388.900416) (xy 58.155019 -388.927919) (xy 58.131347 -388.978416) (xy 58.100574 -389.024929)
			(xy 58.063357 -389.066466) (xy 58.020489 -389.102141) (xy 57.972883 -389.131195) (xy 57.921554 -389.153007)
			(xy 57.867597 -389.167113) (xy 57.81216 -389.173213) (xy 57.756426 -389.171176) (xy 57.701583 -389.161046)
			(xy 57.648799 -389.143039) (xy 57.599199 -389.117538) (xy 57.553841 -389.085087) (xy 57.513692 -389.046378)
			(xy 57.479606 -389.002235) (xy 57.45231 -388.9536) (xy 57.432387 -388.901509) (xy 57.420261 -388.847072)
			(xy 57.41619 -388.79145) (xy 56.255716 -388.79145) (xy 56.256173 -388.794552) (xy 56.256682 -388.822438)
			(xy 56.256173 -388.850324) (xy 56.248053 -388.9055) (xy 56.231985 -388.958907) (xy 56.208313 -389.009404)
			(xy 56.17754 -389.055917) (xy 56.140323 -389.097454) (xy 56.097455 -389.133129) (xy 56.049849 -389.162183)
			(xy 55.99852 -389.183995) (xy 55.944563 -389.198101) (xy 55.889126 -389.204201) (xy 55.833392 -389.202164)
			(xy 55.778549 -389.192034) (xy 55.725765 -389.174027) (xy 55.676165 -389.148526) (xy 55.630807 -389.116075)
			(xy 55.590658 -389.077366) (xy 55.556572 -389.033223) (xy 55.529276 -388.984588) (xy 55.509353 -388.932497)
			(xy 55.497227 -388.87806) (xy 55.493156 -388.822438) (xy 46.682406 -388.822438) (xy 46.682406 -391.145014)
			(xy 56.036208 -391.145014) (xy 56.040279 -391.089392) (xy 56.052405 -391.034955) (xy 56.072328 -390.982864)
			(xy 56.099624 -390.934229) (xy 56.13371 -390.890086) (xy 56.173859 -390.851377) (xy 56.219217 -390.818926)
			(xy 56.268817 -390.793425) (xy 56.321601 -390.775418) (xy 56.376444 -390.765288) (xy 56.432178 -390.763251)
			(xy 56.487615 -390.769351) (xy 56.541572 -390.783457) (xy 56.592901 -390.805269) (xy 56.640507 -390.834323)
			(xy 56.683375 -390.869998) (xy 56.720592 -390.911535) (xy 56.751365 -390.958048) (xy 56.775037 -391.008545)
			(xy 56.791105 -391.061952) (xy 56.799225 -391.117128) (xy 56.799734 -391.145014) (xy 56.799225 -391.1729)
			(xy 56.791105 -391.228076) (xy 56.775037 -391.281483) (xy 56.751365 -391.33198) (xy 56.728021 -391.367264)
			(xy 57.50001 -391.367264) (xy 57.504081 -391.311642) (xy 57.516207 -391.257205) (xy 57.53613 -391.205114)
			(xy 57.563426 -391.156479) (xy 57.597512 -391.112336) (xy 57.637661 -391.073627) (xy 57.683019 -391.041176)
			(xy 57.732619 -391.015675) (xy 57.785403 -390.997668) (xy 57.840246 -390.987538) (xy 57.89598 -390.985501)
			(xy 57.951417 -390.991601) (xy 58.005374 -391.005707) (xy 58.056703 -391.027519) (xy 58.104309 -391.056573)
			(xy 58.147177 -391.092248) (xy 58.151442 -391.097008) (xy 58.991244 -391.097008) (xy 58.995315 -391.041386)
			(xy 59.007441 -390.986949) (xy 59.027364 -390.934858) (xy 59.05466 -390.886223) (xy 59.088746 -390.84208)
			(xy 59.128895 -390.803371) (xy 59.174253 -390.77092) (xy 59.223853 -390.745419) (xy 59.276637 -390.727412)
			(xy 59.33148 -390.717282) (xy 59.387214 -390.715245) (xy 59.442651 -390.721345) (xy 59.496608 -390.735451)
			(xy 59.547937 -390.757263) (xy 59.595543 -390.786317) (xy 59.638411 -390.821992) (xy 59.675628 -390.863529)
			(xy 59.706401 -390.910042) (xy 59.730073 -390.960539) (xy 59.743391 -391.004806) (xy 61.82563 -391.004806)
			(xy 61.829701 -390.949184) (xy 61.841827 -390.894747) (xy 61.86175 -390.842656) (xy 61.889046 -390.794021)
			(xy 61.923132 -390.749878) (xy 61.963281 -390.711169) (xy 62.008639 -390.678718) (xy 62.058239 -390.653217)
			(xy 62.111023 -390.63521) (xy 62.165866 -390.62508) (xy 62.2216 -390.623043) (xy 62.277037 -390.629143)
			(xy 62.330994 -390.643249) (xy 62.382323 -390.665061) (xy 62.429929 -390.694115) (xy 62.472797 -390.72979)
			(xy 62.510014 -390.771327) (xy 62.540787 -390.81784) (xy 62.564459 -390.868337) (xy 62.580527 -390.921744)
			(xy 62.588647 -390.97692) (xy 62.589156 -391.004806) (xy 62.588647 -391.032692) (xy 62.580527 -391.087868)
			(xy 62.577242 -391.098786) (xy 63.318642 -391.098786) (xy 63.322713 -391.043164) (xy 63.334839 -390.988727)
			(xy 63.354762 -390.936636) (xy 63.382058 -390.888001) (xy 63.416144 -390.843858) (xy 63.456293 -390.805149)
			(xy 63.501651 -390.772698) (xy 63.551251 -390.747197) (xy 63.604035 -390.72919) (xy 63.658878 -390.71906)
			(xy 63.714612 -390.717023) (xy 63.770049 -390.723123) (xy 63.824006 -390.737229) (xy 63.875335 -390.759041)
			(xy 63.922941 -390.788095) (xy 63.965809 -390.82377) (xy 64.003026 -390.865307) (xy 64.033799 -390.91182)
			(xy 64.057471 -390.962317) (xy 64.073539 -391.015724) (xy 64.081659 -391.0709) (xy 64.082168 -391.098786)
			(xy 64.081659 -391.126672) (xy 64.073539 -391.181848) (xy 64.057471 -391.235255) (xy 64.033799 -391.285752)
			(xy 64.003026 -391.332265) (xy 63.965809 -391.373802) (xy 63.922941 -391.409477) (xy 63.875335 -391.438531)
			(xy 63.824006 -391.460343) (xy 63.770049 -391.474449) (xy 63.714612 -391.480549) (xy 63.658878 -391.478512)
			(xy 63.604035 -391.468382) (xy 63.551251 -391.450375) (xy 63.501651 -391.424874) (xy 63.456293 -391.392423)
			(xy 63.416144 -391.353714) (xy 63.382058 -391.309571) (xy 63.354762 -391.260936) (xy 63.334839 -391.208845)
			(xy 63.322713 -391.154408) (xy 63.318642 -391.098786) (xy 62.577242 -391.098786) (xy 62.564459 -391.141275)
			(xy 62.540787 -391.191772) (xy 62.510014 -391.238285) (xy 62.472797 -391.279822) (xy 62.429929 -391.315497)
			(xy 62.382323 -391.344551) (xy 62.330994 -391.366363) (xy 62.277037 -391.380469) (xy 62.2216 -391.386569)
			(xy 62.165866 -391.384532) (xy 62.111023 -391.374402) (xy 62.058239 -391.356395) (xy 62.008639 -391.330894)
			(xy 61.963281 -391.298443) (xy 61.923132 -391.259734) (xy 61.889046 -391.215591) (xy 61.86175 -391.166956)
			(xy 61.841827 -391.114865) (xy 61.829701 -391.060428) (xy 61.82563 -391.004806) (xy 59.743391 -391.004806)
			(xy 59.746141 -391.013946) (xy 59.754261 -391.069122) (xy 59.75477 -391.097008) (xy 59.754261 -391.124894)
			(xy 59.746141 -391.18007) (xy 59.730073 -391.233477) (xy 59.706401 -391.283974) (xy 59.675628 -391.330487)
			(xy 59.638411 -391.372024) (xy 59.595543 -391.407699) (xy 59.547937 -391.436753) (xy 59.496608 -391.458565)
			(xy 59.442651 -391.472671) (xy 59.387214 -391.478771) (xy 59.33148 -391.476734) (xy 59.276637 -391.466604)
			(xy 59.223853 -391.448597) (xy 59.174253 -391.423096) (xy 59.128895 -391.390645) (xy 59.088746 -391.351936)
			(xy 59.05466 -391.307793) (xy 59.027364 -391.259158) (xy 59.007441 -391.207067) (xy 58.995315 -391.15263)
			(xy 58.991244 -391.097008) (xy 58.151442 -391.097008) (xy 58.184394 -391.133785) (xy 58.215167 -391.180298)
			(xy 58.238839 -391.230795) (xy 58.254907 -391.284202) (xy 58.263027 -391.339378) (xy 58.263536 -391.367264)
			(xy 58.263027 -391.39515) (xy 58.254907 -391.450326) (xy 58.240847 -391.497058) (xy 60.565028 -391.497058)
			(xy 60.569099 -391.441436) (xy 60.581225 -391.386999) (xy 60.601148 -391.334908) (xy 60.628444 -391.286273)
			(xy 60.66253 -391.24213) (xy 60.702679 -391.203421) (xy 60.748037 -391.17097) (xy 60.797637 -391.145469)
			(xy 60.850421 -391.127462) (xy 60.905264 -391.117332) (xy 60.960998 -391.115295) (xy 61.016435 -391.121395)
			(xy 61.070392 -391.135501) (xy 61.121721 -391.157313) (xy 61.169327 -391.186367) (xy 61.212195 -391.222042)
			(xy 61.249412 -391.263579) (xy 61.280185 -391.310092) (xy 61.303857 -391.360589) (xy 61.319925 -391.413996)
			(xy 61.328045 -391.469172) (xy 61.328554 -391.497058) (xy 61.328045 -391.524944) (xy 61.319925 -391.58012)
			(xy 61.303857 -391.633527) (xy 61.282577 -391.678922) (xy 64.618868 -391.678922) (xy 64.622939 -391.6233)
			(xy 64.635065 -391.568863) (xy 64.654988 -391.516772) (xy 64.682284 -391.468137) (xy 64.71637 -391.423994)
			(xy 64.756519 -391.385285) (xy 64.801877 -391.352834) (xy 64.851477 -391.327333) (xy 64.904261 -391.309326)
			(xy 64.959104 -391.299196) (xy 65.014838 -391.297159) (xy 65.070275 -391.303259) (xy 65.124232 -391.317365)
			(xy 65.175561 -391.339177) (xy 65.223167 -391.368231) (xy 65.266035 -391.403906) (xy 65.303252 -391.445443)
			(xy 65.334025 -391.491956) (xy 65.357697 -391.542453) (xy 65.373765 -391.59586) (xy 65.381885 -391.651036)
			(xy 65.382394 -391.678922) (xy 65.381885 -391.706808) (xy 65.373765 -391.761984) (xy 65.357697 -391.815391)
			(xy 65.334025 -391.865888) (xy 65.303252 -391.912401) (xy 65.266035 -391.953938) (xy 65.223167 -391.989613)
			(xy 65.175561 -392.018667) (xy 65.124232 -392.040479) (xy 65.070275 -392.054585) (xy 65.014838 -392.060685)
			(xy 64.959104 -392.058648) (xy 64.904261 -392.048518) (xy 64.851477 -392.030511) (xy 64.801877 -392.00501)
			(xy 64.756519 -391.972559) (xy 64.71637 -391.93385) (xy 64.682284 -391.889707) (xy 64.654988 -391.841072)
			(xy 64.635065 -391.788981) (xy 64.622939 -391.734544) (xy 64.618868 -391.678922) (xy 61.282577 -391.678922)
			(xy 61.280185 -391.684024) (xy 61.249412 -391.730537) (xy 61.212195 -391.772074) (xy 61.169327 -391.807749)
			(xy 61.121721 -391.836803) (xy 61.070392 -391.858615) (xy 61.016435 -391.872721) (xy 60.960998 -391.878821)
			(xy 60.905264 -391.876784) (xy 60.850421 -391.866654) (xy 60.797637 -391.848647) (xy 60.748037 -391.823146)
			(xy 60.702679 -391.790695) (xy 60.66253 -391.751986) (xy 60.628444 -391.707843) (xy 60.601148 -391.659208)
			(xy 60.581225 -391.607117) (xy 60.569099 -391.55268) (xy 60.565028 -391.497058) (xy 58.240847 -391.497058)
			(xy 58.238839 -391.503733) (xy 58.215167 -391.55423) (xy 58.184394 -391.600743) (xy 58.147177 -391.64228)
			(xy 58.104309 -391.677955) (xy 58.056703 -391.707009) (xy 58.005374 -391.728821) (xy 57.951417 -391.742927)
			(xy 57.89598 -391.749027) (xy 57.840246 -391.74699) (xy 57.785403 -391.73686) (xy 57.732619 -391.718853)
			(xy 57.683019 -391.693352) (xy 57.637661 -391.660901) (xy 57.597512 -391.622192) (xy 57.563426 -391.578049)
			(xy 57.53613 -391.529414) (xy 57.516207 -391.477323) (xy 57.504081 -391.422886) (xy 57.50001 -391.367264)
			(xy 56.728021 -391.367264) (xy 56.720592 -391.378493) (xy 56.683375 -391.42003) (xy 56.640507 -391.455705)
			(xy 56.592901 -391.484759) (xy 56.541572 -391.506571) (xy 56.487615 -391.520677) (xy 56.432178 -391.526777)
			(xy 56.376444 -391.52474) (xy 56.321601 -391.51461) (xy 56.268817 -391.496603) (xy 56.219217 -391.471102)
			(xy 56.173859 -391.438651) (xy 56.13371 -391.399942) (xy 56.099624 -391.355799) (xy 56.072328 -391.307164)
			(xy 56.052405 -391.255073) (xy 56.040279 -391.200636) (xy 56.036208 -391.145014) (xy 46.682406 -391.145014)
			(xy 46.682406 -393.671552) (xy 46.681974 -393.681618) (xy 46.674247 -393.70021) (xy 46.66742 -393.70762)
			(xy 46.38802 -393.98702) (xy 46.381175 -393.994419) (xy 46.373444 -394.013017) (xy 46.373034 -394.023088)
			(xy 46.373034 -397.55729) (xy 47.225044 -397.55729) (xy 47.233827 -397.492446) (xy 47.251235 -397.429368)
			(xy 47.276953 -397.369197) (xy 47.293276 -397.340836) (xy 47.296576 -397.334804) (xy 47.300191 -397.321546)
			(xy 47.300388 -397.314674) (xy 47.300388 -397.028924) (xy 47.300841 -397.018773) (xy 47.308626 -397.000023)
			(xy 47.323013 -396.985699) (xy 47.341797 -396.977997) (xy 47.35195 -396.977616) (xy 48.06823 -396.977616)
			(xy 48.078356 -396.978101) (xy 48.097073 -396.985834) (xy 48.111427 -397.000121) (xy 48.11925 -397.018801)
			(xy 48.119792 -397.028924) (xy 48.119792 -397.314674) (xy 48.119995 -397.321546) (xy 48.123596 -397.334809)
			(xy 48.126904 -397.340836) (xy 48.143233 -397.369193) (xy 48.168948 -397.429366) (xy 48.186354 -397.492445)
			(xy 48.195135 -397.55729) (xy 48.195134 -397.622727) (xy 48.18635 -397.687572) (xy 48.168942 -397.750651)
			(xy 48.143226 -397.810822) (xy 48.126904 -397.839184) (xy 48.123595 -397.845212) (xy 48.119986 -397.858473)
			(xy 48.119792 -397.865346) (xy 48.119792 -398.6149) (xy 48.119985 -398.621773) (xy 48.123592 -398.635036)
			(xy 48.126904 -398.641062) (xy 48.143255 -398.669407) (xy 48.168968 -398.729582) (xy 48.186371 -398.792664)
			(xy 48.19515 -398.857512) (xy 48.195146 -398.92295) (xy 48.186359 -398.987796) (xy 48.168947 -399.050876)
			(xy 48.143227 -399.111048) (xy 48.126904 -399.13941) (xy 48.123586 -399.145433) (xy 48.119982 -399.158698)
			(xy 48.119792 -399.165572) (xy 48.119792 -399.451576) (xy 48.119359 -399.46173) (xy 48.11157 -399.480483)
			(xy 48.097176 -399.494808) (xy 48.078386 -399.502507) (xy 48.06823 -399.502884) (xy 47.35195 -399.502884)
			(xy 47.341829 -399.502333) (xy 47.323114 -399.494626) (xy 47.308757 -399.48036) (xy 47.300932 -399.461693)
			(xy 47.300388 -399.451576) (xy 47.300388 -399.165572) (xy 47.300208 -399.158698) (xy 47.296592 -399.145435)
			(xy 47.293276 -399.13941) (xy 47.276983 -399.111032) (xy 47.251261 -399.050865) (xy 47.233848 -398.98779)
			(xy 47.22506 -398.922948) (xy 47.225056 -398.857514) (xy 47.233835 -398.792671) (xy 47.25124 -398.729593)
			(xy 47.276955 -398.669423) (xy 47.293276 -398.641062) (xy 47.296603 -398.635043) (xy 47.300201 -398.621775)
			(xy 47.300388 -398.6149) (xy 47.300388 -397.865346) (xy 47.30018 -397.858474) (xy 47.296583 -397.845211)
			(xy 47.293276 -397.839184) (xy 47.276961 -397.810818) (xy 47.251241 -397.750649) (xy 47.23383 -397.687571)
			(xy 47.225045 -397.622727) (xy 47.225044 -397.55729) (xy 46.373034 -397.55729) (xy 46.373034 -401.49018)
			(xy 47.223942 -401.49018) (xy 47.227933 -401.428013) (xy 47.239842 -401.366866) (xy 47.259471 -401.307745)
			(xy 47.2865 -401.251619) (xy 47.320484 -401.19941) (xy 47.360866 -401.151975) (xy 47.406982 -401.110094)
			(xy 47.458074 -401.074454) (xy 47.513305 -401.04564) (xy 47.571767 -401.024126) (xy 47.632501 -401.010264)
			(xy 47.694508 -401.004282) (xy 47.756771 -401.006278) (xy 47.818268 -401.016221) (xy 47.877989 -401.033945)
			(xy 47.934952 -401.059162) (xy 47.988223 -401.091455) (xy 48.036928 -401.130295) (xy 48.080265 -401.175045)
			(xy 48.117525 -401.224969) (xy 48.148094 -401.279248) (xy 48.171472 -401.336991) (xy 48.187273 -401.397249)
			(xy 48.195239 -401.459032) (xy 48.195738 -401.49018) (xy 48.195239 -401.521328) (xy 48.187273 -401.583111)
			(xy 48.171472 -401.643369) (xy 48.148094 -401.701112) (xy 48.117525 -401.755391) (xy 48.080265 -401.805315)
			(xy 48.036928 -401.850065) (xy 47.988223 -401.888905) (xy 47.934952 -401.921198) (xy 47.877989 -401.946415)
			(xy 47.818268 -401.964139) (xy 47.756771 -401.974082) (xy 47.694508 -401.976078) (xy 47.632501 -401.970096)
			(xy 47.571767 -401.956234) (xy 47.513305 -401.93472) (xy 47.458074 -401.905906) (xy 47.406982 -401.870266)
			(xy 47.360866 -401.828385) (xy 47.320484 -401.78095) (xy 47.2865 -401.728741) (xy 47.259471 -401.672615)
			(xy 47.239842 -401.613494) (xy 47.227933 -401.552347) (xy 47.223942 -401.49018) (xy 46.373034 -401.49018)
			(xy 46.373034 -402.790152) (xy 47.223942 -402.790152) (xy 47.227933 -402.727985) (xy 47.239842 -402.666838)
			(xy 47.259471 -402.607717) (xy 47.2865 -402.551591) (xy 47.320484 -402.499382) (xy 47.360866 -402.451947)
			(xy 47.406982 -402.410066) (xy 47.458074 -402.374426) (xy 47.513305 -402.345612) (xy 47.571767 -402.324098)
			(xy 47.632501 -402.310236) (xy 47.694508 -402.304254) (xy 47.756771 -402.30625) (xy 47.818268 -402.316193)
			(xy 47.877989 -402.333917) (xy 47.934952 -402.359134) (xy 47.988223 -402.391427) (xy 48.036928 -402.430267)
			(xy 48.080265 -402.475017) (xy 48.117525 -402.524941) (xy 48.148094 -402.57922) (xy 48.171472 -402.636963)
			(xy 48.187273 -402.697221) (xy 48.195239 -402.759004) (xy 48.195738 -402.790152) (xy 48.195239 -402.8213)
			(xy 48.187273 -402.883083) (xy 48.171472 -402.943341) (xy 48.148094 -403.001084) (xy 48.117525 -403.055363)
			(xy 48.080265 -403.105287) (xy 48.036928 -403.150037) (xy 47.988223 -403.188877) (xy 47.934952 -403.22117)
			(xy 47.877989 -403.246387) (xy 47.818268 -403.264111) (xy 47.756771 -403.274054) (xy 47.694508 -403.27605)
			(xy 47.632501 -403.270068) (xy 47.571767 -403.256206) (xy 47.513305 -403.234692) (xy 47.458074 -403.205878)
			(xy 47.406982 -403.170238) (xy 47.360866 -403.128357) (xy 47.320484 -403.080922) (xy 47.2865 -403.028713)
			(xy 47.259471 -402.972587) (xy 47.239842 -402.913466) (xy 47.227933 -402.852319) (xy 47.223942 -402.790152)
			(xy 46.373034 -402.790152) (xy 46.373034 -406.722792) (xy 47.225021 -406.722792) (xy 47.225025 -406.657353)
			(xy 47.233813 -406.592506) (xy 47.251227 -406.529426) (xy 47.27695 -406.469255) (xy 47.293276 -406.440894)
			(xy 47.296591 -406.43487) (xy 47.300197 -406.421606) (xy 47.300388 -406.414732) (xy 47.300388 -405.665432)
			(xy 47.300185 -405.65856) (xy 47.296584 -405.645297) (xy 47.293276 -405.63927) (xy 47.276949 -405.610911)
			(xy 47.25123 -405.55074) (xy 47.233821 -405.487661) (xy 47.225037 -405.422815) (xy 47.225038 -405.357378)
			(xy 47.233822 -405.292533) (xy 47.251232 -405.229454) (xy 47.276952 -405.169283) (xy 47.293276 -405.140922)
			(xy 47.296581 -405.134893) (xy 47.300193 -405.121633) (xy 47.300388 -405.11476) (xy 47.300388 -404.828756)
			(xy 47.300785 -404.818601) (xy 47.308593 -404.79985) (xy 47.322997 -404.785528) (xy 47.341792 -404.777828)
			(xy 47.35195 -404.777448) (xy 48.06823 -404.777448) (xy 48.07836 -404.777902) (xy 48.097083 -404.785641)
			(xy 48.111439 -404.799937) (xy 48.119255 -404.818629) (xy 48.119792 -404.828756) (xy 48.119792 -405.11476)
			(xy 48.12 -405.121632) (xy 48.123598 -405.134895) (xy 48.126904 -405.140922) (xy 48.143222 -405.169286)
			(xy 48.168937 -405.229457) (xy 48.186344 -405.292535) (xy 48.195127 -405.357379) (xy 48.195128 -405.422815)
			(xy 48.186345 -405.487658) (xy 48.168939 -405.550737) (xy 48.143225 -405.610908) (xy 48.126904 -405.63927)
			(xy 48.1236 -405.6453) (xy 48.119988 -405.65856) (xy 48.119792 -405.665432) (xy 48.119792 -406.414732)
			(xy 48.119973 -406.421606) (xy 48.123589 -406.434869) (xy 48.126904 -406.440894) (xy 48.143198 -406.469271)
			(xy 48.168916 -406.529439) (xy 48.186325 -406.592514) (xy 48.195111 -406.657356) (xy 48.195115 -406.72279)
			(xy 48.186336 -406.787632) (xy 48.168934 -406.850709) (xy 48.143223 -406.91088) (xy 48.126904 -406.939242)
			(xy 48.123575 -406.945259) (xy 48.119978 -406.958529) (xy 48.119792 -406.965404) (xy 48.119792 -407.251408)
			(xy 48.119385 -407.261564) (xy 48.111585 -407.280318) (xy 48.097184 -407.294641) (xy 48.078388 -407.302339)
			(xy 48.06823 -407.302716) (xy 47.35195 -407.302716) (xy 47.341821 -407.302231) (xy 47.323093 -407.294512)
			(xy 47.308733 -407.280224) (xy 47.30092 -407.261534) (xy 47.300388 -407.251408) (xy 47.300388 -406.965404)
			(xy 47.300196 -406.958531) (xy 47.296588 -406.945268) (xy 47.293276 -406.939242) (xy 47.276926 -406.910896)
			(xy 47.251208 -406.850722) (xy 47.233802 -406.78764) (xy 47.225021 -406.722792) (xy 46.373034 -406.722792)
			(xy 46.373034 -410.622705) (xy 47.22503 -410.622705) (xy 47.225032 -410.557267) (xy 47.233818 -410.492421)
			(xy 47.25123 -410.429342) (xy 47.276952 -410.369171) (xy 47.293276 -410.34081) (xy 47.296585 -410.334783)
			(xy 47.300195 -410.321521) (xy 47.300388 -410.314648) (xy 47.300388 -409.565348) (xy 47.300179 -409.558476)
			(xy 47.296583 -409.545213) (xy 47.293276 -409.539186) (xy 47.276963 -409.51082) (xy 47.251242 -409.45065)
			(xy 47.233832 -409.387572) (xy 47.225046 -409.322728) (xy 47.225045 -409.257292) (xy 47.233828 -409.192448)
			(xy 47.251235 -409.129369) (xy 47.276953 -409.069199) (xy 47.293276 -409.040838) (xy 47.296576 -409.034806)
			(xy 47.300191 -409.021548) (xy 47.300388 -409.014676) (xy 47.300388 -408.728672) (xy 47.300798 -408.718518)
			(xy 47.308601 -408.699767) (xy 47.323001 -408.685445) (xy 47.341793 -408.677744) (xy 47.35195 -408.677364)
			(xy 48.06823 -408.677364) (xy 48.078362 -408.677803) (xy 48.097088 -408.685545) (xy 48.111444 -408.699846)
			(xy 48.119258 -408.718542) (xy 48.119792 -408.728672) (xy 48.119792 -409.014676) (xy 48.119994 -409.021548)
			(xy 48.123595 -409.034811) (xy 48.126904 -409.040838) (xy 48.143235 -409.069194) (xy 48.168949 -409.129367)
			(xy 48.186355 -409.192447) (xy 48.195136 -409.257292) (xy 48.195135 -409.322729) (xy 48.186351 -409.387574)
			(xy 48.168943 -409.450653) (xy 48.143226 -409.510824) (xy 48.126904 -409.539186) (xy 48.123595 -409.545213)
			(xy 48.119985 -409.558475) (xy 48.119792 -409.565348) (xy 48.119792 -410.314648) (xy 48.120005 -410.32152)
			(xy 48.123599 -410.334782) (xy 48.126904 -410.34081) (xy 48.143211 -410.369179) (xy 48.168928 -410.429349)
			(xy 48.186336 -410.492426) (xy 48.19512 -410.557269) (xy 48.195122 -410.622704) (xy 48.186341 -410.687547)
			(xy 48.168937 -410.750625) (xy 48.143224 -410.810796) (xy 48.126904 -410.839158) (xy 48.123604 -410.84519)
			(xy 48.119989 -410.858448) (xy 48.119792 -410.86532) (xy 48.119792 -411.151324) (xy 48.119398 -411.161481)
			(xy 48.111593 -411.180235) (xy 48.097188 -411.194558) (xy 48.078389 -411.202255) (xy 48.06823 -411.202632)
			(xy 47.35195 -411.202632) (xy 47.341823 -411.202132) (xy 47.323098 -411.194415) (xy 47.308739 -411.180132)
			(xy 47.300923 -411.161448) (xy 47.300388 -411.151324) (xy 47.300388 -410.86532) (xy 47.30019 -410.858447)
			(xy 47.296586 -410.845184) (xy 47.293276 -410.839158) (xy 47.276939 -410.810805) (xy 47.251221 -410.750632)
			(xy 47.233813 -410.687552) (xy 47.22503 -410.622705) (xy 46.373034 -410.622705) (xy 46.373034 -415.868104)
			(xy 46.373459 -415.878173) (xy 46.381178 -415.896773) (xy 46.38802 -415.904172) (xy 47.612554 -417.128706)
			(xy 47.619956 -417.135543) (xy 47.638554 -417.143257) (xy 47.648622 -417.143692)
		)
		(stroke
			(width 0)
			(type solid)
		)
		(fill yes)
		(layer "In5.Cu")
		(net "GND")
	)
	(gr_poly
		(pts
			(xy 248.211848 -163.120832) (xy 248.221373 -163.120443) (xy 248.239131 -163.113544) (xy 248.246392 -163.10737)
			(xy 248.249186 -163.104576) (xy 248.252234 -163.075112) (xy 248.255631 -163.047319) (xy 248.269522 -162.993079)
			(xy 248.291191 -162.941451) (xy 248.320173 -162.893545) (xy 248.355845 -162.850389) (xy 248.397442 -162.81291)
			(xy 248.444069 -162.781912) (xy 248.494726 -162.758062) (xy 248.548325 -162.741872) (xy 248.603715 -162.733689)
			(xy 248.659705 -162.733689) (xy 248.715095 -162.741872) (xy 248.768694 -162.758062) (xy 248.819351 -162.781912)
			(xy 248.865978 -162.81291) (xy 248.907575 -162.850389) (xy 248.943247 -162.893545) (xy 248.972229 -162.941451)
			(xy 248.993898 -162.993079) (xy 249.007789 -163.047319) (xy 249.011186 -163.075112) (xy 249.012202 -163.085526)
			(xy 249.013549 -163.094604) (xy 249.021745 -163.11101) (xy 249.028204 -163.11753) (xy 249.03176 -163.120832)
			(xy 252.691646 -163.120832) (xy 252.701713 -163.120401) (xy 252.720309 -163.112679) (xy 252.727714 -163.105846)
			(xy 253.29769 -162.53587) (xy 253.304533 -162.52847) (xy 253.312258 -162.509872) (xy 253.312676 -162.499802)
			(xy 253.312676 -158.12135) (xy 253.313133 -158.088495) (xy 253.320485 -158.023198) (xy 253.3351 -157.959135)
			(xy 253.356796 -157.89711) (xy 253.3853 -157.837905) (xy 253.420253 -157.782263) (xy 253.461217 -157.730884)
			(xy 253.484126 -157.70733) (xy 253.772416 -157.41904) (xy 253.779262 -157.411642) (xy 253.786988 -157.393043)
			(xy 253.787402 -157.382972) (xy 253.787402 -151.994108) (xy 253.786894 -151.987504) (xy 253.784903 -151.976597)
			(xy 253.773048 -151.957891) (xy 253.764034 -151.951436) (xy 253.687326 -151.905716) (xy 253.681662 -151.902498)
			(xy 253.669189 -151.89876) (xy 253.662688 -151.89835) (xy 253.64948 -151.898096) (xy 253.647956 -151.898858)
			(xy 253.637542 -151.9047) (xy 253.609512 -151.919133) (xy 253.549888 -151.939611) (xy 253.487707 -151.949999)
			(xy 253.456186 -151.950674) (xy 253.448566 -151.950674) (xy 253.420367 -151.949638) (xy 253.364721 -151.940286)
			(xy 253.311059 -151.922839) (xy 253.260552 -151.89768) (xy 253.214301 -151.865356) (xy 253.173316 -151.826573)
			(xy 253.138489 -151.782176) (xy 253.110581 -151.733135) (xy 253.0902 -151.680517) (xy 253.077791 -151.625472)
			(xy 253.073624 -151.569199) (xy 253.077791 -151.512927) (xy 253.0902 -151.457882) (xy 253.110581 -151.405264)
			(xy 253.13849 -151.356223) (xy 253.173316 -151.311826) (xy 253.214302 -151.273043) (xy 253.260553 -151.240719)
			(xy 253.31106 -151.21556) (xy 253.364722 -151.198114) (xy 253.420368 -151.188761) (xy 253.448566 -151.187658)
			(xy 253.456186 -151.187658) (xy 253.487655 -151.188301) (xy 253.549739 -151.198627) (xy 253.609287 -151.219003)
			(xy 253.637288 -151.233378) (xy 253.637796 -151.233886) (xy 253.64821 -151.23922) (xy 253.64948 -151.239982)
			(xy 253.662434 -151.239728) (xy 253.668985 -151.2394) (xy 253.681596 -151.235807) (xy 253.687326 -151.232616)
			(xy 253.732284 -151.205946) (xy 253.76378 -151.18715) (xy 253.770766 -151.18236) (xy 253.781338 -151.169139)
			(xy 253.787024 -151.153193) (xy 253.787402 -151.144732) (xy 253.787402 -147.533106) (xy 253.786863 -147.522087)
			(xy 253.777645 -147.50207) (xy 253.769622 -147.494498) (xy 253.705868 -147.443444) (xy 253.701324 -147.440033)
			(xy 253.691064 -147.435156) (xy 253.685548 -147.433792) (xy 253.674626 -147.431252) (xy 253.662942 -147.434046)
			(xy 253.641715 -147.438667) (xy 253.598557 -147.443638) (xy 253.576836 -147.443952) (xy 253.576328 -147.443952)
			(xy 253.549071 -147.443491) (xy 253.49511 -147.435736) (xy 253.442803 -147.420381) (xy 253.393214 -147.397737)
			(xy 253.347352 -147.368267) (xy 253.306151 -147.332569) (xy 253.27045 -147.291371) (xy 253.240976 -147.245511)
			(xy 253.218329 -147.195923) (xy 253.20297 -147.143617) (xy 253.195211 -147.089657) (xy 253.195211 -147.035143)
			(xy 253.20297 -146.981183) (xy 253.218329 -146.928877) (xy 253.240976 -146.879289) (xy 253.27045 -146.833429)
			(xy 253.306151 -146.792231) (xy 253.347352 -146.756533) (xy 253.393214 -146.727063) (xy 253.442803 -146.704419)
			(xy 253.49511 -146.689064) (xy 253.549071 -146.681309) (xy 253.576328 -146.680936) (xy 253.579376 -146.680936)
			(xy 253.60046 -146.681369) (xy 253.642342 -146.686329) (xy 253.662942 -146.690842) (xy 253.674626 -146.693636)
			(xy 253.685548 -146.691096) (xy 253.691049 -146.689691) (xy 253.701302 -146.684819) (xy 253.705868 -146.681444)
			(xy 253.769622 -146.63039) (xy 253.777641 -146.622816) (xy 253.786853 -146.6028) (xy 253.787402 -146.591782)
			(xy 253.787402 -117.446044) (xy 253.787836 -117.435978) (xy 253.795564 -117.417389) (xy 253.802388 -117.409976)
			(xy 254.355346 -116.857018) (xy 254.360543 -116.851268) (xy 254.367517 -116.837435) (xy 254.369062 -116.82984)
			(xy 254.369824 -116.821458) (xy 254.369824 -116.338604) (xy 254.369478 -116.329913) (xy 254.363631 -116.313545)
			(xy 254.358394 -116.3066) (xy 254.355092 -116.30279) (xy 247.380252 -109.32795) (xy 247.373731 -109.321975)
			(xy 247.357725 -109.314482) (xy 247.340126 -109.312864) (xy 247.331484 -109.314742) (xy 247.247156 -109.336586)
			(xy 247.240676 -109.338474) (xy 247.228968 -109.345178) (xy 247.224042 -109.349794) (xy 247.223788 -109.350048)
			(xy 247.219457 -109.354679) (xy 247.213028 -109.365602) (xy 247.211088 -109.371638) (xy 247.210834 -109.372146)
			(xy 247.203435 -109.396631) (xy 247.182975 -109.443511) (xy 247.156428 -109.487233) (xy 247.124272 -109.527012)
			(xy 247.087084 -109.562132) (xy 247.045532 -109.591961) (xy 247.023128 -109.604302) (xy 247.007269 -109.612493)
			(xy 246.974323 -109.626233) (xy 246.957342 -109.631734) (xy 246.956834 -109.631734) (xy 246.950992 -109.633766)
			(xy 246.940832 -109.639862) (xy 244.615716 -111.964978) (xy 244.609739 -111.971497) (xy 244.602245 -111.987503)
			(xy 244.600635 -112.005102) (xy 244.602508 -112.013746) (xy 244.627908 -112.111536) (xy 244.646704 -112.13084)
			(xy 244.659658 -112.134396) (xy 244.685922 -112.142355) (xy 244.736016 -112.164765) (xy 244.782381 -112.194124)
			(xy 244.82406 -112.229824) (xy 244.860193 -112.271129) (xy 244.890033 -112.317185) (xy 244.912965 -112.367043)
			(xy 244.928515 -112.419672) (xy 244.936361 -112.473987) (xy 244.936772 -112.501426) (xy 244.936307 -112.528677)
			(xy 244.928547 -112.582623) (xy 244.913188 -112.634916) (xy 244.890544 -112.68449) (xy 244.861074 -112.730337)
			(xy 244.82538 -112.771524) (xy 244.784188 -112.807211) (xy 244.738336 -112.836673) (xy 244.688757 -112.85931)
			(xy 244.636462 -112.87466) (xy 244.582515 -112.882411) (xy 244.555264 -112.882934) (xy 244.527829 -112.882456)
			(xy 244.473524 -112.874595) (xy 244.420905 -112.859039) (xy 244.371055 -112.83611) (xy 244.325001 -112.806279)
			(xy 244.283693 -112.770162) (xy 244.247982 -112.728503) (xy 244.218604 -112.68216) (xy 244.196163 -112.632088)
			(xy 244.188234 -112.60582) (xy 244.184678 -112.592866) (xy 244.165374 -112.57407) (xy 244.067584 -112.54867)
			(xy 244.058942 -112.546721) (xy 244.041307 -112.5483) (xy 244.025276 -112.555817) (xy 244.018816 -112.561878)
			(xy 243.278552 -113.302034) (xy 246.513602 -113.302034) (xy 246.517673 -113.246412) (xy 246.529799 -113.191975)
			(xy 246.549722 -113.139884) (xy 246.577018 -113.091249) (xy 246.611104 -113.047106) (xy 246.651253 -113.008397)
			(xy 246.696611 -112.975946) (xy 246.746211 -112.950445) (xy 246.798995 -112.932438) (xy 246.853838 -112.922308)
			(xy 246.909572 -112.920271) (xy 246.965009 -112.926371) (xy 247.018966 -112.940477) (xy 247.070295 -112.962289)
			(xy 247.117901 -112.991343) (xy 247.160769 -113.027018) (xy 247.197986 -113.068555) (xy 247.228759 -113.115068)
			(xy 247.252431 -113.165565) (xy 247.257725 -113.183162) (xy 248.515122 -113.183162) (xy 248.519193 -113.12754)
			(xy 248.531319 -113.073103) (xy 248.551242 -113.021012) (xy 248.578538 -112.972377) (xy 248.612624 -112.928234)
			(xy 248.652773 -112.889525) (xy 248.698131 -112.857074) (xy 248.747731 -112.831573) (xy 248.800515 -112.813566)
			(xy 248.855358 -112.803436) (xy 248.911092 -112.801399) (xy 248.966529 -112.807499) (xy 249.020486 -112.821605)
			(xy 249.071815 -112.843417) (xy 249.119421 -112.872471) (xy 249.162289 -112.908146) (xy 249.199506 -112.949683)
			(xy 249.230279 -112.996196) (xy 249.253951 -113.046693) (xy 249.270019 -113.1001) (xy 249.278139 -113.155276)
			(xy 249.278648 -113.183162) (xy 249.278139 -113.211048) (xy 249.270019 -113.266224) (xy 249.253951 -113.319631)
			(xy 249.230279 -113.370128) (xy 249.199506 -113.416641) (xy 249.162289 -113.458178) (xy 249.119421 -113.493853)
			(xy 249.071815 -113.522907) (xy 249.020486 -113.544719) (xy 248.966529 -113.558825) (xy 248.911092 -113.564925)
			(xy 248.855358 -113.562888) (xy 248.800515 -113.552758) (xy 248.747731 -113.534751) (xy 248.698131 -113.50925)
			(xy 248.652773 -113.476799) (xy 248.612624 -113.43809) (xy 248.578538 -113.393947) (xy 248.551242 -113.345312)
			(xy 248.531319 -113.293221) (xy 248.519193 -113.238784) (xy 248.515122 -113.183162) (xy 247.257725 -113.183162)
			(xy 247.268499 -113.218972) (xy 247.276619 -113.274148) (xy 247.277128 -113.302034) (xy 247.276619 -113.32992)
			(xy 247.268499 -113.385096) (xy 247.252431 -113.438503) (xy 247.228759 -113.489) (xy 247.197986 -113.535513)
			(xy 247.160769 -113.57705) (xy 247.117901 -113.612725) (xy 247.070295 -113.641779) (xy 247.018966 -113.663591)
			(xy 246.965009 -113.677697) (xy 246.909572 -113.683797) (xy 246.853838 -113.68176) (xy 246.798995 -113.67163)
			(xy 246.746211 -113.653623) (xy 246.696611 -113.628122) (xy 246.651253 -113.595671) (xy 246.611104 -113.556962)
			(xy 246.577018 -113.512819) (xy 246.549722 -113.464184) (xy 246.529799 -113.412093) (xy 246.517673 -113.357656)
			(xy 246.513602 -113.302034) (xy 243.278552 -113.302034) (xy 242.275106 -114.305334) (xy 242.268264 -114.312734)
			(xy 242.260541 -114.331332) (xy 242.26012 -114.341402) (xy 242.26012 -114.660426) (xy 244.161308 -114.660426)
			(xy 244.165379 -114.604804) (xy 244.177505 -114.550367) (xy 244.197428 -114.498276) (xy 244.224724 -114.449641)
			(xy 244.25881 -114.405498) (xy 244.298959 -114.366789) (xy 244.344317 -114.334338) (xy 244.393917 -114.308837)
			(xy 244.446701 -114.29083) (xy 244.501544 -114.2807) (xy 244.557278 -114.278663) (xy 244.612715 -114.284763)
			(xy 244.666672 -114.298869) (xy 244.718001 -114.320681) (xy 244.765607 -114.349735) (xy 244.808475 -114.38541)
			(xy 244.845692 -114.426947) (xy 244.876465 -114.47346) (xy 244.900137 -114.523957) (xy 244.916205 -114.577364)
			(xy 244.924325 -114.63254) (xy 244.924834 -114.660426) (xy 244.924325 -114.688312) (xy 244.916205 -114.743488)
			(xy 244.900137 -114.796895) (xy 244.876465 -114.847392) (xy 244.845692 -114.893905) (xy 244.808475 -114.935442)
			(xy 244.765607 -114.971117) (xy 244.718001 -115.000171) (xy 244.666672 -115.021983) (xy 244.612715 -115.036089)
			(xy 244.557278 -115.042189) (xy 244.501544 -115.040152) (xy 244.446701 -115.030022) (xy 244.393917 -115.012015)
			(xy 244.344317 -114.986514) (xy 244.298959 -114.954063) (xy 244.25881 -114.915354) (xy 244.224724 -114.871211)
			(xy 244.197428 -114.822576) (xy 244.177505 -114.770485) (xy 244.165379 -114.716048) (xy 244.161308 -114.660426)
			(xy 242.26012 -114.660426) (xy 242.26012 -117.434106) (xy 245.576852 -117.434106) (xy 245.577309 -117.406735)
			(xy 245.585127 -117.352555) (xy 245.600618 -117.300052) (xy 245.623462 -117.250305) (xy 245.653189 -117.204339)
			(xy 245.670832 -117.183408) (xy 245.671086 -117.183154) (xy 245.676655 -117.176055) (xy 245.682913 -117.159148)
			(xy 245.683278 -117.150134) (xy 245.683278 -117.083078) (xy 245.682936 -117.074059) (xy 245.676679 -117.057142)
			(xy 245.671086 -117.050058) (xy 245.670832 -117.050058) (xy 245.670832 -117.049804) (xy 245.653197 -117.028867)
			(xy 245.623472 -116.9829) (xy 245.600626 -116.933154) (xy 245.585129 -116.880653) (xy 245.577299 -116.826475)
			(xy 245.577299 -116.771734) (xy 245.585127 -116.717556) (xy 245.600622 -116.665054) (xy 245.623467 -116.615308)
			(xy 245.653192 -116.569341) (xy 245.670832 -116.548408) (xy 245.671086 -116.548154) (xy 245.676655 -116.541055)
			(xy 245.682913 -116.524148) (xy 245.683278 -116.515134) (xy 245.683278 -116.448078) (xy 245.682936 -116.439059)
			(xy 245.676679 -116.422142) (xy 245.671086 -116.415058) (xy 245.670832 -116.415058) (xy 245.670832 -116.414804)
			(xy 245.653186 -116.393877) (xy 245.623474 -116.347903) (xy 245.600639 -116.298155) (xy 245.58515 -116.245653)
			(xy 245.577324 -116.191476) (xy 245.576852 -116.164106) (xy 245.577383 -116.136857) (xy 245.585138 -116.082913)
			(xy 245.60049 -116.030621) (xy 245.623128 -115.981047) (xy 245.65259 -115.935198) (xy 245.688276 -115.894009)
			(xy 245.729461 -115.858317) (xy 245.775306 -115.82885) (xy 245.824878 -115.806206) (xy 245.877168 -115.790848)
			(xy 245.931111 -115.783087) (xy 245.95836 -115.782598) (xy 245.985729 -115.783088) (xy 246.039907 -115.7909)
			(xy 246.09241 -115.806384) (xy 246.142157 -115.82922) (xy 246.188125 -115.858939) (xy 246.209058 -115.876578)
			(xy 246.209312 -115.876832) (xy 246.216388 -115.882433) (xy 246.233313 -115.88867) (xy 246.242332 -115.889024)
			(xy 246.309388 -115.889024) (xy 246.318404 -115.888656) (xy 246.33532 -115.882415) (xy 246.342408 -115.876832)
			(xy 246.342408 -115.876578) (xy 246.342662 -115.876578) (xy 246.363595 -115.85894) (xy 246.409568 -115.829229)
			(xy 246.459315 -115.806393) (xy 246.511815 -115.790901) (xy 246.565991 -115.783073) (xy 246.59336 -115.782598)
			(xy 246.620612 -115.783093) (xy 246.674562 -115.790844) (xy 246.72686 -115.806195) (xy 246.77644 -115.828834)
			(xy 246.822294 -115.858298) (xy 246.863487 -115.893989) (xy 246.899181 -115.935179) (xy 246.92865 -115.98103)
			(xy 246.951293 -116.030608) (xy 246.966649 -116.082904) (xy 246.974405 -116.136854) (xy 246.974868 -116.164106)
			(xy 246.974413 -116.191477) (xy 246.966594 -116.245657) (xy 246.951103 -116.29816) (xy 246.928258 -116.347907)
			(xy 246.898531 -116.393873) (xy 246.880888 -116.414804) (xy 246.880634 -116.415058) (xy 246.875051 -116.422147)
			(xy 246.868804 -116.439062) (xy 246.868442 -116.448078) (xy 246.868442 -116.515134) (xy 246.868774 -116.524154)
			(xy 246.875038 -116.541071) (xy 246.880634 -116.548154) (xy 246.880888 -116.548154) (xy 246.880888 -116.548408)
			(xy 246.898534 -116.569336) (xy 246.928257 -116.615305) (xy 246.951101 -116.665052) (xy 246.966597 -116.717555)
			(xy 246.974424 -116.771734) (xy 246.974424 -116.826475) (xy 246.966595 -116.880654) (xy 246.951098 -116.933156)
			(xy 246.928253 -116.982903) (xy 246.898528 -117.028871) (xy 246.880888 -117.049804) (xy 246.880634 -117.050058)
			(xy 246.875051 -117.057147) (xy 246.868804 -117.074062) (xy 246.868442 -117.083078) (xy 246.868442 -117.150134)
			(xy 246.868774 -117.159154) (xy 246.875038 -117.176071) (xy 246.880634 -117.183154) (xy 246.880888 -117.183154)
			(xy 246.880888 -117.183408) (xy 246.898542 -117.204328) (xy 246.928252 -117.250304) (xy 246.951086 -117.300054)
			(xy 246.966573 -117.352558) (xy 246.974397 -117.406736) (xy 246.974868 -117.434106) (xy 246.97473 -117.442234)
			(xy 247.85904 -117.442234) (xy 247.863111 -117.386612) (xy 247.875237 -117.332175) (xy 247.89516 -117.280084)
			(xy 247.922456 -117.231449) (xy 247.956542 -117.187306) (xy 247.996691 -117.148597) (xy 248.042049 -117.116146)
			(xy 248.091649 -117.090645) (xy 248.144433 -117.072638) (xy 248.199276 -117.062508) (xy 248.25501 -117.060471)
			(xy 248.310447 -117.066571) (xy 248.364404 -117.080677) (xy 248.415733 -117.102489) (xy 248.463339 -117.131543)
			(xy 248.506207 -117.167218) (xy 248.543424 -117.208755) (xy 248.574197 -117.255268) (xy 248.597869 -117.305765)
			(xy 248.613937 -117.359172) (xy 248.622057 -117.414348) (xy 248.622566 -117.442234) (xy 248.622057 -117.47012)
			(xy 248.613937 -117.525296) (xy 248.597869 -117.578703) (xy 248.574197 -117.6292) (xy 248.543424 -117.675713)
			(xy 248.506207 -117.71725) (xy 248.463339 -117.752925) (xy 248.415733 -117.781979) (xy 248.364404 -117.803791)
			(xy 248.310447 -117.817897) (xy 248.25501 -117.823997) (xy 248.199276 -117.82196) (xy 248.144433 -117.81183)
			(xy 248.091649 -117.793823) (xy 248.042049 -117.768322) (xy 247.996691 -117.735871) (xy 247.956542 -117.697162)
			(xy 247.922456 -117.653019) (xy 247.89516 -117.604384) (xy 247.875237 -117.552293) (xy 247.863111 -117.497856)
			(xy 247.85904 -117.442234) (xy 246.97473 -117.442234) (xy 246.974416 -117.460663) (xy 246.967047 -117.513262)
			(xy 246.952452 -117.564331) (xy 246.942102 -117.588792) (xy 246.937753 -117.60016) (xy 246.939101 -117.624434)
			(xy 246.944642 -117.635274) (xy 246.986044 -117.706394) (xy 246.99276 -117.716478) (xy 247.013181 -117.729461)
			(xy 247.02516 -117.731286) (xy 247.053143 -117.73446) (xy 247.107807 -117.747998) (xy 247.159886 -117.769425)
			(xy 247.208249 -117.798277) (xy 247.251844 -117.833926) (xy 247.289724 -117.875598) (xy 247.321066 -117.922386)
			(xy 247.345188 -117.973274) (xy 247.361565 -118.027155) (xy 247.367007 -118.063772) (xy 249.006104 -118.063772)
			(xy 249.010175 -118.00815) (xy 249.022301 -117.953713) (xy 249.042224 -117.901622) (xy 249.06952 -117.852987)
			(xy 249.103606 -117.808844) (xy 249.143755 -117.770135) (xy 249.189113 -117.737684) (xy 249.238713 -117.712183)
			(xy 249.291497 -117.694176) (xy 249.34634 -117.684046) (xy 249.402074 -117.682009) (xy 249.457511 -117.688109)
			(xy 249.511468 -117.702215) (xy 249.562797 -117.724027) (xy 249.610403 -117.753081) (xy 249.653271 -117.788756)
			(xy 249.690488 -117.830293) (xy 249.721261 -117.876806) (xy 249.744933 -117.927303) (xy 249.761001 -117.98071)
			(xy 249.76702 -118.021608) (xy 249.885454 -118.021608) (xy 249.885912 -117.994237) (xy 249.893729 -117.940057)
			(xy 249.90922 -117.887554) (xy 249.932064 -117.837807) (xy 249.961791 -117.791841) (xy 249.979434 -117.77091)
			(xy 249.979688 -117.770656) (xy 249.985256 -117.763557) (xy 249.991514 -117.74665) (xy 249.99188 -117.737636)
			(xy 249.99188 -117.67058) (xy 249.991537 -117.661562) (xy 249.98528 -117.644645) (xy 249.979688 -117.63756)
			(xy 249.979434 -117.63756) (xy 249.979434 -117.637306) (xy 249.961801 -117.616367) (xy 249.932075 -117.570401)
			(xy 249.909229 -117.520655) (xy 249.893732 -117.468154) (xy 249.885902 -117.413976) (xy 249.885901 -117.359236)
			(xy 249.893729 -117.305058) (xy 249.909225 -117.252556) (xy 249.932069 -117.20281) (xy 249.961794 -117.156843)
			(xy 249.979434 -117.13591) (xy 249.979688 -117.135656) (xy 249.985256 -117.128557) (xy 249.991514 -117.11165)
			(xy 249.99188 -117.102636) (xy 249.99188 -117.03558) (xy 249.991537 -117.026562) (xy 249.98528 -117.009645)
			(xy 249.979688 -117.00256) (xy 249.979434 -117.00256) (xy 249.979434 -117.002306) (xy 249.96179 -116.981378)
			(xy 249.932077 -116.935405) (xy 249.909242 -116.885656) (xy 249.893752 -116.833154) (xy 249.885926 -116.778978)
			(xy 249.885454 -116.751608) (xy 249.885985 -116.724359) (xy 249.89374 -116.670415) (xy 249.909092 -116.618123)
			(xy 249.931729 -116.568548) (xy 249.961191 -116.5227) (xy 249.996878 -116.48151) (xy 250.038063 -116.445819)
			(xy 250.083908 -116.416351) (xy 250.13348 -116.393708) (xy 250.18577 -116.378349) (xy 250.239713 -116.370588)
			(xy 250.266962 -116.3701) (xy 250.294331 -116.370588) (xy 250.34851 -116.378401) (xy 250.401012 -116.393885)
			(xy 250.45076 -116.416721) (xy 250.496728 -116.446441) (xy 250.51766 -116.46408) (xy 250.517914 -116.464334)
			(xy 250.52499 -116.469936) (xy 250.541915 -116.476172) (xy 250.550934 -116.476526) (xy 250.61799 -116.476526)
			(xy 250.627006 -116.476158) (xy 250.643922 -116.469918) (xy 250.65101 -116.464334) (xy 250.65101 -116.46408)
			(xy 250.651264 -116.46408) (xy 250.672196 -116.446441) (xy 250.718169 -116.41673) (xy 250.767917 -116.393894)
			(xy 250.820417 -116.378403) (xy 250.874593 -116.370574) (xy 250.901962 -116.3701) (xy 250.929214 -116.370591)
			(xy 250.983165 -116.378343) (xy 251.035462 -116.393694) (xy 251.085043 -116.416333) (xy 251.130897 -116.445798)
			(xy 251.17209 -116.481489) (xy 251.207784 -116.522679) (xy 251.237253 -116.568531) (xy 251.259895 -116.618109)
			(xy 251.275251 -116.670406) (xy 251.283007 -116.724356) (xy 251.28347 -116.751608) (xy 251.283016 -116.778979)
			(xy 251.275196 -116.833159) (xy 251.259705 -116.885662) (xy 251.23686 -116.935409) (xy 251.207133 -116.981375)
			(xy 251.18949 -117.002306) (xy 251.189236 -117.00256) (xy 251.183652 -117.009648) (xy 251.177406 -117.026564)
			(xy 251.177044 -117.03558) (xy 251.177044 -117.102636) (xy 251.177374 -117.111656) (xy 251.183639 -117.128573)
			(xy 251.189236 -117.135656) (xy 251.18949 -117.135656) (xy 251.18949 -117.13591) (xy 251.207138 -117.156837)
			(xy 251.236861 -117.202806) (xy 251.259705 -117.252553) (xy 251.2752 -117.305056) (xy 251.283027 -117.359235)
			(xy 251.283026 -117.413977) (xy 251.275197 -117.468156) (xy 251.259701 -117.520658) (xy 251.236855 -117.570405)
			(xy 251.207131 -117.616373) (xy 251.18949 -117.637306) (xy 251.189236 -117.63756) (xy 251.183652 -117.644648)
			(xy 251.177406 -117.661564) (xy 251.177044 -117.67058) (xy 251.177044 -117.737636) (xy 251.177374 -117.746656)
			(xy 251.183639 -117.763573) (xy 251.189236 -117.770656) (xy 251.18949 -117.770656) (xy 251.18949 -117.77091)
			(xy 251.207146 -117.791829) (xy 251.236855 -117.837805) (xy 251.259688 -117.887556) (xy 251.275175 -117.94006)
			(xy 251.282999 -117.994238) (xy 251.28347 -118.021608) (xy 251.283052 -118.048863) (xy 251.275293 -118.102817)
			(xy 251.259934 -118.155118) (xy 251.237288 -118.204701) (xy 251.207815 -118.250556) (xy 251.172117 -118.291749)
			(xy 251.130919 -118.327443) (xy 251.085061 -118.35691) (xy 251.035475 -118.37955) (xy 250.983172 -118.394903)
			(xy 250.929217 -118.402655) (xy 250.901962 -118.403116) (xy 250.874592 -118.402634) (xy 250.820413 -118.394823)
			(xy 250.767909 -118.379339) (xy 250.718162 -118.3565) (xy 250.672195 -118.326777) (xy 250.651264 -118.309136)
			(xy 250.65101 -118.308882) (xy 250.643926 -118.303291) (xy 250.627007 -118.297048) (xy 250.61799 -118.29669)
			(xy 250.550934 -118.29669) (xy 250.541919 -118.297065) (xy 250.525002 -118.3033) (xy 250.517914 -118.308882)
			(xy 250.517914 -118.309136) (xy 250.51766 -118.309136) (xy 250.496721 -118.326766) (xy 250.450749 -118.356478)
			(xy 250.401004 -118.379315) (xy 250.348505 -118.394808) (xy 250.294331 -118.40264) (xy 250.266962 -118.403116)
			(xy 250.23971 -118.402658) (xy 250.185762 -118.394896) (xy 250.133467 -118.379537) (xy 250.08389 -118.356892)
			(xy 250.03804 -118.327422) (xy 249.996851 -118.291728) (xy 249.96116 -118.250535) (xy 249.931694 -118.204683)
			(xy 249.909053 -118.155105) (xy 249.893698 -118.102809) (xy 249.88594 -118.04886) (xy 249.885454 -118.021608)
			(xy 249.76702 -118.021608) (xy 249.769121 -118.035886) (xy 249.76963 -118.063772) (xy 249.769121 -118.091658)
			(xy 249.761001 -118.146834) (xy 249.744933 -118.200241) (xy 249.721261 -118.250738) (xy 249.690488 -118.297251)
			(xy 249.653271 -118.338788) (xy 249.610403 -118.374463) (xy 249.562797 -118.403517) (xy 249.511468 -118.425329)
			(xy 249.457511 -118.439435) (xy 249.402074 -118.445535) (xy 249.34634 -118.443498) (xy 249.291497 -118.433368)
			(xy 249.238713 -118.415361) (xy 249.189113 -118.38986) (xy 249.143755 -118.357409) (xy 249.103606 -118.3187)
			(xy 249.06952 -118.274557) (xy 249.042224 -118.225922) (xy 249.022301 -118.173831) (xy 249.010175 -118.119394)
			(xy 249.006104 -118.063772) (xy 247.367007 -118.063772) (xy 247.369843 -118.082858) (xy 247.370346 -118.111016)
			(xy 247.36986 -118.138267) (xy 247.362104 -118.192215) (xy 247.346749 -118.24451) (xy 247.324107 -118.294087)
			(xy 247.294641 -118.339937) (xy 247.25895 -118.381128) (xy 247.217759 -118.416819) (xy 247.171909 -118.446285)
			(xy 247.122332 -118.468927) (xy 247.070037 -118.484282) (xy 247.016089 -118.492038) (xy 246.961587 -118.492038)
			(xy 246.907639 -118.484282) (xy 246.855344 -118.468927) (xy 246.805767 -118.446285) (xy 246.759917 -118.416819)
			(xy 246.718726 -118.381128) (xy 246.683035 -118.339937) (xy 246.653569 -118.294087) (xy 246.630927 -118.24451)
			(xy 246.615572 -118.192215) (xy 246.607816 -118.138267) (xy 246.60733 -118.111016) (xy 246.60779 -118.08446)
			(xy 246.615156 -118.03186) (xy 246.629747 -117.980791) (xy 246.640096 -117.95633) (xy 246.644431 -117.944957)
			(xy 246.643093 -117.920688) (xy 246.637556 -117.909848) (xy 246.596154 -117.838728) (xy 246.58941 -117.828667)
			(xy 246.569009 -117.815676) (xy 246.557038 -117.813836) (xy 246.527564 -117.810453) (xy 246.470096 -117.795736)
			(xy 246.415599 -117.772298) (xy 246.365389 -117.740703) (xy 246.342662 -117.721634) (xy 246.342408 -117.72138)
			(xy 246.335325 -117.715788) (xy 246.318405 -117.709545) (xy 246.309388 -117.709188) (xy 246.242332 -117.709188)
			(xy 246.233317 -117.709563) (xy 246.2164 -117.715798) (xy 246.209312 -117.72138) (xy 246.209312 -117.721634)
			(xy 246.209058 -117.721634) (xy 246.188119 -117.739265) (xy 246.142148 -117.768977) (xy 246.092402 -117.791814)
			(xy 246.039903 -117.807307) (xy 245.985729 -117.815138) (xy 245.95836 -117.815614) (xy 245.931108 -117.815159)
			(xy 245.87716 -117.807398) (xy 245.824865 -117.792038) (xy 245.775288 -117.769392) (xy 245.729438 -117.739922)
			(xy 245.688248 -117.704228) (xy 245.652557 -117.663035) (xy 245.623091 -117.617183) (xy 245.60045 -117.567604)
			(xy 245.585095 -117.515307) (xy 245.577338 -117.461358) (xy 245.576852 -117.434106) (xy 242.26012 -117.434106)
			(xy 242.26012 -118.089426) (xy 242.395246 -118.089426) (xy 242.399317 -118.033804) (xy 242.411443 -117.979367)
			(xy 242.431366 -117.927276) (xy 242.458662 -117.878641) (xy 242.492748 -117.834498) (xy 242.532897 -117.795789)
			(xy 242.578255 -117.763338) (xy 242.627855 -117.737837) (xy 242.680639 -117.71983) (xy 242.735482 -117.7097)
			(xy 242.791216 -117.707663) (xy 242.846653 -117.713763) (xy 242.90061 -117.727869) (xy 242.951939 -117.749681)
			(xy 242.999545 -117.778735) (xy 243.042413 -117.81441) (xy 243.07963 -117.855947) (xy 243.110403 -117.90246)
			(xy 243.134075 -117.952957) (xy 243.136924 -117.962426) (xy 244.427246 -117.962426) (xy 244.431317 -117.906804)
			(xy 244.443443 -117.852367) (xy 244.463366 -117.800276) (xy 244.490662 -117.751641) (xy 244.524748 -117.707498)
			(xy 244.564897 -117.668789) (xy 244.610255 -117.636338) (xy 244.659855 -117.610837) (xy 244.712639 -117.59283)
			(xy 244.767482 -117.5827) (xy 244.823216 -117.580663) (xy 244.878653 -117.586763) (xy 244.93261 -117.600869)
			(xy 244.983939 -117.622681) (xy 245.031545 -117.651735) (xy 245.074413 -117.68741) (xy 245.11163 -117.728947)
			(xy 245.142403 -117.77546) (xy 245.166075 -117.825957) (xy 245.182143 -117.879364) (xy 245.190263 -117.93454)
			(xy 245.190772 -117.962426) (xy 245.190263 -117.990312) (xy 245.182143 -118.045488) (xy 245.166075 -118.098895)
			(xy 245.142403 -118.149392) (xy 245.11163 -118.195905) (xy 245.074413 -118.237442) (xy 245.031545 -118.273117)
			(xy 244.983939 -118.302171) (xy 244.93261 -118.323983) (xy 244.878653 -118.338089) (xy 244.823216 -118.344189)
			(xy 244.767482 -118.342152) (xy 244.712639 -118.332022) (xy 244.659855 -118.314015) (xy 244.610255 -118.288514)
			(xy 244.564897 -118.256063) (xy 244.524748 -118.217354) (xy 244.490662 -118.173211) (xy 244.463366 -118.124576)
			(xy 244.443443 -118.072485) (xy 244.431317 -118.018048) (xy 244.427246 -117.962426) (xy 243.136924 -117.962426)
			(xy 243.150143 -118.006364) (xy 243.158263 -118.06154) (xy 243.158772 -118.089426) (xy 243.158263 -118.117312)
			(xy 243.150143 -118.172488) (xy 243.134075 -118.225895) (xy 243.110403 -118.276392) (xy 243.07963 -118.322905)
			(xy 243.042413 -118.364442) (xy 242.999545 -118.400117) (xy 242.951939 -118.429171) (xy 242.90061 -118.450983)
			(xy 242.846653 -118.465089) (xy 242.791216 -118.471189) (xy 242.735482 -118.469152) (xy 242.680639 -118.459022)
			(xy 242.627855 -118.441015) (xy 242.578255 -118.415514) (xy 242.532897 -118.383063) (xy 242.492748 -118.344354)
			(xy 242.458662 -118.300211) (xy 242.431366 -118.251576) (xy 242.411443 -118.199485) (xy 242.399317 -118.145048)
			(xy 242.395246 -118.089426) (xy 242.26012 -118.089426) (xy 242.26012 -119.996966) (xy 242.259591 -120.022989)
			(xy 242.251422 -120.07439) (xy 242.235325 -120.123885) (xy 242.211695 -120.170259) (xy 242.181113 -120.212373)
			(xy 242.163092 -120.231154) (xy 242.145819 -120.248426) (xy 242.395246 -120.248426) (xy 242.399317 -120.192804)
			(xy 242.411443 -120.138367) (xy 242.431366 -120.086276) (xy 242.458662 -120.037641) (xy 242.492748 -119.993498)
			(xy 242.532897 -119.954789) (xy 242.578255 -119.922338) (xy 242.627855 -119.896837) (xy 242.680639 -119.87883)
			(xy 242.735482 -119.8687) (xy 242.791216 -119.866663) (xy 242.846653 -119.872763) (xy 242.90061 -119.886869)
			(xy 242.951939 -119.908681) (xy 242.999545 -119.937735) (xy 243.042413 -119.97341) (xy 243.07963 -120.014947)
			(xy 243.110403 -120.06146) (xy 243.134075 -120.111957) (xy 243.135854 -120.11787) (xy 243.411246 -120.11787)
			(xy 243.415317 -120.062248) (xy 243.427443 -120.007811) (xy 243.447366 -119.95572) (xy 243.474662 -119.907085)
			(xy 243.508748 -119.862942) (xy 243.548897 -119.824233) (xy 243.594255 -119.791782) (xy 243.643855 -119.766281)
			(xy 243.696639 -119.748274) (xy 243.751482 -119.738144) (xy 243.807216 -119.736107) (xy 243.862653 -119.742207)
			(xy 243.91661 -119.756313) (xy 243.967939 -119.778125) (xy 244.015545 -119.807179) (xy 244.058413 -119.842854)
			(xy 244.09563 -119.884391) (xy 244.126403 -119.930904) (xy 244.150075 -119.981401) (xy 244.166143 -120.034808)
			(xy 244.174263 -120.089984) (xy 244.174772 -120.11787) (xy 244.427246 -120.11787) (xy 244.431317 -120.062248)
			(xy 244.443443 -120.007811) (xy 244.463366 -119.95572) (xy 244.490662 -119.907085) (xy 244.524748 -119.862942)
			(xy 244.564897 -119.824233) (xy 244.610255 -119.791782) (xy 244.659855 -119.766281) (xy 244.712639 -119.748274)
			(xy 244.767482 -119.738144) (xy 244.823216 -119.736107) (xy 244.878653 -119.742207) (xy 244.93261 -119.756313)
			(xy 244.983939 -119.778125) (xy 245.031545 -119.807179) (xy 245.074413 -119.842854) (xy 245.11163 -119.884391)
			(xy 245.142403 -119.930904) (xy 245.166075 -119.981401) (xy 245.182143 -120.034808) (xy 245.190263 -120.089984)
			(xy 245.190772 -120.11787) (xy 245.190263 -120.145756) (xy 245.189134 -120.15343) (xy 247.62282 -120.15343)
			(xy 247.626891 -120.097808) (xy 247.639017 -120.043371) (xy 247.65894 -119.99128) (xy 247.686236 -119.942645)
			(xy 247.720322 -119.898502) (xy 247.760471 -119.859793) (xy 247.805829 -119.827342) (xy 247.855429 -119.801841)
			(xy 247.908213 -119.783834) (xy 247.963056 -119.773704) (xy 248.01879 -119.771667) (xy 248.074227 -119.777767)
			(xy 248.128184 -119.791873) (xy 248.179513 -119.813685) (xy 248.227119 -119.842739) (xy 248.269987 -119.878414)
			(xy 248.307204 -119.919951) (xy 248.337977 -119.966464) (xy 248.361649 -120.016961) (xy 248.377717 -120.070368)
			(xy 248.385837 -120.125544) (xy 248.386346 -120.15343) (xy 248.385837 -120.181316) (xy 248.377717 -120.236492)
			(xy 248.361649 -120.289899) (xy 248.337977 -120.340396) (xy 248.307204 -120.386909) (xy 248.269987 -120.428446)
			(xy 248.227119 -120.464121) (xy 248.179513 -120.493175) (xy 248.128184 -120.514987) (xy 248.074227 -120.529093)
			(xy 248.01879 -120.535193) (xy 247.963056 -120.533156) (xy 247.908213 -120.523026) (xy 247.855429 -120.505019)
			(xy 247.805829 -120.479518) (xy 247.760471 -120.447067) (xy 247.720322 -120.408358) (xy 247.686236 -120.364215)
			(xy 247.65894 -120.31558) (xy 247.639017 -120.263489) (xy 247.626891 -120.209052) (xy 247.62282 -120.15343)
			(xy 245.189134 -120.15343) (xy 245.182143 -120.200932) (xy 245.166075 -120.254339) (xy 245.142403 -120.304836)
			(xy 245.11163 -120.351349) (xy 245.074413 -120.392886) (xy 245.031545 -120.428561) (xy 244.983939 -120.457615)
			(xy 244.93261 -120.479427) (xy 244.878653 -120.493533) (xy 244.823216 -120.499633) (xy 244.767482 -120.497596)
			(xy 244.712639 -120.487466) (xy 244.659855 -120.469459) (xy 244.610255 -120.443958) (xy 244.564897 -120.411507)
			(xy 244.524748 -120.372798) (xy 244.490662 -120.328655) (xy 244.463366 -120.28002) (xy 244.443443 -120.227929)
			(xy 244.431317 -120.173492) (xy 244.427246 -120.11787) (xy 244.174772 -120.11787) (xy 244.174263 -120.145756)
			(xy 244.166143 -120.200932) (xy 244.150075 -120.254339) (xy 244.126403 -120.304836) (xy 244.09563 -120.351349)
			(xy 244.058413 -120.392886) (xy 244.015545 -120.428561) (xy 243.967939 -120.457615) (xy 243.91661 -120.479427)
			(xy 243.862653 -120.493533) (xy 243.807216 -120.499633) (xy 243.751482 -120.497596) (xy 243.696639 -120.487466)
			(xy 243.643855 -120.469459) (xy 243.594255 -120.443958) (xy 243.548897 -120.411507) (xy 243.508748 -120.372798)
			(xy 243.474662 -120.328655) (xy 243.447366 -120.28002) (xy 243.427443 -120.227929) (xy 243.415317 -120.173492)
			(xy 243.411246 -120.11787) (xy 243.135854 -120.11787) (xy 243.150143 -120.165364) (xy 243.158263 -120.22054)
			(xy 243.158772 -120.248426) (xy 243.158263 -120.276312) (xy 243.150143 -120.331488) (xy 243.134075 -120.384895)
			(xy 243.110403 -120.435392) (xy 243.07963 -120.481905) (xy 243.042413 -120.523442) (xy 242.999545 -120.559117)
			(xy 242.951939 -120.588171) (xy 242.90061 -120.609983) (xy 242.846653 -120.624089) (xy 242.791216 -120.630189)
			(xy 242.735482 -120.628152) (xy 242.680639 -120.618022) (xy 242.627855 -120.600015) (xy 242.578255 -120.574514)
			(xy 242.532897 -120.542063) (xy 242.492748 -120.503354) (xy 242.458662 -120.459211) (xy 242.431366 -120.410576)
			(xy 242.411443 -120.358485) (xy 242.399317 -120.304048) (xy 242.395246 -120.248426) (xy 242.145819 -120.248426)
			(xy 240.823437 -121.57075) (xy 245.81993 -121.57075) (xy 245.820355 -121.544434) (xy 245.827597 -121.492304)
			(xy 245.841924 -121.44166) (xy 245.863064 -121.393461) (xy 245.890618 -121.348618) (xy 245.924065 -121.307981)
			(xy 245.94312 -121.289826) (xy 245.950515 -121.282299) (xy 245.959043 -121.263023) (xy 245.95963 -121.252488)
			(xy 245.95963 -121.177812) (xy 245.959099 -121.167263) (xy 245.950564 -121.147968) (xy 245.94312 -121.140474)
			(xy 245.924063 -121.12232) (xy 245.890605 -121.081691) (xy 245.863046 -121.03685) (xy 245.841907 -120.988649)
			(xy 245.827591 -120.938001) (xy 245.820368 -120.885866) (xy 245.81993 -120.85955) (xy 245.820416 -120.832299)
			(xy 245.828172 -120.778351) (xy 245.843527 -120.726056) (xy 245.866169 -120.676479) (xy 245.895635 -120.630629)
			(xy 245.931326 -120.589438) (xy 245.972517 -120.553747) (xy 246.018367 -120.524281) (xy 246.067944 -120.501639)
			(xy 246.120239 -120.486284) (xy 246.174187 -120.478528) (xy 246.228689 -120.478528) (xy 246.282637 -120.486284)
			(xy 246.334932 -120.501639) (xy 246.384509 -120.524281) (xy 246.430359 -120.553747) (xy 246.47155 -120.589438)
			(xy 246.507241 -120.630629) (xy 246.536707 -120.676479) (xy 246.559349 -120.726056) (xy 246.574704 -120.778351)
			(xy 246.58246 -120.832299) (xy 246.582946 -120.85955) (xy 246.582529 -120.885866) (xy 246.575286 -120.937997)
			(xy 246.560959 -120.988642) (xy 246.539817 -121.036841) (xy 246.512261 -121.081683) (xy 246.478812 -121.12232)
			(xy 246.459756 -121.140474) (xy 246.452372 -121.148011) (xy 246.443836 -121.167279) (xy 246.443246 -121.177812)
			(xy 246.443246 -121.252488) (xy 246.443754 -121.26304) (xy 246.452303 -121.282337) (xy 246.459756 -121.289826)
			(xy 246.478828 -121.307965) (xy 246.512281 -121.348599) (xy 246.539837 -121.393444) (xy 246.560972 -121.441647)
			(xy 246.575286 -121.492297) (xy 246.582509 -121.544433) (xy 246.582946 -121.57075) (xy 246.58246 -121.598001)
			(xy 246.574704 -121.651949) (xy 246.559349 -121.704244) (xy 246.536707 -121.753821) (xy 246.507241 -121.799671)
			(xy 246.47155 -121.840862) (xy 246.430359 -121.876553) (xy 246.384509 -121.906019) (xy 246.334932 -121.928661)
			(xy 246.282637 -121.944016) (xy 246.228689 -121.951772) (xy 246.174187 -121.951772) (xy 246.120239 -121.944016)
			(xy 246.067944 -121.928661) (xy 246.018367 -121.906019) (xy 245.972517 -121.876553) (xy 245.931326 -121.840862)
			(xy 245.895635 -121.799671) (xy 245.866169 -121.753821) (xy 245.843527 -121.704244) (xy 245.828172 -121.651949)
			(xy 245.820416 -121.598001) (xy 245.81993 -121.57075) (xy 240.823437 -121.57075) (xy 240.101538 -122.292618)
			(xy 241.98021 -122.292618) (xy 241.984281 -122.236996) (xy 241.996407 -122.182559) (xy 242.01633 -122.130468)
			(xy 242.043626 -122.081833) (xy 242.077712 -122.03769) (xy 242.117861 -121.998981) (xy 242.163219 -121.96653)
			(xy 242.212819 -121.941029) (xy 242.265603 -121.923022) (xy 242.320446 -121.912892) (xy 242.37618 -121.910855)
			(xy 242.431617 -121.916955) (xy 242.485574 -121.931061) (xy 242.536903 -121.952873) (xy 242.584509 -121.981927)
			(xy 242.627377 -122.017602) (xy 242.664594 -122.059139) (xy 242.695367 -122.105652) (xy 242.719039 -122.156149)
			(xy 242.735107 -122.209556) (xy 242.743227 -122.264732) (xy 242.743736 -122.292618) (xy 242.743227 -122.320504)
			(xy 242.735107 -122.37568) (xy 242.719039 -122.429087) (xy 242.695367 -122.479584) (xy 242.664594 -122.526097)
			(xy 242.627377 -122.567634) (xy 242.584509 -122.603309) (xy 242.536903 -122.632363) (xy 242.485574 -122.654175)
			(xy 242.431617 -122.668281) (xy 242.37618 -122.674381) (xy 242.320446 -122.672344) (xy 242.265603 -122.662214)
			(xy 242.212819 -122.644207) (xy 242.163219 -122.618706) (xy 242.117861 -122.586255) (xy 242.077712 -122.547546)
			(xy 242.043626 -122.503403) (xy 242.01633 -122.454768) (xy 241.996407 -122.402677) (xy 241.984281 -122.34824)
			(xy 241.98021 -122.292618) (xy 240.101538 -122.292618) (xy 236.354874 -126.039118) (xy 236.348022 -126.046514)
			(xy 236.340283 -126.065113) (xy 236.339888 -126.075186) (xy 236.339888 -141.232382) (xy 236.34269 -141.235932)
			(xy 236.349331 -141.242069) (xy 236.353096 -141.244574) (xy 236.417866 -141.285976) (xy 236.424114 -141.289685)
			(xy 236.438038 -141.293819) (xy 236.445298 -141.294104) (xy 236.473492 -141.294104) (xy 236.483144 -141.29004)
			(xy 236.49051 -141.286992) (xy 236.512816 -141.27836) (xy 236.559056 -141.266133) (xy 236.582712 -141.262608)
			(xy 236.591856 -141.261338) (xy 236.599476 -141.257274) (xy 236.603207 -141.25518) (xy 236.609975 -141.249946)
			(xy 236.612938 -141.24686) (xy 236.634274 -141.223746) (xy 236.639642 -141.217033) (xy 236.645989 -141.201069)
			(xy 236.64672 -141.192504) (xy 236.64672 -132.722112) (xy 236.65434 -132.70357) (xy 236.659674 -132.698236)
			(xy 236.661452 -132.696458) (xy 237.289594 -132.068316) (xy 237.291118 -132.066792) (xy 237.291626 -132.066538)
			(xy 237.292642 -132.065522) (xy 237.29696 -132.061204) (xy 237.315502 -132.053584) (xy 238.385604 -132.053584)
			(xy 238.397449 -132.052964) (xy 238.418636 -132.042365) (xy 238.426244 -132.033264) (xy 238.426244 -131.994148)
			(xy 238.426771 -131.968124) (xy 238.434939 -131.916721) (xy 238.451033 -131.867224) (xy 238.474659 -131.820847)
			(xy 238.505238 -131.778729) (xy 238.523272 -131.75996) (xy 241.02949 -129.253996) (xy 241.036337 -129.246598)
			(xy 241.044071 -129.228) (xy 241.044476 -129.217928) (xy 241.044476 -128.01727) (xy 241.045002 -127.991246)
			(xy 241.053167 -127.939841) (xy 241.069259 -127.890343) (xy 241.092885 -127.843965) (xy 241.123465 -127.801847)
			(xy 241.141504 -127.783082) (xy 241.48669 -127.43815) (xy 241.49353 -127.430749) (xy 241.501248 -127.412151)
			(xy 241.501676 -127.402082) (xy 241.501676 -126.406402) (xy 241.49685 -126.400814) (xy 241.4905 -126.39548)
			(xy 241.440208 -126.359666) (xy 241.4397 -126.359666) (xy 241.421666 -126.346458) (xy 241.415395 -126.342618)
			(xy 241.401328 -126.338358) (xy 241.39398 -126.338076) (xy 241.37747 -126.34087) (xy 241.373914 -126.34214)
			(xy 241.345181 -126.350928) (xy 241.285845 -126.360372) (xy 241.255804 -126.360936) (xy 241.255042 -126.360936)
			(xy 241.227785 -126.360476) (xy 241.173826 -126.352723) (xy 241.121519 -126.33737) (xy 241.07193 -126.314728)
			(xy 241.026068 -126.285259) (xy 240.984867 -126.249563) (xy 240.949166 -126.208366) (xy 240.919692 -126.162507)
			(xy 240.897045 -126.112921) (xy 240.881686 -126.060615) (xy 240.873927 -126.006657) (xy 240.873927 -125.952143)
			(xy 240.881686 -125.898185) (xy 240.897045 -125.845879) (xy 240.919692 -125.796293) (xy 240.949166 -125.750434)
			(xy 240.984867 -125.709237) (xy 241.026068 -125.673541) (xy 241.07193 -125.644072) (xy 241.121519 -125.62143)
			(xy 241.173826 -125.606077) (xy 241.227785 -125.598324) (xy 241.255042 -125.59792) (xy 241.255804 -125.59792)
			(xy 241.286785 -125.598568) (xy 241.347922 -125.608653) (xy 241.37747 -125.617986) (xy 241.377724 -125.617986)
			(xy 241.383502 -125.61984) (xy 241.395576 -125.621001) (xy 241.4016 -125.620272) (xy 241.413284 -125.618494)
			(xy 241.441732 -125.598174) (xy 241.44224 -125.598174) (xy 241.490754 -125.563122) (xy 241.49383 -125.560833)
			(xy 241.499319 -125.555478) (xy 241.501676 -125.552454) (xy 241.501676 -125.390402) (xy 241.49685 -125.384814)
			(xy 241.4905 -125.37948) (xy 241.440208 -125.343666) (xy 241.4397 -125.343666) (xy 241.421666 -125.330458)
			(xy 241.415395 -125.326618) (xy 241.401328 -125.322358) (xy 241.39398 -125.322076) (xy 241.37747 -125.32487)
			(xy 241.373914 -125.32614) (xy 241.345181 -125.334928) (xy 241.285845 -125.344372) (xy 241.255804 -125.344936)
			(xy 241.255042 -125.344936) (xy 241.227785 -125.344476) (xy 241.173826 -125.336723) (xy 241.121519 -125.32137)
			(xy 241.07193 -125.298728) (xy 241.026068 -125.269259) (xy 240.984867 -125.233563) (xy 240.949166 -125.192366)
			(xy 240.919692 -125.146507) (xy 240.897045 -125.096921) (xy 240.881686 -125.044615) (xy 240.873927 -124.990657)
			(xy 240.873927 -124.936143) (xy 240.881686 -124.882185) (xy 240.897045 -124.829879) (xy 240.919692 -124.780293)
			(xy 240.949166 -124.734434) (xy 240.984867 -124.693237) (xy 241.026068 -124.657541) (xy 241.07193 -124.628072)
			(xy 241.121519 -124.60543) (xy 241.173826 -124.590077) (xy 241.227785 -124.582324) (xy 241.255042 -124.58192)
			(xy 241.255804 -124.58192) (xy 241.286785 -124.582568) (xy 241.347922 -124.592653) (xy 241.37747 -124.601986)
			(xy 241.377724 -124.601986) (xy 241.383502 -124.60384) (xy 241.395576 -124.605001) (xy 241.4016 -124.604272)
			(xy 241.413284 -124.602494) (xy 241.441732 -124.582174) (xy 241.44224 -124.582174) (xy 241.490754 -124.547122)
			(xy 241.49383 -124.544833) (xy 241.499319 -124.539478) (xy 241.501676 -124.536454) (xy 241.501676 -124.154946)
			(xy 241.502204 -124.128923) (xy 241.510372 -124.07752) (xy 241.526467 -124.028024) (xy 241.550095 -123.981649)
			(xy 241.580676 -123.939533) (xy 241.598704 -123.920758) (xy 243.142262 -122.3772) (xy 243.146431 -122.372847)
			(xy 243.152728 -122.362573) (xy 243.154708 -122.35688) (xy 243.154708 -122.356626) (xy 243.163143 -122.331067)
			(xy 243.186195 -122.282431) (xy 243.215852 -122.237517) (xy 243.251526 -122.197215) (xy 243.292508 -122.162326)
			(xy 243.337986 -122.13354) (xy 243.387057 -122.11143) (xy 243.438748 -122.096435) (xy 243.492033 -122.088851)
			(xy 243.518944 -122.088402) (xy 243.546193 -122.088891) (xy 243.600135 -122.096653) (xy 243.652424 -122.112012)
			(xy 243.701995 -122.134656) (xy 243.747839 -122.164123) (xy 243.789023 -122.199815) (xy 243.824709 -122.241004)
			(xy 243.85417 -122.286852) (xy 243.876807 -122.336427) (xy 243.892159 -122.388718) (xy 243.899913 -122.442661)
			(xy 243.900452 -122.46991) (xy 243.899991 -122.496811) (xy 243.892431 -122.550079) (xy 243.877464 -122.601757)
			(xy 243.855385 -122.650819) (xy 243.826633 -122.696294) (xy 243.791778 -122.737279) (xy 243.751512 -122.772961)
			(xy 243.706632 -122.802633) (xy 243.658028 -122.825705) (xy 243.632482 -122.834146) (xy 243.631974 -122.834146)
			(xy 243.62631 -122.836189) (xy 243.616043 -122.84247) (xy 243.611654 -122.846592) (xy 243.208422 -123.249752)
			(xy 244.109967 -123.249752) (xy 244.109967 -123.195248) (xy 244.117724 -123.141299) (xy 244.13308 -123.089002)
			(xy 244.155722 -123.039423) (xy 244.185189 -122.993572) (xy 244.220882 -122.95238) (xy 244.262073 -122.916688)
			(xy 244.307925 -122.887221) (xy 244.357504 -122.864579) (xy 244.4098 -122.849224) (xy 244.46375 -122.841467)
			(xy 244.491002 -122.841004) (xy 244.518032 -122.841498) (xy 244.571549 -122.849136) (xy 244.623451 -122.864259)
			(xy 244.672695 -122.886564) (xy 244.718294 -122.915602) (xy 244.759332 -122.950791) (xy 244.777514 -122.970798)
			(xy 244.777768 -122.971052) (xy 244.785208 -122.978703) (xy 244.804695 -122.987369) (xy 244.81536 -122.987816)
			(xy 244.90299 -122.988324) (xy 244.922548 -122.979688) (xy 244.929914 -122.971306) (xy 244.948074 -122.951582)
			(xy 244.988975 -122.916918) (xy 245.034331 -122.88833) (xy 245.083246 -122.866381) (xy 245.134755 -122.851505)
			(xy 245.187841 -122.843997) (xy 245.214648 -122.843544) (xy 245.242018 -122.84403) (xy 245.296196 -122.851841)
			(xy 245.3487 -122.867325) (xy 245.398447 -122.890163) (xy 245.444414 -122.919884) (xy 245.465346 -122.937524)
			(xy 245.4656 -122.937778) (xy 245.472676 -122.94338) (xy 245.489601 -122.949615) (xy 245.49862 -122.94997)
			(xy 245.565676 -122.94997) (xy 245.574692 -122.949608) (xy 245.59161 -122.943364) (xy 245.598696 -122.937778)
			(xy 245.598696 -122.937524) (xy 245.59895 -122.937524) (xy 245.619883 -122.919883) (xy 245.665851 -122.890159)
			(xy 245.715597 -122.867313) (xy 245.768099 -122.851817) (xy 245.822277 -122.843988) (xy 245.877019 -122.843988)
			(xy 245.931197 -122.851817) (xy 245.983699 -122.867313) (xy 246.033445 -122.890159) (xy 246.079413 -122.919883)
			(xy 246.100346 -122.937524) (xy 246.1006 -122.937778) (xy 246.107676 -122.94338) (xy 246.124601 -122.949615)
			(xy 246.13362 -122.94997) (xy 246.200676 -122.94997) (xy 246.209692 -122.949608) (xy 246.22661 -122.943364)
			(xy 246.233696 -122.937778) (xy 246.234204 -122.937524) (xy 246.246938 -122.926579) (xy 246.274029 -122.906738)
			(xy 246.288306 -122.8979) (xy 246.297196 -122.892566) (xy 246.309388 -122.875548) (xy 246.329708 -122.78233)
			(xy 246.32539 -122.761756) (xy 246.319548 -122.75312) (xy 246.303548 -122.729056) (xy 246.278207 -122.677124)
			(xy 246.260982 -122.621966) (xy 246.252266 -122.564842) (xy 246.25173 -122.53595) (xy 246.252216 -122.508699)
			(xy 246.259972 -122.454751) (xy 246.275327 -122.402456) (xy 246.297969 -122.352879) (xy 246.327435 -122.307029)
			(xy 246.363126 -122.265838) (xy 246.404317 -122.230147) (xy 246.450167 -122.200681) (xy 246.499744 -122.178039)
			(xy 246.552039 -122.162684) (xy 246.605987 -122.154928) (xy 246.660489 -122.154928) (xy 246.714437 -122.162684)
			(xy 246.766732 -122.178039) (xy 246.816309 -122.200681) (xy 246.862159 -122.230147) (xy 246.90335 -122.265838)
			(xy 246.939041 -122.307029) (xy 246.968507 -122.352879) (xy 246.991149 -122.402456) (xy 247.006504 -122.454751)
			(xy 247.01426 -122.508699) (xy 247.014746 -122.53595) (xy 247.014198 -122.56404) (xy 247.005979 -122.619614)
			(xy 246.989696 -122.673381) (xy 246.965702 -122.724178) (xy 246.934515 -122.770905) (xy 246.896812 -122.812552)
			(xy 246.853407 -122.848217) (xy 246.82958 -122.863102) (xy 246.82069 -122.868436) (xy 246.808498 -122.885454)
			(xy 246.788178 -122.978672) (xy 246.792496 -122.999246) (xy 246.798338 -123.007882) (xy 246.814337 -123.031946)
			(xy 246.839679 -123.083878) (xy 246.856905 -123.139036) (xy 246.865621 -123.19616) (xy 246.866156 -123.225052)
			(xy 246.865577 -123.2523) (xy 246.857829 -123.306242) (xy 246.842482 -123.358532) (xy 246.81985 -123.408106)
			(xy 246.790393 -123.453954) (xy 246.754711 -123.495143) (xy 246.713531 -123.530836) (xy 246.66769 -123.560304)
			(xy 246.618122 -123.582948) (xy 246.565836 -123.598308) (xy 246.511896 -123.60607) (xy 246.484648 -123.60656)
			(xy 246.457278 -123.606076) (xy 246.4031 -123.598264) (xy 246.350596 -123.582779) (xy 246.300849 -123.559942)
			(xy 246.254882 -123.53022) (xy 246.23395 -123.51258) (xy 246.233696 -123.512326) (xy 246.226621 -123.506723)
			(xy 246.209695 -123.500488) (xy 246.200676 -123.500134) (xy 246.13362 -123.500134) (xy 246.124603 -123.500493)
			(xy 246.107686 -123.506739) (xy 246.1006 -123.512326) (xy 246.100346 -123.51258) (xy 246.079413 -123.530221)
			(xy 246.033445 -123.559945) (xy 245.983699 -123.582791) (xy 245.931197 -123.598287) (xy 245.877019 -123.606116)
			(xy 245.822277 -123.606116) (xy 245.768099 -123.598287) (xy 245.715597 -123.582791) (xy 245.665851 -123.559945)
			(xy 245.619883 -123.530221) (xy 245.59895 -123.51258) (xy 245.598696 -123.512326) (xy 245.591621 -123.506723)
			(xy 245.574695 -123.500488) (xy 245.565676 -123.500134) (xy 245.49862 -123.500134) (xy 245.489603 -123.500493)
			(xy 245.472686 -123.506739) (xy 245.4656 -123.512326) (xy 245.4656 -123.51258) (xy 245.465346 -123.51258)
			(xy 245.444405 -123.530208) (xy 245.398435 -123.559922) (xy 245.34869 -123.582761) (xy 245.296191 -123.598254)
			(xy 245.242017 -123.606085) (xy 245.214648 -123.60656) (xy 245.187618 -123.606078) (xy 245.134101 -123.598435)
			(xy 245.0822 -123.583308) (xy 245.032957 -123.561001) (xy 244.987358 -123.531961) (xy 244.946319 -123.496772)
			(xy 244.928136 -123.476766) (xy 244.927882 -123.476512) (xy 244.920414 -123.468893) (xy 244.900949 -123.460207)
			(xy 244.89029 -123.459748) (xy 244.80266 -123.45924) (xy 244.783102 -123.467876) (xy 244.775736 -123.476258)
			(xy 244.757564 -123.49597) (xy 244.716664 -123.530633) (xy 244.67131 -123.559221) (xy 244.622398 -123.581172)
			(xy 244.570891 -123.59605) (xy 244.517808 -123.603564) (xy 244.491002 -123.60402) (xy 244.46375 -123.603533)
			(xy 244.4098 -123.595776) (xy 244.357504 -123.580421) (xy 244.307925 -123.557779) (xy 244.262073 -123.528312)
			(xy 244.220882 -123.49262) (xy 244.185189 -123.451428) (xy 244.155722 -123.405577) (xy 244.13308 -123.355998)
			(xy 244.117724 -123.303701) (xy 244.109967 -123.249752) (xy 243.208422 -123.249752) (xy 242.18011 -124.277882)
			(xy 242.173275 -124.285285) (xy 242.165569 -124.303883) (xy 242.165124 -124.31395) (xy 242.165124 -125.057916)
			(xy 242.981478 -125.057916) (xy 242.985549 -125.002294) (xy 242.997675 -124.947857) (xy 243.017598 -124.895766)
			(xy 243.044894 -124.847131) (xy 243.07898 -124.802988) (xy 243.119129 -124.764279) (xy 243.164487 -124.731828)
			(xy 243.214087 -124.706327) (xy 243.266871 -124.68832) (xy 243.321714 -124.67819) (xy 243.377448 -124.676153)
			(xy 243.432885 -124.682253) (xy 243.486842 -124.696359) (xy 243.538171 -124.718171) (xy 243.585777 -124.747225)
			(xy 243.628645 -124.7829) (xy 243.665862 -124.824437) (xy 243.696635 -124.87095) (xy 243.720307 -124.921447)
			(xy 243.736375 -124.974854) (xy 243.744495 -125.03003) (xy 243.745004 -125.057916) (xy 243.744495 -125.085802)
			(xy 243.736375 -125.140978) (xy 243.720307 -125.194385) (xy 243.696635 -125.244882) (xy 243.665862 -125.291395)
			(xy 243.628645 -125.332932) (xy 243.585777 -125.368607) (xy 243.538171 -125.397661) (xy 243.524769 -125.403356)
			(xy 247.744234 -125.403356) (xy 247.744725 -125.375987) (xy 247.752535 -125.321808) (xy 247.768018 -125.269305)
			(xy 247.790855 -125.219558) (xy 247.820575 -125.17359) (xy 247.838214 -125.152658) (xy 247.838468 -125.152404)
			(xy 247.844067 -125.145326) (xy 247.850304 -125.128402) (xy 247.85066 -125.119384) (xy 247.85066 -125.052328)
			(xy 247.850298 -125.043311) (xy 247.844055 -125.026394) (xy 247.838468 -125.019308) (xy 247.838214 -125.019308)
			(xy 247.838214 -125.019054) (xy 247.820589 -124.998111) (xy 247.790875 -124.952141) (xy 247.768036 -124.902397)
			(xy 247.752541 -124.849898) (xy 247.74471 -124.795724) (xy 247.744234 -124.768356) (xy 247.74472 -124.741105)
			(xy 247.752476 -124.687157) (xy 247.767831 -124.634862) (xy 247.790473 -124.585285) (xy 247.819939 -124.539435)
			(xy 247.85563 -124.498244) (xy 247.896821 -124.462553) (xy 247.942671 -124.433087) (xy 247.992248 -124.410445)
			(xy 248.044543 -124.39509) (xy 248.098491 -124.387334) (xy 248.152993 -124.387334) (xy 248.206941 -124.39509)
			(xy 248.259236 -124.410445) (xy 248.308813 -124.433087) (xy 248.354663 -124.462553) (xy 248.395854 -124.498244)
			(xy 248.431545 -124.539435) (xy 248.461011 -124.585285) (xy 248.483653 -124.634862) (xy 248.499008 -124.687157)
			(xy 248.506764 -124.741105) (xy 248.50725 -124.768356) (xy 248.50677 -124.795726) (xy 248.498958 -124.849905)
			(xy 248.483472 -124.902408) (xy 248.460633 -124.952155) (xy 248.430911 -124.998122) (xy 248.41327 -125.019054)
			(xy 248.413016 -125.019308) (xy 248.407422 -125.026389) (xy 248.401179 -125.04331) (xy 248.400824 -125.052328)
			(xy 248.400824 -125.119384) (xy 248.401184 -125.128401) (xy 248.407429 -125.145318) (xy 248.413016 -125.152404)
			(xy 248.41327 -125.152404) (xy 248.41327 -125.152658) (xy 248.430898 -125.173599) (xy 248.460613 -125.219569)
			(xy 248.483451 -125.269314) (xy 248.498945 -125.321813) (xy 248.506775 -125.375987) (xy 248.50725 -125.403356)
			(xy 248.506764 -125.430607) (xy 248.499008 -125.484555) (xy 248.483653 -125.53685) (xy 248.461011 -125.586427)
			(xy 248.431545 -125.632277) (xy 248.395854 -125.673468) (xy 248.354663 -125.709159) (xy 248.308813 -125.738625)
			(xy 248.259236 -125.761267) (xy 248.206941 -125.776622) (xy 248.152993 -125.784378) (xy 248.098491 -125.784378)
			(xy 248.044543 -125.776622) (xy 247.992248 -125.761267) (xy 247.942671 -125.738625) (xy 247.896821 -125.709159)
			(xy 247.85563 -125.673468) (xy 247.819939 -125.632277) (xy 247.790473 -125.586427) (xy 247.767831 -125.53685)
			(xy 247.752476 -125.484555) (xy 247.74472 -125.430607) (xy 247.744234 -125.403356) (xy 243.524769 -125.403356)
			(xy 243.486842 -125.419473) (xy 243.432885 -125.433579) (xy 243.377448 -125.439679) (xy 243.321714 -125.437642)
			(xy 243.266871 -125.427512) (xy 243.214087 -125.409505) (xy 243.164487 -125.384004) (xy 243.119129 -125.351553)
			(xy 243.07898 -125.312844) (xy 243.044894 -125.268701) (xy 243.017598 -125.220066) (xy 242.997675 -125.167975)
			(xy 242.985549 -125.113538) (xy 242.981478 -125.057916) (xy 242.165124 -125.057916) (xy 242.165124 -126.107444)
			(xy 243.356382 -126.107444) (xy 243.360453 -126.051822) (xy 243.372579 -125.997385) (xy 243.392502 -125.945294)
			(xy 243.419798 -125.896659) (xy 243.453884 -125.852516) (xy 243.494033 -125.813807) (xy 243.539391 -125.781356)
			(xy 243.588991 -125.755855) (xy 243.641775 -125.737848) (xy 243.696618 -125.727718) (xy 243.752352 -125.725681)
			(xy 243.807789 -125.731781) (xy 243.861746 -125.745887) (xy 243.913075 -125.767699) (xy 243.960681 -125.796753)
			(xy 244.003549 -125.832428) (xy 244.022607 -125.853698) (xy 248.684796 -125.853698) (xy 248.685262 -125.826328)
			(xy 248.69308 -125.772149) (xy 248.708569 -125.719646) (xy 248.731411 -125.669899) (xy 248.761135 -125.623932)
			(xy 248.778776 -125.603) (xy 248.77903 -125.602746) (xy 248.784607 -125.595653) (xy 248.790858 -125.578741)
			(xy 248.791222 -125.569726) (xy 248.791222 -125.50267) (xy 248.790875 -125.493652) (xy 248.78462 -125.476736)
			(xy 248.77903 -125.46965) (xy 248.778776 -125.46965) (xy 248.778776 -125.469396) (xy 248.761118 -125.448479)
			(xy 248.73141 -125.402502) (xy 248.708578 -125.35275) (xy 248.693091 -125.300247) (xy 248.685268 -125.246068)
			(xy 248.684796 -125.218698) (xy 248.685282 -125.191447) (xy 248.693038 -125.137499) (xy 248.708393 -125.085204)
			(xy 248.731035 -125.035627) (xy 248.760501 -124.989777) (xy 248.796192 -124.948586) (xy 248.837383 -124.912895)
			(xy 248.883233 -124.883429) (xy 248.93281 -124.860787) (xy 248.985105 -124.845432) (xy 249.039053 -124.837676)
			(xy 249.093555 -124.837676) (xy 249.147503 -124.845432) (xy 249.199798 -124.860787) (xy 249.249375 -124.883429)
			(xy 249.295225 -124.912895) (xy 249.336416 -124.948586) (xy 249.372107 -124.989777) (xy 249.401573 -125.035627)
			(xy 249.424215 -125.085204) (xy 249.43957 -125.137499) (xy 249.447326 -125.191447) (xy 249.447812 -125.218698)
			(xy 249.447342 -125.246068) (xy 249.439525 -125.300247) (xy 249.424036 -125.35275) (xy 249.401196 -125.402497)
			(xy 249.371472 -125.448464) (xy 249.353832 -125.469396) (xy 249.353578 -125.46965) (xy 249.348004 -125.476745)
			(xy 249.34175 -125.493655) (xy 249.341386 -125.50267) (xy 249.341386 -125.569726) (xy 249.341734 -125.578744)
			(xy 249.347988 -125.59566) (xy 249.353578 -125.602746) (xy 249.353832 -125.602746) (xy 249.353832 -125.603)
			(xy 249.37149 -125.623917) (xy 249.401198 -125.669895) (xy 249.424029 -125.719646) (xy 249.439516 -125.77215)
			(xy 249.44734 -125.826328) (xy 249.447812 -125.853698) (xy 249.447326 -125.880949) (xy 249.43957 -125.934897)
			(xy 249.424215 -125.987192) (xy 249.401573 -126.036769) (xy 249.372107 -126.082619) (xy 249.336416 -126.12381)
			(xy 249.295225 -126.159501) (xy 249.249375 -126.188967) (xy 249.199798 -126.211609) (xy 249.147503 -126.226964)
			(xy 249.093555 -126.23472) (xy 249.039053 -126.23472) (xy 248.985105 -126.226964) (xy 248.93281 -126.211609)
			(xy 248.883233 -126.188967) (xy 248.837383 -126.159501) (xy 248.796192 -126.12381) (xy 248.760501 -126.082619)
			(xy 248.731035 -126.036769) (xy 248.708393 -125.987192) (xy 248.693038 -125.934897) (xy 248.685282 -125.880949)
			(xy 248.684796 -125.853698) (xy 244.022607 -125.853698) (xy 244.040766 -125.873965) (xy 244.071539 -125.920478)
			(xy 244.095211 -125.970975) (xy 244.111279 -126.024382) (xy 244.119399 -126.079558) (xy 244.119908 -126.107444)
			(xy 244.119399 -126.13533) (xy 244.111279 -126.190506) (xy 244.095211 -126.243913) (xy 244.071539 -126.29441)
			(xy 244.040766 -126.340923) (xy 244.003549 -126.38246) (xy 243.960681 -126.418135) (xy 243.913075 -126.447189)
			(xy 243.861746 -126.469001) (xy 243.807789 -126.483107) (xy 243.752352 -126.489207) (xy 243.696618 -126.48717)
			(xy 243.641775 -126.47704) (xy 243.588991 -126.459033) (xy 243.539391 -126.433532) (xy 243.494033 -126.401081)
			(xy 243.453884 -126.362372) (xy 243.419798 -126.318229) (xy 243.392502 -126.269594) (xy 243.372579 -126.217503)
			(xy 243.360453 -126.163066) (xy 243.356382 -126.107444) (xy 242.165124 -126.107444) (xy 242.165124 -126.530354)
			(xy 249.893328 -126.530354) (xy 249.893869 -126.50269) (xy 249.901862 -126.447941) (xy 249.917672 -126.39492)
			(xy 249.94097 -126.344735) (xy 249.971267 -126.298439) (xy 250.007929 -126.257001) (xy 250.050188 -126.221287)
			(xy 250.073414 -126.20625) (xy 250.083065 -126.199582) (xy 250.095524 -126.179744) (xy 250.09729 -126.16815)
			(xy 250.105164 -126.08814) (xy 250.105759 -126.076503) (xy 250.097704 -126.054668) (xy 250.08967 -126.04623)
			(xy 250.089416 -126.045976) (xy 250.070844 -126.027886) (xy 250.038264 -125.987556) (xy 250.011449 -125.943184)
			(xy 249.990895 -125.895587) (xy 249.97698 -125.845644) (xy 249.969961 -125.794277) (xy 249.969528 -125.768354)
			(xy 249.969935 -125.7411) (xy 249.977699 -125.687148) (xy 249.993062 -125.634849) (xy 250.015711 -125.585269)
			(xy 250.045185 -125.539417) (xy 250.080885 -125.498227) (xy 250.122083 -125.462536) (xy 250.167941 -125.433071)
			(xy 250.217526 -125.410433) (xy 250.269828 -125.395081) (xy 250.323782 -125.387329) (xy 250.351036 -125.386846)
			(xy 250.378408 -125.38728) (xy 250.432588 -125.395104) (xy 250.485092 -125.4106) (xy 250.534839 -125.433449)
			(xy 250.580804 -125.463181) (xy 250.601734 -125.480826) (xy 250.601988 -125.48108) (xy 250.609067 -125.486677)
			(xy 250.62599 -125.492915) (xy 250.635008 -125.493272) (xy 250.702064 -125.493272) (xy 250.71108 -125.492904)
			(xy 250.727997 -125.486665) (xy 250.735084 -125.48108) (xy 250.735084 -125.480826) (xy 250.735338 -125.480826)
			(xy 250.756286 -125.463207) (xy 250.802254 -125.433491) (xy 250.851997 -125.410651) (xy 250.904495 -125.395155)
			(xy 250.958668 -125.387322) (xy 250.986036 -125.386846) (xy 251.013286 -125.387344) (xy 251.067231 -125.395104)
			(xy 251.119523 -125.410462) (xy 251.169097 -125.433104) (xy 251.214945 -125.462569) (xy 251.256134 -125.498259)
			(xy 251.291824 -125.539447) (xy 251.321291 -125.585294) (xy 251.343935 -125.634868) (xy 251.359293 -125.687159)
			(xy 251.367055 -125.741104) (xy 251.367544 -125.768354) (xy 251.367014 -125.797271) (xy 251.35829 -125.854442)
			(xy 251.341036 -125.909642) (xy 251.315647 -125.961604) (xy 251.282704 -126.009138) (xy 251.242964 -126.051155)
			(xy 251.220478 -126.069344) (xy 251.211657 -126.076938) (xy 251.201482 -126.097849) (xy 251.20092 -126.109476)
			(xy 251.20092 -126.189232) (xy 251.201448 -126.200865) (xy 251.211644 -126.221775) (xy 251.220478 -126.229364)
			(xy 251.24294 -126.247581) (xy 251.282677 -126.289595) (xy 251.315619 -126.337124) (xy 251.341012 -126.38908)
			(xy 251.358273 -126.444273) (xy 251.367006 -126.501439) (xy 251.367544 -126.530354) (xy 251.367002 -126.557604)
			(xy 251.359252 -126.61155) (xy 251.347151 -126.652782) (xy 251.638816 -126.652782) (xy 251.639268 -126.625411)
			(xy 251.647088 -126.571231) (xy 251.662581 -126.518728) (xy 251.685426 -126.468981) (xy 251.715153 -126.423015)
			(xy 251.732796 -126.402084) (xy 251.73305 -126.40183) (xy 251.738636 -126.394743) (xy 251.744882 -126.377826)
			(xy 251.745242 -126.36881) (xy 251.745242 -126.301754) (xy 251.744872 -126.292738) (xy 251.738635 -126.27582)
			(xy 251.73305 -126.268734) (xy 251.732796 -126.268734) (xy 251.732796 -126.26848) (xy 251.715139 -126.247561)
			(xy 251.685417 -126.20159) (xy 251.662575 -126.151841) (xy 251.647081 -126.099337) (xy 251.639255 -126.045158)
			(xy 251.639257 -125.990415) (xy 251.647087 -125.936236) (xy 251.662584 -125.883733) (xy 251.68543 -125.833986)
			(xy 251.715155 -125.788017) (xy 251.732796 -125.767084) (xy 251.73305 -125.76683) (xy 251.738636 -125.759743)
			(xy 251.744882 -125.742826) (xy 251.745242 -125.73381) (xy 251.745242 -125.666754) (xy 251.744872 -125.657738)
			(xy 251.738635 -125.64082) (xy 251.73305 -125.633734) (xy 251.732796 -125.633734) (xy 251.732796 -125.63348)
			(xy 251.715139 -125.612561) (xy 251.685417 -125.56659) (xy 251.662575 -125.516841) (xy 251.647081 -125.464337)
			(xy 251.639255 -125.410158) (xy 251.639257 -125.355415) (xy 251.647087 -125.301236) (xy 251.662584 -125.248733)
			(xy 251.68543 -125.198986) (xy 251.715155 -125.153017) (xy 251.732796 -125.132084) (xy 251.73305 -125.13183)
			(xy 251.738636 -125.124743) (xy 251.744882 -125.107826) (xy 251.745242 -125.09881) (xy 251.745242 -125.031754)
			(xy 251.744872 -125.022738) (xy 251.738635 -125.00582) (xy 251.73305 -124.998734) (xy 251.732796 -124.998734)
			(xy 251.732796 -124.99848) (xy 251.71518 -124.977529) (xy 251.685465 -124.931561) (xy 251.662625 -124.881819)
			(xy 251.647128 -124.829322) (xy 251.639294 -124.77515) (xy 251.638816 -124.747782) (xy 251.639302 -124.720531)
			(xy 251.647058 -124.666583) (xy 251.662413 -124.614288) (xy 251.685055 -124.564711) (xy 251.714521 -124.518861)
			(xy 251.750212 -124.47767) (xy 251.791403 -124.441979) (xy 251.837253 -124.412513) (xy 251.88683 -124.389871)
			(xy 251.939125 -124.374516) (xy 251.993073 -124.36676) (xy 252.047575 -124.36676) (xy 252.101523 -124.374516)
			(xy 252.153818 -124.389871) (xy 252.203395 -124.412513) (xy 252.249245 -124.441979) (xy 252.290436 -124.47767)
			(xy 252.326127 -124.518861) (xy 252.355593 -124.564711) (xy 252.378235 -124.614288) (xy 252.39359 -124.666583)
			(xy 252.401346 -124.720531) (xy 252.401832 -124.747782) (xy 252.401372 -124.775153) (xy 252.393555 -124.829333)
			(xy 252.378066 -124.881836) (xy 252.355222 -124.931583) (xy 252.325495 -124.977549) (xy 252.307852 -124.99848)
			(xy 252.307598 -124.998734) (xy 252.302033 -125.005835) (xy 252.295773 -125.022741) (xy 252.295406 -125.031754)
			(xy 252.295406 -125.09881) (xy 252.295757 -125.107828) (xy 252.302009 -125.124744) (xy 252.307598 -125.13183)
			(xy 252.307852 -125.13183) (xy 252.307852 -125.132084) (xy 252.325476 -125.153031) (xy 252.355203 -125.198995)
			(xy 252.378051 -125.248739) (xy 252.393549 -125.301239) (xy 252.40138 -125.355416) (xy 252.401382 -125.410156)
			(xy 252.393555 -125.464334) (xy 252.37806 -125.516835) (xy 252.355216 -125.566581) (xy 252.325492 -125.612548)
			(xy 252.307852 -125.63348) (xy 252.307598 -125.633734) (xy 252.302033 -125.640835) (xy 252.295773 -125.657741)
			(xy 252.295406 -125.666754) (xy 252.295406 -125.73381) (xy 252.295757 -125.742828) (xy 252.302009 -125.759744)
			(xy 252.307598 -125.76683) (xy 252.307852 -125.76683) (xy 252.307852 -125.767084) (xy 252.325476 -125.788031)
			(xy 252.355203 -125.833995) (xy 252.378051 -125.883739) (xy 252.393549 -125.936239) (xy 252.40138 -125.990416)
			(xy 252.401382 -126.045156) (xy 252.393555 -126.099334) (xy 252.37806 -126.151835) (xy 252.355216 -126.201581)
			(xy 252.325492 -126.247548) (xy 252.307852 -126.26848) (xy 252.307598 -126.268734) (xy 252.302033 -126.275835)
			(xy 252.295773 -126.292741) (xy 252.295406 -126.301754) (xy 252.295406 -126.36881) (xy 252.295757 -126.377828)
			(xy 252.302009 -126.394744) (xy 252.307598 -126.40183) (xy 252.307852 -126.40183) (xy 252.307852 -126.402084)
			(xy 252.32549 -126.423017) (xy 252.355203 -126.468989) (xy 252.37804 -126.518736) (xy 252.393532 -126.571237)
			(xy 252.401359 -126.625413) (xy 252.401832 -126.652782) (xy 252.401346 -126.680033) (xy 252.39359 -126.733981)
			(xy 252.378235 -126.786276) (xy 252.355593 -126.835853) (xy 252.326127 -126.881703) (xy 252.290436 -126.922894)
			(xy 252.249245 -126.958585) (xy 252.203395 -126.988051) (xy 252.153818 -127.010693) (xy 252.101523 -127.026048)
			(xy 252.047575 -127.033804) (xy 251.993073 -127.033804) (xy 251.939125 -127.026048) (xy 251.88683 -127.010693)
			(xy 251.837253 -126.988051) (xy 251.791403 -126.958585) (xy 251.750212 -126.922894) (xy 251.714521 -126.881703)
			(xy 251.685055 -126.835853) (xy 251.662413 -126.786276) (xy 251.647058 -126.733981) (xy 251.639302 -126.680033)
			(xy 251.638816 -126.652782) (xy 251.347151 -126.652782) (xy 251.343904 -126.663845) (xy 251.321269 -126.713422)
			(xy 251.291809 -126.759274) (xy 251.256124 -126.800466) (xy 251.214939 -126.83616) (xy 251.169094 -126.86563)
			(xy 251.119521 -126.888275) (xy 251.067231 -126.903635) (xy 251.013286 -126.911396) (xy 250.986036 -126.911862)
			(xy 250.95972 -126.911449) (xy 250.907589 -126.904205) (xy 250.856944 -126.889876) (xy 250.808745 -126.868733)
			(xy 250.763903 -126.841177) (xy 250.723267 -126.807728) (xy 250.705112 -126.788672) (xy 250.697578 -126.781284)
			(xy 250.678308 -126.772749) (xy 250.667774 -126.772162) (xy 250.593098 -126.772162) (xy 250.582548 -126.772688)
			(xy 250.563254 -126.781227) (xy 250.55576 -126.788672) (xy 250.537611 -126.807735) (xy 250.496981 -126.841192)
			(xy 250.452139 -126.868751) (xy 250.403937 -126.889888) (xy 250.353288 -126.904204) (xy 250.301153 -126.911425)
			(xy 250.274836 -126.911862) (xy 250.247582 -126.911411) (xy 250.193628 -126.903658) (xy 250.141327 -126.888304)
			(xy 250.091744 -126.865662) (xy 250.045889 -126.836194) (xy 250.004694 -126.800499) (xy 249.969 -126.759303)
			(xy 249.939533 -126.713447) (xy 249.916892 -126.663863) (xy 249.90154 -126.611562) (xy 249.893788 -126.557608)
			(xy 249.893328 -126.530354) (xy 242.165124 -126.530354) (xy 242.165124 -127.051308) (xy 242.94414 -127.051308)
			(xy 242.948211 -126.995686) (xy 242.960337 -126.941249) (xy 242.98026 -126.889158) (xy 243.007556 -126.840523)
			(xy 243.041642 -126.79638) (xy 243.081791 -126.757671) (xy 243.127149 -126.72522) (xy 243.176749 -126.699719)
			(xy 243.229533 -126.681712) (xy 243.284376 -126.671582) (xy 243.34011 -126.669545) (xy 243.395547 -126.675645)
			(xy 243.449504 -126.689751) (xy 243.500833 -126.711563) (xy 243.548439 -126.740617) (xy 243.591307 -126.776292)
			(xy 243.628524 -126.817829) (xy 243.659297 -126.864342) (xy 243.682969 -126.914839) (xy 243.699037 -126.968246)
			(xy 243.707157 -127.023422) (xy 243.707666 -127.051308) (xy 243.707157 -127.079194) (xy 243.699037 -127.13437)
			(xy 243.682969 -127.187777) (xy 243.659297 -127.238274) (xy 243.628524 -127.284787) (xy 243.591307 -127.326324)
			(xy 243.548439 -127.361999) (xy 243.500833 -127.391053) (xy 243.449504 -127.412865) (xy 243.395547 -127.426971)
			(xy 243.34011 -127.433071) (xy 243.284376 -127.431034) (xy 243.229533 -127.420904) (xy 243.176749 -127.402897)
			(xy 243.127149 -127.377396) (xy 243.081791 -127.344945) (xy 243.041642 -127.306236) (xy 243.007556 -127.262093)
			(xy 242.98026 -127.213458) (xy 242.960337 -127.161367) (xy 242.948211 -127.10693) (xy 242.94414 -127.051308)
			(xy 242.165124 -127.051308) (xy 242.165124 -127.561086) (xy 242.164594 -127.587108) (xy 242.156422 -127.638508)
			(xy 242.140322 -127.688001) (xy 242.116691 -127.734373) (xy 242.086108 -127.776485) (xy 242.068096 -127.795274)
			(xy 242.03279 -127.83058) (xy 242.025954 -127.837946) (xy 242.01822 -127.856475) (xy 242.018226 -127.876554)
			(xy 242.025971 -127.895079) (xy 242.03279 -127.902462) (xy 242.045744 -127.915416) (xy 242.081558 -127.918972)
			(xy 242.096798 -127.908812) (xy 242.120492 -127.893503) (xy 242.171439 -127.869285) (xy 242.225398 -127.852839)
			(xy 242.281191 -127.844526) (xy 242.309396 -127.844042) (xy 242.336766 -127.844514) (xy 242.390944 -127.852338)
			(xy 242.443447 -127.867826) (xy 242.493197 -127.890659) (xy 242.539172 -127.92037) (xy 242.560094 -127.938022)
			(xy 242.560348 -127.938022) (xy 242.560348 -127.938276) (xy 242.567432 -127.943871) (xy 242.584349 -127.950133)
			(xy 242.593368 -127.950468) (xy 242.660424 -127.950468) (xy 242.66944 -127.950106) (xy 242.686355 -127.943859)
			(xy 242.693444 -127.938276) (xy 242.693698 -127.938022) (xy 242.714631 -127.920381) (xy 242.760599 -127.890657)
			(xy 242.810345 -127.867811) (xy 242.862847 -127.852315) (xy 242.917025 -127.844486) (xy 242.971767 -127.844486)
			(xy 243.025945 -127.852315) (xy 243.078447 -127.867811) (xy 243.128193 -127.890657) (xy 243.174161 -127.920381)
			(xy 243.195094 -127.938022) (xy 243.195348 -127.938022) (xy 243.195348 -127.938276) (xy 243.202432 -127.943871)
			(xy 243.219349 -127.950133) (xy 243.228368 -127.950468) (xy 243.295424 -127.950468) (xy 243.30444 -127.950106)
			(xy 243.321355 -127.943859) (xy 243.328444 -127.938276) (xy 243.328698 -127.938022) (xy 243.349629 -127.920379)
			(xy 243.395595 -127.890651) (xy 243.445342 -127.867806) (xy 243.497845 -127.852315) (xy 243.552025 -127.844495)
			(xy 243.579396 -127.844042) (xy 243.606645 -127.844505) (xy 243.66059 -127.85226) (xy 243.712881 -127.867614)
			(xy 243.762455 -127.890253) (xy 243.808303 -127.919717) (xy 243.849491 -127.955406) (xy 243.88518 -127.996594)
			(xy 243.914645 -128.042441) (xy 243.937284 -128.092015) (xy 243.952639 -128.144306) (xy 243.960395 -128.198251)
			(xy 243.960395 -128.252749) (xy 243.952639 -128.306694) (xy 243.937284 -128.358985) (xy 243.914645 -128.408559)
			(xy 243.88518 -128.454406) (xy 243.849491 -128.495594) (xy 243.808303 -128.531283) (xy 243.762455 -128.560747)
			(xy 243.712881 -128.583386) (xy 243.66059 -128.59874) (xy 243.606645 -128.606495) (xy 243.579396 -128.607058)
			(xy 243.552026 -128.606586) (xy 243.497849 -128.598761) (xy 243.445347 -128.583272) (xy 243.395597 -128.560437)
			(xy 243.349623 -128.530726) (xy 243.328698 -128.513078) (xy 243.328444 -128.513078) (xy 243.328444 -128.512824)
			(xy 243.32136 -128.50723) (xy 243.304443 -128.500971) (xy 243.295424 -128.500632) (xy 243.228368 -128.500632)
			(xy 243.219353 -128.500995) (xy 243.202439 -128.507244) (xy 243.195348 -128.512824) (xy 243.195094 -128.513078)
			(xy 243.174161 -128.530719) (xy 243.128193 -128.560443) (xy 243.078447 -128.583289) (xy 243.025945 -128.598785)
			(xy 242.971767 -128.606614) (xy 242.917025 -128.606614) (xy 242.862847 -128.598785) (xy 242.810345 -128.583289)
			(xy 242.760599 -128.560443) (xy 242.714631 -128.530719) (xy 242.693698 -128.513078) (xy 242.693444 -128.513078)
			(xy 242.693444 -128.512824) (xy 242.68636 -128.50723) (xy 242.669443 -128.500971) (xy 242.660424 -128.500632)
			(xy 242.593368 -128.500632) (xy 242.584353 -128.500995) (xy 242.567439 -128.507244) (xy 242.560348 -128.512824)
			(xy 242.560094 -128.513078) (xy 242.539163 -128.530721) (xy 242.493197 -128.560448) (xy 242.44345 -128.583291)
			(xy 242.390946 -128.598782) (xy 242.336767 -128.6066) (xy 242.309396 -128.607058) (xy 242.282145 -128.606594)
			(xy 242.228197 -128.598837) (xy 242.175902 -128.58348) (xy 242.126326 -128.560836) (xy 242.080477 -128.531367)
			(xy 242.039289 -128.495673) (xy 242.0036 -128.45448) (xy 241.974138 -128.408627) (xy 241.951501 -128.359047)
			(xy 241.936152 -128.30675) (xy 241.928402 -128.252801) (xy 241.927888 -128.22555) (xy 241.929666 -128.188212)
			(xy 241.93119 -128.17221) (xy 241.915442 -128.14427) (xy 241.81435 -128.096518) (xy 241.80471 -128.092479)
			(xy 241.783843 -128.09174) (xy 241.764411 -128.099379) (xy 241.756692 -128.106424) (xy 241.72291 -128.140206)
			(xy 241.716064 -128.147605) (xy 241.70833 -128.166202) (xy 241.707924 -128.176274) (xy 241.707924 -129.376932)
			(xy 241.707398 -129.402956) (xy 241.699233 -129.45436) (xy 241.68314 -129.503859) (xy 241.659514 -129.550236)
			(xy 241.628934 -129.592355) (xy 241.610896 -129.61112) (xy 239.774859 -131.447157) (xy 241.913309 -131.447157)
			(xy 241.913309 -131.392643) (xy 241.921067 -131.338685) (xy 241.936426 -131.28638) (xy 241.959072 -131.236793)
			(xy 241.988544 -131.190934) (xy 242.024243 -131.149736) (xy 242.065442 -131.114038) (xy 242.111302 -131.084567)
			(xy 242.160889 -131.061922) (xy 242.213195 -131.046565) (xy 242.267153 -131.038808) (xy 242.29441 -131.038346)
			(xy 242.321781 -131.038795) (xy 242.375961 -131.046615) (xy 242.428465 -131.062108) (xy 242.478212 -131.084953)
			(xy 242.524177 -131.114682) (xy 242.545108 -131.132326) (xy 242.545362 -131.13258) (xy 242.552448 -131.138166)
			(xy 242.569366 -131.144411) (xy 242.578382 -131.144772) (xy 242.645438 -131.144772) (xy 242.654457 -131.144439)
			(xy 242.671375 -131.138175) (xy 242.678458 -131.13258) (xy 242.678458 -131.132326) (xy 242.678712 -131.132326)
			(xy 242.699645 -131.114685) (xy 242.745613 -131.084961) (xy 242.795359 -131.062115) (xy 242.847861 -131.046619)
			(xy 242.902039 -131.03879) (xy 242.956781 -131.03879) (xy 243.010959 -131.046619) (xy 243.063461 -131.062115)
			(xy 243.113207 -131.084961) (xy 243.159175 -131.114685) (xy 243.180108 -131.132326) (xy 243.180362 -131.13258)
			(xy 243.187448 -131.138166) (xy 243.204366 -131.144411) (xy 243.213382 -131.144772) (xy 243.280438 -131.144772)
			(xy 243.289457 -131.144439) (xy 243.306375 -131.138175) (xy 243.313458 -131.13258) (xy 243.313458 -131.132326)
			(xy 243.313712 -131.132326) (xy 243.33467 -131.114719) (xy 243.380635 -131.085001) (xy 243.430376 -131.062159)
			(xy 243.482871 -131.04666) (xy 243.537043 -131.038824) (xy 243.56441 -131.038346) (xy 243.591657 -131.038925)
			(xy 243.645598 -131.046682) (xy 243.697885 -131.062036) (xy 243.747455 -131.084675) (xy 243.793298 -131.114138)
			(xy 243.834482 -131.149825) (xy 243.870168 -131.19101) (xy 243.89963 -131.236854) (xy 243.922268 -131.286425)
			(xy 243.937621 -131.338712) (xy 243.945376 -131.392653) (xy 243.945376 -131.447147) (xy 243.937621 -131.501088)
			(xy 243.922268 -131.553375) (xy 243.89963 -131.602946) (xy 243.870168 -131.64879) (xy 243.834482 -131.689975)
			(xy 243.793298 -131.725662) (xy 243.747455 -131.755125) (xy 243.697885 -131.777764) (xy 243.645598 -131.793118)
			(xy 243.591657 -131.800875) (xy 243.56441 -131.801362) (xy 243.53704 -131.800899) (xy 243.48286 -131.793082)
			(xy 243.430356 -131.777593) (xy 243.38061 -131.75475) (xy 243.334643 -131.725024) (xy 243.313712 -131.707382)
			(xy 243.313458 -131.707128) (xy 243.306365 -131.701551) (xy 243.289453 -131.695301) (xy 243.280438 -131.694936)
			(xy 243.213382 -131.694936) (xy 243.204363 -131.695276) (xy 243.187446 -131.701535) (xy 243.180362 -131.707128)
			(xy 243.180108 -131.707382) (xy 243.159175 -131.725023) (xy 243.113207 -131.754747) (xy 243.063461 -131.777593)
			(xy 243.010959 -131.793089) (xy 242.956781 -131.800918) (xy 242.902039 -131.800918) (xy 242.847861 -131.793089)
			(xy 242.795359 -131.777593) (xy 242.745613 -131.754747) (xy 242.699645 -131.725023) (xy 242.678712 -131.707382)
			(xy 242.678458 -131.707128) (xy 242.671365 -131.701551) (xy 242.654453 -131.695301) (xy 242.645438 -131.694936)
			(xy 242.578382 -131.694936) (xy 242.569363 -131.695276) (xy 242.552446 -131.701535) (xy 242.545362 -131.707128)
			(xy 242.545362 -131.707382) (xy 242.545108 -131.707382) (xy 242.524181 -131.725028) (xy 242.478207 -131.754739)
			(xy 242.428459 -131.777574) (xy 242.375957 -131.793064) (xy 242.32178 -131.800889) (xy 242.29441 -131.801362)
			(xy 242.267153 -131.800992) (xy 242.213195 -131.793235) (xy 242.160889 -131.777878) (xy 242.111302 -131.755233)
			(xy 242.065442 -131.725762) (xy 242.024243 -131.690064) (xy 241.988544 -131.648866) (xy 241.959072 -131.603007)
			(xy 241.936426 -131.55342) (xy 241.921067 -131.501115) (xy 241.913309 -131.447157) (xy 239.774859 -131.447157)
			(xy 239.255046 -131.96697) (xy 239.24837 -131.97437) (xy 239.240786 -131.99278) (xy 239.240799 -132.01269)
			(xy 239.244124 -132.022088) (xy 239.255046 -132.048758) (xy 239.26016 -132.050998) (xy 239.271055 -132.053434)
			(xy 239.276636 -132.053584) (xy 239.321594 -132.053584) (xy 239.340136 -132.061204) (xy 239.347248 -132.068316)
			(xy 239.752632 -132.473446) (xy 240.557304 -133.278118) (xy 240.559082 -133.279896) (xy 240.564416 -133.28523)
			(xy 240.572036 -133.303772) (xy 240.572036 -133.443726) (xy 243.322856 -133.443726) (xy 243.323323 -133.417412)
			(xy 243.330555 -133.365283) (xy 243.344873 -133.314639) (xy 243.366006 -133.26644) (xy 243.393553 -133.221596)
			(xy 243.426993 -133.180958) (xy 243.446046 -133.162802) (xy 243.453441 -133.155274) (xy 243.461971 -133.135999)
			(xy 243.462556 -133.125464) (xy 243.462556 -133.050788) (xy 243.46206 -133.040234) (xy 243.453503 -133.020938)
			(xy 243.446046 -133.01345) (xy 243.426963 -132.995322) (xy 243.39351 -132.954685) (xy 243.365956 -132.909839)
			(xy 243.344823 -132.861633) (xy 243.330511 -132.810981) (xy 243.323292 -132.758844) (xy 243.322856 -132.732526)
			(xy 243.323342 -132.705275) (xy 243.331098 -132.651327) (xy 243.346453 -132.599032) (xy 243.369095 -132.549455)
			(xy 243.398561 -132.503605) (xy 243.434252 -132.462414) (xy 243.475443 -132.426723) (xy 243.521293 -132.397257)
			(xy 243.57087 -132.374615) (xy 243.623165 -132.35926) (xy 243.677113 -132.351504) (xy 243.731615 -132.351504)
			(xy 243.785563 -132.35926) (xy 243.837858 -132.374615) (xy 243.887435 -132.397257) (xy 243.933285 -132.426723)
			(xy 243.974476 -132.462414) (xy 244.010167 -132.503605) (xy 244.039633 -132.549455) (xy 244.062275 -132.599032)
			(xy 244.07763 -132.651327) (xy 244.085386 -132.705275) (xy 244.085872 -132.732526) (xy 244.085431 -132.758841)
			(xy 244.078192 -132.810971) (xy 244.063868 -132.861615) (xy 244.042731 -132.909814) (xy 244.01518 -132.954656)
			(xy 243.981736 -132.995295) (xy 243.962682 -133.01345) (xy 243.955254 -133.020949) (xy 243.946745 -133.040246)
			(xy 243.946172 -133.050788) (xy 243.946172 -133.125464) (xy 243.946716 -133.136012) (xy 243.955242 -133.155307)
			(xy 243.962682 -133.162802) (xy 243.981728 -133.180967) (xy 244.015187 -133.221594) (xy 244.042747 -133.266433)
			(xy 244.063888 -133.314631) (xy 244.078207 -133.365277) (xy 244.085433 -133.41741) (xy 244.085872 -133.443726)
			(xy 244.085386 -133.470977) (xy 244.07763 -133.524925) (xy 244.062275 -133.57722) (xy 244.039633 -133.626797)
			(xy 244.010167 -133.672647) (xy 243.974476 -133.713838) (xy 243.933285 -133.749529) (xy 243.887435 -133.778995)
			(xy 243.837858 -133.801637) (xy 243.785563 -133.816992) (xy 243.731615 -133.824748) (xy 243.677113 -133.824748)
			(xy 243.623165 -133.816992) (xy 243.57087 -133.801637) (xy 243.521293 -133.778995) (xy 243.475443 -133.749529)
			(xy 243.434252 -133.713838) (xy 243.398561 -133.672647) (xy 243.369095 -133.626797) (xy 243.346453 -133.57722)
			(xy 243.331098 -133.524925) (xy 243.323342 -133.470977) (xy 243.322856 -133.443726) (xy 240.572036 -133.443726)
			(xy 240.572036 -135.142051) (xy 241.56187 -135.142051) (xy 241.56187 -135.087549) (xy 241.569626 -135.033603)
			(xy 241.58498 -134.981309) (xy 241.60762 -134.931732) (xy 241.637084 -134.885882) (xy 241.672774 -134.844692)
			(xy 241.713962 -134.809) (xy 241.75981 -134.779532) (xy 241.809385 -134.756889) (xy 241.861677 -134.741531)
			(xy 241.915623 -134.733772) (xy 241.942874 -134.733284) (xy 241.971792 -134.733789) (xy 242.028965 -134.742516)
			(xy 242.084166 -134.759775) (xy 242.136128 -134.785169) (xy 242.183661 -134.818116) (xy 242.225676 -134.857862)
			(xy 242.243864 -134.88035) (xy 242.251656 -134.889338) (xy 242.273122 -134.899526) (xy 242.285012 -134.899908)
			(xy 242.378484 -134.897876) (xy 242.39982 -134.8867) (xy 242.406678 -134.876794) (xy 242.422076 -134.855884)
			(xy 242.457654 -134.818057) (xy 242.498033 -134.785405) (xy 242.542468 -134.75853) (xy 242.590136 -134.73793)
			(xy 242.640158 -134.723985) (xy 242.691609 -134.716952) (xy 242.717574 -134.71652) (xy 242.744944 -134.716996)
			(xy 242.799123 -134.724811) (xy 242.851626 -134.740297) (xy 242.901373 -134.763137) (xy 242.94734 -134.79286)
			(xy 242.968272 -134.8105) (xy 242.968526 -134.810754) (xy 242.975625 -134.816322) (xy 242.992532 -134.822579)
			(xy 243.001546 -134.822946) (xy 243.068602 -134.822946) (xy 243.07762 -134.822601) (xy 243.094538 -134.816346)
			(xy 243.101622 -134.810754) (xy 243.101622 -134.8105) (xy 243.101876 -134.8105) (xy 243.122809 -134.792859)
			(xy 243.168777 -134.763135) (xy 243.218523 -134.740289) (xy 243.271025 -134.724793) (xy 243.325203 -134.716964)
			(xy 243.379945 -134.716964) (xy 243.434123 -134.724793) (xy 243.486625 -134.740289) (xy 243.536371 -134.763135)
			(xy 243.582339 -134.792859) (xy 243.603272 -134.8105) (xy 243.603526 -134.810754) (xy 243.610625 -134.816322)
			(xy 243.627532 -134.822579) (xy 243.636546 -134.822946) (xy 243.703602 -134.822946) (xy 243.71262 -134.822601)
			(xy 243.729538 -134.816346) (xy 243.736622 -134.810754) (xy 243.73713 -134.8105) (xy 243.749868 -134.79956)
			(xy 243.776957 -134.779716) (xy 243.791232 -134.770876) (xy 243.800122 -134.765542) (xy 243.812314 -134.748524)
			(xy 243.832634 -134.655306) (xy 243.828316 -134.634732) (xy 243.822474 -134.626096) (xy 243.806467 -134.602037)
			(xy 243.781127 -134.550103) (xy 243.763903 -134.494944) (xy 243.75519 -134.437819) (xy 243.754656 -134.408926)
			(xy 243.755142 -134.381675) (xy 243.762898 -134.327727) (xy 243.778253 -134.275432) (xy 243.800895 -134.225855)
			(xy 243.830361 -134.180005) (xy 243.866052 -134.138814) (xy 243.907243 -134.103123) (xy 243.953093 -134.073657)
			(xy 244.00267 -134.051015) (xy 244.054965 -134.03566) (xy 244.108913 -134.027904) (xy 244.163415 -134.027904)
			(xy 244.217363 -134.03566) (xy 244.269658 -134.051015) (xy 244.319235 -134.073657) (xy 244.365085 -134.103123)
			(xy 244.406276 -134.138814) (xy 244.441967 -134.180005) (xy 244.471433 -134.225855) (xy 244.494075 -134.275432)
			(xy 244.50943 -134.327727) (xy 244.517186 -134.381675) (xy 244.517672 -134.408926) (xy 244.51722 -134.437019)
			(xy 244.508988 -134.492599) (xy 244.492691 -134.546371) (xy 244.468682 -134.597169) (xy 244.43748 -134.643895)
			(xy 244.399761 -134.685539) (xy 244.35634 -134.721198) (xy 244.332506 -134.736078) (xy 244.323616 -134.741412)
			(xy 244.311424 -134.75843) (xy 244.291104 -134.851648) (xy 244.295422 -134.872222) (xy 244.301264 -134.880858)
			(xy 244.317244 -134.904934) (xy 244.342592 -134.956861) (xy 244.359824 -135.012015) (xy 244.368545 -135.069136)
			(xy 244.369082 -135.098028) (xy 244.368648 -135.125281) (xy 244.360887 -135.179232) (xy 244.345527 -135.231529)
			(xy 244.322881 -135.281108) (xy 244.293409 -135.32696) (xy 244.257712 -135.368151) (xy 244.216517 -135.403842)
			(xy 244.170661 -135.433307) (xy 244.121079 -135.455946) (xy 244.068779 -135.471299) (xy 244.014827 -135.479052)
			(xy 243.987574 -135.479536) (xy 243.960202 -135.479101) (xy 243.906021 -135.471278) (xy 243.853517 -135.455782)
			(xy 243.803771 -135.432933) (xy 243.757806 -135.403201) (xy 243.736876 -135.385556) (xy 243.736622 -135.385302)
			(xy 243.729533 -135.379719) (xy 243.712618 -135.37347) (xy 243.703602 -135.37311) (xy 243.636546 -135.37311)
			(xy 243.627531 -135.373487) (xy 243.610614 -135.379721) (xy 243.603526 -135.385302) (xy 243.603526 -135.385556)
			(xy 243.603272 -135.385556) (xy 243.582339 -135.403197) (xy 243.536371 -135.432921) (xy 243.486625 -135.455767)
			(xy 243.434123 -135.471263) (xy 243.379945 -135.479092) (xy 243.325203 -135.479092) (xy 243.271025 -135.471263)
			(xy 243.218523 -135.455767) (xy 243.168777 -135.432921) (xy 243.122809 -135.403197) (xy 243.101876 -135.385556)
			(xy 243.101622 -135.385302) (xy 243.094533 -135.379719) (xy 243.077618 -135.37347) (xy 243.068602 -135.37311)
			(xy 243.001546 -135.37311) (xy 242.992531 -135.373487) (xy 242.975614 -135.379721) (xy 242.968526 -135.385302)
			(xy 242.968526 -135.385556) (xy 242.968272 -135.385556) (xy 242.947318 -135.403168) (xy 242.901352 -135.432885)
			(xy 242.85161 -135.455727) (xy 242.799114 -135.471225) (xy 242.744942 -135.479059) (xy 242.717574 -135.479536)
			(xy 242.688658 -135.478989) (xy 242.631487 -135.470269) (xy 242.576288 -135.453018) (xy 242.524325 -135.427632)
			(xy 242.476791 -135.394693) (xy 242.434774 -135.354954) (xy 242.416584 -135.33247) (xy 242.408767 -135.323508)
			(xy 242.38732 -135.313305) (xy 242.375436 -135.312912) (xy 242.281964 -135.314944) (xy 242.260628 -135.32612)
			(xy 242.25377 -135.336026) (xy 242.238348 -135.356918) (xy 242.202774 -135.394744) (xy 242.162398 -135.427397)
			(xy 242.117968 -135.454274) (xy 242.070303 -135.474877) (xy 242.020285 -135.488827) (xy 241.968837 -135.495865)
			(xy 241.942874 -135.4963) (xy 241.915623 -135.495828) (xy 241.861677 -135.488069) (xy 241.809385 -135.472711)
			(xy 241.75981 -135.450068) (xy 241.713962 -135.4206) (xy 241.672774 -135.384908) (xy 241.637084 -135.343718)
			(xy 241.60762 -135.297868) (xy 241.58498 -135.248291) (xy 241.569626 -135.195997) (xy 241.56187 -135.142051)
			(xy 240.572036 -135.142051) (xy 240.572036 -135.532114) (xy 240.572297 -135.539758) (xy 240.576825 -135.55436)
			(xy 240.580926 -135.560816) (xy 240.585209 -135.566664) (xy 240.596438 -135.575821) (xy 240.603024 -135.57885)
			(xy 240.610898 -135.582152) (xy 240.685828 -135.612378) (xy 240.695386 -135.615591) (xy 240.715525 -135.615213)
			(xy 240.724944 -135.611616) (xy 240.746534 -135.602218) (xy 240.753646 -135.59536) (xy 240.775215 -135.574846)
			(xy 240.823532 -135.540088) (xy 240.876661 -135.513252) (xy 240.933311 -135.49499) (xy 240.99211 -135.485745)
			(xy 241.02187 -135.485124) (xy 241.036094 -135.485378) (xy 241.045238 -135.48614) (xy 241.073957 -135.488434)
			(xy 241.130275 -135.500577) (xy 241.184127 -135.521048) (xy 241.23429 -135.549383) (xy 241.279623 -135.584936)
			(xy 241.319096 -135.626901) (xy 241.351812 -135.674322) (xy 241.377027 -135.726123) (xy 241.394168 -135.781126)
			(xy 241.402846 -135.83808) (xy 241.403378 -135.866886) (xy 241.402916 -135.894139) (xy 241.39516 -135.94809)
			(xy 241.379805 -136.000387) (xy 241.357163 -136.049967) (xy 241.327695 -136.09582) (xy 241.292001 -136.137012)
			(xy 241.250807 -136.172704) (xy 241.204953 -136.202171) (xy 241.155372 -136.224811) (xy 241.103074 -136.240163)
			(xy 241.049123 -136.247917) (xy 241.02187 -136.248394) (xy 241.00917 -136.248394) (xy 240.980605 -136.246936)
			(xy 240.924364 -136.236524) (xy 240.870309 -136.217829) (xy 240.819653 -136.191271) (xy 240.773532 -136.157444)
			(xy 240.752884 -136.13765) (xy 240.745772 -136.130792) (xy 240.72088 -136.120378) (xy 240.712644 -136.117989)
			(xy 240.695506 -136.118234) (xy 240.687352 -136.120886) (xy 240.655094 -136.13384) (xy 240.603786 -136.154414)
			(xy 240.594621 -136.158604) (xy 240.580307 -136.172768) (xy 240.572516 -136.191337) (xy 240.572036 -136.201404)
			(xy 240.572036 -137.037064) (xy 240.572703 -137.049711) (xy 240.584694 -137.07198) (xy 240.594896 -137.079482)
			(xy 240.597436 -137.081006) (xy 240.661444 -137.11682) (xy 240.667167 -137.119784) (xy 240.67964 -137.123011)
			(xy 240.686082 -137.12317) (xy 240.711736 -137.12317) (xy 240.718315 -137.122955) (xy 240.731042 -137.119605)
			(xy 240.736882 -137.116566) (xy 240.758677 -137.104513) (xy 240.804723 -137.08553) (xy 240.852844 -137.072686)
			(xy 240.902225 -137.066198) (xy 240.927128 -137.065766) (xy 240.954451 -137.066255) (xy 241.00854 -137.074036)
			(xy 241.060971 -137.089434) (xy 241.110677 -137.112137) (xy 241.156647 -137.141682) (xy 241.197944 -137.177469)
			(xy 241.233729 -137.218768) (xy 241.263272 -137.264739) (xy 241.268566 -137.276332) (xy 245.24716 -137.276332)
			(xy 245.247563 -137.250016) (xy 245.254808 -137.197884) (xy 245.269139 -137.147239) (xy 245.290283 -137.09904)
			(xy 245.317842 -137.054198) (xy 245.351292 -137.013562) (xy 245.37035 -136.995408) (xy 245.377743 -136.987879)
			(xy 245.386274 -136.968605) (xy 245.38686 -136.95807) (xy 245.38686 -136.883394) (xy 245.386359 -136.872841)
			(xy 245.377805 -136.853545) (xy 245.37035 -136.846056) (xy 245.351271 -136.827925) (xy 245.317818 -136.787289)
			(xy 245.290263 -136.742443) (xy 245.269129 -136.694238) (xy 245.254816 -136.643586) (xy 245.247596 -136.591449)
			(xy 245.24716 -136.565132) (xy 245.247646 -136.537881) (xy 245.255402 -136.483933) (xy 245.270757 -136.431638)
			(xy 245.293399 -136.382061) (xy 245.322865 -136.336211) (xy 245.358556 -136.29502) (xy 245.399747 -136.259329)
			(xy 245.445597 -136.229863) (xy 245.495174 -136.207221) (xy 245.547469 -136.191866) (xy 245.601417 -136.18411)
			(xy 245.655919 -136.18411) (xy 245.709867 -136.191866) (xy 245.762162 -136.207221) (xy 245.811739 -136.229863)
			(xy 245.857589 -136.259329) (xy 245.89878 -136.29502) (xy 245.934471 -136.336211) (xy 245.963937 -136.382061)
			(xy 245.986579 -136.431638) (xy 246.001934 -136.483933) (xy 246.00969 -136.537881) (xy 246.010176 -136.565132)
			(xy 246.009738 -136.591447) (xy 246.002498 -136.643577) (xy 245.988174 -136.694221) (xy 245.967036 -136.74242)
			(xy 245.939484 -136.787262) (xy 245.90604 -136.827901) (xy 245.886986 -136.846056) (xy 245.8796 -136.85359)
			(xy 245.871067 -136.872861) (xy 245.870476 -136.883394) (xy 245.870476 -136.95807) (xy 245.871015 -136.968618)
			(xy 245.879544 -136.987913) (xy 245.886986 -136.995408) (xy 245.906036 -137.013569) (xy 245.939494 -137.054198)
			(xy 245.967054 -137.099036) (xy 245.988194 -137.147236) (xy 246.002512 -137.197883) (xy 246.009737 -137.250016)
			(xy 246.010176 -137.276332) (xy 246.00969 -137.303583) (xy 246.001934 -137.357531) (xy 245.986579 -137.409826)
			(xy 245.963937 -137.459403) (xy 245.934471 -137.505253) (xy 245.89878 -137.546444) (xy 245.857589 -137.582135)
			(xy 245.811739 -137.611601) (xy 245.762162 -137.634243) (xy 245.709867 -137.649598) (xy 245.655919 -137.657354)
			(xy 245.601417 -137.657354) (xy 245.547469 -137.649598) (xy 245.495174 -137.634243) (xy 245.445597 -137.611601)
			(xy 245.399747 -137.582135) (xy 245.358556 -137.546444) (xy 245.322865 -137.505253) (xy 245.293399 -137.459403)
			(xy 245.270757 -137.409826) (xy 245.255402 -137.357531) (xy 245.247646 -137.303583) (xy 245.24716 -137.276332)
			(xy 241.268566 -137.276332) (xy 241.285972 -137.314446) (xy 241.301368 -137.366878) (xy 241.309146 -137.420967)
			(xy 241.309652 -137.44829) (xy 241.309157 -137.476041) (xy 241.301137 -137.530959) (xy 241.285262 -137.584141)
			(xy 241.261866 -137.63447) (xy 241.231442 -137.680889) (xy 241.194628 -137.722423) (xy 241.189586 -137.726674)
			(xy 246.187722 -137.726674) (xy 246.188167 -137.699303) (xy 246.195989 -137.645123) (xy 246.211483 -137.592619)
			(xy 246.234329 -137.542873) (xy 246.264059 -137.496907) (xy 246.281702 -137.475976) (xy 246.281956 -137.475722)
			(xy 246.287546 -137.468638) (xy 246.293789 -137.451719) (xy 246.294148 -137.442702) (xy 246.294148 -137.375646)
			(xy 246.29378 -137.36663) (xy 246.287541 -137.349712) (xy 246.281956 -137.342626) (xy 246.281702 -137.342626)
			(xy 246.281702 -137.342372) (xy 246.264084 -137.321423) (xy 246.234369 -137.275455) (xy 246.211529 -137.225712)
			(xy 246.196033 -137.173215) (xy 246.188199 -137.119042) (xy 246.187722 -137.091674) (xy 246.188208 -137.064423)
			(xy 246.195964 -137.010475) (xy 246.211319 -136.95818) (xy 246.233961 -136.908603) (xy 246.263427 -136.862753)
			(xy 246.299118 -136.821562) (xy 246.340309 -136.785871) (xy 246.386159 -136.756405) (xy 246.435736 -136.733763)
			(xy 246.488031 -136.718408) (xy 246.541979 -136.710652) (xy 246.596481 -136.710652) (xy 246.650429 -136.718408)
			(xy 246.702724 -136.733763) (xy 246.752301 -136.756405) (xy 246.798151 -136.785871) (xy 246.839342 -136.821562)
			(xy 246.875033 -136.862753) (xy 246.904499 -136.908603) (xy 246.927141 -136.95818) (xy 246.942496 -137.010475)
			(xy 246.950252 -137.064423) (xy 246.950738 -137.091674) (xy 246.950272 -137.119044) (xy 246.942456 -137.173224)
			(xy 246.926968 -137.225728) (xy 246.904126 -137.275475) (xy 246.8744 -137.321441) (xy 246.856758 -137.342372)
			(xy 246.856504 -137.342626) (xy 246.850943 -137.34973) (xy 246.844681 -137.366633) (xy 246.844312 -137.375646)
			(xy 246.844312 -137.442702) (xy 246.844665 -137.451719) (xy 246.850915 -137.468636) (xy 246.856504 -137.475722)
			(xy 246.856758 -137.475722) (xy 246.856758 -137.475976) (xy 246.874393 -137.496912) (xy 246.904107 -137.542883)
			(xy 246.926944 -137.592629) (xy 246.942436 -137.645129) (xy 246.950264 -137.699305) (xy 246.950738 -137.726674)
			(xy 246.950252 -137.753925) (xy 246.942496 -137.807873) (xy 246.927141 -137.860168) (xy 246.904499 -137.909745)
			(xy 246.875033 -137.955595) (xy 246.839342 -137.996786) (xy 246.798151 -138.032477) (xy 246.752301 -138.061943)
			(xy 246.702724 -138.084585) (xy 246.650429 -138.09994) (xy 246.596481 -138.107696) (xy 246.541979 -138.107696)
			(xy 246.488031 -138.09994) (xy 246.435736 -138.084585) (xy 246.386159 -138.061943) (xy 246.340309 -138.032477)
			(xy 246.299118 -137.996786) (xy 246.263427 -137.955595) (xy 246.233961 -137.909745) (xy 246.211319 -137.860168)
			(xy 246.195964 -137.807873) (xy 246.188208 -137.753925) (xy 246.187722 -137.726674) (xy 241.189586 -137.726674)
			(xy 241.152196 -137.7582) (xy 241.105039 -137.787467) (xy 241.054147 -137.809611) (xy 241.000589 -137.824166)
			(xy 240.973102 -137.82802) (xy 240.970562 -137.828528) (xy 240.966783 -137.838985) (xy 240.951964 -137.855528)
			(xy 240.931568 -137.864319) (xy 240.909366 -137.863732) (xy 240.899188 -137.859262) (xy 240.79835 -137.808716)
			(xy 240.79327 -137.80643) (xy 240.773745 -137.798914) (xy 240.736322 -137.780203) (xy 240.718594 -137.769092)
			(xy 240.707995 -137.765543) (xy 240.685719 -137.766996) (xy 240.675668 -137.771886) (xy 240.673128 -137.77341)
			(xy 240.598198 -137.815066) (xy 240.590458 -137.819769) (xy 240.578661 -137.833495) (xy 240.572373 -137.850466)
			(xy 240.572036 -137.859516) (xy 240.572036 -138.40333) (xy 247.396254 -138.40333) (xy 247.396765 -138.375665)
			(xy 247.404761 -138.320914) (xy 247.420576 -138.267891) (xy 247.443879 -138.217707) (xy 247.474181 -138.171411)
			(xy 247.510848 -138.129973) (xy 247.553112 -138.094262) (xy 247.57634 -138.079226) (xy 247.586005 -138.072575)
			(xy 247.598456 -138.052725) (xy 247.600216 -138.041126) (xy 247.60809 -137.961116) (xy 247.608693 -137.949479)
			(xy 247.600631 -137.927644) (xy 247.592596 -137.919206) (xy 247.592342 -137.918952) (xy 247.573763 -137.900868)
			(xy 247.541183 -137.860538) (xy 247.514369 -137.816164) (xy 247.493815 -137.768566) (xy 247.479902 -137.718622)
			(xy 247.472885 -137.667253) (xy 247.472454 -137.64133) (xy 247.473006 -137.614081) (xy 247.480757 -137.560138)
			(xy 247.496107 -137.507847) (xy 247.518742 -137.458272) (xy 247.548201 -137.412424) (xy 247.583886 -137.371234)
			(xy 247.625069 -137.335542) (xy 247.670913 -137.306074) (xy 247.720483 -137.283431) (xy 247.772771 -137.268072)
			(xy 247.826713 -137.260311) (xy 247.853962 -137.259822) (xy 247.881332 -137.260305) (xy 247.93551 -137.268118)
			(xy 247.988013 -137.283603) (xy 248.037761 -137.306441) (xy 248.083728 -137.336162) (xy 248.10466 -137.353802)
			(xy 248.104914 -137.354056) (xy 248.111988 -137.359661) (xy 248.128915 -137.365895) (xy 248.137934 -137.366248)
			(xy 248.20499 -137.366248) (xy 248.214008 -137.365897) (xy 248.230925 -137.359647) (xy 248.23801 -137.354056)
			(xy 248.23801 -137.353802) (xy 248.238264 -137.353802) (xy 248.259199 -137.336167) (xy 248.305171 -137.306454)
			(xy 248.354918 -137.283617) (xy 248.407418 -137.268126) (xy 248.461593 -137.260296) (xy 248.488962 -137.259822)
			(xy 248.516215 -137.260291) (xy 248.570168 -137.268043) (xy 248.622467 -137.283396) (xy 248.672049 -137.306036)
			(xy 248.717904 -137.335503) (xy 248.759098 -137.371197) (xy 248.794792 -137.41239) (xy 248.82426 -137.458244)
			(xy 248.846901 -137.507825) (xy 248.862255 -137.560125) (xy 248.870009 -137.614077) (xy 248.87047 -137.64133)
			(xy 248.869913 -137.670246) (xy 248.861194 -137.727416) (xy 248.843944 -137.782614) (xy 248.81856 -137.834576)
			(xy 248.785623 -137.882111) (xy 248.745887 -137.924129) (xy 248.723404 -137.94232) (xy 248.714598 -137.949929)
			(xy 248.704414 -137.970828) (xy 248.703846 -137.982452) (xy 248.703846 -138.062208) (xy 248.704379 -138.073841)
			(xy 248.71457 -138.094752) (xy 248.723404 -138.10234) (xy 248.745907 -138.120507) (xy 248.785641 -138.162532)
			(xy 248.818578 -138.210072) (xy 248.843963 -138.262038) (xy 248.861215 -138.31724) (xy 248.869938 -138.374413)
			(xy 248.87047 -138.40333) (xy 248.870073 -138.430585) (xy 248.862311 -138.484541) (xy 248.850205 -138.525758)
			(xy 249.141742 -138.525758) (xy 249.142232 -138.498389) (xy 249.150042 -138.44421) (xy 249.165525 -138.391707)
			(xy 249.188362 -138.341959) (xy 249.218082 -138.295992) (xy 249.235722 -138.27506) (xy 249.235976 -138.274806)
			(xy 249.241575 -138.267728) (xy 249.247812 -138.250804) (xy 249.248168 -138.241786) (xy 249.248168 -138.17473)
			(xy 249.247803 -138.165714) (xy 249.241562 -138.148796) (xy 249.235976 -138.14171) (xy 249.235722 -138.14171)
			(xy 249.235722 -138.141456) (xy 249.21804 -138.120556) (xy 249.188318 -138.074583) (xy 249.165475 -138.024831)
			(xy 249.149982 -137.972324) (xy 249.142158 -137.918141) (xy 249.142162 -137.863396) (xy 249.149996 -137.809214)
			(xy 249.165497 -137.75671) (xy 249.188348 -137.706962) (xy 249.218079 -137.660993) (xy 249.235722 -137.64006)
			(xy 249.235976 -137.639806) (xy 249.241575 -137.632728) (xy 249.247812 -137.615804) (xy 249.248168 -137.606786)
			(xy 249.248168 -137.53973) (xy 249.247803 -137.530714) (xy 249.241562 -137.513796) (xy 249.235976 -137.50671)
			(xy 249.235722 -137.50671) (xy 249.235722 -137.506456) (xy 249.21804 -137.485556) (xy 249.188318 -137.439583)
			(xy 249.165475 -137.389831) (xy 249.149982 -137.337324) (xy 249.142158 -137.283141) (xy 249.142162 -137.228396)
			(xy 249.149996 -137.174214) (xy 249.165497 -137.12171) (xy 249.188348 -137.071962) (xy 249.218079 -137.025993)
			(xy 249.235722 -137.00506) (xy 249.235976 -137.004806) (xy 249.241575 -136.997728) (xy 249.247812 -136.980804)
			(xy 249.248168 -136.971786) (xy 249.248168 -136.90473) (xy 249.247803 -136.895714) (xy 249.241562 -136.878796)
			(xy 249.235976 -136.87171) (xy 249.235722 -136.87171) (xy 249.235722 -136.871456) (xy 249.218099 -136.850511)
			(xy 249.188384 -136.804542) (xy 249.165545 -136.754798) (xy 249.15005 -136.7023) (xy 249.142218 -136.648126)
			(xy 249.141742 -136.620758) (xy 249.142228 -136.593507) (xy 249.149984 -136.539559) (xy 249.165339 -136.487264)
			(xy 249.187981 -136.437687) (xy 249.217447 -136.391837) (xy 249.253138 -136.350646) (xy 249.294329 -136.314955)
			(xy 249.340179 -136.285489) (xy 249.389756 -136.262847) (xy 249.442051 -136.247492) (xy 249.495999 -136.239736)
			(xy 249.550501 -136.239736) (xy 249.604449 -136.247492) (xy 249.656744 -136.262847) (xy 249.706321 -136.285489)
			(xy 249.752171 -136.314955) (xy 249.793362 -136.350646) (xy 249.829053 -136.391837) (xy 249.858519 -136.437687)
			(xy 249.881161 -136.487264) (xy 249.896516 -136.539559) (xy 249.904272 -136.593507) (xy 249.904758 -136.620758)
			(xy 249.904278 -136.648128) (xy 249.896465 -136.702307) (xy 249.88098 -136.75481) (xy 249.858141 -136.804557)
			(xy 249.828418 -136.850524) (xy 249.810778 -136.871456) (xy 249.810524 -136.87171) (xy 249.804918 -136.878783)
			(xy 249.798685 -136.895711) (xy 249.798332 -136.90473) (xy 249.798332 -136.971786) (xy 249.798689 -136.980803)
			(xy 249.804936 -136.99772) (xy 249.810524 -137.004806) (xy 249.810778 -137.004806) (xy 249.810778 -137.00506)
			(xy 249.828377 -137.026026) (xy 249.858103 -137.071988) (xy 249.880951 -137.121729) (xy 249.89645 -137.174226)
			(xy 249.904283 -137.2284) (xy 249.904287 -137.283137) (xy 249.896464 -137.337312) (xy 249.880973 -137.389812)
			(xy 249.858134 -137.439556) (xy 249.828415 -137.485523) (xy 249.810778 -137.506456) (xy 249.810524 -137.50671)
			(xy 249.804918 -137.513783) (xy 249.798685 -137.530711) (xy 249.798332 -137.53973) (xy 249.798332 -137.606786)
			(xy 249.798689 -137.615803) (xy 249.804936 -137.63272) (xy 249.810524 -137.639806) (xy 249.810778 -137.639806)
			(xy 249.810778 -137.64006) (xy 249.828377 -137.661026) (xy 249.858103 -137.706988) (xy 249.880951 -137.756729)
			(xy 249.89645 -137.809226) (xy 249.904283 -137.8634) (xy 249.904287 -137.918137) (xy 249.896464 -137.972312)
			(xy 249.880973 -138.024812) (xy 249.858134 -138.074556) (xy 249.828415 -138.120523) (xy 249.810778 -138.141456)
			(xy 249.810524 -138.14171) (xy 249.804918 -138.148783) (xy 249.798685 -138.165711) (xy 249.798332 -138.17473)
			(xy 249.798332 -138.241786) (xy 249.798689 -138.250803) (xy 249.804936 -138.26772) (xy 249.810524 -138.274806)
			(xy 249.810778 -138.274806) (xy 249.810778 -138.27506) (xy 249.828408 -138.295999) (xy 249.858122 -138.34197)
			(xy 249.88096 -138.391715) (xy 249.896453 -138.444215) (xy 249.904283 -138.498389) (xy 249.904758 -138.525758)
			(xy 249.904257 -138.554374) (xy 249.895719 -138.610964) (xy 249.878815 -138.665642) (xy 249.853924 -138.717177)
			(xy 249.821605 -138.764409) (xy 249.782587 -138.806278) (xy 249.760486 -138.824462) (xy 249.760232 -138.824716)
			(xy 249.751694 -138.832326) (xy 249.741807 -138.852918) (xy 249.741182 -138.86434) (xy 249.74169 -138.94435)
			(xy 249.742292 -138.955914) (xy 249.752465 -138.976685) (xy 249.761248 -138.984228) (xy 249.77725 -138.997436)
			(xy 249.777504 -138.99769) (xy 249.784586 -139.003283) (xy 249.801506 -139.009526) (xy 249.810524 -139.009882)
			(xy 249.87758 -139.009882) (xy 249.886596 -139.00952) (xy 249.903514 -139.003276) (xy 249.9106 -138.99769)
			(xy 249.9106 -138.997436) (xy 249.910854 -138.997436) (xy 249.931787 -138.979795) (xy 249.977755 -138.950071)
			(xy 250.027501 -138.927225) (xy 250.080003 -138.911729) (xy 250.134181 -138.9039) (xy 250.188923 -138.9039)
			(xy 250.243101 -138.911729) (xy 250.295603 -138.927225) (xy 250.345349 -138.950071) (xy 250.391317 -138.979795)
			(xy 250.41225 -138.997436) (xy 250.412504 -138.99769) (xy 250.419586 -139.003283) (xy 250.436506 -139.009526)
			(xy 250.445524 -139.009882) (xy 250.51258 -139.009882) (xy 250.521596 -139.00952) (xy 250.538514 -139.003276)
			(xy 250.5456 -138.99769) (xy 250.5456 -138.997436) (xy 250.545854 -138.997436) (xy 250.566787 -138.979795)
			(xy 250.612755 -138.950071) (xy 250.662501 -138.927225) (xy 250.715003 -138.911729) (xy 250.769181 -138.9039)
			(xy 250.823923 -138.9039) (xy 250.878101 -138.911729) (xy 250.930603 -138.927225) (xy 250.980349 -138.950071)
			(xy 251.026317 -138.979795) (xy 251.04725 -138.997436) (xy 251.047504 -138.99769) (xy 251.054586 -139.003283)
			(xy 251.071506 -139.009526) (xy 251.080524 -139.009882) (xy 251.14758 -139.009882) (xy 251.156596 -139.00952)
			(xy 251.173514 -139.003276) (xy 251.1806 -138.99769) (xy 251.1806 -138.997436) (xy 251.180854 -138.997436)
			(xy 251.201797 -138.979811) (xy 251.247766 -138.950095) (xy 251.297511 -138.927256) (xy 251.350009 -138.911762)
			(xy 251.404183 -138.903931) (xy 251.431552 -138.903456) (xy 251.458805 -138.903988) (xy 251.512756 -138.911739)
			(xy 251.565054 -138.927089) (xy 251.614636 -138.949727) (xy 251.660491 -138.979191) (xy 251.701685 -139.014881)
			(xy 251.737381 -139.056071) (xy 251.76685 -139.101922) (xy 251.789494 -139.151501) (xy 251.804851 -139.203797)
			(xy 251.812609 -139.257748) (xy 251.812609 -139.312252) (xy 251.804851 -139.366203) (xy 251.789494 -139.418499)
			(xy 251.76685 -139.468078) (xy 251.737381 -139.513929) (xy 251.701685 -139.555119) (xy 251.660491 -139.590809)
			(xy 251.614636 -139.620273) (xy 251.565054 -139.642911) (xy 251.512756 -139.658261) (xy 251.458805 -139.666012)
			(xy 251.431552 -139.666472) (xy 251.404183 -139.665982) (xy 251.350004 -139.658171) (xy 251.297501 -139.642688)
			(xy 251.247754 -139.619851) (xy 251.201786 -139.590131) (xy 251.180854 -139.572492) (xy 251.1806 -139.572238)
			(xy 251.173523 -139.566638) (xy 251.156599 -139.560401) (xy 251.14758 -139.560046) (xy 251.080524 -139.560046)
			(xy 251.071507 -139.560405) (xy 251.05459 -139.56665) (xy 251.047504 -139.572238) (xy 251.04725 -139.572492)
			(xy 251.026317 -139.590133) (xy 250.980349 -139.619857) (xy 250.930603 -139.642703) (xy 250.878101 -139.658199)
			(xy 250.823923 -139.666028) (xy 250.769181 -139.666028) (xy 250.715003 -139.658199) (xy 250.662501 -139.642703)
			(xy 250.612755 -139.619857) (xy 250.566787 -139.590133) (xy 250.545854 -139.572492) (xy 250.5456 -139.572238)
			(xy 250.538523 -139.566638) (xy 250.521599 -139.560401) (xy 250.51258 -139.560046) (xy 250.445524 -139.560046)
			(xy 250.436507 -139.560405) (xy 250.41959 -139.56665) (xy 250.412504 -139.572238) (xy 250.412504 -139.572492)
			(xy 250.41225 -139.572492) (xy 250.391317 -139.590133) (xy 250.345349 -139.619857) (xy 250.295603 -139.642703)
			(xy 250.243101 -139.658199) (xy 250.188923 -139.666028) (xy 250.134181 -139.666028) (xy 250.080003 -139.658199)
			(xy 250.027501 -139.642703) (xy 249.977755 -139.619857) (xy 249.931787 -139.590133) (xy 249.910854 -139.572492)
			(xy 249.9106 -139.572238) (xy 249.903523 -139.566638) (xy 249.886599 -139.560401) (xy 249.87758 -139.560046)
			(xy 249.810524 -139.560046) (xy 249.801507 -139.560405) (xy 249.78459 -139.56665) (xy 249.777504 -139.572238)
			(xy 249.777504 -139.572492) (xy 249.77725 -139.572492) (xy 249.756309 -139.59012) (xy 249.710339 -139.619834)
			(xy 249.660593 -139.642672) (xy 249.608095 -139.658166) (xy 249.553921 -139.665997) (xy 249.526552 -139.666472)
			(xy 249.499298 -139.666067) (xy 249.445345 -139.658303) (xy 249.393047 -139.64294) (xy 249.343467 -139.62029)
			(xy 249.297615 -139.590816) (xy 249.256425 -139.555116) (xy 249.220734 -139.513917) (xy 249.191269 -139.468059)
			(xy 249.168631 -139.418474) (xy 249.153279 -139.366172) (xy 249.145527 -139.312218) (xy 249.145044 -139.284964)
			(xy 249.14556 -139.256349) (xy 249.154094 -139.199759) (xy 249.170996 -139.145081) (xy 249.195884 -139.093547)
			(xy 249.2282 -139.046313) (xy 249.267216 -139.004444) (xy 249.289316 -138.98626) (xy 249.28957 -138.986006)
			(xy 249.298099 -138.978387) (xy 249.307991 -138.957802) (xy 249.30862 -138.946382) (xy 249.308112 -138.866372)
			(xy 249.307496 -138.85481) (xy 249.297333 -138.834039) (xy 249.288554 -138.826494) (xy 249.266101 -138.808313)
			(xy 249.226429 -138.766317) (xy 249.193545 -138.718817) (xy 249.168202 -138.666901) (xy 249.150979 -138.611756)
			(xy 249.142272 -138.554644) (xy 249.141742 -138.525758) (xy 248.850205 -138.525758) (xy 248.846949 -138.536842)
			(xy 248.8243 -138.586425) (xy 248.794826 -138.63228) (xy 248.759125 -138.673473) (xy 248.717925 -138.709166)
			(xy 248.672065 -138.738633) (xy 248.622478 -138.761273) (xy 248.570174 -138.776625) (xy 248.516217 -138.784378)
			(xy 248.488962 -138.784838) (xy 248.462646 -138.784416) (xy 248.410515 -138.777174) (xy 248.359871 -138.762848)
			(xy 248.311671 -138.741707) (xy 248.266829 -138.714152) (xy 248.226192 -138.680704) (xy 248.208038 -138.661648)
			(xy 248.200498 -138.654268) (xy 248.181232 -138.64573) (xy 248.1707 -138.645138) (xy 248.096024 -138.645138)
			(xy 248.085473 -138.645655) (xy 248.066177 -138.654197) (xy 248.058686 -138.661648) (xy 248.04054 -138.680712)
			(xy 247.999907 -138.714167) (xy 247.955064 -138.741724) (xy 247.906862 -138.76286) (xy 247.856213 -138.777176)
			(xy 247.804079 -138.7844) (xy 247.777762 -138.784838) (xy 247.750511 -138.784358) (xy 247.696565 -138.776597)
			(xy 247.644272 -138.761238) (xy 247.594696 -138.738595) (xy 247.548848 -138.709127) (xy 247.507659 -138.673436)
			(xy 247.471968 -138.632246) (xy 247.442501 -138.586397) (xy 247.419859 -138.536821) (xy 247.404502 -138.484527)
			(xy 247.396742 -138.430581) (xy 247.396254 -138.40333) (xy 240.572036 -138.40333) (xy 240.572036 -138.424158)
			(xy 240.572476 -138.433312) (xy 240.578992 -138.450428) (xy 240.591075 -138.464191) (xy 240.59896 -138.468862)
			(xy 240.644426 -138.492992) (xy 240.678208 -138.511026) (xy 240.684421 -138.514096) (xy 240.697952 -138.517071)
			(xy 240.704878 -138.516868) (xy 240.71834 -138.516106) (xy 240.730024 -138.508486) (xy 240.730532 -138.507978)
			(xy 240.745545 -138.498119) (xy 240.777095 -138.480946) (xy 240.793524 -138.473688) (xy 240.825334 -138.460889)
			(xy 240.892158 -138.445557) (xy 240.926366 -138.443208) (xy 240.954413 -138.442436) (xy 241.010229 -138.448133)
			(xy 241.064611 -138.461935) (xy 241.116389 -138.483545) (xy 241.164447 -138.5125) (xy 241.207751 -138.548174)
			(xy 241.245369 -138.589801) (xy 241.276492 -138.636484) (xy 241.300449 -138.687218) (xy 241.316725 -138.740912)
			(xy 241.324969 -138.796409) (xy 241.3254 -138.824462) (xy 241.324939 -138.851716) (xy 241.317187 -138.905671)
			(xy 241.301834 -138.957973) (xy 241.279193 -139.007557) (xy 241.249726 -139.053415) (xy 241.214032 -139.094611)
			(xy 241.172839 -139.130308) (xy 241.126984 -139.159779) (xy 241.077401 -139.182423) (xy 241.0251 -139.19778)
			(xy 240.971146 -139.205537) (xy 240.943892 -139.20597) (xy 240.943638 -139.20597) (xy 240.91532 -139.205455)
			(xy 240.859306 -139.197081) (xy 240.805148 -139.18051) (xy 240.754038 -139.156108) (xy 240.730278 -139.140692)
			(xy 240.724468 -139.137034) (xy 240.711464 -139.132642) (xy 240.704624 -139.132056) (xy 240.690654 -139.131294)
			(xy 240.644426 -139.155932) (xy 240.59896 -139.180062) (xy 240.591046 -139.184698) (xy 240.578933 -139.198452)
			(xy 240.57247 -139.215602) (xy 240.572036 -139.224766) (xy 240.572036 -139.99591) (xy 240.572437 -140.00514)
			(xy 240.578987 -140.0224) (xy 240.591232 -140.036214) (xy 240.599214 -140.040868) (xy 240.640108 -140.062458)
			(xy 240.680494 -140.08354) (xy 240.68555 -140.085755) (xy 240.696313 -140.088201) (xy 240.70183 -140.088366)
			(xy 240.713768 -140.087604) (xy 240.724944 -140.083794) (xy 240.731548 -140.079222) (xy 240.755645 -140.063122)
			(xy 240.807679 -140.037611) (xy 240.862971 -140.020257) (xy 240.920251 -140.011458) (xy 240.949226 -140.010896)
			(xy 240.949734 -140.010896) (xy 240.976983 -140.011384) (xy 241.030927 -140.019144) (xy 241.083217 -140.034502)
			(xy 241.132789 -140.057145) (xy 241.178635 -140.086612) (xy 241.219821 -140.122303) (xy 241.255508 -140.163492)
			(xy 241.284971 -140.20934) (xy 241.30761 -140.258915) (xy 241.322963 -140.311206) (xy 241.330718 -140.365151)
			(xy 241.330718 -140.419649) (xy 241.322963 -140.473594) (xy 241.30761 -140.525885) (xy 241.284971 -140.57546)
			(xy 241.255508 -140.621308) (xy 241.219821 -140.662497) (xy 241.178635 -140.698188) (xy 241.132789 -140.727655)
			(xy 241.083217 -140.750298) (xy 241.030927 -140.765656) (xy 240.976983 -140.773416) (xy 240.949734 -140.773912)
			(xy 240.920685 -140.773363) (xy 240.863259 -140.764544) (xy 240.807835 -140.74712) (xy 240.755693 -140.721494)
			(xy 240.731548 -140.705332) (xy 240.725709 -140.701527) (xy 240.712574 -140.696882) (xy 240.70564 -140.696188)
			(xy 240.691924 -140.695426) (xy 240.605818 -140.740384) (xy 240.599214 -140.74394) (xy 240.591237 -140.748592)
			(xy 240.579015 -140.762416) (xy 240.57248 -140.779672) (xy 240.572036 -140.788898) (xy 240.572036 -141.046551)
			(xy 242.955054 -141.046551) (xy 242.955054 -140.992049) (xy 242.96281 -140.938101) (xy 242.978164 -140.885806)
			(xy 243.000804 -140.836228) (xy 243.030269 -140.790376) (xy 243.065959 -140.749184) (xy 243.107147 -140.71349)
			(xy 243.152996 -140.684021) (xy 243.202572 -140.661377) (xy 243.254865 -140.646017) (xy 243.308813 -140.638256)
			(xy 243.336064 -140.637768) (xy 243.362379 -140.638203) (xy 243.414508 -140.645446) (xy 243.465151 -140.659772)
			(xy 243.51335 -140.680911) (xy 243.558193 -140.708462) (xy 243.598832 -140.741905) (xy 243.616988 -140.760958)
			(xy 243.624518 -140.76835) (xy 243.643791 -140.776881) (xy 243.654326 -140.777468) (xy 243.729002 -140.777468)
			(xy 243.739555 -140.776963) (xy 243.75885 -140.768412) (xy 243.76634 -140.760958) (xy 243.784475 -140.741882)
			(xy 243.82511 -140.708428) (xy 243.869955 -140.680873) (xy 243.91816 -140.659738) (xy 243.96881 -140.645425)
			(xy 244.020947 -140.638204) (xy 244.047264 -140.637768) (xy 244.074517 -140.638277) (xy 244.128468 -140.646029)
			(xy 244.180767 -140.661381) (xy 244.230349 -140.68402) (xy 244.276203 -140.713485) (xy 244.317398 -140.749177)
			(xy 244.353093 -140.790368) (xy 244.382563 -140.83622) (xy 244.405206 -140.885799) (xy 244.420563 -140.938097)
			(xy 244.428321 -140.992047) (xy 244.428321 -141.046553) (xy 244.420563 -141.100503) (xy 244.405206 -141.152801)
			(xy 244.382563 -141.20238) (xy 244.353093 -141.248232) (xy 244.317398 -141.289423) (xy 244.276203 -141.325115)
			(xy 244.230349 -141.35458) (xy 244.180767 -141.377219) (xy 244.128468 -141.392571) (xy 244.074517 -141.400323)
			(xy 244.047264 -141.400784) (xy 244.020949 -141.400346) (xy 243.968819 -141.393106) (xy 243.918176 -141.378781)
			(xy 243.869977 -141.357643) (xy 243.825134 -141.330092) (xy 243.784496 -141.296648) (xy 243.76634 -141.277594)
			(xy 243.758806 -141.270207) (xy 243.739535 -141.261675) (xy 243.729002 -141.261084) (xy 243.654326 -141.261084)
			(xy 243.643777 -141.261619) (xy 243.624482 -141.270151) (xy 243.616988 -141.277594) (xy 243.59883 -141.296647)
			(xy 243.558201 -141.330105) (xy 243.513361 -141.357664) (xy 243.465161 -141.378803) (xy 243.414514 -141.393121)
			(xy 243.36238 -141.400346) (xy 243.336064 -141.400784) (xy 243.308813 -141.400344) (xy 243.254865 -141.392583)
			(xy 243.202572 -141.377223) (xy 243.152996 -141.354579) (xy 243.107147 -141.32511) (xy 243.065959 -141.289416)
			(xy 243.030269 -141.248224) (xy 243.000804 -141.202372) (xy 242.978164 -141.152794) (xy 242.96281 -141.100499)
			(xy 242.955054 -141.046551) (xy 240.572036 -141.046551) (xy 240.572036 -143.078551) (xy 242.955054 -143.078551)
			(xy 242.955054 -143.024049) (xy 242.96281 -142.970101) (xy 242.978164 -142.917806) (xy 243.000804 -142.868228)
			(xy 243.030269 -142.822376) (xy 243.065959 -142.781184) (xy 243.107147 -142.74549) (xy 243.152996 -142.716021)
			(xy 243.202572 -142.693377) (xy 243.254865 -142.678017) (xy 243.308813 -142.670256) (xy 243.336064 -142.669768)
			(xy 243.362379 -142.670203) (xy 243.414508 -142.677446) (xy 243.465151 -142.691772) (xy 243.51335 -142.712911)
			(xy 243.558193 -142.740462) (xy 243.598832 -142.773905) (xy 243.616988 -142.792958) (xy 243.624518 -142.80035)
			(xy 243.643791 -142.808881) (xy 243.654326 -142.809468) (xy 243.729002 -142.809468) (xy 243.739555 -142.808963)
			(xy 243.75885 -142.800412) (xy 243.76634 -142.792958) (xy 243.784475 -142.773882) (xy 243.82511 -142.740428)
			(xy 243.869955 -142.712873) (xy 243.91816 -142.691738) (xy 243.96881 -142.677425) (xy 244.020947 -142.670204)
			(xy 244.047264 -142.669768) (xy 244.074517 -142.670277) (xy 244.128468 -142.678029) (xy 244.180767 -142.693381)
			(xy 244.230349 -142.71602) (xy 244.276203 -142.745485) (xy 244.317398 -142.781177) (xy 244.353093 -142.822368)
			(xy 244.382563 -142.86822) (xy 244.405206 -142.917799) (xy 244.420563 -142.970097) (xy 244.428321 -143.024047)
			(xy 244.428321 -143.078553) (xy 244.420563 -143.132503) (xy 244.405206 -143.184801) (xy 244.382563 -143.23438)
			(xy 244.353093 -143.280232) (xy 244.317398 -143.321423) (xy 244.276203 -143.357115) (xy 244.230349 -143.38658)
			(xy 244.180767 -143.409219) (xy 244.128468 -143.424571) (xy 244.074517 -143.432323) (xy 244.047264 -143.432784)
			(xy 244.020949 -143.432346) (xy 243.968819 -143.425106) (xy 243.918176 -143.410781) (xy 243.869977 -143.389643)
			(xy 243.825134 -143.362092) (xy 243.784496 -143.328648) (xy 243.76634 -143.309594) (xy 243.758806 -143.302207)
			(xy 243.739535 -143.293675) (xy 243.729002 -143.293084) (xy 243.654326 -143.293084) (xy 243.643777 -143.293619)
			(xy 243.624482 -143.302151) (xy 243.616988 -143.309594) (xy 243.59883 -143.328647) (xy 243.558201 -143.362105)
			(xy 243.513361 -143.389664) (xy 243.465161 -143.410803) (xy 243.414514 -143.425121) (xy 243.36238 -143.432346)
			(xy 243.336064 -143.432784) (xy 243.308813 -143.432344) (xy 243.254865 -143.424583) (xy 243.202572 -143.409223)
			(xy 243.152996 -143.386579) (xy 243.107147 -143.35711) (xy 243.065959 -143.321416) (xy 243.030269 -143.280224)
			(xy 243.000804 -143.234372) (xy 242.978164 -143.184794) (xy 242.96281 -143.132499) (xy 242.955054 -143.078551)
			(xy 240.572036 -143.078551) (xy 240.572036 -143.966438) (xy 251.664216 -143.966438) (xy 251.664626 -143.940462)
			(xy 251.671676 -143.88899) (xy 251.685652 -143.838952) (xy 251.706293 -143.791276) (xy 251.733218 -143.746845)
			(xy 251.765928 -143.706483) (xy 251.803816 -143.670936) (xy 251.824744 -143.655542) (xy 251.834235 -143.64791)
			(xy 251.84538 -143.626298) (xy 251.84608 -143.61414) (xy 251.84608 -143.531336) (xy 251.845388 -143.519174)
			(xy 251.834248 -143.497553) (xy 251.824744 -143.489934) (xy 251.803825 -143.474531) (xy 251.765949 -143.438978)
			(xy 251.733248 -143.398614) (xy 251.70633 -143.354184) (xy 251.685691 -143.306511) (xy 251.671714 -143.256479)
			(xy 251.664658 -143.205012) (xy 251.664216 -143.179038) (xy 251.664724 -143.150299) (xy 251.673354 -143.093472)
			(xy 251.690409 -143.038582) (xy 251.715503 -142.98687) (xy 251.748069 -142.939507) (xy 251.76734 -142.91818)
			(xy 251.773944 -142.911322) (xy 251.781056 -142.893288) (xy 251.781056 -142.804388) (xy 251.773944 -142.786354)
			(xy 251.76734 -142.779496) (xy 251.748106 -142.758137) (xy 251.715538 -142.71078) (xy 251.690444 -142.659074)
			(xy 251.67339 -142.604188) (xy 251.664763 -142.547365) (xy 251.664759 -142.489891) (xy 251.673378 -142.433066)
			(xy 251.690423 -142.378178) (xy 251.71551 -142.326468) (xy 251.748071 -142.279106) (xy 251.76734 -142.25778)
			(xy 251.773944 -142.250922) (xy 251.781056 -142.232888) (xy 251.781056 -142.143988) (xy 251.773944 -142.125954)
			(xy 251.76734 -142.119096) (xy 251.748106 -142.097737) (xy 251.715538 -142.05038) (xy 251.690444 -141.998674)
			(xy 251.67339 -141.943788) (xy 251.664763 -141.886965) (xy 251.664759 -141.829491) (xy 251.673378 -141.772666)
			(xy 251.690423 -141.717778) (xy 251.71551 -141.666068) (xy 251.748071 -141.618706) (xy 251.76734 -141.59738)
			(xy 251.773944 -141.590522) (xy 251.781056 -141.572488) (xy 251.781056 -141.483588) (xy 251.773944 -141.465554)
			(xy 251.76734 -141.458696) (xy 251.748106 -141.437337) (xy 251.715538 -141.38998) (xy 251.690444 -141.338274)
			(xy 251.67339 -141.283388) (xy 251.664763 -141.226565) (xy 251.664759 -141.169091) (xy 251.673378 -141.112266)
			(xy 251.690423 -141.057378) (xy 251.71551 -141.005668) (xy 251.748071 -140.958306) (xy 251.76734 -140.93698)
			(xy 251.773944 -140.930122) (xy 251.781056 -140.912088) (xy 251.781056 -140.823188) (xy 251.773944 -140.805154)
			(xy 251.76734 -140.798296) (xy 251.748088 -140.776953) (xy 251.715519 -140.729595) (xy 251.690423 -140.677888)
			(xy 251.673368 -140.623001) (xy 251.66474 -140.566176) (xy 251.664216 -140.537438) (xy 251.664702 -140.510187)
			(xy 251.672458 -140.456239) (xy 251.687813 -140.403944) (xy 251.710455 -140.354367) (xy 251.739921 -140.308517)
			(xy 251.775612 -140.267326) (xy 251.816803 -140.231635) (xy 251.862653 -140.202169) (xy 251.91223 -140.179527)
			(xy 251.964525 -140.164172) (xy 252.018473 -140.156416) (xy 252.072975 -140.156416) (xy 252.126923 -140.164172)
			(xy 252.179218 -140.179527) (xy 252.228795 -140.202169) (xy 252.274645 -140.231635) (xy 252.315836 -140.267326)
			(xy 252.351527 -140.308517) (xy 252.380993 -140.354367) (xy 252.403635 -140.403944) (xy 252.41899 -140.456239)
			(xy 252.426746 -140.510187) (xy 252.427232 -140.537438) (xy 252.426723 -140.566177) (xy 252.418095 -140.623005)
			(xy 252.401041 -140.677896) (xy 252.375947 -140.729607) (xy 252.34338 -140.776969) (xy 252.324108 -140.798296)
			(xy 252.317504 -140.805154) (xy 252.310392 -140.823188) (xy 252.310392 -140.912088) (xy 252.317504 -140.930122)
			(xy 252.324108 -140.93698) (xy 252.343415 -140.958275) (xy 252.375976 -141.005644) (xy 252.401064 -141.057361)
			(xy 252.418109 -141.112256) (xy 252.426728 -141.169087) (xy 252.426724 -141.226568) (xy 252.418097 -141.283398)
			(xy 252.401043 -141.338291) (xy 252.375948 -141.390004) (xy 252.34338 -141.437368) (xy 252.324108 -141.458696)
			(xy 252.317504 -141.465554) (xy 252.310392 -141.483588) (xy 252.310392 -141.572488) (xy 252.317504 -141.590522)
			(xy 252.324108 -141.59738) (xy 252.343415 -141.618675) (xy 252.375976 -141.666044) (xy 252.401064 -141.717761)
			(xy 252.418109 -141.772656) (xy 252.426728 -141.829487) (xy 252.426724 -141.886968) (xy 252.418097 -141.943798)
			(xy 252.401043 -141.998691) (xy 252.375948 -142.050404) (xy 252.34338 -142.097768) (xy 252.324108 -142.119096)
			(xy 252.317504 -142.125954) (xy 252.310392 -142.143988) (xy 252.310392 -142.232888) (xy 252.317504 -142.250922)
			(xy 252.324108 -142.25778) (xy 252.343415 -142.279075) (xy 252.375976 -142.326444) (xy 252.401064 -142.378161)
			(xy 252.418109 -142.433056) (xy 252.426728 -142.489887) (xy 252.426724 -142.547368) (xy 252.418097 -142.604198)
			(xy 252.401043 -142.659091) (xy 252.375948 -142.710804) (xy 252.34338 -142.758168) (xy 252.324108 -142.779496)
			(xy 252.317504 -142.786354) (xy 252.310392 -142.804388) (xy 252.310392 -142.893288) (xy 252.317504 -142.911322)
			(xy 252.324108 -142.91818) (xy 252.343387 -142.9395) (xy 252.375954 -142.986863) (xy 252.401046 -143.038576)
			(xy 252.418094 -143.093469) (xy 252.426713 -143.150298) (xy 252.427232 -143.179038) (xy 252.426826 -143.205015)
			(xy 252.419777 -143.256488) (xy 252.405803 -143.306526) (xy 252.385161 -143.354203) (xy 252.358235 -143.398634)
			(xy 252.325524 -143.438996) (xy 252.287633 -143.474541) (xy 252.266704 -143.489934) (xy 252.257233 -143.497587)
			(xy 252.246075 -143.519183) (xy 252.245368 -143.531336) (xy 252.245368 -143.61414) (xy 252.246056 -143.626303)
			(xy 252.257197 -143.647925) (xy 252.266704 -143.655542) (xy 252.287622 -143.670946) (xy 252.325497 -143.7065)
			(xy 252.358195 -143.746865) (xy 252.385113 -143.791295) (xy 252.405752 -143.838966) (xy 252.41973 -143.888998)
			(xy 252.426789 -143.940464) (xy 252.427232 -143.966438) (xy 252.426746 -143.993689) (xy 252.41899 -144.047637)
			(xy 252.403635 -144.099932) (xy 252.380993 -144.149509) (xy 252.351527 -144.195359) (xy 252.315836 -144.23655)
			(xy 252.274645 -144.272241) (xy 252.228795 -144.301707) (xy 252.179218 -144.324349) (xy 252.126923 -144.339704)
			(xy 252.072975 -144.34746) (xy 252.018473 -144.34746) (xy 251.964525 -144.339704) (xy 251.91223 -144.324349)
			(xy 251.862653 -144.301707) (xy 251.816803 -144.272241) (xy 251.775612 -144.23655) (xy 251.739921 -144.195359)
			(xy 251.710455 -144.149509) (xy 251.687813 -144.099932) (xy 251.672458 -144.047637) (xy 251.664702 -143.993689)
			(xy 251.664216 -143.966438) (xy 240.572036 -143.966438) (xy 240.572036 -145.110551) (xy 242.955054 -145.110551)
			(xy 242.955054 -145.056049) (xy 242.96281 -145.002101) (xy 242.978164 -144.949806) (xy 243.000804 -144.900228)
			(xy 243.030269 -144.854376) (xy 243.065959 -144.813184) (xy 243.107147 -144.77749) (xy 243.152996 -144.748021)
			(xy 243.202572 -144.725377) (xy 243.254865 -144.710017) (xy 243.308813 -144.702256) (xy 243.336064 -144.701768)
			(xy 243.362379 -144.702203) (xy 243.414508 -144.709446) (xy 243.465151 -144.723772) (xy 243.51335 -144.744911)
			(xy 243.558193 -144.772462) (xy 243.598832 -144.805905) (xy 243.616988 -144.824958) (xy 243.624518 -144.83235)
			(xy 243.643791 -144.840881) (xy 243.654326 -144.841468) (xy 243.729002 -144.841468) (xy 243.739555 -144.840963)
			(xy 243.75885 -144.832412) (xy 243.76634 -144.824958) (xy 243.784475 -144.805882) (xy 243.82511 -144.772428)
			(xy 243.869955 -144.744873) (xy 243.91816 -144.723738) (xy 243.96881 -144.709425) (xy 244.020947 -144.702204)
			(xy 244.047264 -144.701768) (xy 244.074517 -144.702277) (xy 244.128468 -144.710029) (xy 244.180767 -144.725381)
			(xy 244.230349 -144.74802) (xy 244.276203 -144.777485) (xy 244.317398 -144.813177) (xy 244.353093 -144.854368)
			(xy 244.382563 -144.90022) (xy 244.405206 -144.949799) (xy 244.406511 -144.954244) (xy 250.138946 -144.954244)
			(xy 250.139519 -144.926996) (xy 250.147268 -144.873054) (xy 250.162616 -144.820764) (xy 250.185248 -144.77119)
			(xy 250.214706 -144.725341) (xy 250.250388 -144.684152) (xy 250.291569 -144.64846) (xy 250.337411 -144.618991)
			(xy 250.386979 -144.596347) (xy 250.439266 -144.580988) (xy 250.493206 -144.573225) (xy 250.520454 -144.572736)
			(xy 250.549228 -144.573258) (xy 250.606123 -144.581908) (xy 250.661074 -144.599005) (xy 250.712834 -144.624159)
			(xy 250.76023 -144.656801) (xy 250.781566 -144.676114) (xy 250.78944 -144.68348) (xy 250.809252 -144.690592)
			(xy 250.905518 -144.683226) (xy 250.924314 -144.67332) (xy 250.930918 -144.664938) (xy 250.949154 -144.642763)
			(xy 250.991086 -144.603551) (xy 251.03842 -144.571064) (xy 251.090085 -144.546034) (xy 251.144918 -144.529026)
			(xy 251.201679 -144.520423) (xy 251.230384 -144.519904) (xy 251.257637 -144.52037) (xy 251.311588 -144.528125)
			(xy 251.363887 -144.54348) (xy 251.413468 -144.566121) (xy 251.459322 -144.595589) (xy 251.500515 -144.631282)
			(xy 251.536209 -144.672475) (xy 251.565677 -144.718329) (xy 251.588319 -144.767909) (xy 251.603674 -144.820208)
			(xy 251.611429 -144.874159) (xy 251.611892 -144.901412) (xy 251.611444 -144.928315) (xy 251.603871 -144.981586)
			(xy 251.588889 -145.033265) (xy 251.566797 -145.082327) (xy 251.538032 -145.127799) (xy 251.503165 -145.16878)
			(xy 251.462887 -145.204457) (xy 251.440696 -145.219674) (xy 251.429774 -145.226786) (xy 251.417836 -145.249646)
			(xy 251.419868 -145.361914) (xy 251.432822 -145.384266) (xy 251.443998 -145.391124) (xy 251.467599 -145.406047)
			(xy 251.510551 -145.441725) (xy 251.547844 -145.483283) (xy 251.578682 -145.529833) (xy 251.602406 -145.58038)
			(xy 251.618508 -145.633846) (xy 251.626646 -145.689087) (xy 251.627132 -145.717006) (xy 251.626677 -145.744)
			(xy 251.61907 -145.797448) (xy 251.604009 -145.849292) (xy 251.581793 -145.898496) (xy 251.552867 -145.94408)
			(xy 251.535692 -145.96491) (xy 251.52858 -145.973038) (xy 251.522484 -145.993612) (xy 251.533406 -146.078956)
			(xy 251.535196 -146.089497) (xy 251.546239 -146.107781) (xy 251.554742 -146.114262) (xy 251.575947 -146.129649)
			(xy 251.614401 -146.16523) (xy 251.647622 -146.205741) (xy 251.674984 -146.250418) (xy 251.695972 -146.298421)
			(xy 251.71019 -146.348845) (xy 251.717371 -146.400741) (xy 251.71781 -146.426936) (xy 251.717324 -146.454187)
			(xy 251.709568 -146.508135) (xy 251.694213 -146.56043) (xy 251.671571 -146.610007) (xy 251.642105 -146.655857)
			(xy 251.606414 -146.697048) (xy 251.565223 -146.732739) (xy 251.519373 -146.762205) (xy 251.469796 -146.784847)
			(xy 251.417501 -146.800202) (xy 251.363553 -146.807958) (xy 251.309051 -146.807958) (xy 251.255103 -146.800202)
			(xy 251.202808 -146.784847) (xy 251.153231 -146.762205) (xy 251.107381 -146.732739) (xy 251.06619 -146.697048)
			(xy 251.030499 -146.655857) (xy 251.001033 -146.610007) (xy 250.978391 -146.56043) (xy 250.963036 -146.508135)
			(xy 250.95528 -146.454187) (xy 250.954794 -146.426936) (xy 250.955291 -146.399944) (xy 250.96289 -146.346498)
			(xy 250.977943 -146.294656) (xy 251.000149 -146.245451) (xy 251.029064 -146.199864) (xy 251.046234 -146.179032)
			(xy 251.053346 -146.170904) (xy 251.059442 -146.15033) (xy 251.04852 -146.064986) (xy 251.046749 -146.054441)
			(xy 251.035691 -146.036159) (xy 251.027184 -146.02968) (xy 251.002883 -146.012068) (xy 250.959624 -145.970472)
			(xy 250.941078 -145.946876) (xy 250.935236 -145.939002) (xy 250.91771 -145.928588) (xy 250.827286 -145.91538)
			(xy 250.807982 -145.920206) (xy 250.800108 -145.926048) (xy 250.799854 -145.926048) (xy 250.775111 -145.943553)
			(xy 250.721258 -145.971356) (xy 250.663686 -145.990292) (xy 250.603843 -145.999883) (xy 250.57354 -146.00047)
			(xy 250.546286 -146.000007) (xy 250.492333 -145.992255) (xy 250.440033 -145.976902) (xy 250.390451 -145.954261)
			(xy 250.344596 -145.924794) (xy 250.303401 -145.8891) (xy 250.267707 -145.847906) (xy 250.23824 -145.802051)
			(xy 250.215599 -145.752469) (xy 250.200246 -145.700168) (xy 250.192493 -145.646216) (xy 250.192032 -145.618962)
			(xy 250.192467 -145.592928) (xy 250.199559 -145.541345) (xy 250.213591 -145.491203) (xy 250.234305 -145.443433)
			(xy 250.261315 -145.398918) (xy 250.277376 -145.378424) (xy 250.283116 -145.370666) (xy 250.288858 -145.352256)
			(xy 250.288552 -145.34261) (xy 250.282202 -145.262854) (xy 250.273566 -145.245074) (xy 250.2662 -145.238724)
			(xy 250.246561 -145.220536) (xy 250.212035 -145.179632) (xy 250.183562 -145.134305) (xy 250.161703 -145.085445)
			(xy 250.146885 -145.034009) (xy 250.1394 -144.981008) (xy 250.138946 -144.954244) (xy 244.406511 -144.954244)
			(xy 244.420563 -145.002097) (xy 244.428321 -145.056047) (xy 244.428321 -145.110553) (xy 244.420563 -145.164503)
			(xy 244.405206 -145.216801) (xy 244.382563 -145.26638) (xy 244.353093 -145.312232) (xy 244.317398 -145.353423)
			(xy 244.276203 -145.389115) (xy 244.230349 -145.41858) (xy 244.180767 -145.441219) (xy 244.128468 -145.456571)
			(xy 244.074517 -145.464323) (xy 244.047264 -145.464784) (xy 244.020949 -145.464346) (xy 243.968819 -145.457106)
			(xy 243.918176 -145.442781) (xy 243.869977 -145.421643) (xy 243.825134 -145.394092) (xy 243.784496 -145.360648)
			(xy 243.76634 -145.341594) (xy 243.758806 -145.334207) (xy 243.739535 -145.325675) (xy 243.729002 -145.325084)
			(xy 243.654326 -145.325084) (xy 243.643777 -145.325619) (xy 243.624482 -145.334151) (xy 243.616988 -145.341594)
			(xy 243.59883 -145.360647) (xy 243.558201 -145.394105) (xy 243.513361 -145.421664) (xy 243.465161 -145.442803)
			(xy 243.414514 -145.457121) (xy 243.36238 -145.464346) (xy 243.336064 -145.464784) (xy 243.308813 -145.464344)
			(xy 243.254865 -145.456583) (xy 243.202572 -145.441223) (xy 243.152996 -145.418579) (xy 243.107147 -145.38911)
			(xy 243.065959 -145.353416) (xy 243.030269 -145.312224) (xy 243.000804 -145.266372) (xy 242.978164 -145.216794)
			(xy 242.96281 -145.164499) (xy 242.955054 -145.110551) (xy 240.572036 -145.110551) (xy 240.572036 -146.91487)
			(xy 251.816106 -146.91487) (xy 251.820177 -146.859248) (xy 251.832303 -146.804811) (xy 251.852226 -146.75272)
			(xy 251.879522 -146.704085) (xy 251.913608 -146.659942) (xy 251.953757 -146.621233) (xy 251.999115 -146.588782)
			(xy 252.048715 -146.563281) (xy 252.101499 -146.545274) (xy 252.156342 -146.535144) (xy 252.212076 -146.533107)
			(xy 252.267513 -146.539207) (xy 252.32147 -146.553313) (xy 252.372799 -146.575125) (xy 252.420405 -146.604179)
			(xy 252.463273 -146.639854) (xy 252.50049 -146.681391) (xy 252.531263 -146.727904) (xy 252.554935 -146.778401)
			(xy 252.571003 -146.831808) (xy 252.579123 -146.886984) (xy 252.579632 -146.91487) (xy 252.579123 -146.942756)
			(xy 252.571003 -146.997932) (xy 252.554935 -147.051339) (xy 252.531263 -147.101836) (xy 252.50049 -147.148349)
			(xy 252.463273 -147.189886) (xy 252.420405 -147.225561) (xy 252.372799 -147.254615) (xy 252.32147 -147.276427)
			(xy 252.267513 -147.290533) (xy 252.212076 -147.296633) (xy 252.156342 -147.294596) (xy 252.101499 -147.284466)
			(xy 252.048715 -147.266459) (xy 251.999115 -147.240958) (xy 251.953757 -147.208507) (xy 251.913608 -147.169798)
			(xy 251.879522 -147.125655) (xy 251.852226 -147.07702) (xy 251.832303 -147.024929) (xy 251.820177 -146.970492)
			(xy 251.816106 -146.91487) (xy 240.572036 -146.91487) (xy 240.572036 -147.237704) (xy 240.572282 -147.244886)
			(xy 240.576278 -147.258682) (xy 240.57991 -147.264882) (xy 240.58372 -147.270978) (xy 240.594388 -147.280122)
			(xy 240.601246 -147.283424) (xy 240.601754 -147.283678) (xy 240.602516 -147.283932) (xy 240.626996 -147.295732)
			(xy 240.672634 -147.325235) (xy 240.713622 -147.360917) (xy 240.749131 -147.402056) (xy 240.778441 -147.447817)
			(xy 240.80096 -147.497276) (xy 240.816231 -147.54943) (xy 240.823944 -147.603223) (xy 240.823945 -147.657567)
			(xy 240.823932 -147.657656) (xy 243.350443 -147.657656) (xy 243.350443 -147.603144) (xy 243.358201 -147.549188)
			(xy 243.37356 -147.496885) (xy 243.396206 -147.447301) (xy 243.425679 -147.401444) (xy 243.461379 -147.360249)
			(xy 243.502578 -147.324554) (xy 243.548437 -147.295086) (xy 243.598024 -147.272445) (xy 243.650329 -147.257092)
			(xy 243.704286 -147.24934) (xy 243.731542 -147.24888) (xy 243.757857 -147.249326) (xy 243.809986 -147.256566)
			(xy 243.860629 -147.27089) (xy 243.908827 -147.292026) (xy 243.95367 -147.319576) (xy 243.99431 -147.353017)
			(xy 244.012466 -147.37207) (xy 244.020002 -147.379454) (xy 244.039271 -147.38799) (xy 244.049804 -147.38858)
			(xy 244.12448 -147.38858) (xy 244.135031 -147.38806) (xy 244.154327 -147.379519) (xy 244.161818 -147.37207)
			(xy 244.181638 -147.351282) (xy 244.22641 -147.315307) (xy 244.276068 -147.286447) (xy 244.32949 -147.265354)
			(xy 244.385469 -147.252505) (xy 244.442742 -147.24819) (xy 244.500015 -147.252505) (xy 244.555994 -147.265354)
			(xy 244.609416 -147.286447) (xy 244.659074 -147.315307) (xy 244.703846 -147.351282) (xy 244.723666 -147.37207)
			(xy 244.731202 -147.379454) (xy 244.750471 -147.38799) (xy 244.761004 -147.38858) (xy 244.83568 -147.38858)
			(xy 244.846231 -147.38806) (xy 244.865527 -147.379519) (xy 244.873018 -147.37207) (xy 244.891166 -147.353007)
			(xy 244.931798 -147.319552) (xy 244.97664 -147.291994) (xy 245.024842 -147.270857) (xy 245.075491 -147.256542)
			(xy 245.127626 -147.249318) (xy 245.153942 -147.24888) (xy 245.18119 -147.249393) (xy 245.235132 -147.257154)
			(xy 245.28742 -147.272512) (xy 245.33699 -147.295155) (xy 245.382834 -147.324622) (xy 245.424018 -147.360312)
			(xy 245.459703 -147.4015) (xy 245.489165 -147.447347) (xy 245.511802 -147.49692) (xy 245.527155 -147.549209)
			(xy 245.53491 -147.603152) (xy 245.53491 -147.657648) (xy 245.527155 -147.711591) (xy 245.511802 -147.76388)
			(xy 245.489165 -147.813453) (xy 245.459703 -147.8593) (xy 245.424018 -147.900488) (xy 245.382834 -147.936178)
			(xy 245.33699 -147.965645) (xy 245.28742 -147.988288) (xy 245.235132 -148.003646) (xy 245.18119 -148.011407)
			(xy 245.153942 -148.011896) (xy 245.127627 -148.011469) (xy 245.075496 -148.004226) (xy 245.024853 -147.989899)
			(xy 244.976654 -147.968759) (xy 244.931811 -147.941206) (xy 244.891174 -147.907761) (xy 244.873018 -147.888706)
			(xy 244.865491 -147.881311) (xy 244.846215 -147.872783) (xy 244.83568 -147.872196) (xy 244.761004 -147.872196)
			(xy 244.750453 -147.872715) (xy 244.731158 -147.881257) (xy 244.723666 -147.888706) (xy 244.703846 -147.909494)
			(xy 244.659074 -147.945469) (xy 244.609416 -147.974329) (xy 244.555994 -147.995422) (xy 244.500015 -148.008271)
			(xy 244.442742 -148.012586) (xy 244.385469 -148.008271) (xy 244.32949 -147.995422) (xy 244.276068 -147.974329)
			(xy 244.22641 -147.945469) (xy 244.181638 -147.909494) (xy 244.161818 -147.888706) (xy 244.154291 -147.881311)
			(xy 244.135015 -147.872783) (xy 244.12448 -147.872196) (xy 244.049804 -147.872196) (xy 244.039253 -147.872715)
			(xy 244.019958 -147.881257) (xy 244.012466 -147.888706) (xy 243.994321 -147.907772) (xy 243.953689 -147.941228)
			(xy 243.908846 -147.968786) (xy 243.860644 -147.989922) (xy 243.809994 -148.004237) (xy 243.757859 -148.011459)
			(xy 243.731542 -148.011896) (xy 243.704286 -148.01146) (xy 243.650329 -148.003708) (xy 243.598024 -147.988355)
			(xy 243.548437 -147.965714) (xy 243.502578 -147.936246) (xy 243.461379 -147.900551) (xy 243.425679 -147.859356)
			(xy 243.396206 -147.813499) (xy 243.37356 -147.763915) (xy 243.358201 -147.711612) (xy 243.350443 -147.657656)
			(xy 240.823932 -147.657656) (xy 240.816233 -147.71136) (xy 240.800963 -147.763515) (xy 240.778446 -147.812974)
			(xy 240.749137 -147.858736) (xy 240.713629 -147.899875) (xy 240.672642 -147.935558) (xy 240.627005 -147.965063)
			(xy 240.602516 -147.976844) (xy 240.601754 -147.977098) (xy 240.60023 -147.97786) (xy 240.593607 -147.98146)
			(xy 240.582635 -147.991787) (xy 240.57864 -147.99818) (xy 240.575546 -148.003997) (xy 240.572208 -148.016739)
			(xy 240.572182 -148.017738) (xy 248.177556 -148.017738) (xy 248.181627 -147.962116) (xy 248.193753 -147.907679)
			(xy 248.213676 -147.855588) (xy 248.240972 -147.806953) (xy 248.275058 -147.76281) (xy 248.315207 -147.724101)
			(xy 248.360565 -147.69165) (xy 248.410165 -147.666149) (xy 248.462949 -147.648142) (xy 248.517792 -147.638012)
			(xy 248.573526 -147.635975) (xy 248.628963 -147.642075) (xy 248.68292 -147.656181) (xy 248.734249 -147.677993)
			(xy 248.781855 -147.707047) (xy 248.824723 -147.742722) (xy 248.86194 -147.784259) (xy 248.892713 -147.830772)
			(xy 248.916385 -147.881269) (xy 248.932453 -147.934676) (xy 248.940573 -147.989852) (xy 248.941082 -148.017738)
			(xy 248.940573 -148.045624) (xy 248.932453 -148.1008) (xy 248.916385 -148.154207) (xy 248.892713 -148.204704)
			(xy 248.86194 -148.251217) (xy 248.824723 -148.292754) (xy 248.781855 -148.328429) (xy 248.734249 -148.357483)
			(xy 248.68292 -148.379295) (xy 248.628963 -148.393401) (xy 248.573526 -148.399501) (xy 248.517792 -148.397464)
			(xy 248.462949 -148.387334) (xy 248.410165 -148.369327) (xy 248.360565 -148.343826) (xy 248.315207 -148.311375)
			(xy 248.275058 -148.272666) (xy 248.240972 -148.228523) (xy 248.213676 -148.179888) (xy 248.193753 -148.127797)
			(xy 248.181627 -148.07336) (xy 248.177556 -148.017738) (xy 240.572182 -148.017738) (xy 240.572036 -148.023326)
			(xy 240.572036 -149.775926) (xy 240.572285 -149.783107) (xy 240.576286 -149.796899) (xy 240.57991 -149.803104)
			(xy 240.58372 -149.8092) (xy 240.594388 -149.818344) (xy 240.601246 -149.821646) (xy 240.601754 -149.8219)
			(xy 240.602516 -149.822154) (xy 240.626995 -149.833954) (xy 240.672629 -149.863457) (xy 240.713614 -149.899138)
			(xy 240.74912 -149.940275) (xy 240.778428 -149.986035) (xy 240.800944 -150.035492) (xy 240.816213 -150.087643)
			(xy 240.823925 -150.141434) (xy 240.823924 -150.195775) (xy 240.823913 -150.195854) (xy 243.350465 -150.195854)
			(xy 243.350465 -150.141346) (xy 243.358223 -150.087393) (xy 243.373581 -150.035093) (xy 243.396226 -149.985511)
			(xy 243.425697 -149.939657) (xy 243.461394 -149.898465) (xy 243.502591 -149.862772) (xy 243.548448 -149.833306)
			(xy 243.598032 -149.810666) (xy 243.650334 -149.795314) (xy 243.704288 -149.787562) (xy 243.731542 -149.787102)
			(xy 243.757857 -149.787541) (xy 243.809987 -149.794781) (xy 243.86063 -149.809106) (xy 243.908829 -149.830244)
			(xy 243.953672 -149.857795) (xy 243.99431 -149.891238) (xy 244.012466 -149.910292) (xy 244.019999 -149.917679)
			(xy 244.03927 -149.926212) (xy 244.049804 -149.926802) (xy 244.12448 -149.926802) (xy 244.13503 -149.926275)
			(xy 244.154325 -149.917738) (xy 244.161818 -149.910292) (xy 244.181638 -149.889504) (xy 244.22641 -149.853529)
			(xy 244.276068 -149.824669) (xy 244.32949 -149.803576) (xy 244.385469 -149.790727) (xy 244.442742 -149.786412)
			(xy 244.500015 -149.790727) (xy 244.555994 -149.803576) (xy 244.609416 -149.824669) (xy 244.659074 -149.853529)
			(xy 244.703846 -149.889504) (xy 244.723666 -149.910292) (xy 244.731199 -149.917679) (xy 244.75047 -149.926212)
			(xy 244.761004 -149.926802) (xy 244.83568 -149.926802) (xy 244.84623 -149.926275) (xy 244.865525 -149.917738)
			(xy 244.873018 -149.910292) (xy 244.89117 -149.891233) (xy 244.931801 -149.857777) (xy 244.976642 -149.830218)
			(xy 245.024843 -149.80908) (xy 245.075491 -149.794764) (xy 245.127626 -149.78754) (xy 245.153942 -149.787102)
			(xy 245.181192 -149.787571) (xy 245.235137 -149.795332) (xy 245.287428 -149.810691) (xy 245.337001 -149.833336)
			(xy 245.382847 -149.862804) (xy 245.424034 -149.898496) (xy 245.459721 -149.939686) (xy 245.489185 -149.985536)
			(xy 245.511823 -150.035112) (xy 245.520145 -150.063454) (xy 248.03811 -150.063454) (xy 248.042181 -150.007832)
			(xy 248.054307 -149.953395) (xy 248.07423 -149.901304) (xy 248.101526 -149.852669) (xy 248.135612 -149.808526)
			(xy 248.175761 -149.769817) (xy 248.221119 -149.737366) (xy 248.270719 -149.711865) (xy 248.323503 -149.693858)
			(xy 248.378346 -149.683728) (xy 248.43408 -149.681691) (xy 248.489517 -149.687791) (xy 248.543474 -149.701897)
			(xy 248.594803 -149.723709) (xy 248.642409 -149.752763) (xy 248.685277 -149.788438) (xy 248.722494 -149.829975)
			(xy 248.753267 -149.876488) (xy 248.776939 -149.926985) (xy 248.793007 -149.980392) (xy 248.801127 -150.035568)
			(xy 248.801636 -150.063454) (xy 248.801127 -150.09134) (xy 248.793007 -150.146516) (xy 248.776939 -150.199923)
			(xy 248.753267 -150.25042) (xy 248.722494 -150.296933) (xy 248.685277 -150.33847) (xy 248.642409 -150.374145)
			(xy 248.594803 -150.403199) (xy 248.543474 -150.425011) (xy 248.489517 -150.439117) (xy 248.43408 -150.445217)
			(xy 248.378346 -150.44318) (xy 248.323503 -150.43305) (xy 248.270719 -150.415043) (xy 248.221119 -150.389542)
			(xy 248.175761 -150.357091) (xy 248.135612 -150.318382) (xy 248.101526 -150.274239) (xy 248.07423 -150.225604)
			(xy 248.054307 -150.173513) (xy 248.042181 -150.119076) (xy 248.03811 -150.063454) (xy 245.520145 -150.063454)
			(xy 245.527177 -150.087404) (xy 245.534932 -150.14135) (xy 245.534932 -150.19585) (xy 245.527177 -150.249796)
			(xy 245.511823 -150.302088) (xy 245.489185 -150.351664) (xy 245.459721 -150.397514) (xy 245.424034 -150.438704)
			(xy 245.382847 -150.474396) (xy 245.337001 -150.503864) (xy 245.287428 -150.526509) (xy 245.235137 -150.541868)
			(xy 245.181192 -150.549629) (xy 245.153942 -150.550118) (xy 245.127627 -150.549683) (xy 245.075497 -150.542441)
			(xy 245.024854 -150.528115) (xy 244.976655 -150.506976) (xy 244.931813 -150.479425) (xy 244.891174 -150.445982)
			(xy 244.873018 -150.426928) (xy 244.865488 -150.419536) (xy 244.846215 -150.411005) (xy 244.83568 -150.410418)
			(xy 244.761004 -150.410418) (xy 244.750452 -150.410931) (xy 244.731157 -150.419477) (xy 244.723666 -150.426928)
			(xy 244.703846 -150.447716) (xy 244.659074 -150.483691) (xy 244.609416 -150.512551) (xy 244.555994 -150.533644)
			(xy 244.500015 -150.546493) (xy 244.442742 -150.550808) (xy 244.385469 -150.546493) (xy 244.32949 -150.533644)
			(xy 244.276068 -150.512551) (xy 244.22641 -150.483691) (xy 244.181638 -150.447716) (xy 244.161818 -150.426928)
			(xy 244.154288 -150.419536) (xy 244.135015 -150.411005) (xy 244.12448 -150.410418) (xy 244.049804 -150.410418)
			(xy 244.039252 -150.410931) (xy 244.019957 -150.419477) (xy 244.012466 -150.426928) (xy 243.994325 -150.445998)
			(xy 243.953692 -150.479453) (xy 243.908848 -150.507009) (xy 243.860645 -150.528145) (xy 243.809995 -150.542459)
			(xy 243.757859 -150.549681) (xy 243.731542 -150.550118) (xy 243.704288 -150.549638) (xy 243.650334 -150.541886)
			(xy 243.598032 -150.526534) (xy 243.548448 -150.503894) (xy 243.502591 -150.474428) (xy 243.461394 -150.438735)
			(xy 243.425697 -150.397543) (xy 243.396226 -150.351689) (xy 243.373581 -150.302107) (xy 243.358223 -150.249807)
			(xy 243.350465 -150.195854) (xy 240.823913 -150.195854) (xy 240.816211 -150.249565) (xy 240.800941 -150.301716)
			(xy 240.778424 -150.351172) (xy 240.749115 -150.396932) (xy 240.713609 -150.438068) (xy 240.672623 -150.473748)
			(xy 240.626988 -150.50325) (xy 240.602516 -150.515066) (xy 240.601754 -150.51532) (xy 240.60023 -150.516082)
			(xy 240.593603 -150.519678) (xy 240.582618 -150.529997) (xy 240.57864 -150.536402) (xy 240.575536 -150.542217)
			(xy 240.572179 -150.554959) (xy 240.572036 -150.561548) (xy 240.572036 -151.67102) (xy 247.99366 -151.67102)
			(xy 247.997731 -151.615398) (xy 248.009857 -151.560961) (xy 248.02978 -151.50887) (xy 248.057076 -151.460235)
			(xy 248.091162 -151.416092) (xy 248.131311 -151.377383) (xy 248.176669 -151.344932) (xy 248.226269 -151.319431)
			(xy 248.279053 -151.301424) (xy 248.333896 -151.291294) (xy 248.38963 -151.289257) (xy 248.445067 -151.295357)
			(xy 248.499024 -151.309463) (xy 248.550353 -151.331275) (xy 248.597959 -151.360329) (xy 248.640827 -151.396004)
			(xy 248.678044 -151.437541) (xy 248.708817 -151.484054) (xy 248.732489 -151.534551) (xy 248.748557 -151.587958)
			(xy 248.756677 -151.643134) (xy 248.757186 -151.67102) (xy 248.756713 -151.696928) (xy 249.00966 -151.696928)
			(xy 249.013731 -151.641306) (xy 249.025857 -151.586869) (xy 249.04578 -151.534778) (xy 249.073076 -151.486143)
			(xy 249.107162 -151.442) (xy 249.147311 -151.403291) (xy 249.192669 -151.37084) (xy 249.242269 -151.345339)
			(xy 249.295053 -151.327332) (xy 249.349896 -151.317202) (xy 249.40563 -151.315165) (xy 249.461067 -151.321265)
			(xy 249.515024 -151.335371) (xy 249.566353 -151.357183) (xy 249.613959 -151.386237) (xy 249.638435 -151.406606)
			(xy 250.236734 -151.406606) (xy 250.240805 -151.350984) (xy 250.252931 -151.296547) (xy 250.272854 -151.244456)
			(xy 250.30015 -151.195821) (xy 250.334236 -151.151678) (xy 250.374385 -151.112969) (xy 250.419743 -151.080518)
			(xy 250.469343 -151.055017) (xy 250.522127 -151.03701) (xy 250.57697 -151.02688) (xy 250.632704 -151.024843)
			(xy 250.688141 -151.030943) (xy 250.742098 -151.045049) (xy 250.793427 -151.066861) (xy 250.841033 -151.095915)
			(xy 250.883901 -151.13159) (xy 250.921118 -151.173127) (xy 250.951891 -151.21964) (xy 250.975563 -151.270137)
			(xy 250.991631 -151.323544) (xy 250.999751 -151.37872) (xy 251.00026 -151.406606) (xy 250.999751 -151.434492)
			(xy 250.991631 -151.489668) (xy 250.975563 -151.543075) (xy 250.957021 -151.582628) (xy 251.56236 -151.582628)
			(xy 251.566431 -151.527006) (xy 251.578557 -151.472569) (xy 251.59848 -151.420478) (xy 251.625776 -151.371843)
			(xy 251.659862 -151.3277) (xy 251.700011 -151.288991) (xy 251.745369 -151.25654) (xy 251.794969 -151.231039)
			(xy 251.847753 -151.213032) (xy 251.902596 -151.202902) (xy 251.95833 -151.200865) (xy 252.013767 -151.206965)
			(xy 252.067724 -151.221071) (xy 252.119053 -151.242883) (xy 252.166659 -151.271937) (xy 252.209527 -151.307612)
			(xy 252.246744 -151.349149) (xy 252.277517 -151.395662) (xy 252.301189 -151.446159) (xy 252.317257 -151.499566)
			(xy 252.325377 -151.554742) (xy 252.325886 -151.582628) (xy 252.325377 -151.610514) (xy 252.317257 -151.66569)
			(xy 252.301189 -151.719097) (xy 252.277517 -151.769594) (xy 252.246744 -151.816107) (xy 252.209527 -151.857644)
			(xy 252.166659 -151.893319) (xy 252.119053 -151.922373) (xy 252.067724 -151.944185) (xy 252.013767 -151.958291)
			(xy 251.95833 -151.964391) (xy 251.902596 -151.962354) (xy 251.847753 -151.952224) (xy 251.794969 -151.934217)
			(xy 251.745369 -151.908716) (xy 251.700011 -151.876265) (xy 251.659862 -151.837556) (xy 251.625776 -151.793413)
			(xy 251.59848 -151.744778) (xy 251.578557 -151.692687) (xy 251.566431 -151.63825) (xy 251.56236 -151.582628)
			(xy 250.957021 -151.582628) (xy 250.951891 -151.593572) (xy 250.921118 -151.640085) (xy 250.883901 -151.681622)
			(xy 250.841033 -151.717297) (xy 250.793427 -151.746351) (xy 250.742098 -151.768163) (xy 250.688141 -151.782269)
			(xy 250.632704 -151.788369) (xy 250.57697 -151.786332) (xy 250.522127 -151.776202) (xy 250.469343 -151.758195)
			(xy 250.419743 -151.732694) (xy 250.374385 -151.700243) (xy 250.334236 -151.661534) (xy 250.30015 -151.617391)
			(xy 250.272854 -151.568756) (xy 250.252931 -151.516665) (xy 250.240805 -151.462228) (xy 250.236734 -151.406606)
			(xy 249.638435 -151.406606) (xy 249.656827 -151.421912) (xy 249.694044 -151.463449) (xy 249.724817 -151.509962)
			(xy 249.748489 -151.560459) (xy 249.764557 -151.613866) (xy 249.772677 -151.669042) (xy 249.773186 -151.696928)
			(xy 249.772677 -151.724814) (xy 249.764557 -151.77999) (xy 249.748489 -151.833397) (xy 249.724817 -151.883894)
			(xy 249.694044 -151.930407) (xy 249.656827 -151.971944) (xy 249.613959 -152.007619) (xy 249.566353 -152.036673)
			(xy 249.515024 -152.058485) (xy 249.461067 -152.072591) (xy 249.40563 -152.078691) (xy 249.349896 -152.076654)
			(xy 249.295053 -152.066524) (xy 249.242269 -152.048517) (xy 249.192669 -152.023016) (xy 249.147311 -151.990565)
			(xy 249.107162 -151.951856) (xy 249.073076 -151.907713) (xy 249.04578 -151.859078) (xy 249.025857 -151.806987)
			(xy 249.013731 -151.75255) (xy 249.00966 -151.696928) (xy 248.756713 -151.696928) (xy 248.756677 -151.698906)
			(xy 248.748557 -151.754082) (xy 248.732489 -151.807489) (xy 248.708817 -151.857986) (xy 248.678044 -151.904499)
			(xy 248.640827 -151.946036) (xy 248.597959 -151.981711) (xy 248.550353 -152.010765) (xy 248.499024 -152.032577)
			(xy 248.445067 -152.046683) (xy 248.38963 -152.052783) (xy 248.333896 -152.050746) (xy 248.279053 -152.040616)
			(xy 248.226269 -152.022609) (xy 248.176669 -151.997108) (xy 248.131311 -151.964657) (xy 248.091162 -151.925948)
			(xy 248.057076 -151.881805) (xy 248.02978 -151.83317) (xy 248.009857 -151.781079) (xy 247.997731 -151.726642)
			(xy 247.99366 -151.67102) (xy 240.572036 -151.67102) (xy 240.572036 -153.782522) (xy 246.97766 -153.782522)
			(xy 246.981731 -153.7269) (xy 246.993857 -153.672463) (xy 247.01378 -153.620372) (xy 247.041076 -153.571737)
			(xy 247.075162 -153.527594) (xy 247.115311 -153.488885) (xy 247.160669 -153.456434) (xy 247.210269 -153.430933)
			(xy 247.263053 -153.412926) (xy 247.317896 -153.402796) (xy 247.37363 -153.400759) (xy 247.429067 -153.406859)
			(xy 247.483024 -153.420965) (xy 247.534353 -153.442777) (xy 247.581959 -153.471831) (xy 247.624827 -153.507506)
			(xy 247.662044 -153.549043) (xy 247.692817 -153.595556) (xy 247.716489 -153.646053) (xy 247.732557 -153.69946)
			(xy 247.740677 -153.754636) (xy 247.741186 -153.782522) (xy 247.99366 -153.782522) (xy 247.997731 -153.7269)
			(xy 248.009857 -153.672463) (xy 248.02978 -153.620372) (xy 248.057076 -153.571737) (xy 248.091162 -153.527594)
			(xy 248.131311 -153.488885) (xy 248.176669 -153.456434) (xy 248.226269 -153.430933) (xy 248.279053 -153.412926)
			(xy 248.333896 -153.402796) (xy 248.38963 -153.400759) (xy 248.445067 -153.406859) (xy 248.499024 -153.420965)
			(xy 248.550353 -153.442777) (xy 248.597959 -153.471831) (xy 248.640827 -153.507506) (xy 248.678044 -153.549043)
			(xy 248.708817 -153.595556) (xy 248.732489 -153.646053) (xy 248.748557 -153.69946) (xy 248.756677 -153.754636)
			(xy 248.757186 -153.782522) (xy 248.756677 -153.810408) (xy 248.753529 -153.831798) (xy 249.00966 -153.831798)
			(xy 249.013731 -153.776176) (xy 249.025857 -153.721739) (xy 249.04578 -153.669648) (xy 249.073076 -153.621013)
			(xy 249.107162 -153.57687) (xy 249.147311 -153.538161) (xy 249.192669 -153.50571) (xy 249.242269 -153.480209)
			(xy 249.295053 -153.462202) (xy 249.349896 -153.452072) (xy 249.40563 -153.450035) (xy 249.461067 -153.456135)
			(xy 249.515024 -153.470241) (xy 249.566353 -153.492053) (xy 249.613959 -153.521107) (xy 249.656827 -153.556782)
			(xy 249.694044 -153.598319) (xy 249.724817 -153.644832) (xy 249.748489 -153.695329) (xy 249.764557 -153.748736)
			(xy 249.769529 -153.782522) (xy 252.05766 -153.782522) (xy 252.061731 -153.7269) (xy 252.073857 -153.672463)
			(xy 252.09378 -153.620372) (xy 252.121076 -153.571737) (xy 252.155162 -153.527594) (xy 252.195311 -153.488885)
			(xy 252.240669 -153.456434) (xy 252.290269 -153.430933) (xy 252.343053 -153.412926) (xy 252.397896 -153.402796)
			(xy 252.45363 -153.400759) (xy 252.509067 -153.406859) (xy 252.563024 -153.420965) (xy 252.614353 -153.442777)
			(xy 252.661959 -153.471831) (xy 252.704827 -153.507506) (xy 252.742044 -153.549043) (xy 252.772817 -153.595556)
			(xy 252.796489 -153.646053) (xy 252.812557 -153.69946) (xy 252.820677 -153.754636) (xy 252.821186 -153.782522)
			(xy 252.820677 -153.810408) (xy 252.812557 -153.865584) (xy 252.796489 -153.918991) (xy 252.772817 -153.969488)
			(xy 252.742044 -154.016001) (xy 252.704827 -154.057538) (xy 252.661959 -154.093213) (xy 252.614353 -154.122267)
			(xy 252.563024 -154.144079) (xy 252.509067 -154.158185) (xy 252.45363 -154.164285) (xy 252.397896 -154.162248)
			(xy 252.343053 -154.152118) (xy 252.290269 -154.134111) (xy 252.240669 -154.10861) (xy 252.195311 -154.076159)
			(xy 252.155162 -154.03745) (xy 252.121076 -153.993307) (xy 252.09378 -153.944672) (xy 252.073857 -153.892581)
			(xy 252.061731 -153.838144) (xy 252.05766 -153.782522) (xy 249.769529 -153.782522) (xy 249.772677 -153.803912)
			(xy 249.773186 -153.831798) (xy 249.772677 -153.859684) (xy 249.764557 -153.91486) (xy 249.748489 -153.968267)
			(xy 249.724817 -154.018764) (xy 249.694044 -154.065277) (xy 249.656827 -154.106814) (xy 249.613959 -154.142489)
			(xy 249.566353 -154.171543) (xy 249.515024 -154.193355) (xy 249.461067 -154.207461) (xy 249.40563 -154.213561)
			(xy 249.349896 -154.211524) (xy 249.295053 -154.201394) (xy 249.242269 -154.183387) (xy 249.192669 -154.157886)
			(xy 249.147311 -154.125435) (xy 249.107162 -154.086726) (xy 249.073076 -154.042583) (xy 249.04578 -153.993948)
			(xy 249.025857 -153.941857) (xy 249.013731 -153.88742) (xy 249.00966 -153.831798) (xy 248.753529 -153.831798)
			(xy 248.748557 -153.865584) (xy 248.732489 -153.918991) (xy 248.708817 -153.969488) (xy 248.678044 -154.016001)
			(xy 248.640827 -154.057538) (xy 248.597959 -154.093213) (xy 248.550353 -154.122267) (xy 248.499024 -154.144079)
			(xy 248.445067 -154.158185) (xy 248.38963 -154.164285) (xy 248.333896 -154.162248) (xy 248.279053 -154.152118)
			(xy 248.226269 -154.134111) (xy 248.176669 -154.10861) (xy 248.131311 -154.076159) (xy 248.091162 -154.03745)
			(xy 248.057076 -153.993307) (xy 248.02978 -153.944672) (xy 248.009857 -153.892581) (xy 247.997731 -153.838144)
			(xy 247.99366 -153.782522) (xy 247.741186 -153.782522) (xy 247.740677 -153.810408) (xy 247.732557 -153.865584)
			(xy 247.716489 -153.918991) (xy 247.692817 -153.969488) (xy 247.662044 -154.016001) (xy 247.624827 -154.057538)
			(xy 247.581959 -154.093213) (xy 247.534353 -154.122267) (xy 247.483024 -154.144079) (xy 247.429067 -154.158185)
			(xy 247.37363 -154.164285) (xy 247.317896 -154.162248) (xy 247.263053 -154.152118) (xy 247.210269 -154.134111)
			(xy 247.160669 -154.10861) (xy 247.115311 -154.076159) (xy 247.075162 -154.03745) (xy 247.041076 -153.993307)
			(xy 247.01378 -153.944672) (xy 246.993857 -153.892581) (xy 246.981731 -153.838144) (xy 246.97766 -153.782522)
			(xy 240.572036 -153.782522) (xy 240.572036 -155.079192) (xy 242.069872 -155.079192) (xy 242.073943 -155.02357)
			(xy 242.086069 -154.969133) (xy 242.105992 -154.917042) (xy 242.133288 -154.868407) (xy 242.167374 -154.824264)
			(xy 242.207523 -154.785555) (xy 242.252881 -154.753104) (xy 242.302481 -154.727603) (xy 242.355265 -154.709596)
			(xy 242.410108 -154.699466) (xy 242.465842 -154.697429) (xy 242.521279 -154.703529) (xy 242.575236 -154.717635)
			(xy 242.626565 -154.739447) (xy 242.674171 -154.768501) (xy 242.717039 -154.804176) (xy 242.754256 -154.845713)
			(xy 242.785029 -154.892226) (xy 242.808701 -154.942723) (xy 242.824769 -154.99613) (xy 242.832889 -155.051306)
			(xy 242.833398 -155.079192) (xy 242.833333 -155.082748) (xy 243.393722 -155.082748) (xy 243.394148 -155.056433)
			(xy 243.40139 -155.004302) (xy 243.415717 -154.953658) (xy 243.436857 -154.905459) (xy 243.464411 -154.860617)
			(xy 243.497857 -154.819979) (xy 243.516912 -154.801824) (xy 243.524307 -154.794297) (xy 243.532835 -154.775021)
			(xy 243.533422 -154.764486) (xy 243.533422 -154.68981) (xy 243.532895 -154.67926) (xy 243.524358 -154.659965)
			(xy 243.516912 -154.652472) (xy 243.497852 -154.634321) (xy 243.464395 -154.59369) (xy 243.436836 -154.548849)
			(xy 243.415698 -154.500648) (xy 243.401382 -154.449999) (xy 243.394159 -154.397864) (xy 243.393722 -154.371548)
			(xy 243.3942 -154.344295) (xy 243.401951 -154.290343) (xy 243.417303 -154.238044) (xy 243.439942 -154.188462)
			(xy 243.469408 -154.142607) (xy 243.5051 -154.101413) (xy 243.546292 -154.065718) (xy 243.592146 -154.03625)
			(xy 243.641727 -154.013609) (xy 243.694025 -153.998255) (xy 243.747977 -153.990501) (xy 243.77523 -153.99004)
			(xy 243.801545 -153.990475) (xy 243.853676 -153.997714) (xy 243.90432 -154.012039) (xy 243.952519 -154.033178)
			(xy 243.997361 -154.06073) (xy 244.037999 -154.094175) (xy 244.056154 -154.11323) (xy 244.063663 -154.120647)
			(xy 244.082952 -154.129165) (xy 244.093492 -154.12974) (xy 244.168168 -154.12974) (xy 244.178716 -154.129195)
			(xy 244.19801 -154.12067) (xy 244.205506 -154.11323) (xy 244.225326 -154.092442) (xy 244.270098 -154.056467)
			(xy 244.319756 -154.027607) (xy 244.373178 -154.006514) (xy 244.429157 -153.993665) (xy 244.48643 -153.98935)
			(xy 244.543703 -153.993665) (xy 244.599682 -154.006514) (xy 244.653104 -154.027607) (xy 244.702762 -154.056467)
			(xy 244.747534 -154.092442) (xy 244.767354 -154.11323) (xy 244.774863 -154.120647) (xy 244.794152 -154.129165)
			(xy 244.804692 -154.12974) (xy 244.879368 -154.12974) (xy 244.889916 -154.129195) (xy 244.90921 -154.12067)
			(xy 244.916706 -154.11323) (xy 244.936526 -154.092442) (xy 244.981298 -154.056467) (xy 245.030956 -154.027607)
			(xy 245.084378 -154.006514) (xy 245.140357 -153.993665) (xy 245.19763 -153.98935) (xy 245.254903 -153.993665)
			(xy 245.310882 -154.006514) (xy 245.364304 -154.027607) (xy 245.413962 -154.056467) (xy 245.458734 -154.092442)
			(xy 245.478554 -154.11323) (xy 245.486063 -154.120647) (xy 245.505352 -154.129165) (xy 245.515892 -154.12974)
			(xy 245.590568 -154.12974) (xy 245.601116 -154.129195) (xy 245.62041 -154.12067) (xy 245.627906 -154.11323)
			(xy 245.646072 -154.094184) (xy 245.686698 -154.060725) (xy 245.731536 -154.033164) (xy 245.779735 -154.012024)
			(xy 245.830381 -153.997705) (xy 245.882514 -153.990479) (xy 245.90883 -153.99004) (xy 245.936086 -153.990427)
			(xy 245.990042 -153.998189) (xy 246.042344 -154.013552) (xy 246.091928 -154.036201) (xy 246.137783 -154.065677)
			(xy 246.178977 -154.101379) (xy 246.21467 -154.142579) (xy 246.244136 -154.188441) (xy 246.266776 -154.238029)
			(xy 246.282127 -154.290334) (xy 246.289878 -154.344292) (xy 246.290338 -154.371548) (xy 246.289922 -154.397864)
			(xy 246.28268 -154.449996) (xy 246.268352 -154.50064) (xy 246.24721 -154.548839) (xy 246.219654 -154.593681)
			(xy 246.186205 -154.634318) (xy 246.167148 -154.652472) (xy 246.159764 -154.660009) (xy 246.151228 -154.679277)
			(xy 246.150638 -154.68981) (xy 246.150638 -154.764486) (xy 246.15115 -154.775038) (xy 246.159696 -154.794334)
			(xy 246.167148 -154.801824) (xy 246.186217 -154.819965) (xy 246.219671 -154.860599) (xy 246.247227 -154.905443)
			(xy 246.268363 -154.953646) (xy 246.282678 -155.004296) (xy 246.2899 -155.056431) (xy 246.290338 -155.082748)
			(xy 246.289867 -155.109999) (xy 246.282105 -155.163946) (xy 246.266745 -155.216239) (xy 246.2441 -155.265814)
			(xy 246.214632 -155.311663) (xy 246.178939 -155.352852) (xy 246.137749 -155.388543) (xy 246.091899 -155.418009)
			(xy 246.042322 -155.440651) (xy 245.990028 -155.456008) (xy 245.936081 -155.463768) (xy 245.90883 -155.464256)
			(xy 245.882514 -155.463849) (xy 245.830382 -155.456604) (xy 245.779738 -155.442274) (xy 245.731539 -155.42113)
			(xy 245.686697 -155.393573) (xy 245.64606 -155.360123) (xy 245.627906 -155.341066) (xy 245.620375 -155.333675)
			(xy 245.601103 -155.325142) (xy 245.590568 -155.324556) (xy 245.515892 -155.324556) (xy 245.505342 -155.32508)
			(xy 245.486048 -155.33362) (xy 245.478554 -155.341066) (xy 245.458734 -155.361854) (xy 245.413962 -155.397829)
			(xy 245.364304 -155.426689) (xy 245.310882 -155.447782) (xy 245.254903 -155.460631) (xy 245.19763 -155.464946)
			(xy 245.140357 -155.460631) (xy 245.084378 -155.447782) (xy 245.030956 -155.426689) (xy 244.981298 -155.397829)
			(xy 244.936526 -155.361854) (xy 244.916706 -155.341066) (xy 244.909175 -155.333675) (xy 244.889903 -155.325142)
			(xy 244.879368 -155.324556) (xy 244.804692 -155.324556) (xy 244.794142 -155.32508) (xy 244.774848 -155.33362)
			(xy 244.767354 -155.341066) (xy 244.747534 -155.361854) (xy 244.702762 -155.397829) (xy 244.653104 -155.426689)
			(xy 244.599682 -155.447782) (xy 244.543703 -155.460631) (xy 244.48643 -155.464946) (xy 244.429157 -155.460631)
			(xy 244.373178 -155.447782) (xy 244.319756 -155.426689) (xy 244.270098 -155.397829) (xy 244.225326 -155.361854)
			(xy 244.205506 -155.341066) (xy 244.197975 -155.333675) (xy 244.178703 -155.325142) (xy 244.168168 -155.324556)
			(xy 244.093492 -155.324556) (xy 244.082942 -155.32508) (xy 244.063648 -155.33362) (xy 244.056154 -155.341066)
			(xy 244.038027 -155.360149) (xy 243.997389 -155.393602) (xy 243.952543 -155.421155) (xy 243.904337 -155.442288)
			(xy 243.853685 -155.4566) (xy 243.801548 -155.46382) (xy 243.77523 -155.464256) (xy 243.747982 -155.463694)
			(xy 243.694039 -155.455943) (xy 243.641749 -155.440594) (xy 243.592175 -155.41796) (xy 243.546327 -155.388501)
			(xy 243.505138 -155.352818) (xy 243.469446 -155.311636) (xy 243.439978 -155.265793) (xy 243.417333 -155.216224)
			(xy 243.401974 -155.163937) (xy 243.394212 -155.109996) (xy 243.393722 -155.082748) (xy 242.833333 -155.082748)
			(xy 242.832889 -155.107078) (xy 242.824769 -155.162254) (xy 242.808701 -155.215661) (xy 242.785029 -155.266158)
			(xy 242.754256 -155.312671) (xy 242.717039 -155.354208) (xy 242.674171 -155.389883) (xy 242.626565 -155.418937)
			(xy 242.575236 -155.440749) (xy 242.521279 -155.454855) (xy 242.465842 -155.460955) (xy 242.410108 -155.458918)
			(xy 242.355265 -155.448788) (xy 242.302481 -155.430781) (xy 242.252881 -155.40528) (xy 242.207523 -155.372829)
			(xy 242.167374 -155.33412) (xy 242.133288 -155.289977) (xy 242.105992 -155.241342) (xy 242.086069 -155.189251)
			(xy 242.073943 -155.134814) (xy 242.069872 -155.079192) (xy 240.572036 -155.079192) (xy 240.572036 -156.69387)
			(xy 241.0874 -156.69387) (xy 241.091471 -156.638248) (xy 241.103597 -156.583811) (xy 241.12352 -156.53172)
			(xy 241.150816 -156.483085) (xy 241.184902 -156.438942) (xy 241.225051 -156.400233) (xy 241.270409 -156.367782)
			(xy 241.320009 -156.342281) (xy 241.372793 -156.324274) (xy 241.427636 -156.314144) (xy 241.48337 -156.312107)
			(xy 241.538807 -156.318207) (xy 241.592764 -156.332313) (xy 241.644093 -156.354125) (xy 241.691699 -156.383179)
			(xy 241.734567 -156.418854) (xy 241.771784 -156.460391) (xy 241.802557 -156.506904) (xy 241.826229 -156.557401)
			(xy 241.842297 -156.610808) (xy 241.850417 -156.665984) (xy 241.850926 -156.69387) (xy 241.850417 -156.721756)
			(xy 241.842297 -156.776932) (xy 241.826229 -156.830339) (xy 241.802557 -156.880836) (xy 241.771784 -156.927349)
			(xy 241.734567 -156.968886) (xy 241.691699 -157.004561) (xy 241.644093 -157.033615) (xy 241.592764 -157.055427)
			(xy 241.538807 -157.069533) (xy 241.48337 -157.075633) (xy 241.427636 -157.073596) (xy 241.372793 -157.063466)
			(xy 241.320009 -157.045459) (xy 241.270409 -157.019958) (xy 241.225051 -156.987507) (xy 241.184902 -156.948798)
			(xy 241.150816 -156.904655) (xy 241.12352 -156.85602) (xy 241.103597 -156.803929) (xy 241.091471 -156.749492)
			(xy 241.0874 -156.69387) (xy 240.572036 -156.69387) (xy 240.572036 -157.647894) (xy 243.21389 -157.647894)
			(xy 243.214426 -157.621251) (xy 243.222949 -157.568653) (xy 243.239806 -157.518105) (xy 243.264559 -157.470919)
			(xy 243.296567 -157.428318) (xy 243.334998 -157.391409) (xy 243.356638 -157.37586) (xy 243.367927 -157.367502)
			(xy 243.385779 -157.345826) (xy 243.397058 -157.320111) (xy 243.400914 -157.292297) (xy 243.397056 -157.264483)
			(xy 243.385775 -157.238768) (xy 243.367922 -157.217094) (xy 243.356638 -157.208728) (xy 243.335036 -157.193131)
			(xy 243.296621 -157.156218) (xy 243.264621 -157.113623) (xy 243.239863 -157.066449) (xy 243.222988 -157.015916)
			(xy 243.214432 -156.963332) (xy 243.21389 -156.936694) (xy 243.2144 -156.910707) (xy 243.22253 -156.859372)
			(xy 243.238591 -156.809942) (xy 243.262187 -156.763632) (xy 243.292737 -156.721584) (xy 243.329488 -156.684833)
			(xy 243.371536 -156.654283) (xy 243.417846 -156.630687) (xy 243.467276 -156.614626) (xy 243.518611 -156.606496)
			(xy 243.570585 -156.606496) (xy 243.62192 -156.614626) (xy 243.67135 -156.630687) (xy 243.71766 -156.654283)
			(xy 243.759708 -156.684833) (xy 243.796459 -156.721584) (xy 243.827009 -156.763632) (xy 243.850605 -156.809942)
			(xy 243.866666 -156.859372) (xy 243.874796 -156.910707) (xy 243.875306 -156.936694) (xy 243.874763 -156.963336)
			(xy 243.866242 -157.015935) (xy 243.849386 -157.066483) (xy 243.824634 -157.113669) (xy 243.792628 -157.156269)
			(xy 243.754198 -157.193179) (xy 243.732558 -157.208728) (xy 243.721281 -157.217101) (xy 243.70343 -157.238774)
			(xy 243.692151 -157.264486) (xy 243.688293 -157.292297) (xy 243.692149 -157.320108) (xy 243.703427 -157.34582)
			(xy 243.721276 -157.367494) (xy 243.732558 -157.37586) (xy 243.754153 -157.391465) (xy 243.792569 -157.428377)
			(xy 243.82457 -157.47097) (xy 243.849329 -157.518142) (xy 243.866205 -157.568673) (xy 243.874763 -157.621257)
			(xy 243.875306 -157.647894) (xy 244.113812 -157.647894) (xy 244.114338 -157.621251) (xy 244.122862 -157.568651)
			(xy 244.13972 -157.518103) (xy 244.164475 -157.470916) (xy 244.196485 -157.428316) (xy 244.234919 -157.391408)
			(xy 244.25656 -157.37586) (xy 244.267847 -157.3675) (xy 244.285695 -157.345824) (xy 244.296971 -157.320109)
			(xy 244.300827 -157.292297) (xy 244.29697 -157.264484) (xy 244.285691 -157.23877) (xy 244.267842 -157.217095)
			(xy 244.25656 -157.208728) (xy 244.234963 -157.193125) (xy 244.196547 -157.156213) (xy 244.164545 -157.11362)
			(xy 244.139786 -157.066447) (xy 244.122911 -157.015915) (xy 244.114354 -156.963332) (xy 244.113812 -156.936694)
			(xy 244.114322 -156.910707) (xy 244.122452 -156.859372) (xy 244.138513 -156.809942) (xy 244.162109 -156.763632)
			(xy 244.192659 -156.721584) (xy 244.22941 -156.684833) (xy 244.271458 -156.654283) (xy 244.317768 -156.630687)
			(xy 244.367198 -156.614626) (xy 244.418533 -156.606496) (xy 244.470507 -156.606496) (xy 244.521842 -156.614626)
			(xy 244.571272 -156.630687) (xy 244.617582 -156.654283) (xy 244.65963 -156.684833) (xy 244.696381 -156.721584)
			(xy 244.726931 -156.763632) (xy 244.750527 -156.809942) (xy 244.766588 -156.859372) (xy 244.774718 -156.910707)
			(xy 244.775228 -156.936694) (xy 244.774719 -156.963338) (xy 244.766195 -157.01594) (xy 244.749335 -157.06649)
			(xy 244.724577 -157.113677) (xy 244.692563 -157.156276) (xy 244.654124 -157.193182) (xy 244.63248 -157.208728)
			(xy 244.621201 -157.2171) (xy 244.603346 -157.238771) (xy 244.592064 -157.264484) (xy 244.588206 -157.292297)
			(xy 244.592063 -157.320109) (xy 244.603343 -157.345823) (xy 244.621196 -157.367495) (xy 244.63248 -157.37586)
			(xy 244.65408 -157.391459) (xy 244.692494 -157.428373) (xy 244.724494 -157.470967) (xy 244.749252 -157.518141)
			(xy 244.766128 -157.568673) (xy 244.774685 -157.621256) (xy 244.775228 -157.647894) (xy 245.013734 -157.647894)
			(xy 245.014251 -157.62125) (xy 245.022775 -157.56865) (xy 245.039635 -157.518101) (xy 245.064392 -157.470914)
			(xy 245.096403 -157.428315) (xy 245.134839 -157.391407) (xy 245.156482 -157.37586) (xy 245.167776 -157.367505)
			(xy 245.185637 -157.345832) (xy 245.196923 -157.320115) (xy 245.200782 -157.292297) (xy 245.196921 -157.264479)
			(xy 245.185634 -157.238763) (xy 245.167771 -157.217091) (xy 245.156482 -157.208728) (xy 245.13489 -157.193118)
			(xy 245.096472 -157.156209) (xy 245.06447 -157.113617) (xy 245.03971 -157.066446) (xy 245.022833 -157.015915)
			(xy 245.014276 -156.963331) (xy 245.013734 -156.936694) (xy 245.014244 -156.910707) (xy 245.022374 -156.859372)
			(xy 245.038435 -156.809942) (xy 245.062031 -156.763632) (xy 245.092581 -156.721584) (xy 245.129332 -156.684833)
			(xy 245.17138 -156.654283) (xy 245.21769 -156.630687) (xy 245.26712 -156.614626) (xy 245.318455 -156.606496)
			(xy 245.370429 -156.606496) (xy 245.421764 -156.614626) (xy 245.471194 -156.630687) (xy 245.517504 -156.654283)
			(xy 245.559552 -156.684833) (xy 245.596303 -156.721584) (xy 245.626853 -156.763632) (xy 245.650449 -156.809942)
			(xy 245.66651 -156.859372) (xy 245.67464 -156.910707) (xy 245.67515 -156.936694) (xy 245.674631 -156.963338)
			(xy 245.666108 -157.015938) (xy 245.649249 -157.066488) (xy 245.624493 -157.113675) (xy 245.592481 -157.156274)
			(xy 245.554045 -157.193181) (xy 245.532402 -157.208728) (xy 245.521121 -157.217099) (xy 245.503263 -157.238769)
			(xy 245.491978 -157.264483) (xy 245.488119 -157.292297) (xy 245.491976 -157.320111) (xy 245.503259 -157.345825)
			(xy 245.521116 -157.367496) (xy 245.532402 -157.37586) (xy 245.553985 -157.391482) (xy 245.592404 -157.428388)
			(xy 245.624408 -157.470977) (xy 245.64917 -157.518146) (xy 245.666048 -157.568676) (xy 245.674607 -157.621257)
			(xy 245.67515 -157.647894) (xy 245.91391 -157.647894) (xy 245.914437 -157.621251) (xy 245.922961 -157.568652)
			(xy 245.939819 -157.518103) (xy 245.964574 -157.470917) (xy 245.996583 -157.428317) (xy 246.035017 -157.391408)
			(xy 246.056658 -157.37586) (xy 246.067946 -157.3675) (xy 246.085793 -157.345824) (xy 246.09707 -157.320109)
			(xy 246.100926 -157.292297) (xy 246.097068 -157.264484) (xy 246.08579 -157.23877) (xy 246.067941 -157.217095)
			(xy 246.056658 -157.208728) (xy 246.035061 -157.193125) (xy 245.996645 -157.156214) (xy 245.964643 -157.11362)
			(xy 245.939884 -157.066447) (xy 245.923009 -157.015915) (xy 245.914452 -156.963332) (xy 245.91391 -156.936694)
			(xy 245.91442 -156.910707) (xy 245.92255 -156.859372) (xy 245.938611 -156.809942) (xy 245.962207 -156.763632)
			(xy 245.992757 -156.721584) (xy 246.029508 -156.684833) (xy 246.071556 -156.654283) (xy 246.117866 -156.630687)
			(xy 246.167296 -156.614626) (xy 246.218631 -156.606496) (xy 246.270605 -156.606496) (xy 246.32194 -156.614626)
			(xy 246.37137 -156.630687) (xy 246.41768 -156.654283) (xy 246.459728 -156.684833) (xy 246.496479 -156.721584)
			(xy 246.527029 -156.763632) (xy 246.550625 -156.809942) (xy 246.566686 -156.859372) (xy 246.574816 -156.910707)
			(xy 246.575326 -156.936694) (xy 246.574817 -156.963338) (xy 246.566294 -157.01594) (xy 246.549434 -157.06649)
			(xy 246.524675 -157.113677) (xy 246.492661 -157.156276) (xy 246.454222 -157.193182) (xy 246.432578 -157.208728)
			(xy 246.421299 -157.2171) (xy 246.403445 -157.238772) (xy 246.392163 -157.264484) (xy 246.388305 -157.292297)
			(xy 246.392161 -157.320109) (xy 246.403441 -157.345823) (xy 246.421294 -157.367495) (xy 246.432578 -157.37586)
			(xy 246.454178 -157.391459) (xy 246.492592 -157.428373) (xy 246.524592 -157.470967) (xy 246.54935 -157.518141)
			(xy 246.566226 -157.568673) (xy 246.574783 -157.621256) (xy 246.575285 -157.645862) (xy 247.52935 -157.645862)
			(xy 247.529776 -157.619546) (xy 247.537017 -157.567416) (xy 247.551343 -157.516771) (xy 247.572483 -157.468572)
			(xy 247.600038 -157.42373) (xy 247.633484 -157.383093) (xy 247.65254 -157.364938) (xy 247.659918 -157.357396)
			(xy 247.668458 -157.338132) (xy 247.66905 -157.3276) (xy 247.66905 -157.252924) (xy 247.668507 -157.242376)
			(xy 247.65998 -157.223082) (xy 247.65254 -157.215586) (xy 247.633473 -157.197442) (xy 247.600019 -157.156808)
			(xy 247.572463 -157.111965) (xy 247.551327 -157.063763) (xy 247.537012 -157.013114) (xy 247.529788 -156.960979)
			(xy 247.52935 -156.934662) (xy 247.529836 -156.907411) (xy 247.537592 -156.853463) (xy 247.552947 -156.801168)
			(xy 247.575589 -156.751591) (xy 247.605055 -156.705741) (xy 247.640746 -156.66455) (xy 247.681937 -156.628859)
			(xy 247.727787 -156.599393) (xy 247.777364 -156.576751) (xy 247.829659 -156.561396) (xy 247.883607 -156.55364)
			(xy 247.938109 -156.55364) (xy 247.992057 -156.561396) (xy 248.044352 -156.576751) (xy 248.093929 -156.599393)
			(xy 248.139779 -156.628859) (xy 248.158524 -156.645101) (xy 249.513918 -156.645101) (xy 249.518234 -156.587828)
			(xy 249.531084 -156.531849) (xy 249.552177 -156.478427) (xy 249.581038 -156.428769) (xy 249.617015 -156.383997)
			(xy 249.637804 -156.364178) (xy 249.645218 -156.356667) (xy 249.653735 -156.337379) (xy 249.654314 -156.32684)
			(xy 249.654314 -156.252164) (xy 249.65376 -156.241617) (xy 249.645242 -156.222322) (xy 249.637804 -156.214826)
			(xy 249.618769 -156.19665) (xy 249.58531 -156.156025) (xy 249.557748 -156.111189) (xy 249.536606 -156.062992)
			(xy 249.522284 -156.012348) (xy 249.515055 -155.960217) (xy 249.514614 -155.933902) (xy 249.5151 -155.906651)
			(xy 249.522856 -155.852703) (xy 249.538211 -155.800408) (xy 249.560853 -155.750831) (xy 249.590319 -155.704981)
			(xy 249.62601 -155.66379) (xy 249.667201 -155.628099) (xy 249.713051 -155.598633) (xy 249.762628 -155.575991)
			(xy 249.814923 -155.560636) (xy 249.868871 -155.55288) (xy 249.923373 -155.55288) (xy 249.977321 -155.560636)
			(xy 250.029616 -155.575991) (xy 250.079193 -155.598633) (xy 250.125043 -155.628099) (xy 250.166234 -155.66379)
			(xy 250.201925 -155.704981) (xy 250.231391 -155.750831) (xy 250.254033 -155.800408) (xy 250.269388 -155.852703)
			(xy 250.277144 -155.906651) (xy 250.27763 -155.933902) (xy 250.277154 -155.960216) (xy 250.26992 -156.012343)
			(xy 250.255602 -156.062986) (xy 250.234471 -156.111184) (xy 250.206927 -156.156028) (xy 250.17349 -156.196669)
			(xy 250.15444 -156.214826) (xy 250.147031 -156.222341) (xy 250.13851 -156.241626) (xy 250.13793 -156.252164)
			(xy 250.13793 -156.32684) (xy 250.138469 -156.337389) (xy 250.146996 -156.356685) (xy 250.15444 -156.364178)
			(xy 250.175229 -156.383997) (xy 250.211202 -156.42877) (xy 250.24006 -156.478428) (xy 250.261151 -156.53185)
			(xy 250.273999 -156.587829) (xy 250.278314 -156.645101) (xy 250.273999 -156.702374) (xy 250.272863 -156.707322)
			(xy 252.579727 -156.707322) (xy 252.584039 -156.650052) (xy 252.596884 -156.594076) (xy 252.617973 -156.540656)
			(xy 252.646828 -156.491) (xy 252.682798 -156.446228) (xy 252.703584 -156.426408) (xy 252.710982 -156.418883)
			(xy 252.719509 -156.399606) (xy 252.720094 -156.38907) (xy 252.720094 -156.314394) (xy 252.719584 -156.303842)
			(xy 252.711036 -156.284547) (xy 252.703584 -156.277056) (xy 252.684511 -156.258918) (xy 252.651056 -156.218284)
			(xy 252.6235 -156.17344) (xy 252.602364 -156.125236) (xy 252.588051 -156.074586) (xy 252.58083 -156.022449)
			(xy 252.580394 -155.996132) (xy 252.58088 -155.968881) (xy 252.588636 -155.914933) (xy 252.603991 -155.862638)
			(xy 252.626633 -155.813061) (xy 252.656099 -155.767211) (xy 252.69179 -155.72602) (xy 252.732981 -155.690329)
			(xy 252.778831 -155.660863) (xy 252.828408 -155.638221) (xy 252.880703 -155.622866) (xy 252.934651 -155.61511)
			(xy 252.989153 -155.61511) (xy 253.043101 -155.622866) (xy 253.095396 -155.638221) (xy 253.144973 -155.660863)
			(xy 253.190823 -155.690329) (xy 253.232014 -155.72602) (xy 253.267705 -155.767211) (xy 253.297171 -155.813061)
			(xy 253.319813 -155.862638) (xy 253.335168 -155.914933) (xy 253.342924 -155.968881) (xy 253.34341 -155.996132)
			(xy 253.342961 -156.022447) (xy 253.335722 -156.074576) (xy 253.321399 -156.125219) (xy 253.300263 -156.173417)
			(xy 253.272714 -156.218261) (xy 253.239273 -156.2589) (xy 253.22022 -156.277056) (xy 253.212839 -156.284595)
			(xy 253.204302 -156.303862) (xy 253.20371 -156.314394) (xy 253.20371 -156.38907) (xy 253.204239 -156.39962)
			(xy 253.212774 -156.418915) (xy 253.22022 -156.426408) (xy 253.24104 -156.446196) (xy 253.277014 -156.490973)
			(xy 253.305873 -156.540636) (xy 253.326964 -156.594062) (xy 253.33981 -156.650045) (xy 253.344123 -156.707322)
			(xy 253.339804 -156.764598) (xy 253.326951 -156.82058) (xy 253.305854 -156.874003) (xy 253.27699 -156.923663)
			(xy 253.24101 -156.968436) (xy 253.22022 -156.988256) (xy 253.212839 -156.995795) (xy 253.204302 -157.015062)
			(xy 253.20371 -157.025594) (xy 253.20371 -157.10027) (xy 253.204239 -157.11082) (xy 253.212774 -157.130115)
			(xy 253.22022 -157.137608) (xy 253.239276 -157.155763) (xy 253.272733 -157.196393) (xy 253.300291 -157.241234)
			(xy 253.321429 -157.289435) (xy 253.335746 -157.340082) (xy 253.342971 -157.392216) (xy 253.34341 -157.418532)
			(xy 253.342924 -157.445783) (xy 253.335168 -157.499731) (xy 253.319813 -157.552026) (xy 253.297171 -157.601603)
			(xy 253.267705 -157.647453) (xy 253.232014 -157.688644) (xy 253.190823 -157.724335) (xy 253.144973 -157.753801)
			(xy 253.095396 -157.776443) (xy 253.043101 -157.791798) (xy 252.989153 -157.799554) (xy 252.934651 -157.799554)
			(xy 252.880703 -157.791798) (xy 252.828408 -157.776443) (xy 252.778831 -157.753801) (xy 252.732981 -157.724335)
			(xy 252.69179 -157.688644) (xy 252.656099 -157.647453) (xy 252.626633 -157.601603) (xy 252.603991 -157.552026)
			(xy 252.588636 -157.499731) (xy 252.58088 -157.445783) (xy 252.580394 -157.418532) (xy 252.580818 -157.392217)
			(xy 252.588062 -157.340086) (xy 252.60239 -157.289443) (xy 252.62353 -157.241244) (xy 252.651084 -157.196402)
			(xy 252.684529 -157.155764) (xy 252.703584 -157.137608) (xy 252.710982 -157.130083) (xy 252.719509 -157.110806)
			(xy 252.720094 -157.10027) (xy 252.720094 -157.025594) (xy 252.719584 -157.015042) (xy 252.711036 -156.995747)
			(xy 252.703584 -156.988256) (xy 252.682828 -156.968404) (xy 252.646852 -156.923636) (xy 252.617991 -156.873983)
			(xy 252.596897 -156.820566) (xy 252.584045 -156.764591) (xy 252.579727 -156.707322) (xy 250.272863 -156.707322)
			(xy 250.26115 -156.758353) (xy 250.240059 -156.811774) (xy 250.2112 -156.861432) (xy 250.175227 -156.906205)
			(xy 250.15444 -156.926026) (xy 250.147031 -156.933541) (xy 250.13851 -156.952826) (xy 250.13793 -156.963364)
			(xy 250.13793 -157.03804) (xy 250.138469 -157.048589) (xy 250.146996 -157.067885) (xy 250.15444 -157.075378)
			(xy 250.173486 -157.093543) (xy 250.206942 -157.134172) (xy 250.234501 -157.17901) (xy 250.255641 -157.227209)
			(xy 250.269961 -157.277854) (xy 250.277189 -157.329987) (xy 250.27763 -157.356302) (xy 250.277144 -157.383553)
			(xy 250.269388 -157.437501) (xy 250.254033 -157.489796) (xy 250.231391 -157.539373) (xy 250.201925 -157.585223)
			(xy 250.166234 -157.626414) (xy 250.125043 -157.662105) (xy 250.079193 -157.691571) (xy 250.029616 -157.714213)
			(xy 249.977321 -157.729568) (xy 249.923373 -157.737324) (xy 249.868871 -157.737324) (xy 249.814923 -157.729568)
			(xy 249.762628 -157.714213) (xy 249.713051 -157.691571) (xy 249.667201 -157.662105) (xy 249.62601 -157.626414)
			(xy 249.590319 -157.585223) (xy 249.560853 -157.539373) (xy 249.538211 -157.489796) (xy 249.522856 -157.437501)
			(xy 249.5151 -157.383553) (xy 249.514614 -157.356302) (xy 249.515078 -157.329988) (xy 249.522313 -157.277859)
			(xy 249.536633 -157.227216) (xy 249.557766 -157.179017) (xy 249.585312 -157.134174) (xy 249.618752 -157.093534)
			(xy 249.637804 -157.075378) (xy 249.645218 -157.067867) (xy 249.653735 -157.048579) (xy 249.654314 -157.03804)
			(xy 249.654314 -156.963364) (xy 249.65376 -156.952817) (xy 249.645242 -156.933522) (xy 249.637804 -156.926026)
			(xy 249.617017 -156.906205) (xy 249.58104 -156.861433) (xy 249.552178 -156.811776) (xy 249.531084 -156.758354)
			(xy 249.518234 -156.702374) (xy 249.513918 -156.645101) (xy 248.158524 -156.645101) (xy 248.18097 -156.66455)
			(xy 248.216661 -156.705741) (xy 248.246127 -156.751591) (xy 248.268769 -156.801168) (xy 248.284124 -156.853463)
			(xy 248.29188 -156.907411) (xy 248.292366 -156.934662) (xy 248.291951 -156.960978) (xy 248.284707 -157.013109)
			(xy 248.270378 -157.063753) (xy 248.249236 -157.111952) (xy 248.22168 -157.156794) (xy 248.188232 -157.197431)
			(xy 248.169176 -157.215586) (xy 248.16179 -157.223121) (xy 248.153254 -157.24239) (xy 248.152666 -157.252924)
			(xy 248.152666 -157.3276) (xy 248.153192 -157.33815) (xy 248.16173 -157.357444) (xy 248.169176 -157.364938)
			(xy 248.188238 -157.383087) (xy 248.221696 -157.423717) (xy 248.249255 -157.468559) (xy 248.270392 -157.516761)
			(xy 248.284707 -157.56741) (xy 248.291929 -157.619545) (xy 248.292366 -157.645862) (xy 248.29188 -157.673113)
			(xy 248.284124 -157.727061) (xy 248.268769 -157.779356) (xy 248.246127 -157.828933) (xy 248.216661 -157.874783)
			(xy 248.18097 -157.915974) (xy 248.139779 -157.951665) (xy 248.093929 -157.981131) (xy 248.044352 -158.003773)
			(xy 247.992057 -158.019128) (xy 247.938109 -158.026884) (xy 247.883607 -158.026884) (xy 247.829659 -158.019128)
			(xy 247.777364 -158.003773) (xy 247.727787 -157.981131) (xy 247.681937 -157.951665) (xy 247.640746 -157.915974)
			(xy 247.605055 -157.874783) (xy 247.575589 -157.828933) (xy 247.552947 -157.779356) (xy 247.537592 -157.727061)
			(xy 247.529836 -157.673113) (xy 247.52935 -157.645862) (xy 246.575285 -157.645862) (xy 246.575326 -157.647894)
			(xy 246.574816 -157.673881) (xy 246.566686 -157.725216) (xy 246.550625 -157.774646) (xy 246.527029 -157.820956)
			(xy 246.496479 -157.863004) (xy 246.459728 -157.899755) (xy 246.41768 -157.930305) (xy 246.37137 -157.953901)
			(xy 246.32194 -157.969962) (xy 246.270605 -157.978092) (xy 246.218631 -157.978092) (xy 246.167296 -157.969962)
			(xy 246.117866 -157.953901) (xy 246.071556 -157.930305) (xy 246.029508 -157.899755) (xy 245.992757 -157.863004)
			(xy 245.962207 -157.820956) (xy 245.938611 -157.774646) (xy 245.92255 -157.725216) (xy 245.91442 -157.673881)
			(xy 245.91391 -157.647894) (xy 245.67515 -157.647894) (xy 245.67464 -157.673881) (xy 245.66651 -157.725216)
			(xy 245.650449 -157.774646) (xy 245.626853 -157.820956) (xy 245.596303 -157.863004) (xy 245.559552 -157.899755)
			(xy 245.517504 -157.930305) (xy 245.471194 -157.953901) (xy 245.421764 -157.969962) (xy 245.370429 -157.978092)
			(xy 245.318455 -157.978092) (xy 245.26712 -157.969962) (xy 245.21769 -157.953901) (xy 245.17138 -157.930305)
			(xy 245.129332 -157.899755) (xy 245.092581 -157.863004) (xy 245.062031 -157.820956) (xy 245.038435 -157.774646)
			(xy 245.022374 -157.725216) (xy 245.014244 -157.673881) (xy 245.013734 -157.647894) (xy 244.775228 -157.647894)
			(xy 244.774718 -157.673881) (xy 244.766588 -157.725216) (xy 244.750527 -157.774646) (xy 244.726931 -157.820956)
			(xy 244.696381 -157.863004) (xy 244.65963 -157.899755) (xy 244.617582 -157.930305) (xy 244.571272 -157.953901)
			(xy 244.521842 -157.969962) (xy 244.470507 -157.978092) (xy 244.418533 -157.978092) (xy 244.367198 -157.969962)
			(xy 244.317768 -157.953901) (xy 244.271458 -157.930305) (xy 244.22941 -157.899755) (xy 244.192659 -157.863004)
			(xy 244.162109 -157.820956) (xy 244.138513 -157.774646) (xy 244.122452 -157.725216) (xy 244.114322 -157.673881)
			(xy 244.113812 -157.647894) (xy 243.875306 -157.647894) (xy 243.874796 -157.673881) (xy 243.866666 -157.725216)
			(xy 243.850605 -157.774646) (xy 243.827009 -157.820956) (xy 243.796459 -157.863004) (xy 243.759708 -157.899755)
			(xy 243.71766 -157.930305) (xy 243.67135 -157.953901) (xy 243.62192 -157.969962) (xy 243.570585 -157.978092)
			(xy 243.518611 -157.978092) (xy 243.467276 -157.969962) (xy 243.417846 -157.953901) (xy 243.371536 -157.930305)
			(xy 243.329488 -157.899755) (xy 243.292737 -157.863004) (xy 243.262187 -157.820956) (xy 243.238591 -157.774646)
			(xy 243.22253 -157.725216) (xy 243.2144 -157.673881) (xy 243.21389 -157.647894) (xy 240.572036 -157.647894)
			(xy 240.572036 -158.06039) (xy 241.039648 -158.06039) (xy 241.043719 -158.004768) (xy 241.055845 -157.950331)
			(xy 241.075768 -157.89824) (xy 241.103064 -157.849605) (xy 241.13715 -157.805462) (xy 241.177299 -157.766753)
			(xy 241.222657 -157.734302) (xy 241.272257 -157.708801) (xy 241.325041 -157.690794) (xy 241.379884 -157.680664)
			(xy 241.435618 -157.678627) (xy 241.491055 -157.684727) (xy 241.545012 -157.698833) (xy 241.596341 -157.720645)
			(xy 241.643947 -157.749699) (xy 241.686815 -157.785374) (xy 241.724032 -157.826911) (xy 241.754805 -157.873424)
			(xy 241.778477 -157.923921) (xy 241.794545 -157.977328) (xy 241.802665 -158.032504) (xy 241.803174 -158.06039)
			(xy 241.802665 -158.088276) (xy 241.794545 -158.143452) (xy 241.778477 -158.196859) (xy 241.754805 -158.247356)
			(xy 241.724032 -158.293869) (xy 241.686815 -158.335406) (xy 241.643947 -158.371081) (xy 241.596341 -158.400135)
			(xy 241.545012 -158.421947) (xy 241.491055 -158.436053) (xy 241.435618 -158.442153) (xy 241.379884 -158.440116)
			(xy 241.325041 -158.429986) (xy 241.272257 -158.411979) (xy 241.222657 -158.386478) (xy 241.177299 -158.354027)
			(xy 241.13715 -158.315318) (xy 241.103064 -158.271175) (xy 241.075768 -158.22254) (xy 241.055845 -158.170449)
			(xy 241.043719 -158.116012) (xy 241.039648 -158.06039) (xy 240.572036 -158.06039) (xy 240.572036 -158.753302)
			(xy 248.716544 -158.753302) (xy 248.720615 -158.69768) (xy 248.732741 -158.643243) (xy 248.752664 -158.591152)
			(xy 248.77996 -158.542517) (xy 248.814046 -158.498374) (xy 248.854195 -158.459665) (xy 248.899553 -158.427214)
			(xy 248.949153 -158.401713) (xy 249.001937 -158.383706) (xy 249.05678 -158.373576) (xy 249.112514 -158.371539)
			(xy 249.167951 -158.377639) (xy 249.221908 -158.391745) (xy 249.273237 -158.413557) (xy 249.320843 -158.442611)
			(xy 249.363711 -158.478286) (xy 249.400928 -158.519823) (xy 249.431701 -158.566336) (xy 249.455373 -158.616833)
			(xy 249.471441 -158.67024) (xy 249.479561 -158.725416) (xy 249.48007 -158.753302) (xy 249.479561 -158.781188)
			(xy 249.471441 -158.836364) (xy 249.455373 -158.889771) (xy 249.431701 -158.940268) (xy 249.400928 -158.986781)
			(xy 249.363711 -159.028318) (xy 249.320843 -159.063993) (xy 249.273237 -159.093047) (xy 249.221908 -159.114859)
			(xy 249.167951 -159.128965) (xy 249.112514 -159.135065) (xy 249.05678 -159.133028) (xy 249.001937 -159.122898)
			(xy 248.949153 -159.104891) (xy 248.899553 -159.07939) (xy 248.854195 -159.046939) (xy 248.814046 -159.00823)
			(xy 248.77996 -158.964087) (xy 248.752664 -158.915452) (xy 248.732741 -158.863361) (xy 248.720615 -158.808924)
			(xy 248.716544 -158.753302) (xy 240.572036 -158.753302) (xy 240.572036 -159.439102) (xy 241.107974 -159.439102)
			(xy 241.112045 -159.38348) (xy 241.124171 -159.329043) (xy 241.144094 -159.276952) (xy 241.17139 -159.228317)
			(xy 241.205476 -159.184174) (xy 241.245625 -159.145465) (xy 241.290983 -159.113014) (xy 241.340583 -159.087513)
			(xy 241.393367 -159.069506) (xy 241.44821 -159.059376) (xy 241.503944 -159.057339) (xy 241.559381 -159.063439)
			(xy 241.613338 -159.077545) (xy 241.664667 -159.099357) (xy 241.712273 -159.128411) (xy 241.755141 -159.164086)
			(xy 241.792358 -159.205623) (xy 241.823131 -159.252136) (xy 241.846803 -159.302633) (xy 241.862871 -159.35604)
			(xy 241.870991 -159.411216) (xy 241.8715 -159.439102) (xy 241.870991 -159.466988) (xy 241.862871 -159.522164)
			(xy 241.859968 -159.531812) (xy 244.312692 -159.531812) (xy 244.316763 -159.47619) (xy 244.328889 -159.421753)
			(xy 244.348812 -159.369662) (xy 244.376108 -159.321027) (xy 244.410194 -159.276884) (xy 244.450343 -159.238175)
			(xy 244.495701 -159.205724) (xy 244.545301 -159.180223) (xy 244.598085 -159.162216) (xy 244.652928 -159.152086)
			(xy 244.708662 -159.150049) (xy 244.764099 -159.156149) (xy 244.818056 -159.170255) (xy 244.869385 -159.192067)
			(xy 244.916991 -159.221121) (xy 244.959859 -159.256796) (xy 244.997076 -159.298333) (xy 245.027849 -159.344846)
			(xy 245.051521 -159.395343) (xy 245.067589 -159.44875) (xy 245.073458 -159.488632) (xy 246.595898 -159.488632)
			(xy 246.599969 -159.43301) (xy 246.612095 -159.378573) (xy 246.632018 -159.326482) (xy 246.659314 -159.277847)
			(xy 246.6934 -159.233704) (xy 246.733549 -159.194995) (xy 246.778907 -159.162544) (xy 246.828507 -159.137043)
			(xy 246.881291 -159.119036) (xy 246.936134 -159.108906) (xy 246.991868 -159.106869) (xy 247.047305 -159.112969)
			(xy 247.101262 -159.127075) (xy 247.152591 -159.148887) (xy 247.200197 -159.177941) (xy 247.243065 -159.213616)
			(xy 247.280282 -159.255153) (xy 247.311055 -159.301666) (xy 247.334727 -159.352163) (xy 247.350795 -159.40557)
			(xy 247.358915 -159.460746) (xy 247.359424 -159.488632) (xy 247.358915 -159.516518) (xy 247.350795 -159.571694)
			(xy 247.334727 -159.625101) (xy 247.311055 -159.675598) (xy 247.280282 -159.722111) (xy 247.243065 -159.763648)
			(xy 247.200197 -159.799323) (xy 247.152591 -159.828377) (xy 247.101262 -159.850189) (xy 247.047305 -159.864295)
			(xy 246.991868 -159.870395) (xy 246.936134 -159.868358) (xy 246.881291 -159.858228) (xy 246.828507 -159.840221)
			(xy 246.778907 -159.81472) (xy 246.733549 -159.782269) (xy 246.6934 -159.74356) (xy 246.659314 -159.699417)
			(xy 246.632018 -159.650782) (xy 246.612095 -159.598691) (xy 246.599969 -159.544254) (xy 246.595898 -159.488632)
			(xy 245.073458 -159.488632) (xy 245.075709 -159.503926) (xy 245.076218 -159.531812) (xy 245.075709 -159.559698)
			(xy 245.067589 -159.614874) (xy 245.051521 -159.668281) (xy 245.027849 -159.718778) (xy 244.997076 -159.765291)
			(xy 244.959859 -159.806828) (xy 244.916991 -159.842503) (xy 244.869385 -159.871557) (xy 244.818056 -159.893369)
			(xy 244.764099 -159.907475) (xy 244.708662 -159.913575) (xy 244.652928 -159.911538) (xy 244.598085 -159.901408)
			(xy 244.545301 -159.883401) (xy 244.495701 -159.8579) (xy 244.450343 -159.825449) (xy 244.410194 -159.78674)
			(xy 244.376108 -159.742597) (xy 244.348812 -159.693962) (xy 244.328889 -159.641871) (xy 244.316763 -159.587434)
			(xy 244.312692 -159.531812) (xy 241.859968 -159.531812) (xy 241.846803 -159.575571) (xy 241.823131 -159.626068)
			(xy 241.792358 -159.672581) (xy 241.755141 -159.714118) (xy 241.712273 -159.749793) (xy 241.664667 -159.778847)
			(xy 241.613338 -159.800659) (xy 241.559381 -159.814765) (xy 241.503944 -159.820865) (xy 241.44821 -159.818828)
			(xy 241.393367 -159.808698) (xy 241.340583 -159.790691) (xy 241.290983 -159.76519) (xy 241.245625 -159.732739)
			(xy 241.205476 -159.69403) (xy 241.17139 -159.649887) (xy 241.144094 -159.601252) (xy 241.124171 -159.549161)
			(xy 241.112045 -159.494724) (xy 241.107974 -159.439102) (xy 240.572036 -159.439102) (xy 240.572036 -160.673796)
			(xy 240.573052 -160.683448) (xy 240.57468 -160.690692) (xy 240.581522 -160.70386) (xy 240.586514 -160.709356)
			(xy 240.620804 -160.743646) (xy 240.622582 -160.745424) (xy 240.627916 -160.750758) (xy 240.635536 -160.7693)
			(xy 240.635536 -160.965896) (xy 241.137692 -160.965896) (xy 241.141763 -160.910274) (xy 241.153889 -160.855837)
			(xy 241.173812 -160.803746) (xy 241.201108 -160.755111) (xy 241.235194 -160.710968) (xy 241.275343 -160.672259)
			(xy 241.320701 -160.639808) (xy 241.370301 -160.614307) (xy 241.423085 -160.5963) (xy 241.477928 -160.58617)
			(xy 241.533662 -160.584133) (xy 241.589099 -160.590233) (xy 241.643056 -160.604339) (xy 241.694385 -160.626151)
			(xy 241.741991 -160.655205) (xy 241.784859 -160.69088) (xy 241.822076 -160.732417) (xy 241.852849 -160.77893)
			(xy 241.876521 -160.829427) (xy 241.892589 -160.882834) (xy 241.900709 -160.93801) (xy 241.901181 -160.963864)
			(xy 242.529612 -160.963864) (xy 242.533683 -160.908242) (xy 242.545809 -160.853805) (xy 242.565732 -160.801714)
			(xy 242.593028 -160.753079) (xy 242.627114 -160.708936) (xy 242.667263 -160.670227) (xy 242.712621 -160.637776)
			(xy 242.762221 -160.612275) (xy 242.815005 -160.594268) (xy 242.869848 -160.584138) (xy 242.925582 -160.582101)
			(xy 242.981019 -160.588201) (xy 243.034976 -160.602307) (xy 243.086305 -160.624119) (xy 243.133911 -160.653173)
			(xy 243.176779 -160.688848) (xy 243.213996 -160.730385) (xy 243.244769 -160.776898) (xy 243.268441 -160.827395)
			(xy 243.284509 -160.880802) (xy 243.292629 -160.935978) (xy 243.293138 -160.963864) (xy 243.293045 -160.968944)
			(xy 243.80139 -160.968944) (xy 243.805461 -160.913322) (xy 243.817587 -160.858885) (xy 243.83751 -160.806794)
			(xy 243.864806 -160.758159) (xy 243.898892 -160.714016) (xy 243.939041 -160.675307) (xy 243.984399 -160.642856)
			(xy 244.033999 -160.617355) (xy 244.086783 -160.599348) (xy 244.141626 -160.589218) (xy 244.19736 -160.587181)
			(xy 244.252797 -160.593281) (xy 244.306754 -160.607387) (xy 244.358083 -160.629199) (xy 244.405689 -160.658253)
			(xy 244.448557 -160.693928) (xy 244.485774 -160.735465) (xy 244.516547 -160.781978) (xy 244.540219 -160.832475)
			(xy 244.556287 -160.885882) (xy 244.55868 -160.902142) (xy 245.582692 -160.902142) (xy 245.586763 -160.84652)
			(xy 245.598889 -160.792083) (xy 245.618812 -160.739992) (xy 245.646108 -160.691357) (xy 245.680194 -160.647214)
			(xy 245.720343 -160.608505) (xy 245.765701 -160.576054) (xy 245.815301 -160.550553) (xy 245.868085 -160.532546)
			(xy 245.922928 -160.522416) (xy 245.978662 -160.520379) (xy 246.034099 -160.526479) (xy 246.088056 -160.540585)
			(xy 246.139385 -160.562397) (xy 246.186991 -160.591451) (xy 246.229859 -160.627126) (xy 246.267076 -160.668663)
			(xy 246.297849 -160.715176) (xy 246.321521 -160.765673) (xy 246.337589 -160.81908) (xy 246.345709 -160.874256)
			(xy 246.346218 -160.902142) (xy 246.345709 -160.930028) (xy 246.337589 -160.985204) (xy 246.321521 -161.038611)
			(xy 246.297849 -161.089108) (xy 246.267076 -161.135621) (xy 246.229859 -161.177158) (xy 246.186991 -161.212833)
			(xy 246.139385 -161.241887) (xy 246.088056 -161.263699) (xy 246.034099 -161.277805) (xy 245.978662 -161.283905)
			(xy 245.922928 -161.281868) (xy 245.868085 -161.271738) (xy 245.815301 -161.253731) (xy 245.765701 -161.22823)
			(xy 245.720343 -161.195779) (xy 245.680194 -161.15707) (xy 245.646108 -161.112927) (xy 245.618812 -161.064292)
			(xy 245.598889 -161.012201) (xy 245.586763 -160.957764) (xy 245.582692 -160.902142) (xy 244.55868 -160.902142)
			(xy 244.564407 -160.941058) (xy 244.564916 -160.968944) (xy 244.564407 -160.99683) (xy 244.556287 -161.052006)
			(xy 244.540219 -161.105413) (xy 244.516547 -161.15591) (xy 244.485774 -161.202423) (xy 244.448557 -161.24396)
			(xy 244.405689 -161.279635) (xy 244.358083 -161.308689) (xy 244.306754 -161.330501) (xy 244.252797 -161.344607)
			(xy 244.19736 -161.350707) (xy 244.141626 -161.34867) (xy 244.086783 -161.33854) (xy 244.033999 -161.320533)
			(xy 243.984399 -161.295032) (xy 243.939041 -161.262581) (xy 243.898892 -161.223872) (xy 243.864806 -161.179729)
			(xy 243.83751 -161.131094) (xy 243.817587 -161.079003) (xy 243.805461 -161.024566) (xy 243.80139 -160.968944)
			(xy 243.293045 -160.968944) (xy 243.292629 -160.99175) (xy 243.284509 -161.046926) (xy 243.268441 -161.100333)
			(xy 243.244769 -161.15083) (xy 243.213996 -161.197343) (xy 243.176779 -161.23888) (xy 243.133911 -161.274555)
			(xy 243.086305 -161.303609) (xy 243.034976 -161.325421) (xy 242.981019 -161.339527) (xy 242.925582 -161.345627)
			(xy 242.869848 -161.34359) (xy 242.815005 -161.33346) (xy 242.762221 -161.315453) (xy 242.712621 -161.289952)
			(xy 242.667263 -161.257501) (xy 242.627114 -161.218792) (xy 242.593028 -161.174649) (xy 242.565732 -161.126014)
			(xy 242.545809 -161.073923) (xy 242.533683 -161.019486) (xy 242.529612 -160.963864) (xy 241.901181 -160.963864)
			(xy 241.901218 -160.965896) (xy 241.900709 -160.993782) (xy 241.892589 -161.048958) (xy 241.876521 -161.102365)
			(xy 241.852849 -161.152862) (xy 241.822076 -161.199375) (xy 241.784859 -161.240912) (xy 241.741991 -161.276587)
			(xy 241.694385 -161.305641) (xy 241.643056 -161.327453) (xy 241.589099 -161.341559) (xy 241.533662 -161.347659)
			(xy 241.477928 -161.345622) (xy 241.423085 -161.335492) (xy 241.370301 -161.317485) (xy 241.320701 -161.291984)
			(xy 241.275343 -161.259533) (xy 241.235194 -161.220824) (xy 241.201108 -161.176681) (xy 241.173812 -161.128046)
			(xy 241.153889 -161.075955) (xy 241.141763 -161.021518) (xy 241.137692 -160.965896) (xy 240.635536 -160.965896)
			(xy 240.635536 -161.353754) (xy 240.627916 -161.372296) (xy 240.622582 -161.37763) (xy 240.620804 -161.379408)
			(xy 240.62055 -161.379662) (xy 240.415064 -161.584894) (xy 240.407664 -161.591735) (xy 240.389066 -161.599458)
			(xy 240.378996 -161.59988) (xy 237.144052 -161.59988) (xy 237.13402 -161.599443) (xy 237.115445 -161.591867)
			(xy 237.107984 -161.585148) (xy 236.958378 -161.435542) (xy 236.661452 -161.138616) (xy 236.659674 -161.136838)
			(xy 236.65434 -161.131504) (xy 236.64672 -161.112962) (xy 236.64672 -148.171154) (xy 236.64672 -148.169122)
			(xy 236.646051 -148.160542) (xy 236.639694 -148.144563) (xy 236.634274 -148.13788) (xy 236.610652 -148.112226)
			(xy 236.605942 -148.107946) (xy 236.594894 -148.10164) (xy 236.588808 -148.09978) (xy 236.582712 -148.099018)
			(xy 236.55557 -148.094912) (xy 236.502763 -148.079924) (xy 236.45265 -148.05752) (xy 236.406265 -148.028166)
			(xy 236.364567 -147.992466) (xy 236.328416 -147.951158) (xy 236.29856 -147.905095) (xy 236.275614 -147.855228)
			(xy 236.260053 -147.802586) (xy 236.252197 -147.748259) (xy 236.25175 -147.720812) (xy 236.252231 -147.693383)
			(xy 236.260098 -147.639092) (xy 236.275658 -147.586487) (xy 236.298588 -147.536651) (xy 236.328418 -147.490612)
			(xy 236.364532 -147.449318) (xy 236.406187 -147.41362) (xy 236.452523 -147.384255) (xy 236.502587 -147.361826)
			(xy 236.555346 -147.346796) (xy 236.582458 -147.342606) (xy 236.591856 -147.341336) (xy 236.599476 -147.337272)
			(xy 236.603364 -147.335166) (xy 236.610393 -147.329803) (xy 236.613446 -147.326604) (xy 236.633512 -147.304506)
			(xy 236.639568 -147.297334) (xy 236.646362 -147.279849) (xy 236.64672 -147.27047) (xy 236.64672 -147.155154)
			(xy 236.64672 -147.153122) (xy 236.646051 -147.144542) (xy 236.639694 -147.128563) (xy 236.634274 -147.12188)
			(xy 236.610652 -147.096226) (xy 236.605942 -147.091946) (xy 236.594894 -147.08564) (xy 236.588808 -147.08378)
			(xy 236.582712 -147.083018) (xy 236.55557 -147.078912) (xy 236.502763 -147.063924) (xy 236.45265 -147.04152)
			(xy 236.406265 -147.012166) (xy 236.364567 -146.976466) (xy 236.328416 -146.935158) (xy 236.29856 -146.889095)
			(xy 236.275614 -146.839228) (xy 236.260053 -146.786586) (xy 236.252197 -146.732259) (xy 236.25175 -146.704812)
			(xy 236.252231 -146.677383) (xy 236.260098 -146.623092) (xy 236.275658 -146.570487) (xy 236.298588 -146.520651)
			(xy 236.328418 -146.474612) (xy 236.364532 -146.433318) (xy 236.406187 -146.39762) (xy 236.452523 -146.368255)
			(xy 236.502587 -146.345826) (xy 236.555346 -146.330796) (xy 236.582458 -146.326606) (xy 236.591856 -146.325336)
			(xy 236.599476 -146.321272) (xy 236.603364 -146.319166) (xy 236.610393 -146.313803) (xy 236.613446 -146.310604)
			(xy 236.633512 -146.288506) (xy 236.639568 -146.281334) (xy 236.646362 -146.263849) (xy 236.64672 -146.25447)
			(xy 236.64672 -146.139154) (xy 236.64672 -146.137122) (xy 236.646051 -146.128542) (xy 236.639694 -146.112563)
			(xy 236.634274 -146.10588) (xy 236.610652 -146.080226) (xy 236.605942 -146.075946) (xy 236.594894 -146.06964)
			(xy 236.588808 -146.06778) (xy 236.582712 -146.067018) (xy 236.55557 -146.062912) (xy 236.502763 -146.047924)
			(xy 236.45265 -146.02552) (xy 236.406265 -145.996166) (xy 236.364567 -145.960466) (xy 236.328416 -145.919158)
			(xy 236.29856 -145.873095) (xy 236.275614 -145.823228) (xy 236.260053 -145.770586) (xy 236.252197 -145.716259)
			(xy 236.25175 -145.688812) (xy 236.252231 -145.661383) (xy 236.260098 -145.607092) (xy 236.275658 -145.554487)
			(xy 236.298588 -145.504651) (xy 236.328418 -145.458612) (xy 236.364532 -145.417318) (xy 236.406187 -145.38162)
			(xy 236.452523 -145.352255) (xy 236.502587 -145.329826) (xy 236.555346 -145.314796) (xy 236.582458 -145.310606)
			(xy 236.591856 -145.309336) (xy 236.599476 -145.305272) (xy 236.603364 -145.303166) (xy 236.610393 -145.297803)
			(xy 236.613446 -145.294604) (xy 236.633512 -145.272506) (xy 236.639568 -145.265334) (xy 236.646362 -145.247849)
			(xy 236.64672 -145.23847) (xy 236.64672 -145.123154) (xy 236.64672 -145.121122) (xy 236.646051 -145.112542)
			(xy 236.639694 -145.096563) (xy 236.634274 -145.08988) (xy 236.610652 -145.064226) (xy 236.605942 -145.059946)
			(xy 236.594894 -145.05364) (xy 236.588808 -145.05178) (xy 236.582712 -145.051018) (xy 236.55557 -145.046912)
			(xy 236.502763 -145.031924) (xy 236.45265 -145.00952) (xy 236.406265 -144.980166) (xy 236.364567 -144.944466)
			(xy 236.328416 -144.903158) (xy 236.29856 -144.857095) (xy 236.275614 -144.807228) (xy 236.260053 -144.754586)
			(xy 236.252197 -144.700259) (xy 236.25175 -144.672812) (xy 236.252231 -144.645383) (xy 236.260098 -144.591092)
			(xy 236.275658 -144.538487) (xy 236.298588 -144.488651) (xy 236.328418 -144.442612) (xy 236.364532 -144.401318)
			(xy 236.406187 -144.36562) (xy 236.452523 -144.336255) (xy 236.502587 -144.313826) (xy 236.555346 -144.298796)
			(xy 236.582458 -144.294606) (xy 236.591856 -144.293336) (xy 236.599476 -144.289272) (xy 236.603364 -144.287166)
			(xy 236.610393 -144.281803) (xy 236.613446 -144.278604) (xy 236.633512 -144.256506) (xy 236.639568 -144.249334)
			(xy 236.646362 -144.231849) (xy 236.64672 -144.22247) (xy 236.64672 -142.091156) (xy 236.646251 -142.081797)
			(xy 236.639486 -142.064338) (xy 236.633512 -142.05712) (xy 236.613446 -142.035022) (xy 236.608287 -142.029737)
			(xy 236.595638 -142.022125) (xy 236.588554 -142.020036) (xy 236.582966 -142.019274) (xy 236.559244 -142.015673)
			(xy 236.51288 -142.003314) (xy 236.49051 -141.994636) (xy 236.483144 -141.991588) (xy 236.473492 -141.987524)
			(xy 236.445298 -141.987524) (xy 236.438029 -141.987756) (xy 236.424091 -141.99189) (xy 236.417866 -141.995652)
			(xy 236.353096 -142.037054) (xy 236.34934 -142.039571) (xy 236.342698 -142.045704) (xy 236.339888 -142.049246)
			(xy 236.339888 -143.222218) (xy 236.339363 -143.248243) (xy 236.331201 -143.29965) (xy 236.315112 -143.349151)
			(xy 236.291491 -143.395533) (xy 236.260916 -143.437657) (xy 236.24286 -143.456406) (xy 235.033566 -144.6657)
			(xy 235.033127 -144.669243) (xy 235.033129 -144.676381) (xy 235.033566 -144.679924) (xy 235.921296 -145.567654)
			(xy 235.939329 -145.586425) (xy 235.969911 -145.628541) (xy 235.99354 -145.674917) (xy 236.009637 -145.724414)
			(xy 236.017805 -145.775818) (xy 236.018324 -145.801842) (xy 236.018324 -159.639) (xy 236.017793 -159.665022)
			(xy 236.009619 -159.716421) (xy 235.993518 -159.765912) (xy 235.969885 -159.812282) (xy 235.939302 -159.854393)
			(xy 235.921296 -159.873188) (xy 234.723686 -161.070798) (xy 234.719513 -161.075149) (xy 234.71321 -161.085421)
			(xy 234.71124 -161.091118) (xy 234.71124 -161.091372) (xy 234.702804 -161.116929) (xy 234.679751 -161.165561)
			(xy 234.650093 -161.210472) (xy 234.614419 -161.250769) (xy 234.573436 -161.285653) (xy 234.527958 -161.314433)
			(xy 234.478887 -161.336537) (xy 234.427197 -161.351526) (xy 234.373914 -161.359103) (xy 234.347004 -161.359596)
			(xy 234.319751 -161.359133) (xy 234.265801 -161.351376) (xy 234.213503 -161.336021) (xy 234.163923 -161.313378)
			(xy 234.11807 -161.28391) (xy 234.076878 -161.248216) (xy 234.041185 -161.207023) (xy 234.011718 -161.16117)
			(xy 233.989077 -161.11159) (xy 233.973722 -161.059292) (xy 233.965967 -161.005341) (xy 233.965496 -160.978088)
			(xy 233.965958 -160.951188) (xy 233.973518 -160.897922) (xy 233.988486 -160.846246) (xy 234.010566 -160.797186)
			(xy 234.03932 -160.751715) (xy 234.074176 -160.710734) (xy 234.114445 -160.675056) (xy 234.159326 -160.64539)
			(xy 234.20793 -160.622323) (xy 234.233466 -160.613852) (xy 234.233974 -160.613852) (xy 234.239635 -160.611805)
			(xy 234.249896 -160.605516) (xy 234.254294 -160.601406) (xy 235.342684 -159.513016) (xy 235.343192 -159.505904)
			(xy 235.343192 -156.020516) (xy 235.343039 -156.015281) (xy 235.34087 -156.005037) (xy 235.338874 -156.000196)
			(xy 235.334302 -155.990036) (xy 235.269532 -155.932378) (xy 235.265527 -155.928986) (xy 235.256436 -155.923744)
			(xy 235.251498 -155.921964) (xy 235.241338 -155.918662) (xy 235.23067 -155.919678) (xy 235.196634 -155.92171)
			(xy 235.189522 -155.92171) (xy 235.16234 -155.921124) (xy 235.108552 -155.913197) (xy 235.056434 -155.897714)
			(xy 235.007042 -155.874989) (xy 234.961377 -155.845483) (xy 234.920363 -155.809792) (xy 234.884831 -155.76864)
			(xy 234.855502 -155.722861) (xy 234.832968 -155.673382) (xy 234.817687 -155.621205) (xy 234.809968 -155.567386)
			(xy 234.809538 -155.540202) (xy 234.810001 -155.51295) (xy 234.817758 -155.459002) (xy 234.833115 -155.406706)
			(xy 234.855758 -155.357129) (xy 234.885226 -155.311279) (xy 234.920921 -155.270089) (xy 234.962114 -155.2344)
			(xy 235.007967 -155.204936) (xy 235.057547 -155.182299) (xy 235.109845 -155.166949) (xy 235.163794 -155.159198)
			(xy 235.191046 -155.158694) (xy 235.213673 -155.158968) (xy 235.258623 -155.164183) (xy 235.280708 -155.169108)
			(xy 235.28655 -155.170378) (xy 235.297472 -155.170378) (xy 235.306753 -155.169022) (xy 235.323481 -155.160577)
			(xy 235.336058 -155.146685) (xy 235.342802 -155.129201) (xy 235.343192 -155.119832) (xy 235.343192 -155.071572)
			(xy 235.342803 -155.061989) (xy 235.335807 -155.044148) (xy 235.322761 -155.03011) (xy 235.305479 -155.021828)
			(xy 235.295948 -155.020772) (xy 235.288582 -155.020772) (xy 235.284518 -155.02128) (xy 235.280454 -155.022296)
			(xy 235.258434 -155.027232) (xy 235.21361 -155.032456) (xy 235.191046 -155.03271) (xy 235.163791 -155.03225)
			(xy 235.109835 -155.024498) (xy 235.057531 -155.009146) (xy 235.007945 -154.986506) (xy 234.962086 -154.95704)
			(xy 234.920888 -154.921346) (xy 234.885189 -154.880152) (xy 234.855717 -154.834297) (xy 234.833071 -154.784714)
			(xy 234.817712 -154.732412) (xy 234.809954 -154.678457) (xy 234.809538 -154.651202) (xy 234.810019 -154.624018)
			(xy 234.817735 -154.570202) (xy 234.833013 -154.518025) (xy 234.855542 -154.468546) (xy 234.884866 -154.422765)
			(xy 234.920391 -154.38161) (xy 234.961399 -154.345915) (xy 235.007058 -154.316401) (xy 235.056444 -154.293668)
			(xy 235.108556 -154.278174) (xy 235.16234 -154.270235) (xy 235.189522 -154.269694) (xy 235.191554 -154.269694)
			(xy 235.201351 -154.269762) (xy 235.220919 -154.270776) (xy 235.23067 -154.271726) (xy 235.241338 -154.272742)
			(xy 235.251498 -154.26944) (xy 235.256454 -154.2677) (xy 235.265551 -154.262453) (xy 235.269532 -154.259026)
			(xy 235.328206 -154.206956) (xy 235.331492 -154.203546) (xy 235.336863 -154.195749) (xy 235.338874 -154.191462)
			(xy 235.343192 -154.181556) (xy 235.343192 -145.934938) (xy 235.342684 -145.927826) (xy 234.464352 -145.049494)
			(xy 234.459999 -145.045325) (xy 234.449724 -145.039031) (xy 234.444032 -145.037048) (xy 234.443778 -145.037048)
			(xy 234.418217 -145.028626) (xy 234.369575 -145.005598) (xy 234.324653 -144.975961) (xy 234.284343 -144.940303)
			(xy 234.249446 -144.899333) (xy 234.220655 -144.853864) (xy 234.198541 -144.8048) (xy 234.183544 -144.753114)
			(xy 234.175962 -144.699833) (xy 234.175944 -144.646016) (xy 234.183492 -144.59273) (xy 234.198455 -144.541035)
			(xy 234.220537 -144.491956) (xy 234.249298 -144.446468) (xy 234.284168 -144.405475) (xy 234.324455 -144.369792)
			(xy 234.369357 -144.340125) (xy 234.417984 -144.317065) (xy 234.443524 -144.308576) (xy 234.444032 -144.308576)
			(xy 234.449696 -144.306534) (xy 234.459965 -144.300253) (xy 234.464352 -144.29613) (xy 235.661454 -143.099282)
			(xy 235.668303 -143.091885) (xy 235.676038 -143.073286) (xy 235.67644 -143.063214) (xy 235.67644 -126.233936)
			(xy 235.676023 -126.223884) (xy 235.668327 -126.205314) (xy 235.654098 -126.191114) (xy 235.644944 -126.186946)
			(xy 235.63072 -126.18085) (xy 235.600748 -126.186946) (xy 228.74859 -133.03885) (xy 228.741742 -133.046247)
			(xy 228.734011 -133.064846) (xy 228.733604 -133.074918) (xy 228.733604 -134.21487) (xy 228.73404 -134.224934)
			(xy 228.741773 -134.24352) (xy 228.74859 -134.250938) (xy 228.894894 -134.396988) (xy 228.917788 -134.420554)
			(xy 228.958736 -134.471939) (xy 228.993677 -134.527583) (xy 229.022173 -134.586787) (xy 229.043868 -134.648807)
			(xy 229.058487 -134.712864) (xy 229.065848 -134.778156) (xy 229.066344 -134.811008) (xy 229.066344 -134.811262)
			(xy 229.065797 -134.847537) (xy 229.056834 -134.919532) (xy 229.039052 -134.98987) (xy 229.012724 -135.057475)
			(xy 228.978253 -135.121313) (xy 228.936165 -135.180408) (xy 228.887104 -135.233856) (xy 228.859842 -135.257794)
			(xy 228.849174 -135.266684) (xy 228.847142 -135.271256) (xy 228.845247 -135.275485) (xy 228.842823 -135.284429)
			(xy 228.842316 -135.289036) (xy 228.839776 -135.354314) (xy 228.839823 -135.364093) (xy 228.846345 -135.382511)
			(xy 228.852476 -135.390128) (xy 228.854254 -135.391906) (xy 228.874688 -135.413455) (xy 228.909305 -135.461705)
			(xy 228.93603 -135.514735) (xy 228.954217 -135.571265) (xy 228.963428 -135.62993) (xy 228.963982 -135.659622)
			(xy 228.963517 -135.686873) (xy 228.955757 -135.74082) (xy 228.940399 -135.793114) (xy 228.917755 -135.84269)
			(xy 228.888286 -135.888538) (xy 228.852592 -135.929726) (xy 228.8114 -135.965415) (xy 228.765548 -135.994878)
			(xy 228.715969 -136.017516) (xy 228.663673 -136.032868) (xy 228.609725 -136.040621) (xy 228.582474 -136.04113)
			(xy 228.555926 -136.040671) (xy 228.503343 -136.033307) (xy 228.452289 -136.018725) (xy 228.403748 -135.997206)
			(xy 228.35866 -135.969166) (xy 228.317894 -135.935147) (xy 228.282237 -135.895804) (xy 228.252379 -135.851899)
			(xy 228.228895 -135.804279) (xy 228.212239 -135.753863) (xy 228.202733 -135.701624) (xy 228.20122 -135.675116)
			(xy 228.200966 -135.666988) (xy 228.200966 -135.659622) (xy 228.201364 -135.633986) (xy 228.208191 -135.58317)
			(xy 228.221751 -135.533724) (xy 228.2418 -135.486534) (xy 228.25456 -135.464296) (xy 228.255068 -135.463534)
			(xy 228.257647 -135.45906) (xy 228.2611 -135.449328) (xy 228.261926 -135.44423) (xy 228.263196 -135.434578)
			(xy 228.24059 -135.355584) (xy 228.227382 -135.339582) (xy 228.21773 -135.334756) (xy 228.189972 -135.320388)
			(xy 228.1374 -135.286575) (xy 228.088737 -135.247344) (xy 228.066346 -135.225536) (xy 227.733606 -134.892796)
			(xy 227.710712 -134.86923) (xy 227.669767 -134.817844) (xy 227.634827 -134.7622) (xy 227.606332 -134.702996)
			(xy 227.584639 -134.640976) (xy 227.570021 -134.576919) (xy 227.562662 -134.511628) (xy 227.562156 -134.478776)
			(xy 227.562156 -133.595618) (xy 227.561734 -133.585572) (xy 227.554028 -133.567018) (xy 227.539789 -133.552843)
			(xy 227.53066 -133.548628) (xy 227.516436 -133.542532) (xy 227.486464 -133.548628) (xy 225.627438 -135.407654)
			(xy 225.620596 -135.415054) (xy 225.612875 -135.433652) (xy 225.612452 -135.443722) (xy 225.612452 -135.659622)
			(xy 226.422456 -135.659622) (xy 226.426527 -135.604) (xy 226.438653 -135.549563) (xy 226.458576 -135.497472)
			(xy 226.485872 -135.448837) (xy 226.519958 -135.404694) (xy 226.560107 -135.365985) (xy 226.605465 -135.333534)
			(xy 226.655065 -135.308033) (xy 226.707849 -135.290026) (xy 226.762692 -135.279896) (xy 226.818426 -135.277859)
			(xy 226.873863 -135.283959) (xy 226.92782 -135.298065) (xy 226.979149 -135.319877) (xy 227.026755 -135.348931)
			(xy 227.069623 -135.384606) (xy 227.10684 -135.426143) (xy 227.137613 -135.472656) (xy 227.161285 -135.523153)
			(xy 227.177353 -135.57656) (xy 227.185473 -135.631736) (xy 227.185982 -135.659622) (xy 227.185473 -135.687508)
			(xy 227.177353 -135.742684) (xy 227.161285 -135.796091) (xy 227.137613 -135.846588) (xy 227.10684 -135.893101)
			(xy 227.069623 -135.934638) (xy 227.026755 -135.970313) (xy 226.979149 -135.999367) (xy 226.92782 -136.021179)
			(xy 226.873863 -136.035285) (xy 226.818426 -136.041385) (xy 226.762692 -136.039348) (xy 226.707849 -136.029218)
			(xy 226.655065 -136.011211) (xy 226.605465 -135.98571) (xy 226.560107 -135.953259) (xy 226.519958 -135.91455)
			(xy 226.485872 -135.870407) (xy 226.458576 -135.821772) (xy 226.438653 -135.769681) (xy 226.426527 -135.715244)
			(xy 226.422456 -135.659622) (xy 225.612452 -135.659622) (xy 225.611956 -135.693722) (xy 225.604039 -135.761462)
			(xy 225.58831 -135.827825) (xy 225.564984 -135.891913) (xy 225.534376 -135.952859) (xy 225.496899 -136.00984)
			(xy 225.45306 -136.062085) (xy 225.403453 -136.108888) (xy 225.348747 -136.149614) (xy 225.289683 -136.183715)
			(xy 225.22706 -136.210728) (xy 225.161724 -136.230288) (xy 225.09456 -136.242131) (xy 225.026474 -136.246097)
			(xy 224.958388 -136.242131) (xy 224.891224 -136.230288) (xy 224.825888 -136.210728) (xy 224.763265 -136.183715)
			(xy 224.704201 -136.149614) (xy 224.649495 -136.108888) (xy 224.599888 -136.062085) (xy 224.556049 -136.00984)
			(xy 224.518572 -135.952859) (xy 224.487964 -135.891913) (xy 224.464638 -135.827825) (xy 224.448909 -135.761462)
			(xy 224.440992 -135.693722) (xy 224.440496 -135.659622) (xy 224.440496 -135.18007) (xy 224.440974 -135.147192)
			(xy 224.448366 -135.081853) (xy 224.463019 -135.017751) (xy 224.484751 -134.955689) (xy 224.513287 -134.896448)
			(xy 224.548271 -134.840771) (xy 224.589263 -134.789356) (xy 224.6122 -134.765796) (xy 238.599726 -120.77827)
			(xy 238.606558 -120.770907) (xy 238.614313 -120.752393) (xy 238.614376 -120.732321) (xy 238.610902 -120.722898)
			(xy 238.60506 -120.708674) (xy 238.57966 -120.691656) (xy 236.147356 -120.691656) (xy 236.137291 -120.692089)
			(xy 236.118703 -120.699821) (xy 236.111288 -120.706642) (xy 235.933996 -120.883934) (xy 235.933087 -120.892711)
			(xy 235.936591 -120.909991) (xy 235.940854 -120.917716) (xy 235.956856 -120.943116) (xy 235.956856 -120.943624)
			(xy 235.961936 -120.953784) (xy 235.968286 -120.972834) (xy 235.970547 -120.978724) (xy 235.977487 -120.989256)
			(xy 235.982002 -120.993662) (xy 235.984034 -120.99544) (xy 236.003592 -121.011442) (xy 236.015022 -121.018554)
			(xy 236.020864 -121.021094) (xy 236.027722 -121.022364) (xy 236.054151 -121.027183) (xy 236.105408 -121.043266)
			(xy 236.153902 -121.06638) (xy 236.198674 -121.096069) (xy 236.238839 -121.131745) (xy 236.273601 -121.172703)
			(xy 236.302274 -121.218133) (xy 236.324291 -121.267135) (xy 236.339215 -121.318742) (xy 236.346753 -121.371931)
			(xy 236.347254 -121.398792) (xy 236.346769 -121.426045) (xy 236.339013 -121.479996) (xy 236.323659 -121.532294)
			(xy 236.301019 -121.581875) (xy 236.271554 -121.62773) (xy 236.235863 -121.668925) (xy 236.194673 -121.704622)
			(xy 236.148823 -121.734094) (xy 236.099245 -121.756741) (xy 236.046949 -121.772102) (xy 235.992999 -121.779865)
			(xy 235.965746 -121.7803) (xy 235.938862 -121.779844) (xy 235.885626 -121.772305) (xy 235.833975 -121.75737)
			(xy 235.784931 -121.735334) (xy 235.739465 -121.706634) (xy 235.698476 -121.671837) (xy 235.662776 -121.631633)
			(xy 235.633071 -121.586816) (xy 235.60995 -121.538275) (xy 235.593869 -121.486968) (xy 235.589064 -121.460514)
			(xy 235.588048 -121.453656) (xy 235.58246 -121.441718) (xy 235.575856 -121.43359) (xy 235.561124 -121.415556)
			(xy 235.557117 -121.411229) (xy 235.547493 -121.40442) (xy 235.542074 -121.402094) (xy 235.463842 -121.375424)
			(xy 235.458848 -121.374256) (xy 235.448607 -121.37374) (xy 235.443522 -121.374408) (xy 235.326428 -121.491502)
			(xy 235.322253 -121.495851) (xy 235.315945 -121.506122) (xy 235.313982 -121.511822) (xy 235.313982 -121.512076)
			(xy 235.305546 -121.537635) (xy 235.282494 -121.586269) (xy 235.252837 -121.631183) (xy 235.217163 -121.671483)
			(xy 235.176181 -121.706372) (xy 235.130703 -121.735156) (xy 235.081632 -121.757264) (xy 235.029941 -121.772259)
			(xy 234.976657 -121.779841) (xy 234.949746 -121.7803) (xy 234.922491 -121.77984) (xy 234.868536 -121.772088)
			(xy 234.816233 -121.756736) (xy 234.766647 -121.734096) (xy 234.720789 -121.704629) (xy 234.679592 -121.668935)
			(xy 234.643894 -121.627741) (xy 234.614422 -121.581886) (xy 234.591777 -121.532303) (xy 234.57642 -121.480001)
			(xy 234.568663 -121.426047) (xy 234.568238 -121.398792) (xy 234.568699 -121.371891) (xy 234.576258 -121.318622)
			(xy 234.591225 -121.266944) (xy 234.613303 -121.21788) (xy 234.642055 -121.172405) (xy 234.67691 -121.131419)
			(xy 234.717176 -121.095736) (xy 234.762056 -121.066063) (xy 234.810659 -121.042989) (xy 234.836208 -121.034556)
			(xy 234.836716 -121.034556) (xy 234.84238 -121.032514) (xy 234.85265 -121.026234) (xy 234.857036 -121.02211)
			(xy 235.754164 -120.124982) (xy 235.772945 -120.106871) (xy 235.815144 -120.076191) (xy 235.861625 -120.052495)
			(xy 235.911243 -120.036369) (xy 235.962774 -120.02821) (xy 235.98886 -120.0277) (xy 238.561626 -120.0277)
			(xy 238.571694 -120.027272) (xy 238.590292 -120.019551) (xy 238.597694 -120.012714) (xy 239.48009 -119.130572)
			(xy 239.486933 -119.123172) (xy 239.494659 -119.104574) (xy 239.495076 -119.094504) (xy 239.495076 -113.672874)
			(xy 239.495602 -113.64685) (xy 239.503766 -113.595445) (xy 239.519858 -113.545946) (xy 239.543484 -113.499568)
			(xy 239.574063 -113.457449) (xy 239.592104 -113.438686) (xy 239.67313 -113.35766) (xy 239.679978 -113.350263)
			(xy 239.687709 -113.331664) (xy 239.688116 -113.321592) (xy 239.688116 -113.240058) (xy 239.688672 -113.212119)
			(xy 239.698253 -113.15707) (xy 239.707166 -113.130584) (xy 239.715556 -113.108618) (xy 239.737787 -113.067187)
			(xy 239.765799 -113.029423) (xy 239.782096 -113.012474) (xy 243.27485 -109.519466) (xy 243.276628 -109.51718)
			(xy 243.276628 -105.579672) (xy 243.276201 -105.569603) (xy 243.268482 -105.551004) (xy 243.261642 -105.543604)
			(xy 237.007908 -99.28987) (xy 237.000513 -99.283015) (xy 236.981915 -99.275266) (xy 236.97184 -99.274884)
			(xy 226.604576 -99.274884) (xy 226.601127 -99.277588) (xy 226.59513 -99.283978) (xy 226.592638 -99.287584)
			(xy 226.582478 -99.303586) (xy 226.551236 -99.35337) (xy 226.547604 -99.35957) (xy 226.543612 -99.373367)
			(xy 226.543362 -99.380548) (xy 226.543362 -99.410012) (xy 226.547934 -99.420172) (xy 226.558684 -99.445019)
			(xy 226.573847 -99.49699) (xy 226.581501 -99.550583) (xy 226.58197 -99.577652) (xy 226.581484 -99.604903)
			(xy 226.573728 -99.658851) (xy 226.558373 -99.711146) (xy 226.535731 -99.760723) (xy 226.506265 -99.806573)
			(xy 226.470574 -99.847764) (xy 226.429383 -99.883455) (xy 226.383533 -99.912921) (xy 226.333956 -99.935563)
			(xy 226.281661 -99.950918) (xy 226.227713 -99.958674) (xy 226.173211 -99.958674) (xy 226.119263 -99.950918)
			(xy 226.066968 -99.935563) (xy 226.017391 -99.912921) (xy 225.971541 -99.883455) (xy 225.93035 -99.847764)
			(xy 225.894659 -99.806573) (xy 225.865193 -99.760723) (xy 225.842551 -99.711146) (xy 225.827196 -99.658851)
			(xy 225.81944 -99.604903) (xy 225.818954 -99.577652) (xy 225.818954 -99.577398) (xy 225.81948 -99.548547)
			(xy 225.828175 -99.491503) (xy 225.84538 -99.436425) (xy 225.857562 -99.410266) (xy 225.860241 -99.404347)
			(xy 225.862812 -99.391615) (xy 225.862642 -99.38512) (xy 225.86188 -99.372928) (xy 225.808032 -99.287076)
			(xy 225.80558 -99.28361) (xy 225.799712 -99.277474) (xy 225.796348 -99.274884) (xy 225.3361 -99.274884)
			(xy 225.310013 -99.274398) (xy 225.258481 -99.266232) (xy 225.208862 -99.250101) (xy 225.162379 -99.226402)
			(xy 225.120179 -99.19572) (xy 225.101404 -99.177602) (xy 223.614234 -97.690432) (xy 223.609882 -97.686261)
			(xy 223.599607 -97.679966) (xy 223.593914 -97.677986) (xy 223.59366 -97.677986) (xy 223.568099 -97.669552)
			(xy 223.51946 -97.646503) (xy 223.474543 -97.616848) (xy 223.434238 -97.581175) (xy 223.399346 -97.540193)
			(xy 223.370558 -97.494714) (xy 223.348447 -97.445642) (xy 223.33345 -97.393949) (xy 223.325866 -97.340662)
			(xy 223.325436 -97.31375) (xy 223.325896 -97.286496) (xy 223.333647 -97.232542) (xy 223.349 -97.180241)
			(xy 223.37164 -97.130657) (xy 223.401107 -97.084801) (xy 223.436801 -97.043606) (xy 223.477996 -97.007911)
			(xy 223.523852 -96.978443) (xy 223.573435 -96.955802) (xy 223.625736 -96.940449) (xy 223.67969 -96.932696)
			(xy 223.706944 -96.932242) (xy 223.733844 -96.932706) (xy 223.787109 -96.940269) (xy 223.838783 -96.955239)
			(xy 223.887842 -96.97732) (xy 223.933313 -97.006073) (xy 223.974295 -97.040928) (xy 224.009974 -97.081195)
			(xy 224.039642 -97.126074) (xy 224.062713 -97.174675) (xy 224.07118 -97.200212) (xy 224.07118 -97.20072)
			(xy 224.073224 -97.206383) (xy 224.079508 -97.216649) (xy 224.083626 -97.22104) (xy 225.458528 -98.595942)
			(xy 225.465925 -98.60279) (xy 225.484524 -98.610524) (xy 225.494596 -98.610928) (xy 225.935286 -98.610928)
			(xy 225.942652 -98.60407) (xy 225.962972 -98.579178) (xy 225.993706 -98.541332) (xy 225.999623 -98.533297)
			(xy 226.005389 -98.514213) (xy 226.004882 -98.504248) (xy 226.004374 -98.499676) (xy 226.003866 -98.497136)
			(xy 226.000269 -98.478228) (xy 225.996451 -98.439928) (xy 225.996246 -98.420682) (xy 225.996246 -98.419158)
			(xy 225.996785 -98.39344) (xy 226.003931 -98.342499) (xy 226.017857 -98.292981) (xy 226.038312 -98.245783)
			(xy 226.064924 -98.201762) (xy 226.09721 -98.161717) (xy 226.134585 -98.126374) (xy 226.15525 -98.111056)
			(xy 226.162611 -98.105261) (xy 226.172911 -98.08963) (xy 226.175316 -98.080576) (xy 226.176332 -98.073718)
			(xy 226.179888 -98.031046) (xy 226.180172 -98.019988) (xy 226.172395 -97.999306) (xy 226.164902 -97.991168)
			(xy 226.089464 -97.91573) (xy 226.066517 -97.892176) (xy 226.025495 -97.840778) (xy 225.99049 -97.785107)
			(xy 225.961943 -97.725865) (xy 225.940213 -97.663797) (xy 225.925574 -97.599685) (xy 225.918211 -97.534337)
			(xy 225.91776 -97.501456) (xy 225.91776 -97.324418) (xy 225.917321 -97.314355) (xy 225.909581 -97.295776)
			(xy 225.902774 -97.28835) (xy 224.007934 -95.39351) (xy 223.98385 -95.368681) (xy 223.941069 -95.314322)
			(xy 223.904981 -95.255308) (xy 223.890078 -95.224092) (xy 223.889062 -95.22206) (xy 223.87374 -95.191347)
			(xy 223.849691 -95.12706) (xy 223.833462 -95.060368) (xy 223.825283 -94.992219) (xy 223.8248 -94.9579)
			(xy 223.8248 -88.37041) (xy 223.825324 -88.335621) (xy 223.833708 -88.26655) (xy 223.850354 -88.198992)
			(xy 223.875019 -88.133933) (xy 223.907345 -88.07232) (xy 223.946861 -88.015052) (xy 223.992989 -87.962963)
			(xy 224.045058 -87.916812) (xy 224.10231 -87.877273) (xy 224.163909 -87.84492) (xy 224.228957 -87.820227)
			(xy 224.296508 -87.803552) (xy 224.365575 -87.795139) (xy 224.400364 -87.794592) (xy 224.432847 -87.795042)
			(xy 224.497399 -87.802364) (xy 224.560717 -87.816908) (xy 224.621994 -87.838488) (xy 224.680452 -87.86683)
			(xy 224.735347 -87.901575) (xy 224.78598 -87.942279) (xy 224.831709 -87.988425) (xy 224.871951 -88.039427)
			(xy 224.906195 -88.094635) (xy 224.920556 -88.123776) (xy 224.923355 -88.129322) (xy 224.931188 -88.13896)
			(xy 224.93605 -88.142826) (xy 224.940876 -88.146636) (xy 224.951798 -88.151208) (xy 225.00082 -88.15959)
			(xy 225.042222 -88.166448) (xy 225.053816 -88.167341) (xy 225.075785 -88.159796) (xy 225.084386 -88.15197)
			(xy 225.168206 -88.06815) (xy 225.173402 -88.0624) (xy 225.180376 -88.048567) (xy 225.181922 -88.040972)
			(xy 225.182684 -88.03259) (xy 225.182684 -87.932514) (xy 225.183208 -87.897724) (xy 225.191591 -87.828652)
			(xy 225.208236 -87.761094) (xy 225.232902 -87.696033) (xy 225.265227 -87.634419) (xy 225.304742 -87.577149)
			(xy 225.350871 -87.525059) (xy 225.40294 -87.478907) (xy 225.460191 -87.439365) (xy 225.52179 -87.407011)
			(xy 225.586839 -87.382316) (xy 225.65439 -87.365639) (xy 225.723459 -87.357224) (xy 225.758248 -87.356696)
			(xy 225.758756 -87.356696) (xy 225.772877 -87.356789) (xy 225.801083 -87.358187) (xy 225.815144 -87.35949)
			(xy 225.825812 -87.360506) (xy 225.846132 -87.353902) (xy 225.91014 -87.296244) (xy 225.91781 -87.288731)
			(xy 225.926514 -87.269126) (xy 225.926904 -87.258398) (xy 225.926904 -86.298278) (xy 225.926477 -86.28821)
			(xy 225.918757 -86.269611) (xy 225.911918 -86.26221) (xy 225.825558 -86.17585) (xy 225.808002 -86.157636)
			(xy 225.778263 -86.116713) (xy 225.755299 -86.071639) (xy 225.739674 -86.023526) (xy 225.731775 -85.97356)
			(xy 225.731324 -85.948266) (xy 225.731324 -85.191346) (xy 225.731823 -85.166057) (xy 225.739737 -85.116102)
			(xy 225.755363 -85.067998) (xy 225.778316 -85.022928) (xy 225.808032 -84.982) (xy 225.825558 -84.963762)
			(xy 225.911918 -84.877402) (xy 225.918773 -84.870007) (xy 225.926522 -84.851409) (xy 225.926904 -84.841334)
			(xy 225.926904 -74.469244) (xy 225.926492 -74.459217) (xy 225.91883 -74.440684) (xy 225.904656 -74.426497)
			(xy 225.886131 -74.418817) (xy 225.876104 -74.418444) (xy 225.01098 -74.418444) (xy 225.004969 -74.418607)
			(xy 224.993282 -74.421422) (xy 224.987866 -74.424032) (xy 224.984393 -74.425873) (xy 224.978018 -74.43047)
			(xy 224.975166 -74.433176) (xy 224.886012 -74.52233) (xy 224.883308 -74.525183) (xy 224.878721 -74.531564)
			(xy 224.876868 -74.53503) (xy 224.874285 -74.540457) (xy 224.87146 -74.552136) (xy 224.87128 -74.558144)
			(xy 224.87128 -76.08316) (xy 224.875344 -76.092558) (xy 224.884742 -76.116057) (xy 224.897969 -76.16491)
			(xy 224.904641 -76.21508) (xy 224.905062 -76.240386) (xy 224.905062 -76.241148) (xy 224.904572 -76.268396)
			(xy 224.89681 -76.322336) (xy 224.88145 -76.374622) (xy 224.858806 -76.42419) (xy 224.829338 -76.470031)
			(xy 224.793645 -76.511212) (xy 224.752456 -76.546894) (xy 224.706608 -76.576351) (xy 224.657034 -76.598983)
			(xy 224.604744 -76.61433) (xy 224.550802 -76.622079) (xy 224.523554 -76.622656) (xy 224.495694 -76.622147)
			(xy 224.440567 -76.61404) (xy 224.387205 -76.598005) (xy 224.33674 -76.574383) (xy 224.290245 -76.543676)
			(xy 224.248708 -76.506536) (xy 224.230438 -76.485496) (xy 224.225866 -76.479908) (xy 224.206562 -76.47051)
			(xy 224.121472 -76.467208) (xy 224.110909 -76.467264) (xy 224.091233 -76.474882) (xy 224.083372 -76.48194)
			(xy 223.67113 -76.894436) (xy 223.666957 -76.898786) (xy 223.660656 -76.90906) (xy 223.658684 -76.914756)
			(xy 223.658684 -76.91501) (xy 223.649561 -76.942511) (xy 223.624178 -76.994594) (xy 223.591214 -77.042242)
			(xy 223.551426 -77.084359) (xy 223.505728 -77.119978) (xy 223.455172 -77.148279) (xy 223.400918 -77.168614)
			(xy 223.37268 -77.175106) (xy 223.372426 -77.175106) (xy 223.36415 -77.177153) (xy 223.349534 -77.185908)
			(xy 223.338614 -77.198985) (xy 223.335342 -77.206856) (xy 223.300544 -77.299312) (xy 223.3041 -77.324712)
			(xy 223.308164 -77.3303) (xy 223.323175 -77.350412) (xy 223.348354 -77.393825) (xy 223.36763 -77.440162)
			(xy 223.380669 -77.488625) (xy 223.387247 -77.538379) (xy 223.387666 -77.563472) (xy 224.659188 -77.563472)
			(xy 224.663259 -77.50785) (xy 224.675385 -77.453413) (xy 224.695308 -77.401322) (xy 224.722604 -77.352687)
			(xy 224.75669 -77.308544) (xy 224.796839 -77.269835) (xy 224.842197 -77.237384) (xy 224.891797 -77.211883)
			(xy 224.944581 -77.193876) (xy 224.999424 -77.183746) (xy 225.055158 -77.181709) (xy 225.110595 -77.187809)
			(xy 225.164552 -77.201915) (xy 225.215881 -77.223727) (xy 225.263487 -77.252781) (xy 225.306355 -77.288456)
			(xy 225.343572 -77.329993) (xy 225.374345 -77.376506) (xy 225.398017 -77.427003) (xy 225.414085 -77.48041)
			(xy 225.422205 -77.535586) (xy 225.422714 -77.563472) (xy 225.422205 -77.591358) (xy 225.414085 -77.646534)
			(xy 225.398017 -77.699941) (xy 225.374345 -77.750438) (xy 225.343572 -77.796951) (xy 225.306355 -77.838488)
			(xy 225.263487 -77.874163) (xy 225.215881 -77.903217) (xy 225.164552 -77.925029) (xy 225.110595 -77.939135)
			(xy 225.055158 -77.945235) (xy 224.999424 -77.943198) (xy 224.944581 -77.933068) (xy 224.891797 -77.915061)
			(xy 224.842197 -77.88956) (xy 224.796839 -77.857109) (xy 224.75669 -77.8184) (xy 224.722604 -77.774257)
			(xy 224.695308 -77.725622) (xy 224.675385 -77.673531) (xy 224.663259 -77.619094) (xy 224.659188 -77.563472)
			(xy 223.387666 -77.563472) (xy 223.38718 -77.590723) (xy 223.379424 -77.644671) (xy 223.364069 -77.696966)
			(xy 223.341427 -77.746543) (xy 223.311961 -77.792393) (xy 223.27627 -77.833584) (xy 223.235079 -77.869275)
			(xy 223.189229 -77.898741) (xy 223.139652 -77.921383) (xy 223.087357 -77.936738) (xy 223.033409 -77.944494)
			(xy 222.978907 -77.944494) (xy 222.924959 -77.936738) (xy 222.872664 -77.921383) (xy 222.823087 -77.898741)
			(xy 222.777237 -77.869275) (xy 222.736046 -77.833584) (xy 222.700355 -77.792393) (xy 222.670889 -77.746543)
			(xy 222.648247 -77.696966) (xy 222.632892 -77.644671) (xy 222.625136 -77.590723) (xy 222.62465 -77.563472)
			(xy 222.62465 -77.548994) (xy 222.626011 -77.523779) (xy 222.634558 -77.474011) (xy 222.649596 -77.425806)
			(xy 222.670861 -77.380005) (xy 222.684086 -77.358494) (xy 222.689928 -77.345794) (xy 222.696278 -77.324712)
			(xy 222.69586 -77.314691) (xy 222.688191 -77.296174) (xy 222.674018 -77.282003) (xy 222.655499 -77.274338)
			(xy 222.645478 -77.273912) (xy 222.636334 -77.274674) (xy 222.619028 -77.277668) (xy 222.584047 -77.280845)
			(xy 222.566484 -77.281024) (xy 222.537361 -77.280474) (xy 222.479792 -77.271628) (xy 222.424233 -77.254143)
			(xy 222.371973 -77.228425) (xy 222.34779 -77.21219) (xy 222.343382 -77.209279) (xy 222.333647 -77.205185)
			(xy 222.328486 -77.204062) (xy 222.246698 -77.28585) (xy 222.223133 -77.308745) (xy 222.171748 -77.349694)
			(xy 222.116105 -77.384637) (xy 222.056901 -77.413134) (xy 221.994881 -77.434829) (xy 221.930822 -77.449448)
			(xy 221.865531 -77.456808) (xy 221.832678 -77.4573) (xy 221.499684 -77.4573) (xy 221.4855 -77.457203)
			(xy 221.457167 -77.455804) (xy 221.443042 -77.454506) (xy 221.432122 -77.453998) (xy 221.411476 -77.461119)
			(xy 221.403164 -77.468222) (xy 221.381066 -77.48905) (xy 221.357444 -77.511656) (xy 221.353651 -77.515503)
			(xy 221.347625 -77.524467) (xy 221.345506 -77.529436) (xy 221.341696 -77.538834) (xy 221.34195 -77.55001)
			(xy 221.342204 -77.563218) (xy 221.342204 -77.563726) (xy 221.34195 -77.574648) (xy 221.34195 -77.575156)
			(xy 221.340636 -77.602567) (xy 221.331118 -77.656611) (xy 221.313956 -77.708734) (xy 221.289503 -77.757861)
			(xy 221.258265 -77.802977) (xy 221.220884 -77.843153) (xy 221.178134 -77.877558) (xy 221.130895 -77.905484)
			(xy 221.080143 -77.926354) (xy 221.05366 -77.93355) (xy 221.042738 -77.936344) (xy 221.034922 -77.938581)
			(xy 221.021185 -77.947259) (xy 221.015814 -77.953362) (xy 221.015052 -77.954378) (xy 221.015052 -78.579472)
			(xy 222.62414 -78.579472) (xy 222.628211 -78.52385) (xy 222.640337 -78.469413) (xy 222.66026 -78.417322)
			(xy 222.687556 -78.368687) (xy 222.721642 -78.324544) (xy 222.761791 -78.285835) (xy 222.807149 -78.253384)
			(xy 222.856749 -78.227883) (xy 222.909533 -78.209876) (xy 222.964376 -78.199746) (xy 223.02011 -78.197709)
			(xy 223.075547 -78.203809) (xy 223.129504 -78.217915) (xy 223.180833 -78.239727) (xy 223.228439 -78.268781)
			(xy 223.271307 -78.304456) (xy 223.308524 -78.345993) (xy 223.339297 -78.392506) (xy 223.362969 -78.443003)
			(xy 223.379037 -78.49641) (xy 223.387157 -78.551586) (xy 223.387666 -78.579472) (xy 224.659188 -78.579472)
			(xy 224.663259 -78.52385) (xy 224.675385 -78.469413) (xy 224.695308 -78.417322) (xy 224.722604 -78.368687)
			(xy 224.75669 -78.324544) (xy 224.796839 -78.285835) (xy 224.842197 -78.253384) (xy 224.891797 -78.227883)
			(xy 224.944581 -78.209876) (xy 224.999424 -78.199746) (xy 225.055158 -78.197709) (xy 225.110595 -78.203809)
			(xy 225.164552 -78.217915) (xy 225.215881 -78.239727) (xy 225.263487 -78.268781) (xy 225.306355 -78.304456)
			(xy 225.343572 -78.345993) (xy 225.374345 -78.392506) (xy 225.398017 -78.443003) (xy 225.414085 -78.49641)
			(xy 225.422205 -78.551586) (xy 225.422714 -78.579472) (xy 225.422205 -78.607358) (xy 225.414085 -78.662534)
			(xy 225.398017 -78.715941) (xy 225.374345 -78.766438) (xy 225.343572 -78.812951) (xy 225.306355 -78.854488)
			(xy 225.263487 -78.890163) (xy 225.215881 -78.919217) (xy 225.164552 -78.941029) (xy 225.110595 -78.955135)
			(xy 225.055158 -78.961235) (xy 224.999424 -78.959198) (xy 224.944581 -78.949068) (xy 224.891797 -78.931061)
			(xy 224.842197 -78.90556) (xy 224.796839 -78.873109) (xy 224.75669 -78.8344) (xy 224.722604 -78.790257)
			(xy 224.695308 -78.741622) (xy 224.675385 -78.689531) (xy 224.663259 -78.635094) (xy 224.659188 -78.579472)
			(xy 223.387666 -78.579472) (xy 223.387157 -78.607358) (xy 223.379037 -78.662534) (xy 223.362969 -78.715941)
			(xy 223.339297 -78.766438) (xy 223.308524 -78.812951) (xy 223.271307 -78.854488) (xy 223.228439 -78.890163)
			(xy 223.180833 -78.919217) (xy 223.129504 -78.941029) (xy 223.075547 -78.955135) (xy 223.02011 -78.961235)
			(xy 222.964376 -78.959198) (xy 222.909533 -78.949068) (xy 222.856749 -78.931061) (xy 222.807149 -78.90556)
			(xy 222.761791 -78.873109) (xy 222.721642 -78.8344) (xy 222.687556 -78.790257) (xy 222.66026 -78.741622)
			(xy 222.640337 -78.689531) (xy 222.628211 -78.635094) (xy 222.62414 -78.579472) (xy 221.015052 -78.579472)
			(xy 221.015052 -79.204312) (xy 221.01956 -79.210035) (xy 221.03117 -79.218825) (xy 221.037912 -79.221584)
			(xy 221.05366 -79.225394) (xy 221.08079 -79.232723) (xy 221.132695 -79.254258) (xy 221.180881 -79.283172)
			(xy 221.224306 -79.31884) (xy 221.26203 -79.360492) (xy 221.293237 -79.407225) (xy 221.317254 -79.45803)
			(xy 221.33356 -79.511808) (xy 221.341802 -79.567395) (xy 221.341802 -79.595472) (xy 222.62414 -79.595472)
			(xy 222.628211 -79.53985) (xy 222.640337 -79.485413) (xy 222.66026 -79.433322) (xy 222.687556 -79.384687)
			(xy 222.721642 -79.340544) (xy 222.761791 -79.301835) (xy 222.807149 -79.269384) (xy 222.856749 -79.243883)
			(xy 222.909533 -79.225876) (xy 222.964376 -79.215746) (xy 223.02011 -79.213709) (xy 223.075547 -79.219809)
			(xy 223.129504 -79.233915) (xy 223.180833 -79.255727) (xy 223.228439 -79.284781) (xy 223.271307 -79.320456)
			(xy 223.308524 -79.361993) (xy 223.339297 -79.408506) (xy 223.362969 -79.459003) (xy 223.379037 -79.51241)
			(xy 223.387157 -79.567586) (xy 223.387666 -79.595472) (xy 224.659188 -79.595472) (xy 224.663259 -79.53985)
			(xy 224.675385 -79.485413) (xy 224.695308 -79.433322) (xy 224.722604 -79.384687) (xy 224.75669 -79.340544)
			(xy 224.796839 -79.301835) (xy 224.842197 -79.269384) (xy 224.891797 -79.243883) (xy 224.944581 -79.225876)
			(xy 224.999424 -79.215746) (xy 225.055158 -79.213709) (xy 225.110595 -79.219809) (xy 225.164552 -79.233915)
			(xy 225.215881 -79.255727) (xy 225.263487 -79.284781) (xy 225.306355 -79.320456) (xy 225.343572 -79.361993)
			(xy 225.374345 -79.408506) (xy 225.398017 -79.459003) (xy 225.414085 -79.51241) (xy 225.422205 -79.567586)
			(xy 225.422714 -79.595472) (xy 225.422205 -79.623358) (xy 225.414085 -79.678534) (xy 225.398017 -79.731941)
			(xy 225.374345 -79.782438) (xy 225.343572 -79.828951) (xy 225.306355 -79.870488) (xy 225.263487 -79.906163)
			(xy 225.215881 -79.935217) (xy 225.164552 -79.957029) (xy 225.110595 -79.971135) (xy 225.055158 -79.977235)
			(xy 224.999424 -79.975198) (xy 224.944581 -79.965068) (xy 224.891797 -79.947061) (xy 224.842197 -79.92156)
			(xy 224.796839 -79.889109) (xy 224.75669 -79.8504) (xy 224.722604 -79.806257) (xy 224.695308 -79.757622)
			(xy 224.675385 -79.705531) (xy 224.663259 -79.651094) (xy 224.659188 -79.595472) (xy 223.387666 -79.595472)
			(xy 223.387157 -79.623358) (xy 223.379037 -79.678534) (xy 223.362969 -79.731941) (xy 223.339297 -79.782438)
			(xy 223.308524 -79.828951) (xy 223.271307 -79.870488) (xy 223.228439 -79.906163) (xy 223.180833 -79.935217)
			(xy 223.129504 -79.957029) (xy 223.075547 -79.971135) (xy 223.02011 -79.977235) (xy 222.964376 -79.975198)
			(xy 222.909533 -79.965068) (xy 222.856749 -79.947061) (xy 222.807149 -79.92156) (xy 222.761791 -79.889109)
			(xy 222.721642 -79.8504) (xy 222.687556 -79.806257) (xy 222.66026 -79.757622) (xy 222.640337 -79.705531)
			(xy 222.628211 -79.651094) (xy 222.62414 -79.595472) (xy 221.341802 -79.595472) (xy 221.341803 -79.623591)
			(xy 221.333563 -79.679179) (xy 221.317259 -79.732957) (xy 221.293244 -79.783763) (xy 221.262038 -79.830498)
			(xy 221.224316 -79.87215) (xy 221.180892 -79.90782) (xy 221.132707 -79.936736) (xy 221.080803 -79.958273)
			(xy 221.05366 -79.96555) (xy 221.042738 -79.968344) (xy 221.034922 -79.970581) (xy 221.021185 -79.979259)
			(xy 221.015814 -79.985362) (xy 221.015052 -79.986378) (xy 221.015052 -80.611472) (xy 222.62414 -80.611472)
			(xy 222.628211 -80.55585) (xy 222.640337 -80.501413) (xy 222.66026 -80.449322) (xy 222.687556 -80.400687)
			(xy 222.721642 -80.356544) (xy 222.761791 -80.317835) (xy 222.807149 -80.285384) (xy 222.856749 -80.259883)
			(xy 222.909533 -80.241876) (xy 222.964376 -80.231746) (xy 223.02011 -80.229709) (xy 223.075547 -80.235809)
			(xy 223.129504 -80.249915) (xy 223.180833 -80.271727) (xy 223.228439 -80.300781) (xy 223.271307 -80.336456)
			(xy 223.308524 -80.377993) (xy 223.339297 -80.424506) (xy 223.362969 -80.475003) (xy 223.379037 -80.52841)
			(xy 223.387157 -80.583586) (xy 223.387666 -80.611472) (xy 224.659188 -80.611472) (xy 224.663259 -80.55585)
			(xy 224.675385 -80.501413) (xy 224.695308 -80.449322) (xy 224.722604 -80.400687) (xy 224.75669 -80.356544)
			(xy 224.796839 -80.317835) (xy 224.842197 -80.285384) (xy 224.891797 -80.259883) (xy 224.944581 -80.241876)
			(xy 224.999424 -80.231746) (xy 225.055158 -80.229709) (xy 225.110595 -80.235809) (xy 225.164552 -80.249915)
			(xy 225.215881 -80.271727) (xy 225.263487 -80.300781) (xy 225.306355 -80.336456) (xy 225.343572 -80.377993)
			(xy 225.374345 -80.424506) (xy 225.398017 -80.475003) (xy 225.414085 -80.52841) (xy 225.422205 -80.583586)
			(xy 225.422714 -80.611472) (xy 225.422205 -80.639358) (xy 225.414085 -80.694534) (xy 225.398017 -80.747941)
			(xy 225.374345 -80.798438) (xy 225.343572 -80.844951) (xy 225.306355 -80.886488) (xy 225.263487 -80.922163)
			(xy 225.215881 -80.951217) (xy 225.164552 -80.973029) (xy 225.110595 -80.987135) (xy 225.055158 -80.993235)
			(xy 224.999424 -80.991198) (xy 224.944581 -80.981068) (xy 224.891797 -80.963061) (xy 224.842197 -80.93756)
			(xy 224.796839 -80.905109) (xy 224.75669 -80.8664) (xy 224.722604 -80.822257) (xy 224.695308 -80.773622)
			(xy 224.675385 -80.721531) (xy 224.663259 -80.667094) (xy 224.659188 -80.611472) (xy 223.387666 -80.611472)
			(xy 223.387157 -80.639358) (xy 223.379037 -80.694534) (xy 223.362969 -80.747941) (xy 223.339297 -80.798438)
			(xy 223.308524 -80.844951) (xy 223.271307 -80.886488) (xy 223.228439 -80.922163) (xy 223.180833 -80.951217)
			(xy 223.129504 -80.973029) (xy 223.075547 -80.987135) (xy 223.02011 -80.993235) (xy 222.964376 -80.991198)
			(xy 222.909533 -80.981068) (xy 222.856749 -80.963061) (xy 222.807149 -80.93756) (xy 222.761791 -80.905109)
			(xy 222.721642 -80.8664) (xy 222.687556 -80.822257) (xy 222.66026 -80.773622) (xy 222.640337 -80.721531)
			(xy 222.628211 -80.667094) (xy 222.62414 -80.611472) (xy 221.015052 -80.611472) (xy 221.015052 -81.236312)
			(xy 221.01956 -81.242035) (xy 221.03117 -81.250825) (xy 221.037912 -81.253584) (xy 221.05366 -81.257394)
			(xy 221.08079 -81.264723) (xy 221.132695 -81.286258) (xy 221.180881 -81.315172) (xy 221.224306 -81.35084)
			(xy 221.26203 -81.392492) (xy 221.293237 -81.439225) (xy 221.317254 -81.49003) (xy 221.33356 -81.543808)
			(xy 221.341802 -81.599395) (xy 221.341802 -81.627472) (xy 222.62414 -81.627472) (xy 222.628211 -81.57185)
			(xy 222.640337 -81.517413) (xy 222.66026 -81.465322) (xy 222.687556 -81.416687) (xy 222.721642 -81.372544)
			(xy 222.761791 -81.333835) (xy 222.807149 -81.301384) (xy 222.856749 -81.275883) (xy 222.909533 -81.257876)
			(xy 222.964376 -81.247746) (xy 223.02011 -81.245709) (xy 223.075547 -81.251809) (xy 223.129504 -81.265915)
			(xy 223.180833 -81.287727) (xy 223.228439 -81.316781) (xy 223.271307 -81.352456) (xy 223.308524 -81.393993)
			(xy 223.339297 -81.440506) (xy 223.362969 -81.491003) (xy 223.379037 -81.54441) (xy 223.387157 -81.599586)
			(xy 223.387666 -81.627472) (xy 224.650044 -81.627472) (xy 224.654115 -81.57185) (xy 224.666241 -81.517413)
			(xy 224.686164 -81.465322) (xy 224.71346 -81.416687) (xy 224.747546 -81.372544) (xy 224.787695 -81.333835)
			(xy 224.833053 -81.301384) (xy 224.882653 -81.275883) (xy 224.935437 -81.257876) (xy 224.99028 -81.247746)
			(xy 225.046014 -81.245709) (xy 225.101451 -81.251809) (xy 225.155408 -81.265915) (xy 225.206737 -81.287727)
			(xy 225.254343 -81.316781) (xy 225.297211 -81.352456) (xy 225.334428 -81.393993) (xy 225.365201 -81.440506)
			(xy 225.388873 -81.491003) (xy 225.404941 -81.54441) (xy 225.413061 -81.599586) (xy 225.41357 -81.627472)
			(xy 225.413061 -81.655358) (xy 225.404941 -81.710534) (xy 225.388873 -81.763941) (xy 225.365201 -81.814438)
			(xy 225.334428 -81.860951) (xy 225.297211 -81.902488) (xy 225.254343 -81.938163) (xy 225.206737 -81.967217)
			(xy 225.155408 -81.989029) (xy 225.101451 -82.003135) (xy 225.046014 -82.009235) (xy 224.99028 -82.007198)
			(xy 224.935437 -81.997068) (xy 224.882653 -81.979061) (xy 224.833053 -81.95356) (xy 224.787695 -81.921109)
			(xy 224.747546 -81.8824) (xy 224.71346 -81.838257) (xy 224.686164 -81.789622) (xy 224.666241 -81.737531)
			(xy 224.654115 -81.683094) (xy 224.650044 -81.627472) (xy 223.387666 -81.627472) (xy 223.387157 -81.655358)
			(xy 223.379037 -81.710534) (xy 223.362969 -81.763941) (xy 223.339297 -81.814438) (xy 223.308524 -81.860951)
			(xy 223.271307 -81.902488) (xy 223.228439 -81.938163) (xy 223.180833 -81.967217) (xy 223.129504 -81.989029)
			(xy 223.075547 -82.003135) (xy 223.02011 -82.009235) (xy 222.964376 -82.007198) (xy 222.909533 -81.997068)
			(xy 222.856749 -81.979061) (xy 222.807149 -81.95356) (xy 222.761791 -81.921109) (xy 222.721642 -81.8824)
			(xy 222.687556 -81.838257) (xy 222.66026 -81.789622) (xy 222.640337 -81.737531) (xy 222.628211 -81.683094)
			(xy 222.62414 -81.627472) (xy 221.341802 -81.627472) (xy 221.341803 -81.655591) (xy 221.333563 -81.711179)
			(xy 221.317259 -81.764957) (xy 221.293244 -81.815763) (xy 221.262038 -81.862498) (xy 221.224316 -81.90415)
			(xy 221.180892 -81.93982) (xy 221.132707 -81.968736) (xy 221.080803 -81.990273) (xy 221.05366 -81.99755)
			(xy 221.042738 -82.000344) (xy 221.034922 -82.002581) (xy 221.021185 -82.011259) (xy 221.015814 -82.017362)
			(xy 221.015052 -82.018378) (xy 221.015052 -82.643472) (xy 222.62414 -82.643472) (xy 222.628211 -82.58785)
			(xy 222.640337 -82.533413) (xy 222.66026 -82.481322) (xy 222.687556 -82.432687) (xy 222.721642 -82.388544)
			(xy 222.761791 -82.349835) (xy 222.807149 -82.317384) (xy 222.856749 -82.291883) (xy 222.909533 -82.273876)
			(xy 222.964376 -82.263746) (xy 223.02011 -82.261709) (xy 223.075547 -82.267809) (xy 223.129504 -82.281915)
			(xy 223.180833 -82.303727) (xy 223.228439 -82.332781) (xy 223.271307 -82.368456) (xy 223.308524 -82.409993)
			(xy 223.339297 -82.456506) (xy 223.362969 -82.507003) (xy 223.379037 -82.56041) (xy 223.387157 -82.615586)
			(xy 223.387666 -82.643472) (xy 224.650044 -82.643472) (xy 224.654115 -82.58785) (xy 224.666241 -82.533413)
			(xy 224.686164 -82.481322) (xy 224.71346 -82.432687) (xy 224.747546 -82.388544) (xy 224.787695 -82.349835)
			(xy 224.833053 -82.317384) (xy 224.882653 -82.291883) (xy 224.935437 -82.273876) (xy 224.99028 -82.263746)
			(xy 225.046014 -82.261709) (xy 225.101451 -82.267809) (xy 225.155408 -82.281915) (xy 225.206737 -82.303727)
			(xy 225.254343 -82.332781) (xy 225.297211 -82.368456) (xy 225.334428 -82.409993) (xy 225.365201 -82.456506)
			(xy 225.388873 -82.507003) (xy 225.404941 -82.56041) (xy 225.413061 -82.615586) (xy 225.41357 -82.643472)
			(xy 225.413061 -82.671358) (xy 225.404941 -82.726534) (xy 225.388873 -82.779941) (xy 225.365201 -82.830438)
			(xy 225.334428 -82.876951) (xy 225.297211 -82.918488) (xy 225.254343 -82.954163) (xy 225.206737 -82.983217)
			(xy 225.155408 -83.005029) (xy 225.101451 -83.019135) (xy 225.046014 -83.025235) (xy 224.99028 -83.023198)
			(xy 224.935437 -83.013068) (xy 224.882653 -82.995061) (xy 224.833053 -82.96956) (xy 224.787695 -82.937109)
			(xy 224.747546 -82.8984) (xy 224.71346 -82.854257) (xy 224.686164 -82.805622) (xy 224.666241 -82.753531)
			(xy 224.654115 -82.699094) (xy 224.650044 -82.643472) (xy 223.387666 -82.643472) (xy 223.387157 -82.671358)
			(xy 223.379037 -82.726534) (xy 223.362969 -82.779941) (xy 223.339297 -82.830438) (xy 223.308524 -82.876951)
			(xy 223.271307 -82.918488) (xy 223.228439 -82.954163) (xy 223.180833 -82.983217) (xy 223.129504 -83.005029)
			(xy 223.075547 -83.019135) (xy 223.02011 -83.025235) (xy 222.964376 -83.023198) (xy 222.909533 -83.013068)
			(xy 222.856749 -82.995061) (xy 222.807149 -82.96956) (xy 222.761791 -82.937109) (xy 222.721642 -82.8984)
			(xy 222.687556 -82.854257) (xy 222.66026 -82.805622) (xy 222.640337 -82.753531) (xy 222.628211 -82.699094)
			(xy 222.62414 -82.643472) (xy 221.015052 -82.643472) (xy 221.015052 -83.104228) (xy 221.019561 -83.10995)
			(xy 221.031172 -83.118738) (xy 221.037912 -83.1215) (xy 221.05366 -83.12531) (xy 221.080788 -83.132639)
			(xy 221.132692 -83.154173) (xy 221.180876 -83.183087) (xy 221.224298 -83.218754) (xy 221.26202 -83.260404)
			(xy 221.293226 -83.307136) (xy 221.317241 -83.357939) (xy 221.333545 -83.411715) (xy 221.341787 -83.4673)
			(xy 221.341787 -83.523494) (xy 221.333547 -83.579079) (xy 221.317243 -83.632855) (xy 221.304662 -83.659472)
			(xy 222.62414 -83.659472) (xy 222.628211 -83.60385) (xy 222.640337 -83.549413) (xy 222.66026 -83.497322)
			(xy 222.687556 -83.448687) (xy 222.721642 -83.404544) (xy 222.761791 -83.365835) (xy 222.807149 -83.333384)
			(xy 222.856749 -83.307883) (xy 222.909533 -83.289876) (xy 222.964376 -83.279746) (xy 223.02011 -83.277709)
			(xy 223.075547 -83.283809) (xy 223.129504 -83.297915) (xy 223.180833 -83.319727) (xy 223.228439 -83.348781)
			(xy 223.271307 -83.384456) (xy 223.308524 -83.425993) (xy 223.339297 -83.472506) (xy 223.362969 -83.523003)
			(xy 223.379037 -83.57641) (xy 223.387157 -83.631586) (xy 223.387666 -83.659472) (xy 224.650044 -83.659472)
			(xy 224.654115 -83.60385) (xy 224.666241 -83.549413) (xy 224.686164 -83.497322) (xy 224.71346 -83.448687)
			(xy 224.747546 -83.404544) (xy 224.787695 -83.365835) (xy 224.833053 -83.333384) (xy 224.882653 -83.307883)
			(xy 224.935437 -83.289876) (xy 224.99028 -83.279746) (xy 225.046014 -83.277709) (xy 225.101451 -83.283809)
			(xy 225.155408 -83.297915) (xy 225.206737 -83.319727) (xy 225.254343 -83.348781) (xy 225.297211 -83.384456)
			(xy 225.334428 -83.425993) (xy 225.365201 -83.472506) (xy 225.388873 -83.523003) (xy 225.404941 -83.57641)
			(xy 225.413061 -83.631586) (xy 225.41357 -83.659472) (xy 225.413061 -83.687358) (xy 225.404941 -83.742534)
			(xy 225.388873 -83.795941) (xy 225.365201 -83.846438) (xy 225.334428 -83.892951) (xy 225.297211 -83.934488)
			(xy 225.254343 -83.970163) (xy 225.206737 -83.999217) (xy 225.155408 -84.021029) (xy 225.101451 -84.035135)
			(xy 225.046014 -84.041235) (xy 224.99028 -84.039198) (xy 224.935437 -84.029068) (xy 224.882653 -84.011061)
			(xy 224.833053 -83.98556) (xy 224.787695 -83.953109) (xy 224.747546 -83.9144) (xy 224.71346 -83.870257)
			(xy 224.686164 -83.821622) (xy 224.666241 -83.769531) (xy 224.654115 -83.715094) (xy 224.650044 -83.659472)
			(xy 223.387666 -83.659472) (xy 223.387157 -83.687358) (xy 223.379037 -83.742534) (xy 223.362969 -83.795941)
			(xy 223.339297 -83.846438) (xy 223.308524 -83.892951) (xy 223.271307 -83.934488) (xy 223.228439 -83.970163)
			(xy 223.180833 -83.999217) (xy 223.129504 -84.021029) (xy 223.075547 -84.035135) (xy 223.02011 -84.041235)
			(xy 222.964376 -84.039198) (xy 222.909533 -84.029068) (xy 222.856749 -84.011061) (xy 222.807149 -83.98556)
			(xy 222.761791 -83.953109) (xy 222.721642 -83.9144) (xy 222.687556 -83.870257) (xy 222.66026 -83.821622)
			(xy 222.640337 -83.769531) (xy 222.628211 -83.715094) (xy 222.62414 -83.659472) (xy 221.304662 -83.659472)
			(xy 221.293229 -83.683659) (xy 221.262024 -83.730391) (xy 221.224302 -83.772042) (xy 221.18088 -83.80771)
			(xy 221.132697 -83.836624) (xy 221.080794 -83.858159) (xy 221.05366 -83.865466) (xy 221.042738 -83.86826)
			(xy 221.034922 -83.870498) (xy 221.021188 -83.879178) (xy 221.015814 -83.885278) (xy 221.015052 -83.886294)
			(xy 221.015052 -84.374228) (xy 221.019561 -84.37995) (xy 221.031172 -84.388738) (xy 221.037912 -84.3915)
			(xy 221.05366 -84.39531) (xy 221.080788 -84.402639) (xy 221.132692 -84.424173) (xy 221.180876 -84.453087)
			(xy 221.224298 -84.488754) (xy 221.26202 -84.530404) (xy 221.293226 -84.577136) (xy 221.317241 -84.627939)
			(xy 221.331652 -84.675472) (xy 222.62414 -84.675472) (xy 222.628211 -84.61985) (xy 222.640337 -84.565413)
			(xy 222.66026 -84.513322) (xy 222.687556 -84.464687) (xy 222.721642 -84.420544) (xy 222.761791 -84.381835)
			(xy 222.807149 -84.349384) (xy 222.856749 -84.323883) (xy 222.909533 -84.305876) (xy 222.964376 -84.295746)
			(xy 223.02011 -84.293709) (xy 223.075547 -84.299809) (xy 223.129504 -84.313915) (xy 223.180833 -84.335727)
			(xy 223.228439 -84.364781) (xy 223.271307 -84.400456) (xy 223.308524 -84.441993) (xy 223.339297 -84.488506)
			(xy 223.362969 -84.539003) (xy 223.379037 -84.59241) (xy 223.387157 -84.647586) (xy 223.387666 -84.675472)
			(xy 224.650044 -84.675472) (xy 224.654115 -84.61985) (xy 224.666241 -84.565413) (xy 224.686164 -84.513322)
			(xy 224.71346 -84.464687) (xy 224.747546 -84.420544) (xy 224.787695 -84.381835) (xy 224.833053 -84.349384)
			(xy 224.882653 -84.323883) (xy 224.935437 -84.305876) (xy 224.99028 -84.295746) (xy 225.046014 -84.293709)
			(xy 225.101451 -84.299809) (xy 225.155408 -84.313915) (xy 225.206737 -84.335727) (xy 225.254343 -84.364781)
			(xy 225.297211 -84.400456) (xy 225.334428 -84.441993) (xy 225.365201 -84.488506) (xy 225.388873 -84.539003)
			(xy 225.404941 -84.59241) (xy 225.413061 -84.647586) (xy 225.41357 -84.675472) (xy 225.413061 -84.703358)
			(xy 225.404941 -84.758534) (xy 225.388873 -84.811941) (xy 225.365201 -84.862438) (xy 225.334428 -84.908951)
			(xy 225.297211 -84.950488) (xy 225.254343 -84.986163) (xy 225.206737 -85.015217) (xy 225.155408 -85.037029)
			(xy 225.101451 -85.051135) (xy 225.046014 -85.057235) (xy 224.99028 -85.055198) (xy 224.935437 -85.045068)
			(xy 224.882653 -85.027061) (xy 224.833053 -85.00156) (xy 224.787695 -84.969109) (xy 224.747546 -84.9304)
			(xy 224.71346 -84.886257) (xy 224.686164 -84.837622) (xy 224.666241 -84.785531) (xy 224.654115 -84.731094)
			(xy 224.650044 -84.675472) (xy 223.387666 -84.675472) (xy 223.387157 -84.703358) (xy 223.379037 -84.758534)
			(xy 223.362969 -84.811941) (xy 223.339297 -84.862438) (xy 223.308524 -84.908951) (xy 223.271307 -84.950488)
			(xy 223.228439 -84.986163) (xy 223.180833 -85.015217) (xy 223.129504 -85.037029) (xy 223.075547 -85.051135)
			(xy 223.02011 -85.057235) (xy 222.964376 -85.055198) (xy 222.909533 -85.045068) (xy 222.856749 -85.027061)
			(xy 222.807149 -85.00156) (xy 222.761791 -84.969109) (xy 222.721642 -84.9304) (xy 222.687556 -84.886257)
			(xy 222.66026 -84.837622) (xy 222.640337 -84.785531) (xy 222.628211 -84.731094) (xy 222.62414 -84.675472)
			(xy 221.331652 -84.675472) (xy 221.333545 -84.681715) (xy 221.341787 -84.7373) (xy 221.341787 -84.793494)
			(xy 221.333547 -84.849079) (xy 221.317243 -84.902855) (xy 221.293229 -84.953659) (xy 221.262024 -85.000391)
			(xy 221.224302 -85.042042) (xy 221.18088 -85.07771) (xy 221.132697 -85.106624) (xy 221.080794 -85.128159)
			(xy 221.05366 -85.135466) (xy 221.042738 -85.13826) (xy 221.034922 -85.140498) (xy 221.021188 -85.149178)
			(xy 221.015814 -85.155278) (xy 221.015052 -85.156294) (xy 221.015052 -86.616794) (xy 221.019116 -86.62162)
			(xy 221.06128 -86.665562) (xy 221.067884 -86.67242) (xy 221.101158 -86.68766) (xy 221.110556 -86.688168)
			(xy 221.139158 -86.690609) (xy 221.195208 -86.702995) (xy 221.248769 -86.723641) (xy 221.298632 -86.752081)
			(xy 221.343669 -86.787672) (xy 221.382863 -86.829611) (xy 221.41533 -86.87695) (xy 221.440336 -86.92862)
			(xy 221.457316 -86.983453) (xy 221.465886 -87.040212) (xy 221.46641 -87.068914) (xy 221.465869 -87.097902)
			(xy 221.457095 -87.155209) (xy 221.439752 -87.21053) (xy 221.414238 -87.262589) (xy 221.381141 -87.310188)
			(xy 221.341223 -87.352232) (xy 221.295403 -87.387753) (xy 221.244737 -87.415932) (xy 221.19039 -87.43612)
			(xy 221.162118 -87.442548) (xy 221.150688 -87.444834) (xy 221.144846 -87.447882) (xy 221.114366 -87.478616)
			(xy 221.112338 -87.484553) (xy 221.110914 -87.497015) (xy 221.111572 -87.503254) (xy 221.168468 -87.56015)
			(xy 221.191415 -87.583704) (xy 221.211539 -87.608918) (xy 221.615252 -87.608918) (xy 221.619323 -87.553296)
			(xy 221.631449 -87.498859) (xy 221.651372 -87.446768) (xy 221.678668 -87.398133) (xy 221.712754 -87.35399)
			(xy 221.752903 -87.315281) (xy 221.798261 -87.28283) (xy 221.847861 -87.257329) (xy 221.900645 -87.239322)
			(xy 221.955488 -87.229192) (xy 222.011222 -87.227155) (xy 222.066659 -87.233255) (xy 222.120616 -87.247361)
			(xy 222.171945 -87.269173) (xy 222.219551 -87.298227) (xy 222.262419 -87.333902) (xy 222.299636 -87.375439)
			(xy 222.330409 -87.421952) (xy 222.354081 -87.472449) (xy 222.370149 -87.525856) (xy 222.378269 -87.581032)
			(xy 222.378778 -87.608918) (xy 222.378269 -87.636804) (xy 222.370149 -87.69198) (xy 222.354081 -87.745387)
			(xy 222.330409 -87.795884) (xy 222.299636 -87.842397) (xy 222.262419 -87.883934) (xy 222.219551 -87.919609)
			(xy 222.171945 -87.948663) (xy 222.120616 -87.970475) (xy 222.066659 -87.984581) (xy 222.011222 -87.990681)
			(xy 221.955488 -87.988644) (xy 221.900645 -87.978514) (xy 221.847861 -87.960507) (xy 221.798261 -87.935006)
			(xy 221.752903 -87.902555) (xy 221.712754 -87.863846) (xy 221.678668 -87.819703) (xy 221.651372 -87.771068)
			(xy 221.631449 -87.718977) (xy 221.619323 -87.66454) (xy 221.615252 -87.608918) (xy 221.211539 -87.608918)
			(xy 221.232437 -87.635103) (xy 221.267442 -87.690774) (xy 221.295989 -87.750016) (xy 221.31772 -87.812084)
			(xy 221.33236 -87.876195) (xy 221.339725 -87.941543) (xy 221.340172 -87.974424) (xy 221.340172 -90.247216)
			(xy 221.339695 -90.280094) (xy 221.332304 -90.345433) (xy 221.317651 -90.409536) (xy 221.29592 -90.471598)
			(xy 221.267383 -90.530839) (xy 221.232399 -90.586516) (xy 221.191406 -90.637931) (xy 221.168468 -90.66149)
			(xy 220.39961 -91.430348) (xy 221.146114 -91.430348) (xy 221.150185 -91.374726) (xy 221.162311 -91.320289)
			(xy 221.182234 -91.268198) (xy 221.20953 -91.219563) (xy 221.243616 -91.17542) (xy 221.283765 -91.136711)
			(xy 221.329123 -91.10426) (xy 221.378723 -91.078759) (xy 221.431507 -91.060752) (xy 221.48635 -91.050622)
			(xy 221.542084 -91.048585) (xy 221.597521 -91.054685) (xy 221.651478 -91.068791) (xy 221.702807 -91.090603)
			(xy 221.750413 -91.119657) (xy 221.793281 -91.155332) (xy 221.830498 -91.196869) (xy 221.861271 -91.243382)
			(xy 221.884943 -91.293879) (xy 221.901011 -91.347286) (xy 221.909131 -91.402462) (xy 221.90964 -91.430348)
			(xy 221.909131 -91.458234) (xy 221.901011 -91.51341) (xy 221.884943 -91.566817) (xy 221.861271 -91.617314)
			(xy 221.830498 -91.663827) (xy 221.793281 -91.705364) (xy 221.750413 -91.741039) (xy 221.702807 -91.770093)
			(xy 221.651478 -91.791905) (xy 221.597521 -91.806011) (xy 221.542084 -91.812111) (xy 221.48635 -91.810074)
			(xy 221.431507 -91.799944) (xy 221.378723 -91.781937) (xy 221.329123 -91.756436) (xy 221.283765 -91.723985)
			(xy 221.243616 -91.685276) (xy 221.20953 -91.641133) (xy 221.182234 -91.592498) (xy 221.162311 -91.540407)
			(xy 221.150185 -91.48597) (xy 221.146114 -91.430348) (xy 220.39961 -91.430348) (xy 217.138504 -94.691454)
			(xy 217.13825 -94.702122) (xy 217.143838 -94.77883) (xy 217.144092 -94.781116) (xy 217.145719 -94.790847)
			(xy 217.155249 -94.808103) (xy 217.162634 -94.814644) (xy 217.162888 -94.814644) (xy 217.165428 -94.816676)
			(xy 217.18888 -94.834817) (xy 217.23041 -94.877128) (xy 217.264901 -94.925352) (xy 217.291522 -94.978327)
			(xy 217.309633 -95.034781) (xy 217.318798 -95.093356) (xy 217.319352 -95.123) (xy 217.698826 -95.123)
			(xy 217.702897 -95.067378) (xy 217.715023 -95.012941) (xy 217.734946 -94.96085) (xy 217.762242 -94.912215)
			(xy 217.796328 -94.868072) (xy 217.836477 -94.829363) (xy 217.881835 -94.796912) (xy 217.931435 -94.771411)
			(xy 217.984219 -94.753404) (xy 218.039062 -94.743274) (xy 218.094796 -94.741237) (xy 218.150233 -94.747337)
			(xy 218.20419 -94.761443) (xy 218.255519 -94.783255) (xy 218.303125 -94.812309) (xy 218.345993 -94.847984)
			(xy 218.38321 -94.889521) (xy 218.413983 -94.936034) (xy 218.437655 -94.986531) (xy 218.453723 -95.039938)
			(xy 218.461843 -95.095114) (xy 218.462352 -95.123) (xy 218.841826 -95.123) (xy 218.845897 -95.067378)
			(xy 218.858023 -95.012941) (xy 218.877946 -94.96085) (xy 218.905242 -94.912215) (xy 218.939328 -94.868072)
			(xy 218.979477 -94.829363) (xy 219.024835 -94.796912) (xy 219.074435 -94.771411) (xy 219.127219 -94.753404)
			(xy 219.182062 -94.743274) (xy 219.237796 -94.741237) (xy 219.293233 -94.747337) (xy 219.34719 -94.761443)
			(xy 219.398519 -94.783255) (xy 219.446125 -94.812309) (xy 219.488993 -94.847984) (xy 219.52621 -94.889521)
			(xy 219.554645 -94.9325) (xy 220.111826 -94.9325) (xy 220.115897 -94.876878) (xy 220.128023 -94.822441)
			(xy 220.147946 -94.77035) (xy 220.175242 -94.721715) (xy 220.209328 -94.677572) (xy 220.249477 -94.638863)
			(xy 220.294835 -94.606412) (xy 220.344435 -94.580911) (xy 220.397219 -94.562904) (xy 220.452062 -94.552774)
			(xy 220.507796 -94.550737) (xy 220.563233 -94.556837) (xy 220.61719 -94.570943) (xy 220.668519 -94.592755)
			(xy 220.716125 -94.621809) (xy 220.758993 -94.657484) (xy 220.79621 -94.699021) (xy 220.826983 -94.745534)
			(xy 220.850655 -94.796031) (xy 220.866723 -94.849438) (xy 220.874843 -94.904614) (xy 220.875352 -94.9325)
			(xy 220.874843 -94.960386) (xy 220.866723 -95.015562) (xy 220.850655 -95.068969) (xy 220.826983 -95.119466)
			(xy 220.79621 -95.165979) (xy 220.758993 -95.207516) (xy 220.716125 -95.243191) (xy 220.668519 -95.272245)
			(xy 220.61719 -95.294057) (xy 220.563233 -95.308163) (xy 220.507796 -95.314263) (xy 220.452062 -95.312226)
			(xy 220.397219 -95.302096) (xy 220.344435 -95.284089) (xy 220.294835 -95.258588) (xy 220.249477 -95.226137)
			(xy 220.209328 -95.187428) (xy 220.175242 -95.143285) (xy 220.147946 -95.09465) (xy 220.128023 -95.042559)
			(xy 220.115897 -94.988122) (xy 220.111826 -94.9325) (xy 219.554645 -94.9325) (xy 219.556983 -94.936034)
			(xy 219.580655 -94.986531) (xy 219.596723 -95.039938) (xy 219.604843 -95.095114) (xy 219.605352 -95.123)
			(xy 219.604843 -95.150886) (xy 219.596723 -95.206062) (xy 219.580655 -95.259469) (xy 219.556983 -95.309966)
			(xy 219.52621 -95.356479) (xy 219.488993 -95.398016) (xy 219.446125 -95.433691) (xy 219.398519 -95.462745)
			(xy 219.34719 -95.484557) (xy 219.293233 -95.498663) (xy 219.237796 -95.504763) (xy 219.182062 -95.502726)
			(xy 219.127219 -95.492596) (xy 219.074435 -95.474589) (xy 219.024835 -95.449088) (xy 218.979477 -95.416637)
			(xy 218.939328 -95.377928) (xy 218.905242 -95.333785) (xy 218.877946 -95.28515) (xy 218.858023 -95.233059)
			(xy 218.845897 -95.178622) (xy 218.841826 -95.123) (xy 218.462352 -95.123) (xy 218.461843 -95.150886)
			(xy 218.453723 -95.206062) (xy 218.437655 -95.259469) (xy 218.413983 -95.309966) (xy 218.38321 -95.356479)
			(xy 218.345993 -95.398016) (xy 218.303125 -95.433691) (xy 218.255519 -95.462745) (xy 218.20419 -95.484557)
			(xy 218.150233 -95.498663) (xy 218.094796 -95.504763) (xy 218.039062 -95.502726) (xy 217.984219 -95.492596)
			(xy 217.931435 -95.474589) (xy 217.881835 -95.449088) (xy 217.836477 -95.416637) (xy 217.796328 -95.377928)
			(xy 217.762242 -95.333785) (xy 217.734946 -95.28515) (xy 217.715023 -95.233059) (xy 217.702897 -95.178622)
			(xy 217.698826 -95.123) (xy 217.319352 -95.123) (xy 217.318866 -95.150252) (xy 217.31111 -95.204202)
			(xy 217.295755 -95.2565) (xy 217.273115 -95.30608) (xy 217.243649 -95.351933) (xy 217.207958 -95.393127)
			(xy 217.166769 -95.428823) (xy 217.120918 -95.458294) (xy 217.071341 -95.48094) (xy 217.019046 -95.496301)
			(xy 216.965096 -95.504063) (xy 216.937844 -95.504508) (xy 216.92235 -95.504254) (xy 216.913968 -95.504)
			(xy 216.894918 -95.51162) (xy 216.887552 -95.518732) (xy 216.835482 -95.569278) (xy 216.828433 -95.57673)
			(xy 216.820446 -95.595605) (xy 216.819988 -95.605854) (xy 216.819988 -97.282) (xy 218.206826 -97.282)
			(xy 218.210897 -97.226378) (xy 218.223023 -97.171941) (xy 218.242946 -97.11985) (xy 218.270242 -97.071215)
			(xy 218.304328 -97.027072) (xy 218.344477 -96.988363) (xy 218.389835 -96.955912) (xy 218.439435 -96.930411)
			(xy 218.492219 -96.912404) (xy 218.547062 -96.902274) (xy 218.602796 -96.900237) (xy 218.658233 -96.906337)
			(xy 218.71219 -96.920443) (xy 218.763519 -96.942255) (xy 218.811125 -96.971309) (xy 218.853993 -97.006984)
			(xy 218.89121 -97.048521) (xy 218.921983 -97.095034) (xy 218.945655 -97.145531) (xy 218.961723 -97.198938)
			(xy 218.969843 -97.254114) (xy 218.970352 -97.282) (xy 218.969843 -97.309886) (xy 218.961723 -97.365062)
			(xy 218.945655 -97.418469) (xy 218.921983 -97.468966) (xy 218.89121 -97.515479) (xy 218.872823 -97.536)
			(xy 219.095826 -97.536) (xy 219.099897 -97.480378) (xy 219.112023 -97.425941) (xy 219.131946 -97.37385)
			(xy 219.159242 -97.325215) (xy 219.193328 -97.281072) (xy 219.233477 -97.242363) (xy 219.278835 -97.209912)
			(xy 219.328435 -97.184411) (xy 219.381219 -97.166404) (xy 219.436062 -97.156274) (xy 219.491796 -97.154237)
			(xy 219.547233 -97.160337) (xy 219.60119 -97.174443) (xy 219.652519 -97.196255) (xy 219.700125 -97.225309)
			(xy 219.742993 -97.260984) (xy 219.78021 -97.302521) (xy 219.787639 -97.31375) (xy 222.308926 -97.31375)
			(xy 222.312997 -97.258128) (xy 222.325123 -97.203691) (xy 222.345046 -97.1516) (xy 222.372342 -97.102965)
			(xy 222.406428 -97.058822) (xy 222.446577 -97.020113) (xy 222.491935 -96.987662) (xy 222.541535 -96.962161)
			(xy 222.594319 -96.944154) (xy 222.649162 -96.934024) (xy 222.704896 -96.931987) (xy 222.760333 -96.938087)
			(xy 222.81429 -96.952193) (xy 222.865619 -96.974005) (xy 222.913225 -97.003059) (xy 222.956093 -97.038734)
			(xy 222.99331 -97.080271) (xy 223.024083 -97.126784) (xy 223.047755 -97.177281) (xy 223.063823 -97.230688)
			(xy 223.071943 -97.285864) (xy 223.072452 -97.31375) (xy 223.071943 -97.341636) (xy 223.063823 -97.396812)
			(xy 223.047755 -97.450219) (xy 223.024083 -97.500716) (xy 222.99331 -97.547229) (xy 222.956093 -97.588766)
			(xy 222.913225 -97.624441) (xy 222.865619 -97.653495) (xy 222.81429 -97.675307) (xy 222.760333 -97.689413)
			(xy 222.704896 -97.695513) (xy 222.649162 -97.693476) (xy 222.594319 -97.683346) (xy 222.541535 -97.665339)
			(xy 222.491935 -97.639838) (xy 222.446577 -97.607387) (xy 222.406428 -97.568678) (xy 222.372342 -97.524535)
			(xy 222.345046 -97.4759) (xy 222.325123 -97.423809) (xy 222.312997 -97.369372) (xy 222.308926 -97.31375)
			(xy 219.787639 -97.31375) (xy 219.810983 -97.349034) (xy 219.834655 -97.399531) (xy 219.850723 -97.452938)
			(xy 219.858843 -97.508114) (xy 219.859352 -97.536) (xy 219.858843 -97.563886) (xy 219.850723 -97.619062)
			(xy 219.834655 -97.672469) (xy 219.810983 -97.722966) (xy 219.78021 -97.769479) (xy 219.761823 -97.79)
			(xy 219.984826 -97.79) (xy 219.988897 -97.734378) (xy 220.001023 -97.679941) (xy 220.020946 -97.62785)
			(xy 220.048242 -97.579215) (xy 220.082328 -97.535072) (xy 220.122477 -97.496363) (xy 220.167835 -97.463912)
			(xy 220.217435 -97.438411) (xy 220.270219 -97.420404) (xy 220.325062 -97.410274) (xy 220.380796 -97.408237)
			(xy 220.436233 -97.414337) (xy 220.49019 -97.428443) (xy 220.541519 -97.450255) (xy 220.589125 -97.479309)
			(xy 220.631993 -97.514984) (xy 220.66921 -97.556521) (xy 220.699983 -97.603034) (xy 220.723655 -97.653531)
			(xy 220.739723 -97.706938) (xy 220.747843 -97.762114) (xy 220.748352 -97.79) (xy 220.747843 -97.817886)
			(xy 220.739723 -97.873062) (xy 220.723655 -97.926469) (xy 220.699983 -97.976966) (xy 220.66921 -98.023479)
			(xy 220.631993 -98.065016) (xy 220.589125 -98.100691) (xy 220.541519 -98.129745) (xy 220.49019 -98.151557)
			(xy 220.436233 -98.165663) (xy 220.380796 -98.171763) (xy 220.325062 -98.169726) (xy 220.270219 -98.159596)
			(xy 220.217435 -98.141589) (xy 220.167835 -98.116088) (xy 220.122477 -98.083637) (xy 220.082328 -98.044928)
			(xy 220.048242 -98.000785) (xy 220.020946 -97.95215) (xy 220.001023 -97.900059) (xy 219.988897 -97.845622)
			(xy 219.984826 -97.79) (xy 219.761823 -97.79) (xy 219.742993 -97.811016) (xy 219.700125 -97.846691)
			(xy 219.652519 -97.875745) (xy 219.60119 -97.897557) (xy 219.547233 -97.911663) (xy 219.491796 -97.917763)
			(xy 219.436062 -97.915726) (xy 219.381219 -97.905596) (xy 219.328435 -97.887589) (xy 219.278835 -97.862088)
			(xy 219.233477 -97.829637) (xy 219.193328 -97.790928) (xy 219.159242 -97.746785) (xy 219.131946 -97.69815)
			(xy 219.112023 -97.646059) (xy 219.099897 -97.591622) (xy 219.095826 -97.536) (xy 218.872823 -97.536)
			(xy 218.853993 -97.557016) (xy 218.811125 -97.592691) (xy 218.763519 -97.621745) (xy 218.71219 -97.643557)
			(xy 218.658233 -97.657663) (xy 218.602796 -97.663763) (xy 218.547062 -97.661726) (xy 218.492219 -97.651596)
			(xy 218.439435 -97.633589) (xy 218.389835 -97.608088) (xy 218.344477 -97.575637) (xy 218.304328 -97.536928)
			(xy 218.270242 -97.492785) (xy 218.242946 -97.44415) (xy 218.223023 -97.392059) (xy 218.210897 -97.337622)
			(xy 218.206826 -97.282) (xy 216.819988 -97.282) (xy 216.819988 -99.335844) (xy 216.819226 -99.346766)
			(xy 216.823036 -99.356672) (xy 216.825133 -99.361711) (xy 216.831145 -99.370818) (xy 216.834974 -99.374706)
			(xy 216.889838 -99.428046) (xy 216.896711 -99.433522) (xy 216.913076 -99.439889) (xy 216.921842 -99.440492)
			(xy 216.937844 -99.440238) (xy 216.96509 -99.440727) (xy 217.019026 -99.448488) (xy 217.071309 -99.463845)
			(xy 217.120875 -99.486486) (xy 217.166714 -99.51595) (xy 217.207894 -99.551637) (xy 217.243577 -99.592821)
			(xy 217.273035 -99.638664) (xy 217.295671 -99.688232) (xy 217.311022 -99.740517) (xy 217.318776 -99.794454)
			(xy 217.318776 -99.848946) (xy 217.311022 -99.902883) (xy 217.295671 -99.955168) (xy 217.273035 -100.004736)
			(xy 217.243577 -100.050579) (xy 217.221552 -100.076) (xy 218.371672 -100.076) (xy 218.375743 -100.020378)
			(xy 218.387869 -99.965941) (xy 218.407792 -99.91385) (xy 218.435088 -99.865215) (xy 218.469174 -99.821072)
			(xy 218.509323 -99.782363) (xy 218.554681 -99.749912) (xy 218.604281 -99.724411) (xy 218.657065 -99.706404)
			(xy 218.711908 -99.696274) (xy 218.767642 -99.694237) (xy 218.823079 -99.700337) (xy 218.877036 -99.714443)
			(xy 218.928365 -99.736255) (xy 218.975971 -99.765309) (xy 219.018839 -99.800984) (xy 219.037669 -99.822)
			(xy 219.984826 -99.822) (xy 219.988897 -99.766378) (xy 220.001023 -99.711941) (xy 220.020946 -99.65985)
			(xy 220.048242 -99.611215) (xy 220.082328 -99.567072) (xy 220.122477 -99.528363) (xy 220.167835 -99.495912)
			(xy 220.217435 -99.470411) (xy 220.270219 -99.452404) (xy 220.325062 -99.442274) (xy 220.380796 -99.440237)
			(xy 220.436233 -99.446337) (xy 220.49019 -99.460443) (xy 220.541519 -99.482255) (xy 220.579633 -99.505516)
			(xy 221.292926 -99.505516) (xy 221.296997 -99.449894) (xy 221.309123 -99.395457) (xy 221.329046 -99.343366)
			(xy 221.356342 -99.294731) (xy 221.390428 -99.250588) (xy 221.430577 -99.211879) (xy 221.475935 -99.179428)
			(xy 221.525535 -99.153927) (xy 221.578319 -99.13592) (xy 221.633162 -99.12579) (xy 221.688896 -99.123753)
			(xy 221.744333 -99.129853) (xy 221.79829 -99.143959) (xy 221.849619 -99.165771) (xy 221.897225 -99.194825)
			(xy 221.940093 -99.2305) (xy 221.97731 -99.272037) (xy 222.008083 -99.31855) (xy 222.031755 -99.369047)
			(xy 222.047823 -99.422454) (xy 222.055943 -99.47763) (xy 222.056345 -99.499674) (xy 222.606868 -99.499674)
			(xy 222.610939 -99.444052) (xy 222.623065 -99.389615) (xy 222.642988 -99.337524) (xy 222.670284 -99.288889)
			(xy 222.70437 -99.244746) (xy 222.744519 -99.206037) (xy 222.789877 -99.173586) (xy 222.839477 -99.148085)
			(xy 222.892261 -99.130078) (xy 222.947104 -99.119948) (xy 223.002838 -99.117911) (xy 223.058275 -99.124011)
			(xy 223.112232 -99.138117) (xy 223.163561 -99.159929) (xy 223.211167 -99.188983) (xy 223.254035 -99.224658)
			(xy 223.291252 -99.266195) (xy 223.322025 -99.312708) (xy 223.334419 -99.339146) (xy 223.880932 -99.339146)
			(xy 223.885003 -99.283524) (xy 223.897129 -99.229087) (xy 223.917052 -99.176996) (xy 223.944348 -99.128361)
			(xy 223.978434 -99.084218) (xy 224.018583 -99.045509) (xy 224.063941 -99.013058) (xy 224.113541 -98.987557)
			(xy 224.166325 -98.96955) (xy 224.221168 -98.95942) (xy 224.276902 -98.957383) (xy 224.332339 -98.963483)
			(xy 224.386296 -98.977589) (xy 224.437625 -98.999401) (xy 224.485231 -99.028455) (xy 224.528099 -99.06413)
			(xy 224.565316 -99.105667) (xy 224.596089 -99.15218) (xy 224.619761 -99.202677) (xy 224.635829 -99.256084)
			(xy 224.643949 -99.31126) (xy 224.644458 -99.339146) (xy 224.643949 -99.367032) (xy 224.635829 -99.422208)
			(xy 224.619761 -99.475615) (xy 224.596089 -99.526112) (xy 224.565316 -99.572625) (xy 224.528099 -99.614162)
			(xy 224.485231 -99.649837) (xy 224.437625 -99.678891) (xy 224.386296 -99.700703) (xy 224.332339 -99.714809)
			(xy 224.276902 -99.720909) (xy 224.221168 -99.718872) (xy 224.166325 -99.708742) (xy 224.113541 -99.690735)
			(xy 224.063941 -99.665234) (xy 224.018583 -99.632783) (xy 223.978434 -99.594074) (xy 223.944348 -99.549931)
			(xy 223.917052 -99.501296) (xy 223.897129 -99.449205) (xy 223.885003 -99.394768) (xy 223.880932 -99.339146)
			(xy 223.334419 -99.339146) (xy 223.345697 -99.363205) (xy 223.361765 -99.416612) (xy 223.369885 -99.471788)
			(xy 223.370394 -99.499674) (xy 223.369885 -99.52756) (xy 223.361765 -99.582736) (xy 223.345697 -99.636143)
			(xy 223.322025 -99.68664) (xy 223.291252 -99.733153) (xy 223.254035 -99.77469) (xy 223.211167 -99.810365)
			(xy 223.163561 -99.839419) (xy 223.112232 -99.861231) (xy 223.058275 -99.875337) (xy 223.002838 -99.881437)
			(xy 222.947104 -99.8794) (xy 222.892261 -99.86927) (xy 222.839477 -99.851263) (xy 222.789877 -99.825762)
			(xy 222.744519 -99.793311) (xy 222.70437 -99.754602) (xy 222.670284 -99.710459) (xy 222.642988 -99.661824)
			(xy 222.623065 -99.609733) (xy 222.610939 -99.555296) (xy 222.606868 -99.499674) (xy 222.056345 -99.499674)
			(xy 222.056452 -99.505516) (xy 222.055943 -99.533402) (xy 222.047823 -99.588578) (xy 222.031755 -99.641985)
			(xy 222.008083 -99.692482) (xy 221.97731 -99.738995) (xy 221.940093 -99.780532) (xy 221.897225 -99.816207)
			(xy 221.849619 -99.845261) (xy 221.79829 -99.867073) (xy 221.744333 -99.881179) (xy 221.688896 -99.887279)
			(xy 221.633162 -99.885242) (xy 221.578319 -99.875112) (xy 221.525535 -99.857105) (xy 221.475935 -99.831604)
			(xy 221.430577 -99.799153) (xy 221.390428 -99.760444) (xy 221.356342 -99.716301) (xy 221.329046 -99.667666)
			(xy 221.309123 -99.615575) (xy 221.296997 -99.561138) (xy 221.292926 -99.505516) (xy 220.579633 -99.505516)
			(xy 220.589125 -99.511309) (xy 220.631993 -99.546984) (xy 220.66921 -99.588521) (xy 220.699983 -99.635034)
			(xy 220.723655 -99.685531) (xy 220.739723 -99.738938) (xy 220.747843 -99.794114) (xy 220.748352 -99.822)
			(xy 220.747843 -99.849886) (xy 220.739723 -99.905062) (xy 220.723655 -99.958469) (xy 220.699983 -100.008966)
			(xy 220.66921 -100.055479) (xy 220.631993 -100.097016) (xy 220.589125 -100.132691) (xy 220.541519 -100.161745)
			(xy 220.49019 -100.183557) (xy 220.436233 -100.197663) (xy 220.380796 -100.203763) (xy 220.325062 -100.201726)
			(xy 220.270219 -100.191596) (xy 220.217435 -100.173589) (xy 220.167835 -100.148088) (xy 220.122477 -100.115637)
			(xy 220.082328 -100.076928) (xy 220.048242 -100.032785) (xy 220.020946 -99.98415) (xy 220.001023 -99.932059)
			(xy 219.988897 -99.877622) (xy 219.984826 -99.822) (xy 219.037669 -99.822) (xy 219.056056 -99.842521)
			(xy 219.086829 -99.889034) (xy 219.110501 -99.939531) (xy 219.126569 -99.992938) (xy 219.134689 -100.048114)
			(xy 219.135198 -100.076) (xy 219.134689 -100.103886) (xy 219.126569 -100.159062) (xy 219.110501 -100.212469)
			(xy 219.086829 -100.262966) (xy 219.056056 -100.309479) (xy 219.018839 -100.351016) (xy 218.975971 -100.386691)
			(xy 218.928365 -100.415745) (xy 218.877036 -100.437557) (xy 218.823079 -100.451663) (xy 218.767642 -100.457763)
			(xy 218.711908 -100.455726) (xy 218.657065 -100.445596) (xy 218.604281 -100.427589) (xy 218.554681 -100.402088)
			(xy 218.509323 -100.369637) (xy 218.469174 -100.330928) (xy 218.435088 -100.286785) (xy 218.407792 -100.23815)
			(xy 218.387869 -100.186059) (xy 218.375743 -100.131622) (xy 218.371672 -100.076) (xy 217.221552 -100.076)
			(xy 217.207894 -100.091763) (xy 217.166714 -100.12745) (xy 217.120875 -100.156914) (xy 217.071309 -100.179555)
			(xy 217.019026 -100.194912) (xy 216.96509 -100.202673) (xy 216.937844 -100.203254) (xy 216.937844 -100.203508)
			(xy 216.911644 -100.203078) (xy 216.859737 -100.195916) (xy 216.809297 -100.181722) (xy 216.761272 -100.160762)
			(xy 216.716567 -100.133429) (xy 216.696036 -100.117148) (xy 216.689432 -100.111306) (xy 216.668096 -100.103432)
			(xy 216.660972 -100.10106) (xy 216.645992 -100.100163) (xy 216.638632 -100.101654) (xy 216.563956 -100.119434)
			(xy 216.554424 -100.122229) (xy 216.538343 -100.133857) (xy 216.532714 -100.14204) (xy 216.531698 -100.143564)
			(xy 216.488518 -100.24745) (xy 216.418414 -100.417122) (xy 216.417652 -100.420424) (xy 216.412206 -100.441419)
			(xy 216.398601 -100.48261) (xy 216.390474 -100.50272) (xy 216.093722 -101.219) (xy 220.238826 -101.219)
			(xy 220.242897 -101.163378) (xy 220.255023 -101.108941) (xy 220.274946 -101.05685) (xy 220.302242 -101.008215)
			(xy 220.336328 -100.964072) (xy 220.376477 -100.925363) (xy 220.421835 -100.892912) (xy 220.471435 -100.867411)
			(xy 220.524219 -100.849404) (xy 220.579062 -100.839274) (xy 220.634796 -100.837237) (xy 220.690233 -100.843337)
			(xy 220.74419 -100.857443) (xy 220.795519 -100.879255) (xy 220.843125 -100.908309) (xy 220.885993 -100.943984)
			(xy 220.92321 -100.985521) (xy 220.953983 -101.032034) (xy 220.977655 -101.082531) (xy 220.993723 -101.135938)
			(xy 221.001843 -101.191114) (xy 221.002352 -101.219) (xy 221.001843 -101.246886) (xy 220.993723 -101.302062)
			(xy 220.977655 -101.355469) (xy 220.953983 -101.405966) (xy 220.92321 -101.452479) (xy 220.885993 -101.494016)
			(xy 220.843125 -101.529691) (xy 220.795519 -101.558745) (xy 220.74419 -101.580557) (xy 220.690233 -101.594663)
			(xy 220.634796 -101.600763) (xy 220.579062 -101.598726) (xy 220.524219 -101.588596) (xy 220.471435 -101.570589)
			(xy 220.421835 -101.545088) (xy 220.376477 -101.512637) (xy 220.336328 -101.473928) (xy 220.302242 -101.429785)
			(xy 220.274946 -101.38115) (xy 220.255023 -101.329059) (xy 220.242897 -101.274622) (xy 220.238826 -101.219)
			(xy 216.093722 -101.219) (xy 215.393091 -102.910132) (xy 224.984056 -102.910132) (xy 224.984527 -102.882762)
			(xy 224.992342 -102.828582) (xy 225.007829 -102.776079) (xy 225.03067 -102.726332) (xy 225.060394 -102.680365)
			(xy 225.078036 -102.659434) (xy 225.07829 -102.65918) (xy 225.08389 -102.652103) (xy 225.090129 -102.635179)
			(xy 225.090482 -102.62616) (xy 225.090482 -102.559104) (xy 225.090127 -102.550087) (xy 225.083879 -102.53317)
			(xy 225.07829 -102.526084) (xy 225.078036 -102.526084) (xy 225.078036 -102.52583) (xy 225.060426 -102.504872)
			(xy 225.0307 -102.458909) (xy 225.007852 -102.409167) (xy 224.992353 -102.356669) (xy 224.984521 -102.302493)
			(xy 224.984517 -102.247755) (xy 224.992342 -102.193579) (xy 225.007835 -102.141078) (xy 225.030676 -102.091333)
			(xy 225.060397 -102.045367) (xy 225.078036 -102.024434) (xy 225.07829 -102.02418) (xy 225.08389 -102.017103)
			(xy 225.090129 -102.000179) (xy 225.090482 -101.99116) (xy 225.090482 -101.924104) (xy 225.090127 -101.915087)
			(xy 225.083879 -101.89817) (xy 225.07829 -101.891084) (xy 225.078036 -101.891084) (xy 225.078036 -101.89083)
			(xy 225.060403 -101.869893) (xy 225.030689 -101.823922) (xy 225.007851 -101.774176) (xy 224.992359 -101.721676)
			(xy 224.98453 -101.667501) (xy 224.984056 -101.640132) (xy 224.984542 -101.612881) (xy 224.992298 -101.558933)
			(xy 225.007653 -101.506638) (xy 225.030295 -101.457061) (xy 225.059761 -101.411211) (xy 225.095452 -101.37002)
			(xy 225.136643 -101.334329) (xy 225.182493 -101.304863) (xy 225.23207 -101.282221) (xy 225.284365 -101.266866)
			(xy 225.338313 -101.25911) (xy 225.392815 -101.25911) (xy 225.446763 -101.266866) (xy 225.499058 -101.282221)
			(xy 225.548635 -101.304863) (xy 225.594485 -101.334329) (xy 225.635676 -101.37002) (xy 225.671367 -101.411211)
			(xy 225.700833 -101.457061) (xy 225.723475 -101.506638) (xy 225.73883 -101.558933) (xy 225.746586 -101.612881)
			(xy 225.747072 -101.640132) (xy 225.746632 -101.667503) (xy 225.738809 -101.721684) (xy 225.723314 -101.774187)
			(xy 225.700466 -101.823934) (xy 225.670736 -101.869899) (xy 225.653092 -101.89083) (xy 225.652838 -101.891084)
			(xy 225.647245 -101.898166) (xy 225.641004 -101.915086) (xy 225.640646 -101.924104) (xy 225.640646 -101.99116)
			(xy 225.641012 -102.000176) (xy 225.647252 -102.017094) (xy 225.652838 -102.02418) (xy 225.653092 -102.02418)
			(xy 225.653092 -102.024434) (xy 225.670763 -102.045342) (xy 225.700485 -102.091314) (xy 225.723328 -102.141065)
			(xy 225.738821 -102.193571) (xy 225.746646 -102.247752) (xy 225.746642 -102.302496) (xy 225.73881 -102.356677)
			(xy 225.723311 -102.40918) (xy 225.700462 -102.458928) (xy 225.670734 -102.504897) (xy 225.653092 -102.52583)
			(xy 225.652838 -102.526084) (xy 225.647245 -102.533166) (xy 225.641004 -102.550086) (xy 225.640646 -102.559104)
			(xy 225.640646 -102.62616) (xy 225.641012 -102.635176) (xy 225.647252 -102.652094) (xy 225.648871 -102.654148)
			(xy 226.6389 -102.654148) (xy 226.6389 -102.599652) (xy 226.646655 -102.54571) (xy 226.662008 -102.493421)
			(xy 226.684645 -102.443849) (xy 226.714107 -102.398003) (xy 226.749792 -102.356816) (xy 226.790976 -102.321127)
			(xy 226.836819 -102.291661) (xy 226.886389 -102.26902) (xy 226.938677 -102.253663) (xy 226.992618 -102.245903)
			(xy 227.019866 -102.245414) (xy 227.046182 -102.245833) (xy 227.098312 -102.253077) (xy 227.148956 -102.267405)
			(xy 227.197155 -102.288547) (xy 227.241997 -102.316102) (xy 227.282635 -102.349549) (xy 227.30079 -102.368604)
			(xy 227.308313 -102.376004) (xy 227.327592 -102.384529) (xy 227.338128 -102.385114) (xy 227.412804 -102.385114)
			(xy 227.423355 -102.384596) (xy 227.44265 -102.376053) (xy 227.450142 -102.368604) (xy 227.468285 -102.349536)
			(xy 227.508917 -102.31608) (xy 227.55376 -102.288522) (xy 227.601963 -102.267386) (xy 227.652613 -102.253072)
			(xy 227.704749 -102.24585) (xy 227.731066 -102.245414) (xy 227.758322 -102.245831) (xy 227.81228 -102.253584)
			(xy 227.864585 -102.268938) (xy 227.914172 -102.29158) (xy 227.960032 -102.321049) (xy 228.001231 -102.356745)
			(xy 228.036931 -102.397941) (xy 228.066404 -102.443798) (xy 228.08612 -102.486968) (xy 228.66223 -102.486968)
			(xy 228.66267 -102.459597) (xy 228.670493 -102.405416) (xy 228.685988 -102.352913) (xy 228.708835 -102.303166)
			(xy 228.738566 -102.257201) (xy 228.75621 -102.23627) (xy 228.756464 -102.236016) (xy 228.762058 -102.228935)
			(xy 228.768298 -102.212014) (xy 228.768656 -102.202996) (xy 228.768656 -102.13594) (xy 228.768289 -102.126924)
			(xy 228.76205 -102.110006) (xy 228.756464 -102.10292) (xy 228.75621 -102.10292) (xy 228.75621 -102.102666)
			(xy 228.738539 -102.081758) (xy 228.708816 -102.035786) (xy 228.685974 -101.986035) (xy 228.670481 -101.93353)
			(xy 228.662656 -101.879348) (xy 228.662659 -101.824604) (xy 228.670491 -101.770423) (xy 228.685991 -101.71792)
			(xy 228.70884 -101.668172) (xy 228.738568 -101.622203) (xy 228.75621 -101.60127) (xy 228.756464 -101.601016)
			(xy 228.762058 -101.593935) (xy 228.768298 -101.577014) (xy 228.768656 -101.567996) (xy 228.768656 -101.50094)
			(xy 228.768289 -101.491924) (xy 228.76205 -101.475006) (xy 228.756464 -101.46792) (xy 228.75621 -101.46792)
			(xy 228.75621 -101.467666) (xy 228.73859 -101.446719) (xy 228.708875 -101.40075) (xy 228.686035 -101.351007)
			(xy 228.67054 -101.298509) (xy 228.662707 -101.244336) (xy 228.66223 -101.216968) (xy 228.662716 -101.189717)
			(xy 228.670472 -101.135769) (xy 228.685827 -101.083474) (xy 228.708469 -101.033897) (xy 228.737935 -100.988047)
			(xy 228.773626 -100.946856) (xy 228.814817 -100.911165) (xy 228.860667 -100.881699) (xy 228.910244 -100.859057)
			(xy 228.962539 -100.843702) (xy 229.016487 -100.835946) (xy 229.070989 -100.835946) (xy 229.124937 -100.843702)
			(xy 229.177232 -100.859057) (xy 229.226809 -100.881699) (xy 229.272659 -100.911165) (xy 229.31385 -100.946856)
			(xy 229.349541 -100.988047) (xy 229.379007 -101.033897) (xy 229.401649 -101.083474) (xy 229.417004 -101.135769)
			(xy 229.42476 -101.189717) (xy 229.425246 -101.216968) (xy 229.424774 -101.244338) (xy 229.41696 -101.298518)
			(xy 229.401473 -101.351021) (xy 229.378632 -101.400768) (xy 229.348907 -101.446735) (xy 229.331266 -101.467666)
			(xy 229.331012 -101.46792) (xy 229.325412 -101.474998) (xy 229.319173 -101.491921) (xy 229.31882 -101.50094)
			(xy 229.31882 -101.567996) (xy 229.319174 -101.577013) (xy 229.325423 -101.59393) (xy 229.331012 -101.601016)
			(xy 229.331266 -101.601016) (xy 229.331266 -101.60127) (xy 229.348876 -101.622228) (xy 229.378602 -101.668191)
			(xy 229.40145 -101.717933) (xy 229.416949 -101.770432) (xy 229.424781 -101.824607) (xy 229.424784 -101.879345)
			(xy 229.416959 -101.933521) (xy 229.401467 -101.986022) (xy 229.378625 -102.035766) (xy 229.348905 -102.081733)
			(xy 229.331266 -102.102666) (xy 229.331012 -102.10292) (xy 229.325412 -102.109998) (xy 229.319173 -102.126921)
			(xy 229.31882 -102.13594) (xy 229.31882 -102.202996) (xy 229.319174 -102.212013) (xy 229.325423 -102.22893)
			(xy 229.331012 -102.236016) (xy 229.331266 -102.236016) (xy 229.331266 -102.23627) (xy 229.348899 -102.257207)
			(xy 229.378613 -102.303178) (xy 229.401451 -102.352924) (xy 229.416943 -102.405424) (xy 229.424772 -102.459599)
			(xy 229.425246 -102.486968) (xy 229.424979 -102.501954) (xy 231.856534 -102.501954) (xy 231.857023 -102.474585)
			(xy 231.864834 -102.420406) (xy 231.880318 -102.367903) (xy 231.903154 -102.318156) (xy 231.932875 -102.272188)
			(xy 231.950514 -102.251256) (xy 231.950768 -102.251002) (xy 231.956368 -102.243925) (xy 231.962605 -102.227001)
			(xy 231.96296 -102.217982) (xy 231.96296 -102.150926) (xy 231.962599 -102.141909) (xy 231.956355 -102.124992)
			(xy 231.950768 -102.117906) (xy 231.950514 -102.117906) (xy 231.950514 -102.117652) (xy 231.932829 -102.096755)
			(xy 231.903107 -102.050781) (xy 231.880265 -102.001029) (xy 231.864773 -101.948521) (xy 231.856949 -101.894338)
			(xy 231.856954 -101.839593) (xy 231.864788 -101.785411) (xy 231.880289 -101.732906) (xy 231.90314 -101.683158)
			(xy 231.932871 -101.637189) (xy 231.950514 -101.616256) (xy 231.950768 -101.616002) (xy 231.956368 -101.608925)
			(xy 231.962605 -101.592001) (xy 231.96296 -101.582982) (xy 231.96296 -101.515926) (xy 231.962599 -101.506909)
			(xy 231.956355 -101.489992) (xy 231.950768 -101.482906) (xy 231.950514 -101.482906) (xy 231.950514 -101.482652)
			(xy 231.932888 -101.461709) (xy 231.903174 -101.41574) (xy 231.880335 -101.365995) (xy 231.864841 -101.313496)
			(xy 231.85701 -101.259322) (xy 231.856534 -101.231954) (xy 231.85702 -101.204703) (xy 231.864776 -101.150755)
			(xy 231.880131 -101.09846) (xy 231.902773 -101.048883) (xy 231.932239 -101.003033) (xy 231.96793 -100.961842)
			(xy 232.009121 -100.926151) (xy 232.054971 -100.896685) (xy 232.104548 -100.874043) (xy 232.156843 -100.858688)
			(xy 232.210791 -100.850932) (xy 232.265293 -100.850932) (xy 232.319241 -100.858688) (xy 232.371536 -100.874043)
			(xy 232.421113 -100.896685) (xy 232.466963 -100.926151) (xy 232.508154 -100.961842) (xy 232.543845 -101.003033)
			(xy 232.573311 -101.048883) (xy 232.595953 -101.09846) (xy 232.611308 -101.150755) (xy 232.619064 -101.204703)
			(xy 232.61955 -101.231954) (xy 232.619069 -101.259324) (xy 232.611257 -101.313503) (xy 232.595772 -101.366006)
			(xy 232.572933 -101.415753) (xy 232.543211 -101.46172) (xy 232.52557 -101.482652) (xy 232.525316 -101.482906)
			(xy 232.519723 -101.489988) (xy 232.513479 -101.506908) (xy 232.513124 -101.515926) (xy 232.513124 -101.582982)
			(xy 232.513485 -101.591999) (xy 232.519729 -101.608916) (xy 232.525316 -101.616002) (xy 232.52557 -101.616002)
			(xy 232.52557 -101.616256) (xy 232.543166 -101.637225) (xy 232.572893 -101.683187) (xy 232.595741 -101.732927)
			(xy 232.611241 -101.785423) (xy 232.619074 -101.839597) (xy 232.619079 -101.894334) (xy 232.611256 -101.948509)
			(xy 232.595765 -102.001008) (xy 232.572926 -102.050753) (xy 232.543208 -102.096719) (xy 232.52557 -102.117652)
			(xy 232.525316 -102.117906) (xy 232.519723 -102.124988) (xy 232.513479 -102.141908) (xy 232.513124 -102.150926)
			(xy 232.513124 -102.217982) (xy 232.513485 -102.226999) (xy 232.519729 -102.243916) (xy 232.525316 -102.251002)
			(xy 232.52557 -102.251002) (xy 232.52557 -102.251256) (xy 232.543197 -102.272198) (xy 232.572912 -102.318167)
			(xy 232.595751 -102.367912) (xy 232.611244 -102.420411) (xy 232.619075 -102.474585) (xy 232.61955 -102.501954)
			(xy 232.619064 -102.529205) (xy 232.611308 -102.583153) (xy 232.595953 -102.635448) (xy 232.573311 -102.685025)
			(xy 232.543845 -102.730875) (xy 232.508154 -102.772066) (xy 232.466963 -102.807757) (xy 232.421113 -102.837223)
			(xy 232.371536 -102.859865) (xy 232.319241 -102.87522) (xy 232.265293 -102.882976) (xy 232.210791 -102.882976)
			(xy 232.156843 -102.87522) (xy 232.104548 -102.859865) (xy 232.054971 -102.837223) (xy 232.009121 -102.807757)
			(xy 231.96793 -102.772066) (xy 231.932239 -102.730875) (xy 231.902773 -102.685025) (xy 231.880131 -102.635448)
			(xy 231.864776 -102.583153) (xy 231.85702 -102.529205) (xy 231.856534 -102.501954) (xy 229.424979 -102.501954)
			(xy 229.42476 -102.514219) (xy 229.417004 -102.568167) (xy 229.401649 -102.620462) (xy 229.379007 -102.670039)
			(xy 229.349541 -102.715889) (xy 229.31385 -102.75708) (xy 229.272659 -102.792771) (xy 229.226809 -102.822237)
			(xy 229.177232 -102.844879) (xy 229.124937 -102.860234) (xy 229.070989 -102.86799) (xy 229.016487 -102.86799)
			(xy 228.962539 -102.860234) (xy 228.910244 -102.844879) (xy 228.860667 -102.822237) (xy 228.814817 -102.792771)
			(xy 228.773626 -102.75708) (xy 228.737935 -102.715889) (xy 228.708469 -102.670039) (xy 228.685827 -102.620462)
			(xy 228.670472 -102.568167) (xy 228.662716 -102.514219) (xy 228.66223 -102.486968) (xy 228.08612 -102.486968)
			(xy 228.08905 -102.493383) (xy 228.104409 -102.545687) (xy 228.112167 -102.599644) (xy 228.112167 -102.654156)
			(xy 228.104409 -102.708113) (xy 228.08905 -102.760417) (xy 228.066404 -102.810002) (xy 228.036931 -102.855859)
			(xy 228.001231 -102.897055) (xy 227.960032 -102.932751) (xy 227.914172 -102.96222) (xy 227.864585 -102.984862)
			(xy 227.81228 -103.000216) (xy 227.758322 -103.007969) (xy 227.731066 -103.00843) (xy 227.704752 -103.007976)
			(xy 227.652623 -103.000737) (xy 227.60198 -102.986414) (xy 227.553782 -102.96528) (xy 227.508938 -102.937732)
			(xy 227.468299 -102.904292) (xy 227.450142 -102.88524) (xy 227.442601 -102.877861) (xy 227.423336 -102.869322)
			(xy 227.412804 -102.86873) (xy 227.338128 -102.86873) (xy 227.327577 -102.869252) (xy 227.308281 -102.877791)
			(xy 227.30079 -102.88524) (xy 227.28264 -102.904301) (xy 227.242008 -102.937756) (xy 227.197167 -102.965313)
			(xy 227.148965 -102.986451) (xy 227.098317 -103.000767) (xy 227.046182 -103.007991) (xy 227.019866 -103.00843)
			(xy 226.992618 -103.007897) (xy 226.938677 -103.000137) (xy 226.886389 -102.98478) (xy 226.836819 -102.962139)
			(xy 226.790976 -102.932673) (xy 226.749792 -102.896984) (xy 226.714107 -102.855797) (xy 226.684645 -102.809951)
			(xy 226.662008 -102.760379) (xy 226.646655 -102.70809) (xy 226.6389 -102.654148) (xy 225.648871 -102.654148)
			(xy 225.652838 -102.65918) (xy 225.653092 -102.659688) (xy 225.664036 -102.672422) (xy 225.683877 -102.699514)
			(xy 225.692716 -102.71379) (xy 225.69805 -102.72268) (xy 225.715068 -102.734872) (xy 225.808286 -102.755192)
			(xy 225.82886 -102.750874) (xy 225.837496 -102.745032) (xy 225.861562 -102.729035) (xy 225.913492 -102.703691)
			(xy 225.96865 -102.686464) (xy 226.025774 -102.677749) (xy 226.054666 -102.677214) (xy 226.081922 -102.677631)
			(xy 226.13588 -102.685384) (xy 226.188185 -102.700738) (xy 226.237772 -102.72338) (xy 226.283632 -102.752849)
			(xy 226.324831 -102.788545) (xy 226.360531 -102.829741) (xy 226.390004 -102.875598) (xy 226.41265 -102.925183)
			(xy 226.428009 -102.977487) (xy 226.435767 -103.031444) (xy 226.435767 -103.085956) (xy 226.428009 -103.139913)
			(xy 226.41265 -103.192217) (xy 226.390004 -103.241802) (xy 226.360531 -103.287659) (xy 226.324831 -103.328855)
			(xy 226.283632 -103.364551) (xy 226.237772 -103.39402) (xy 226.188185 -103.416662) (xy 226.13588 -103.432016)
			(xy 226.081922 -103.439769) (xy 226.054666 -103.44023) (xy 226.026574 -103.439756) (xy 225.970996 -103.431525)
			(xy 225.917227 -103.415229) (xy 225.866429 -103.391223) (xy 225.819703 -103.360025) (xy 225.778058 -103.322311)
			(xy 225.742396 -103.278895) (xy 225.727514 -103.255064) (xy 225.72218 -103.246174) (xy 225.705162 -103.233982)
			(xy 225.611944 -103.213662) (xy 225.59137 -103.21798) (xy 225.582734 -103.223822) (xy 225.558664 -103.239812)
			(xy 225.506735 -103.265157) (xy 225.451579 -103.282385) (xy 225.394456 -103.291103) (xy 225.365564 -103.29164)
			(xy 225.338313 -103.291156) (xy 225.284367 -103.283395) (xy 225.232074 -103.268037) (xy 225.182499 -103.245394)
			(xy 225.13665 -103.215927) (xy 225.095462 -103.180236) (xy 225.059771 -103.139046) (xy 225.030304 -103.093197)
			(xy 225.007661 -103.043622) (xy 224.992304 -102.991329) (xy 224.984544 -102.937383) (xy 224.984056 -102.910132)
			(xy 215.393091 -102.910132) (xy 215.150954 -103.494586) (xy 215.151533 -103.498191) (xy 215.153574 -103.505202)
			(xy 215.155018 -103.508556) (xy 215.15832 -103.515922) (xy 215.161368 -103.523034) (xy 215.168734 -103.533702)
			(xy 215.171782 -103.53675) (xy 215.172299 -103.537258) (xy 220.43085 -103.537258) (xy 220.434921 -103.481636)
			(xy 220.447047 -103.427199) (xy 220.46697 -103.375108) (xy 220.494266 -103.326473) (xy 220.528352 -103.28233)
			(xy 220.568501 -103.243621) (xy 220.613859 -103.21117) (xy 220.663459 -103.185669) (xy 220.716243 -103.167662)
			(xy 220.771086 -103.157532) (xy 220.82682 -103.155495) (xy 220.882257 -103.161595) (xy 220.936214 -103.175701)
			(xy 220.987543 -103.197513) (xy 221.035149 -103.226567) (xy 221.078017 -103.262242) (xy 221.115234 -103.303779)
			(xy 221.146007 -103.350292) (xy 221.169679 -103.400789) (xy 221.185747 -103.454196) (xy 221.193867 -103.509372)
			(xy 221.194376 -103.537258) (xy 221.193867 -103.565144) (xy 221.185747 -103.62032) (xy 221.169679 -103.673727)
			(xy 221.146007 -103.724224) (xy 221.115234 -103.770737) (xy 221.078017 -103.812274) (xy 221.035149 -103.847949)
			(xy 220.987543 -103.877003) (xy 220.936214 -103.898815) (xy 220.882257 -103.912921) (xy 220.82682 -103.919021)
			(xy 220.771086 -103.916984) (xy 220.716243 -103.906854) (xy 220.663459 -103.888847) (xy 220.613859 -103.863346)
			(xy 220.568501 -103.830895) (xy 220.528352 -103.792186) (xy 220.494266 -103.748043) (xy 220.46697 -103.699408)
			(xy 220.447047 -103.647317) (xy 220.434921 -103.59288) (xy 220.43085 -103.537258) (xy 215.172299 -103.537258)
			(xy 215.190161 -103.554819) (xy 215.222383 -103.595044) (xy 215.248899 -103.639239) (xy 215.269227 -103.6866)
			(xy 215.282997 -103.736266) (xy 215.289959 -103.787333) (xy 215.2904 -103.813102) (xy 215.2904 -103.81361)
			(xy 215.289914 -103.840861) (xy 215.282156 -103.894807) (xy 215.2668 -103.9471) (xy 215.244158 -103.996675)
			(xy 215.214691 -104.042524) (xy 215.179 -104.083712) (xy 215.13781 -104.119402) (xy 215.09196 -104.148867)
			(xy 215.042383 -104.171506) (xy 214.990089 -104.18686) (xy 214.936143 -104.194615) (xy 214.908892 -104.195118)
			(xy 214.895176 -104.194864) (xy 214.88654 -104.19461) (xy 214.878584 -104.195081) (xy 214.863566 -104.200397)
			(xy 214.857076 -104.205024) (xy 214.737953 -104.492552) (xy 215.414096 -104.492552) (xy 215.418167 -104.43693)
			(xy 215.430293 -104.382493) (xy 215.450216 -104.330402) (xy 215.477512 -104.281767) (xy 215.511598 -104.237624)
			(xy 215.551747 -104.198915) (xy 215.597105 -104.166464) (xy 215.646705 -104.140963) (xy 215.699489 -104.122956)
			(xy 215.754332 -104.112826) (xy 215.810066 -104.110789) (xy 215.865503 -104.116889) (xy 215.91946 -104.130995)
			(xy 215.970789 -104.152807) (xy 216.018395 -104.181861) (xy 216.061263 -104.217536) (xy 216.09848 -104.259073)
			(xy 216.129253 -104.305586) (xy 216.152925 -104.356083) (xy 216.168993 -104.40949) (xy 216.177113 -104.464666)
			(xy 216.177622 -104.492552) (xy 216.177113 -104.520438) (xy 216.168993 -104.575614) (xy 216.152925 -104.629021)
			(xy 216.147719 -104.640126) (xy 216.7923 -104.640126) (xy 216.796371 -104.584504) (xy 216.808497 -104.530067)
			(xy 216.82842 -104.477976) (xy 216.855716 -104.429341) (xy 216.889802 -104.385198) (xy 216.929951 -104.346489)
			(xy 216.975309 -104.314038) (xy 217.024909 -104.288537) (xy 217.077693 -104.27053) (xy 217.132536 -104.2604)
			(xy 217.18827 -104.258363) (xy 217.243707 -104.264463) (xy 217.297664 -104.278569) (xy 217.348993 -104.300381)
			(xy 217.396599 -104.329435) (xy 217.439467 -104.36511) (xy 217.476684 -104.406647) (xy 217.507457 -104.45316)
			(xy 217.531129 -104.503657) (xy 217.547197 -104.557064) (xy 217.550344 -104.578448) (xy 222.806304 -104.578448)
			(xy 222.806304 -104.523952) (xy 222.814059 -104.470012) (xy 222.829411 -104.417724) (xy 222.852048 -104.368153)
			(xy 222.881508 -104.322308) (xy 222.917193 -104.281121) (xy 222.958376 -104.245432) (xy 223.004218 -104.215967)
			(xy 223.053787 -104.193325) (xy 223.106073 -104.177968) (xy 223.160013 -104.170207) (xy 223.18726 -104.169718)
			(xy 223.21463 -104.170203) (xy 223.268808 -104.178016) (xy 223.321311 -104.1935) (xy 223.371058 -104.216338)
			(xy 223.417026 -104.246058) (xy 223.437958 -104.263698) (xy 223.438212 -104.263952) (xy 223.445286 -104.269556)
			(xy 223.462213 -104.275791) (xy 223.471232 -104.276144) (xy 223.538288 -104.276144) (xy 223.547306 -104.275793)
			(xy 223.564223 -104.269543) (xy 223.571308 -104.263952) (xy 223.571308 -104.263698) (xy 223.571562 -104.263698)
			(xy 223.592497 -104.246063) (xy 223.638469 -104.216351) (xy 223.688216 -104.193514) (xy 223.740716 -104.178022)
			(xy 223.794891 -104.170193) (xy 223.82226 -104.169718) (xy 223.849517 -104.170126) (xy 223.903476 -104.177879)
			(xy 223.955782 -104.193233) (xy 224.00537 -104.215874) (xy 224.051232 -104.245343) (xy 224.092432 -104.28104)
			(xy 224.128133 -104.322236) (xy 224.157606 -104.368094) (xy 224.180253 -104.417681) (xy 224.195612 -104.469985)
			(xy 224.203371 -104.523943) (xy 224.203371 -104.578457) (xy 224.195612 -104.632415) (xy 224.180253 -104.684719)
			(xy 224.157606 -104.734306) (xy 224.128133 -104.780164) (xy 224.092432 -104.82136) (xy 224.051232 -104.857057)
			(xy 224.00537 -104.886526) (xy 223.955782 -104.909167) (xy 223.903476 -104.924521) (xy 223.849517 -104.932274)
			(xy 223.82226 -104.932734) (xy 223.79489 -104.932249) (xy 223.740711 -104.924438) (xy 223.688208 -104.908954)
			(xy 223.638461 -104.886116) (xy 223.592494 -104.856394) (xy 223.571562 -104.838754) (xy 223.571308 -104.8385)
			(xy 223.564223 -104.832911) (xy 223.547305 -104.826666) (xy 223.538288 -104.826308) (xy 223.471232 -104.826308)
			(xy 223.462216 -104.826678) (xy 223.445299 -104.832916) (xy 223.438212 -104.8385) (xy 223.438212 -104.838754)
			(xy 223.437958 -104.838754) (xy 223.417009 -104.856372) (xy 223.371042 -104.886089) (xy 223.321298 -104.908929)
			(xy 223.268801 -104.924425) (xy 223.214628 -104.932258) (xy 223.18726 -104.932734) (xy 223.160013 -104.932193)
			(xy 223.106073 -104.924432) (xy 223.053787 -104.909075) (xy 223.004218 -104.886433) (xy 222.958376 -104.856968)
			(xy 222.917193 -104.821279) (xy 222.881508 -104.780092) (xy 222.852048 -104.734247) (xy 222.829411 -104.684676)
			(xy 222.814059 -104.632388) (xy 222.806304 -104.578448) (xy 217.550344 -104.578448) (xy 217.555317 -104.61224)
			(xy 217.555826 -104.640126) (xy 217.555317 -104.668012) (xy 217.547197 -104.723188) (xy 217.531129 -104.776595)
			(xy 217.507457 -104.827092) (xy 217.476684 -104.873605) (xy 217.439467 -104.915142) (xy 217.396599 -104.950817)
			(xy 217.348993 -104.979871) (xy 217.297664 -105.001683) (xy 217.243707 -105.015789) (xy 217.18827 -105.021889)
			(xy 217.132536 -105.019852) (xy 217.077693 -105.009722) (xy 217.024909 -104.991715) (xy 216.975309 -104.966214)
			(xy 216.929951 -104.933763) (xy 216.889802 -104.895054) (xy 216.855716 -104.850911) (xy 216.82842 -104.802276)
			(xy 216.808497 -104.750185) (xy 216.796371 -104.695748) (xy 216.7923 -104.640126) (xy 216.147719 -104.640126)
			(xy 216.129253 -104.679518) (xy 216.09848 -104.726031) (xy 216.061263 -104.767568) (xy 216.018395 -104.803243)
			(xy 215.970789 -104.832297) (xy 215.91946 -104.854109) (xy 215.865503 -104.868215) (xy 215.810066 -104.874315)
			(xy 215.754332 -104.872278) (xy 215.699489 -104.862148) (xy 215.646705 -104.844141) (xy 215.597105 -104.81864)
			(xy 215.551747 -104.786189) (xy 215.511598 -104.74748) (xy 215.477512 -104.703337) (xy 215.450216 -104.654702)
			(xy 215.430293 -104.602611) (xy 215.418167 -104.548174) (xy 215.414096 -104.492552) (xy 214.737953 -104.492552)
			(xy 214.474663 -105.12806) (xy 217.654632 -105.12806) (xy 217.655118 -105.100809) (xy 217.662874 -105.046861)
			(xy 217.678229 -104.994566) (xy 217.700871 -104.944989) (xy 217.730337 -104.899139) (xy 217.766028 -104.857948)
			(xy 217.807219 -104.822257) (xy 217.853069 -104.792791) (xy 217.902646 -104.770149) (xy 217.954941 -104.754794)
			(xy 218.008889 -104.747038) (xy 218.063391 -104.747038) (xy 218.117339 -104.754794) (xy 218.169634 -104.770149)
			(xy 218.219211 -104.792791) (xy 218.265061 -104.822257) (xy 218.306252 -104.857948) (xy 218.341943 -104.899139)
			(xy 218.371409 -104.944989) (xy 218.394051 -104.994566) (xy 218.409406 -105.046861) (xy 218.417162 -105.100809)
			(xy 218.417648 -105.12806) (xy 218.417163 -105.155052) (xy 218.409562 -105.208499) (xy 218.394508 -105.260343)
			(xy 218.372299 -105.309548) (xy 218.34338 -105.355133) (xy 218.326208 -105.375964) (xy 218.319096 -105.384092)
			(xy 218.313 -105.404666) (xy 218.323922 -105.49001) (xy 218.32568 -105.500559) (xy 218.336746 -105.51884)
			(xy 218.337029 -105.519055) (xy 222.355843 -105.519055) (xy 222.355843 -105.464545) (xy 222.363601 -105.410591)
			(xy 222.378958 -105.35829) (xy 222.401603 -105.308707) (xy 222.431073 -105.262852) (xy 222.46677 -105.221657)
			(xy 222.507966 -105.185962) (xy 222.553823 -105.156494) (xy 222.603407 -105.133852) (xy 222.655709 -105.118497)
			(xy 222.709663 -105.110742) (xy 222.736918 -105.11028) (xy 222.76429 -105.110716) (xy 222.818471 -105.118538)
			(xy 222.870975 -105.134033) (xy 222.920721 -105.156882) (xy 222.966686 -105.186615) (xy 222.987616 -105.20426)
			(xy 222.98787 -105.204514) (xy 222.99496 -105.210096) (xy 223.011874 -105.216345) (xy 223.02089 -105.216706)
			(xy 223.087946 -105.216706) (xy 223.09696 -105.216322) (xy 223.113877 -105.210093) (xy 223.120966 -105.204514)
			(xy 223.120966 -105.20426) (xy 223.12122 -105.20426) (xy 223.142166 -105.186638) (xy 223.188136 -105.156925)
			(xy 223.23788 -105.134086) (xy 223.290377 -105.118591) (xy 223.34455 -105.110757) (xy 223.371918 -105.11028)
			(xy 223.399168 -105.110791) (xy 223.453112 -105.11855) (xy 223.505402 -105.133906) (xy 223.554976 -105.156547)
			(xy 223.600822 -105.186013) (xy 223.642009 -105.221704) (xy 223.677698 -105.262892) (xy 223.707161 -105.30874)
			(xy 223.7298 -105.358314) (xy 223.745154 -105.410606) (xy 223.75291 -105.46455) (xy 223.75291 -105.51905)
			(xy 223.745154 -105.572994) (xy 223.7298 -105.625286) (xy 223.707161 -105.67486) (xy 223.677698 -105.720708)
			(xy 223.642009 -105.761896) (xy 223.600822 -105.797587) (xy 223.554976 -105.827053) (xy 223.505402 -105.849694)
			(xy 223.453112 -105.86505) (xy 223.399168 -105.872809) (xy 223.371918 -105.873296) (xy 223.344548 -105.87282)
			(xy 223.290369 -105.865005) (xy 223.237866 -105.849518) (xy 223.188119 -105.826679) (xy 223.142152 -105.796956)
			(xy 223.12122 -105.779316) (xy 223.120966 -105.779062) (xy 223.113868 -105.773493) (xy 223.09696 -105.767237)
			(xy 223.087946 -105.76687) (xy 223.02089 -105.76687) (xy 223.011873 -105.767229) (xy 222.994957 -105.773476)
			(xy 222.98787 -105.779062) (xy 222.98787 -105.779316) (xy 222.987616 -105.779316) (xy 222.966691 -105.796964)
			(xy 222.920716 -105.826674) (xy 222.870967 -105.849508) (xy 222.818464 -105.864997) (xy 222.764288 -105.872823)
			(xy 222.736918 -105.873296) (xy 222.709663 -105.872858) (xy 222.655709 -105.865103) (xy 222.603407 -105.849748)
			(xy 222.553823 -105.827106) (xy 222.507966 -105.797638) (xy 222.46677 -105.761943) (xy 222.431073 -105.720748)
			(xy 222.401603 -105.674893) (xy 222.378958 -105.62531) (xy 222.363601 -105.573009) (xy 222.355843 -105.519055)
			(xy 218.337029 -105.519055) (xy 218.345258 -105.525316) (xy 218.369563 -105.542923) (xy 218.41282 -105.584522)
			(xy 218.431364 -105.60812) (xy 218.437206 -105.615994) (xy 218.454732 -105.626408) (xy 218.545156 -105.639616)
			(xy 218.56446 -105.63479) (xy 218.572334 -105.628948) (xy 218.572588 -105.628948) (xy 218.597318 -105.611424)
			(xy 218.651176 -105.583625) (xy 218.708752 -105.564695) (xy 218.768598 -105.555109) (xy 218.798902 -105.554526)
			(xy 218.826156 -105.554954) (xy 218.88011 -105.562712) (xy 218.932411 -105.57807) (xy 218.981993 -105.600715)
			(xy 219.027848 -105.630186) (xy 219.069042 -105.665884) (xy 219.104735 -105.707081) (xy 219.134202 -105.752938)
			(xy 219.156843 -105.802523) (xy 219.172196 -105.854825) (xy 219.179949 -105.90878) (xy 219.18041 -105.936034)
			(xy 219.179985 -105.962068) (xy 219.172893 -106.013652) (xy 219.158859 -106.063794) (xy 219.138143 -106.111565)
			(xy 219.111129 -106.156079) (xy 219.095066 -106.176572) (xy 219.089322 -106.184327) (xy 219.083584 -106.202739)
			(xy 219.08389 -106.212386) (xy 219.09024 -106.292142) (xy 219.098876 -106.309922) (xy 219.106242 -106.316272)
			(xy 219.125887 -106.334454) (xy 219.160411 -106.37536) (xy 219.188882 -106.420688) (xy 219.21074 -106.46955)
			(xy 219.225557 -106.520986) (xy 219.233042 -106.573988) (xy 219.233496 -106.600752) (xy 219.233 -106.628004)
			(xy 219.225249 -106.681955) (xy 219.209899 -106.734253) (xy 219.187261 -106.783833) (xy 219.157797 -106.829687)
			(xy 219.122106 -106.870881) (xy 219.080916 -106.906575) (xy 219.035065 -106.936044) (xy 218.985486 -106.958686)
			(xy 218.93319 -106.974042) (xy 218.87924 -106.981797) (xy 218.851988 -106.98226) (xy 218.823214 -106.981747)
			(xy 218.76632 -106.973091) (xy 218.71137 -106.955991) (xy 218.65961 -106.930835) (xy 218.612213 -106.898194)
			(xy 218.590876 -106.878882) (xy 218.583002 -106.871516) (xy 218.56319 -106.864404) (xy 218.466924 -106.87177)
			(xy 218.448128 -106.881676) (xy 218.441524 -106.890058) (xy 218.42332 -106.91226) (xy 218.381381 -106.95147)
			(xy 218.334041 -106.983954) (xy 218.282369 -107.00898) (xy 218.227531 -107.025982) (xy 218.170765 -107.034577)
			(xy 218.142058 -107.035092) (xy 218.114805 -107.034661) (xy 218.060854 -107.026899) (xy 218.008558 -107.011537)
			(xy 217.958979 -106.98889) (xy 217.913128 -106.959418) (xy 217.871938 -106.923721) (xy 217.836247 -106.882525)
			(xy 217.806782 -106.83667) (xy 217.784142 -106.787088) (xy 217.768789 -106.734789) (xy 217.761035 -106.680837)
			(xy 217.76055 -106.653584) (xy 217.761021 -106.626682) (xy 217.768594 -106.573413) (xy 217.783573 -106.521736)
			(xy 217.805662 -106.472675) (xy 217.834423 -106.427203) (xy 217.869285 -106.386221) (xy 217.909558 -106.350541)
			(xy 217.931746 -106.335322) (xy 217.942668 -106.32821) (xy 217.954606 -106.30535) (xy 217.952574 -106.193082)
			(xy 217.93962 -106.17073) (xy 217.928444 -106.163872) (xy 217.904851 -106.148937) (xy 217.861897 -106.113262)
			(xy 217.824601 -106.071707) (xy 217.793762 -106.02516) (xy 217.770037 -105.974614) (xy 217.753934 -105.921149)
			(xy 217.745796 -105.865908) (xy 217.74531 -105.83799) (xy 217.745776 -105.810997) (xy 217.753383 -105.75755)
			(xy 217.768442 -105.705707) (xy 217.790655 -105.656502) (xy 217.819577 -105.610917) (xy 217.83675 -105.590086)
			(xy 217.843862 -105.581958) (xy 217.849958 -105.561384) (xy 217.839036 -105.47604) (xy 217.837233 -105.465503)
			(xy 217.826198 -105.447218) (xy 217.8177 -105.440734) (xy 217.79648 -105.425367) (xy 217.758029 -105.38978)
			(xy 217.724811 -105.349265) (xy 217.697452 -105.304585) (xy 217.676467 -105.256579) (xy 217.66225 -105.206153)
			(xy 217.65507 -105.154256) (xy 217.654632 -105.12806) (xy 214.474663 -105.12806) (xy 214.40521 -105.2957)
			(xy 214.403411 -105.300387) (xy 214.401493 -105.310239) (xy 214.4014 -105.315258) (xy 214.4014 -106.670094)
			(xy 214.401822 -106.680165) (xy 214.409535 -106.698771) (xy 214.416386 -106.706162) (xy 215.121744 -107.41152)
			(xy 221.678754 -107.41152) (xy 221.679217 -107.385206) (xy 221.686451 -107.333076) (xy 221.700769 -107.282433)
			(xy 221.721902 -107.234233) (xy 221.74945 -107.18939) (xy 221.782891 -107.148752) (xy 221.801944 -107.130596)
			(xy 221.809341 -107.12307) (xy 221.81787 -107.103794) (xy 221.818454 -107.093258) (xy 221.818454 -107.018582)
			(xy 221.817907 -107.008034) (xy 221.809386 -106.988738) (xy 221.801944 -106.981244) (xy 221.782858 -106.96312)
			(xy 221.749405 -106.922482) (xy 221.721852 -106.877635) (xy 221.700719 -106.829428) (xy 221.686408 -106.778776)
			(xy 221.679189 -106.726638) (xy 221.678754 -106.70032) (xy 221.679297 -106.673071) (xy 221.68705 -106.619127)
			(xy 221.7024 -106.566836) (xy 221.725036 -106.517261) (xy 221.754497 -106.471413) (xy 221.790182 -106.430223)
			(xy 221.831366 -106.394532) (xy 221.877211 -106.365064) (xy 221.926782 -106.34242) (xy 221.979071 -106.327062)
			(xy 222.033013 -106.319301) (xy 222.060262 -106.318812) (xy 222.087926 -106.319348) (xy 222.142675 -106.327343)
			(xy 222.195696 -106.343155) (xy 222.24588 -106.366454) (xy 222.292176 -106.396751) (xy 222.333615 -106.433413)
			(xy 222.369328 -106.475672) (xy 222.384366 -106.498898) (xy 222.391031 -106.508552) (xy 222.410871 -106.52101)
			(xy 222.422466 -106.522774) (xy 222.502476 -106.530648) (xy 222.514114 -106.531258) (xy 222.53595 -106.523193)
			(xy 222.544386 -106.515154) (xy 222.54464 -106.5149) (xy 222.562719 -106.496317) (xy 222.603052 -106.463739)
			(xy 222.647426 -106.436926) (xy 222.695025 -106.416374) (xy 222.74497 -106.402461) (xy 222.796339 -106.395444)
			(xy 222.822262 -106.395012) (xy 222.849515 -106.395491) (xy 222.903466 -106.403243) (xy 222.955765 -106.418595)
			(xy 223.005346 -106.441235) (xy 223.051201 -106.470701) (xy 223.092394 -106.506393) (xy 223.128089 -106.547585)
			(xy 223.157557 -106.593438) (xy 223.180198 -106.643018) (xy 223.195553 -106.695316) (xy 223.203308 -106.749267)
			(xy 223.20377 -106.77652) (xy 223.203323 -106.803891) (xy 223.195502 -106.858071) (xy 223.180009 -106.910575)
			(xy 223.157162 -106.960321) (xy 223.127433 -107.006287) (xy 223.10979 -107.027218) (xy 223.109536 -107.027472)
			(xy 223.103947 -107.034557) (xy 223.097704 -107.051475) (xy 223.097344 -107.060492) (xy 223.097344 -107.127548)
			(xy 223.097716 -107.136564) (xy 223.103952 -107.153481) (xy 223.109536 -107.160568) (xy 223.10979 -107.160568)
			(xy 223.10979 -107.160822) (xy 223.127404 -107.181774) (xy 223.15712 -107.227741) (xy 223.179961 -107.277484)
			(xy 223.195458 -107.32998) (xy 223.203293 -107.384152) (xy 223.20377 -107.41152) (xy 223.203364 -107.438775)
			(xy 223.195603 -107.49273) (xy 223.180242 -107.545031) (xy 223.157595 -107.594614) (xy 223.128121 -107.640469)
			(xy 223.092421 -107.681663) (xy 223.051223 -107.717356) (xy 223.005363 -107.746823) (xy 222.955777 -107.769463)
			(xy 222.903473 -107.784815) (xy 222.849517 -107.792568) (xy 222.822262 -107.793028) (xy 222.793345 -107.792492)
			(xy 222.736174 -107.783771) (xy 222.680974 -107.766518) (xy 222.629012 -107.74113) (xy 222.581478 -107.708188)
			(xy 222.539462 -107.668447) (xy 222.521272 -107.645962) (xy 222.513674 -107.637146) (xy 222.492766 -107.626969)
			(xy 222.48114 -107.626404) (xy 222.401384 -107.626404) (xy 222.389753 -107.626947) (xy 222.368843 -107.637133)
			(xy 222.361252 -107.645962) (xy 222.343022 -107.668413) (xy 222.301012 -107.708152) (xy 222.253485 -107.741096)
			(xy 222.201531 -107.76649) (xy 222.14634 -107.783753) (xy 222.089176 -107.792489) (xy 222.060262 -107.793028)
			(xy 222.033011 -107.792558) (xy 221.979063 -107.784796) (xy 221.92677 -107.769437) (xy 221.877194 -107.746793)
			(xy 221.831344 -107.717325) (xy 221.790155 -107.681632) (xy 221.754464 -107.640441) (xy 221.724998 -107.594591)
			(xy 221.702356 -107.545013) (xy 221.687 -107.492719) (xy 221.679241 -107.438771) (xy 221.678754 -107.41152)
			(xy 215.121744 -107.41152) (xy 215.546475 -107.836251) (xy 233.797585 -107.836251) (xy 233.797585 -107.781749)
			(xy 233.805342 -107.727802) (xy 233.820697 -107.675508) (xy 233.843337 -107.625932) (xy 233.872803 -107.580082)
			(xy 233.908494 -107.538893) (xy 233.949684 -107.503202) (xy 233.995534 -107.473737) (xy 234.04511 -107.451096)
			(xy 234.097404 -107.435741) (xy 234.151351 -107.427985) (xy 234.178602 -107.427522) (xy 234.204916 -107.427981)
			(xy 234.257045 -107.435217) (xy 234.307689 -107.449537) (xy 234.355888 -107.470671) (xy 234.400731 -107.498219)
			(xy 234.44137 -107.531659) (xy 234.459526 -107.550712) (xy 234.467034 -107.558129) (xy 234.486325 -107.566644)
			(xy 234.496864 -107.567222) (xy 234.57154 -107.567222) (xy 234.582087 -107.566667) (xy 234.601382 -107.558149)
			(xy 234.608878 -107.550712) (xy 234.628698 -107.529924) (xy 234.67347 -107.493949) (xy 234.723128 -107.465089)
			(xy 234.77655 -107.443996) (xy 234.832529 -107.431147) (xy 234.889802 -107.426832) (xy 234.947075 -107.431147)
			(xy 235.003054 -107.443996) (xy 235.056476 -107.465089) (xy 235.106134 -107.493949) (xy 235.150906 -107.529924)
			(xy 235.170726 -107.550712) (xy 235.178234 -107.558129) (xy 235.197525 -107.566644) (xy 235.208064 -107.567222)
			(xy 235.28274 -107.567222) (xy 235.293287 -107.566667) (xy 235.312582 -107.558149) (xy 235.320078 -107.550712)
			(xy 235.338254 -107.531676) (xy 235.378879 -107.498217) (xy 235.423715 -107.470655) (xy 235.471912 -107.449513)
			(xy 235.522556 -107.435192) (xy 235.574687 -107.427963) (xy 235.601002 -107.427522) (xy 235.628255 -107.427948)
			(xy 235.682207 -107.435705) (xy 235.734506 -107.451062) (xy 235.784087 -107.473705) (xy 235.82994 -107.503174)
			(xy 235.871134 -107.538868) (xy 235.906828 -107.580061) (xy 235.936296 -107.625915) (xy 235.958939 -107.675496)
			(xy 235.974295 -107.727795) (xy 235.982052 -107.781747) (xy 235.982052 -107.836253) (xy 235.974295 -107.890205)
			(xy 235.958939 -107.942504) (xy 235.936296 -107.992085) (xy 235.906828 -108.037939) (xy 235.871134 -108.079132)
			(xy 235.82994 -108.114826) (xy 235.784087 -108.144295) (xy 235.734506 -108.166938) (xy 235.682207 -108.182295)
			(xy 235.628255 -108.190052) (xy 235.601002 -108.190538) (xy 235.574687 -108.190089) (xy 235.522557 -108.182853)
			(xy 235.471913 -108.168532) (xy 235.423714 -108.147396) (xy 235.378871 -108.119846) (xy 235.338233 -108.086402)
			(xy 235.320078 -108.067348) (xy 235.31256 -108.059942) (xy 235.293278 -108.051419) (xy 235.28274 -108.050838)
			(xy 235.208064 -108.050838) (xy 235.197515 -108.051377) (xy 235.178219 -108.059904) (xy 235.170726 -108.067348)
			(xy 235.150906 -108.088136) (xy 235.106134 -108.124111) (xy 235.056476 -108.152971) (xy 235.003054 -108.174064)
			(xy 234.947075 -108.186913) (xy 234.889802 -108.191228) (xy 234.832529 -108.186913) (xy 234.77655 -108.174064)
			(xy 234.723128 -108.152971) (xy 234.67347 -108.124111) (xy 234.628698 -108.088136) (xy 234.608878 -108.067348)
			(xy 234.60136 -108.059942) (xy 234.582078 -108.051419) (xy 234.57154 -108.050838) (xy 234.496864 -108.050838)
			(xy 234.486315 -108.051377) (xy 234.467019 -108.059904) (xy 234.459526 -108.067348) (xy 234.44136 -108.086393)
			(xy 234.400732 -108.119849) (xy 234.355893 -108.147409) (xy 234.307695 -108.168548) (xy 234.257049 -108.182868)
			(xy 234.204917 -108.190097) (xy 234.178602 -108.190538) (xy 234.151351 -108.190015) (xy 234.097404 -108.182259)
			(xy 234.04511 -108.166904) (xy 233.995534 -108.144263) (xy 233.949684 -108.114798) (xy 233.908494 -108.079107)
			(xy 233.872803 -108.037918) (xy 233.843337 -107.992068) (xy 233.820697 -107.942492) (xy 233.805342 -107.890198)
			(xy 233.797585 -107.836251) (xy 215.546475 -107.836251) (xy 216.183278 -108.473054) (xy 221.556763 -108.473054)
			(xy 221.556763 -108.418546) (xy 221.564521 -108.364593) (xy 221.579879 -108.312294) (xy 221.602523 -108.262713)
			(xy 221.631994 -108.216859) (xy 221.66769 -108.175666) (xy 221.708886 -108.139973) (xy 221.754742 -108.110507)
			(xy 221.804326 -108.087867) (xy 221.856627 -108.072514) (xy 221.91058 -108.064761) (xy 221.937834 -108.0643)
			(xy 221.965205 -108.064746) (xy 222.019385 -108.072569) (xy 222.071888 -108.088063) (xy 222.121635 -108.110909)
			(xy 222.167601 -108.140637) (xy 222.188532 -108.15828) (xy 222.188786 -108.158534) (xy 222.19587 -108.164125)
			(xy 222.212789 -108.170368) (xy 222.221806 -108.170726) (xy 222.288862 -108.170726) (xy 222.297876 -108.170345)
			(xy 222.314793 -108.164114) (xy 222.321882 -108.158534) (xy 222.321882 -108.15828) (xy 222.322136 -108.15828)
			(xy 222.343069 -108.140639) (xy 222.389037 -108.110915) (xy 222.438783 -108.088069) (xy 222.491285 -108.072573)
			(xy 222.545463 -108.064744) (xy 222.600205 -108.064744) (xy 222.654383 -108.072573) (xy 222.706885 -108.088069)
			(xy 222.756631 -108.110915) (xy 222.802599 -108.140639) (xy 222.823532 -108.15828) (xy 222.823786 -108.158534)
			(xy 222.83087 -108.164125) (xy 222.847789 -108.170368) (xy 222.856806 -108.170726) (xy 222.923862 -108.170726)
			(xy 222.932876 -108.170345) (xy 222.949793 -108.164114) (xy 222.956882 -108.158534) (xy 222.956882 -108.15828)
			(xy 222.957136 -108.15828) (xy 222.978069 -108.140639) (xy 223.024037 -108.110915) (xy 223.073783 -108.088069)
			(xy 223.126285 -108.072573) (xy 223.180463 -108.064744) (xy 223.235205 -108.064744) (xy 223.289383 -108.072573)
			(xy 223.341885 -108.088069) (xy 223.391631 -108.110915) (xy 223.437599 -108.140639) (xy 223.458532 -108.15828)
			(xy 223.458786 -108.158534) (xy 223.46587 -108.164125) (xy 223.482789 -108.170368) (xy 223.491806 -108.170726)
			(xy 223.558862 -108.170726) (xy 223.567876 -108.170345) (xy 223.584793 -108.164114) (xy 223.591882 -108.158534)
			(xy 223.591882 -108.15828) (xy 223.592136 -108.15828) (xy 223.613079 -108.140654) (xy 223.659049 -108.110941)
			(xy 223.708794 -108.088103) (xy 223.761292 -108.072609) (xy 223.815466 -108.064776) (xy 223.842834 -108.0643)
			(xy 223.870084 -108.064772) (xy 223.924029 -108.072533) (xy 223.976321 -108.087891) (xy 224.025895 -108.110535)
			(xy 224.071742 -108.140002) (xy 224.112929 -108.175695) (xy 224.148618 -108.216885) (xy 224.178082 -108.262735)
			(xy 224.200721 -108.312311) (xy 224.216075 -108.364604) (xy 224.22383 -108.41855) (xy 224.22383 -108.47305)
			(xy 224.216075 -108.526996) (xy 224.200721 -108.579289) (xy 224.178082 -108.628865) (xy 224.148618 -108.674715)
			(xy 224.112929 -108.715905) (xy 224.071742 -108.751598) (xy 224.025895 -108.781065) (xy 223.976321 -108.803709)
			(xy 223.924029 -108.819067) (xy 223.870084 -108.826828) (xy 223.842834 -108.827316) (xy 223.815464 -108.82685)
			(xy 223.761284 -108.819036) (xy 223.70878 -108.803548) (xy 223.659033 -108.780705) (xy 223.613067 -108.750979)
			(xy 223.592136 -108.733336) (xy 223.591882 -108.733082) (xy 223.584806 -108.72748) (xy 223.567881 -108.721243)
			(xy 223.558862 -108.72089) (xy 223.491806 -108.72089) (xy 223.48279 -108.721252) (xy 223.465873 -108.727496)
			(xy 223.458786 -108.733082) (xy 223.458532 -108.733336) (xy 223.437599 -108.750977) (xy 223.391631 -108.780701)
			(xy 223.341885 -108.803547) (xy 223.289383 -108.819043) (xy 223.235205 -108.826872) (xy 223.180463 -108.826872)
			(xy 223.126285 -108.819043) (xy 223.073783 -108.803547) (xy 223.024037 -108.780701) (xy 222.978069 -108.750977)
			(xy 222.957136 -108.733336) (xy 222.956882 -108.733082) (xy 222.949806 -108.72748) (xy 222.932881 -108.721243)
			(xy 222.923862 -108.72089) (xy 222.856806 -108.72089) (xy 222.84779 -108.721252) (xy 222.830873 -108.727496)
			(xy 222.823786 -108.733082) (xy 222.823786 -108.733336) (xy 222.823532 -108.733336) (xy 222.802599 -108.750977)
			(xy 222.756631 -108.780701) (xy 222.706885 -108.803547) (xy 222.654383 -108.819043) (xy 222.600205 -108.826872)
			(xy 222.545463 -108.826872) (xy 222.491285 -108.819043) (xy 222.438783 -108.803547) (xy 222.389037 -108.780701)
			(xy 222.343069 -108.750977) (xy 222.322136 -108.733336) (xy 222.321882 -108.733082) (xy 222.314806 -108.72748)
			(xy 222.297881 -108.721243) (xy 222.288862 -108.72089) (xy 222.221806 -108.72089) (xy 222.21279 -108.721252)
			(xy 222.195873 -108.727496) (xy 222.188786 -108.733082) (xy 222.188786 -108.733336) (xy 222.188532 -108.733336)
			(xy 222.167603 -108.750979) (xy 222.121629 -108.780689) (xy 222.071881 -108.803524) (xy 222.019379 -108.819014)
			(xy 221.965203 -108.826842) (xy 221.937834 -108.827316) (xy 221.91058 -108.826839) (xy 221.856627 -108.819086)
			(xy 221.804326 -108.803733) (xy 221.754742 -108.781093) (xy 221.708886 -108.751627) (xy 221.66769 -108.715934)
			(xy 221.631994 -108.674741) (xy 221.602523 -108.628887) (xy 221.579879 -108.579306) (xy 221.564521 -108.527007)
			(xy 221.556763 -108.473054) (xy 216.183278 -108.473054) (xy 218.839077 -111.128853) (xy 221.497087 -111.128853)
			(xy 221.497087 -111.074347) (xy 221.504845 -111.020397) (xy 221.520202 -110.9681) (xy 221.542846 -110.918521)
			(xy 221.572315 -110.87267) (xy 221.608011 -110.83148) (xy 221.649205 -110.795789) (xy 221.69506 -110.766325)
			(xy 221.744641 -110.743686) (xy 221.79694 -110.728335) (xy 221.850891 -110.720584) (xy 221.878144 -110.720124)
			(xy 221.905513 -110.720617) (xy 221.959691 -110.728427) (xy 222.012195 -110.74391) (xy 222.061942 -110.766746)
			(xy 222.10791 -110.796465) (xy 222.128842 -110.814104) (xy 222.129096 -110.814358) (xy 222.136175 -110.819956)
			(xy 222.153098 -110.826194) (xy 222.162116 -110.82655) (xy 222.229172 -110.82655) (xy 222.238189 -110.82619)
			(xy 222.255106 -110.819946) (xy 222.262192 -110.814358) (xy 222.262192 -110.814104) (xy 222.262446 -110.814104)
			(xy 222.283379 -110.796463) (xy 222.329347 -110.766739) (xy 222.379093 -110.743893) (xy 222.431595 -110.728397)
			(xy 222.485773 -110.720568) (xy 222.540515 -110.720568) (xy 222.594693 -110.728397) (xy 222.647195 -110.743893)
			(xy 222.696941 -110.766739) (xy 222.742909 -110.796463) (xy 222.763842 -110.814104) (xy 222.764096 -110.814358)
			(xy 222.771175 -110.819956) (xy 222.788098 -110.826194) (xy 222.797116 -110.82655) (xy 222.864172 -110.82655)
			(xy 222.873189 -110.82619) (xy 222.890106 -110.819946) (xy 222.897192 -110.814358) (xy 222.897192 -110.814104)
			(xy 222.897446 -110.814104) (xy 222.918379 -110.796463) (xy 222.964347 -110.766739) (xy 223.014093 -110.743893)
			(xy 223.066595 -110.728397) (xy 223.120773 -110.720568) (xy 223.175515 -110.720568) (xy 223.229693 -110.728397)
			(xy 223.282195 -110.743893) (xy 223.331941 -110.766739) (xy 223.377909 -110.796463) (xy 223.398842 -110.814104)
			(xy 223.399096 -110.814358) (xy 223.406175 -110.819956) (xy 223.423098 -110.826194) (xy 223.432116 -110.82655)
			(xy 223.499172 -110.82655) (xy 223.508189 -110.82619) (xy 223.525106 -110.819946) (xy 223.532192 -110.814358)
			(xy 223.532192 -110.814104) (xy 223.532446 -110.814104) (xy 223.553388 -110.796477) (xy 223.599358 -110.766764)
			(xy 223.649103 -110.743925) (xy 223.701602 -110.728431) (xy 223.755776 -110.7206) (xy 223.783144 -110.720124)
			(xy 223.810395 -110.720549) (xy 223.864343 -110.728311) (xy 223.916637 -110.743671) (xy 223.966213 -110.766317)
			(xy 224.012061 -110.795787) (xy 224.05325 -110.831481) (xy 224.08894 -110.872674) (xy 224.118404 -110.918526)
			(xy 224.134218 -110.953156) (xy 233.725619 -110.953156) (xy 233.725619 -110.898644) (xy 233.733377 -110.844686)
			(xy 233.748736 -110.792381) (xy 233.771382 -110.742795) (xy 233.800855 -110.696937) (xy 233.836554 -110.65574)
			(xy 233.877753 -110.620043) (xy 233.923613 -110.590572) (xy 233.9732 -110.567929) (xy 234.025505 -110.552573)
			(xy 234.079464 -110.544818) (xy 234.10672 -110.544356) (xy 234.133035 -110.544792) (xy 234.185166 -110.552031)
			(xy 234.23581 -110.566355) (xy 234.284009 -110.587493) (xy 234.328852 -110.615046) (xy 234.369489 -110.648491)
			(xy 234.387644 -110.667546) (xy 234.395155 -110.674961) (xy 234.414443 -110.68348) (xy 234.424982 -110.684056)
			(xy 234.499658 -110.684056) (xy 234.510208 -110.683531) (xy 234.529505 -110.674994) (xy 234.536996 -110.667546)
			(xy 234.556816 -110.646758) (xy 234.601588 -110.610783) (xy 234.651246 -110.581923) (xy 234.704668 -110.56083)
			(xy 234.760647 -110.547981) (xy 234.81792 -110.543666) (xy 234.875193 -110.547981) (xy 234.931172 -110.56083)
			(xy 234.984594 -110.581923) (xy 235.034252 -110.610783) (xy 235.079024 -110.646758) (xy 235.098844 -110.667546)
			(xy 235.106355 -110.674961) (xy 235.125643 -110.68348) (xy 235.136182 -110.684056) (xy 235.210858 -110.684056)
			(xy 235.221408 -110.683531) (xy 235.240705 -110.674994) (xy 235.248196 -110.667546) (xy 235.26635 -110.648489)
			(xy 235.306981 -110.615034) (xy 235.351822 -110.587477) (xy 235.400023 -110.566339) (xy 235.45067 -110.552021)
			(xy 235.502804 -110.544795) (xy 235.52912 -110.544356) (xy 235.556368 -110.544916) (xy 235.610308 -110.552674)
			(xy 235.662595 -110.568029) (xy 235.712165 -110.590669) (xy 235.758009 -110.620133) (xy 235.799193 -110.655821)
			(xy 235.834879 -110.697007) (xy 235.86434 -110.742852) (xy 235.886978 -110.792423) (xy 235.902331 -110.844711)
			(xy 235.910086 -110.898652) (xy 235.910086 -110.953148) (xy 235.902331 -111.007089) (xy 235.886978 -111.059377)
			(xy 235.86434 -111.108948) (xy 235.834879 -111.154793) (xy 235.799193 -111.195979) (xy 235.758009 -111.231667)
			(xy 235.712165 -111.261131) (xy 235.662595 -111.283771) (xy 235.610308 -111.299126) (xy 235.556368 -111.306884)
			(xy 235.52912 -111.307372) (xy 235.502806 -111.3069) (xy 235.450677 -111.299667) (xy 235.400034 -111.28535)
			(xy 235.351835 -111.264218) (xy 235.306992 -111.236673) (xy 235.266352 -111.203234) (xy 235.248196 -111.184182)
			(xy 235.24068 -111.176774) (xy 235.221396 -111.168254) (xy 235.210858 -111.167672) (xy 235.136182 -111.167672)
			(xy 235.125637 -111.16824) (xy 235.106342 -111.176749) (xy 235.098844 -111.184182) (xy 235.079024 -111.20497)
			(xy 235.034252 -111.240945) (xy 234.984594 -111.269805) (xy 234.931172 -111.290898) (xy 234.875193 -111.303747)
			(xy 234.81792 -111.308062) (xy 234.760647 -111.303747) (xy 234.704668 -111.290898) (xy 234.651246 -111.269805)
			(xy 234.601588 -111.240945) (xy 234.556816 -111.20497) (xy 234.536996 -111.184182) (xy 234.52948 -111.176774)
			(xy 234.510196 -111.168254) (xy 234.499658 -111.167672) (xy 234.424982 -111.167672) (xy 234.414437 -111.16824)
			(xy 234.395142 -111.176749) (xy 234.387644 -111.184182) (xy 234.369505 -111.203254) (xy 234.328872 -111.236711)
			(xy 234.284029 -111.264268) (xy 234.235824 -111.285404) (xy 234.185174 -111.299717) (xy 234.133037 -111.306936)
			(xy 234.10672 -111.307372) (xy 234.079464 -111.306982) (xy 234.025505 -111.299227) (xy 233.9732 -111.283871)
			(xy 233.923613 -111.261228) (xy 233.877753 -111.231757) (xy 233.836554 -111.19606) (xy 233.800855 -111.154863)
			(xy 233.771382 -111.109005) (xy 233.748736 -111.059419) (xy 233.733377 -111.007114) (xy 233.725619 -110.953156)
			(xy 224.134218 -110.953156) (xy 224.141044 -110.968104) (xy 224.156398 -111.0204) (xy 224.164154 -111.074348)
			(xy 224.164154 -111.128852) (xy 224.156398 -111.1828) (xy 224.141044 -111.235096) (xy 224.118404 -111.284674)
			(xy 224.08894 -111.330526) (xy 224.05325 -111.371719) (xy 224.012061 -111.407413) (xy 223.966213 -111.436883)
			(xy 223.916637 -111.459529) (xy 223.864343 -111.474889) (xy 223.810395 -111.482651) (xy 223.783144 -111.48314)
			(xy 223.755774 -111.482663) (xy 223.701595 -111.47485) (xy 223.649091 -111.459364) (xy 223.599344 -111.436525)
			(xy 223.553377 -111.406801) (xy 223.532446 -111.38916) (xy 223.532192 -111.388906) (xy 223.525111 -111.383311)
			(xy 223.50819 -111.377069) (xy 223.499172 -111.376714) (xy 223.432116 -111.376714) (xy 223.4231 -111.377075)
			(xy 223.406182 -111.38332) (xy 223.399096 -111.388906) (xy 223.398842 -111.38916) (xy 223.377909 -111.406801)
			(xy 223.331941 -111.436525) (xy 223.282195 -111.459371) (xy 223.229693 -111.474867) (xy 223.175515 -111.482696)
			(xy 223.120773 -111.482696) (xy 223.066595 -111.474867) (xy 223.014093 -111.459371) (xy 222.964347 -111.436525)
			(xy 222.918379 -111.406801) (xy 222.897446 -111.38916) (xy 222.897192 -111.388906) (xy 222.890111 -111.383311)
			(xy 222.87319 -111.377069) (xy 222.864172 -111.376714) (xy 222.797116 -111.376714) (xy 222.7881 -111.377075)
			(xy 222.771182 -111.38332) (xy 222.764096 -111.388906) (xy 222.764096 -111.38916) (xy 222.763842 -111.38916)
			(xy 222.742909 -111.406801) (xy 222.696941 -111.436525) (xy 222.647195 -111.459371) (xy 222.594693 -111.474867)
			(xy 222.540515 -111.482696) (xy 222.485773 -111.482696) (xy 222.431595 -111.474867) (xy 222.379093 -111.459371)
			(xy 222.329347 -111.436525) (xy 222.283379 -111.406801) (xy 222.262446 -111.38916) (xy 222.262192 -111.388906)
			(xy 222.255111 -111.383311) (xy 222.23819 -111.377069) (xy 222.229172 -111.376714) (xy 222.162116 -111.376714)
			(xy 222.1531 -111.377075) (xy 222.136182 -111.38332) (xy 222.129096 -111.388906) (xy 222.129096 -111.38916)
			(xy 222.128842 -111.38916) (xy 222.1079 -111.406787) (xy 222.06193 -111.436502) (xy 222.012186 -111.459341)
			(xy 221.959687 -111.474835) (xy 221.905513 -111.482665) (xy 221.878144 -111.48314) (xy 221.850891 -111.482616)
			(xy 221.79694 -111.474865) (xy 221.744641 -111.459514) (xy 221.69506 -111.436875) (xy 221.649205 -111.407411)
			(xy 221.608011 -111.37172) (xy 221.572315 -111.33053) (xy 221.542846 -111.284679) (xy 221.520202 -111.2351)
			(xy 221.504845 -111.182803) (xy 221.497087 -111.128853) (xy 218.839077 -111.128853) (xy 220.430344 -112.72012)
			(xy 232.673906 -112.72012) (xy 232.674382 -112.69275) (xy 232.682197 -112.638571) (xy 232.697684 -112.586068)
			(xy 232.720524 -112.536321) (xy 232.750246 -112.490354) (xy 232.767886 -112.469422) (xy 232.76814 -112.469168)
			(xy 232.773709 -112.46207) (xy 232.779965 -112.445162) (xy 232.780332 -112.436148) (xy 232.780332 -112.369092)
			(xy 232.779972 -112.360076) (xy 232.773726 -112.343159) (xy 232.76814 -112.336072) (xy 232.767886 -112.336072)
			(xy 232.767886 -112.335818) (xy 232.75024 -112.314892) (xy 232.720529 -112.268917) (xy 232.697695 -112.219168)
			(xy 232.682206 -112.166666) (xy 232.674379 -112.11249) (xy 232.673906 -112.08512) (xy 232.674392 -112.057869)
			(xy 232.682148 -112.003921) (xy 232.697503 -111.951626) (xy 232.720145 -111.902049) (xy 232.749611 -111.856199)
			(xy 232.785302 -111.815008) (xy 232.826493 -111.779317) (xy 232.872343 -111.749851) (xy 232.92192 -111.727209)
			(xy 232.974215 -111.711854) (xy 233.028163 -111.704098) (xy 233.082665 -111.704098) (xy 233.136613 -111.711854)
			(xy 233.188908 -111.727209) (xy 233.238485 -111.749851) (xy 233.284335 -111.779317) (xy 233.325526 -111.815008)
			(xy 233.361217 -111.856199) (xy 233.390683 -111.902049) (xy 233.413325 -111.951626) (xy 233.427314 -111.999268)
			(xy 238.85347 -111.999268) (xy 238.857541 -111.943646) (xy 238.869667 -111.889209) (xy 238.88959 -111.837118)
			(xy 238.916886 -111.788483) (xy 238.950972 -111.74434) (xy 238.991121 -111.705631) (xy 239.036479 -111.67318)
			(xy 239.086079 -111.647679) (xy 239.138863 -111.629672) (xy 239.193706 -111.619542) (xy 239.24944 -111.617505)
			(xy 239.304877 -111.623605) (xy 239.358834 -111.637711) (xy 239.410163 -111.659523) (xy 239.457769 -111.688577)
			(xy 239.500637 -111.724252) (xy 239.537854 -111.765789) (xy 239.568627 -111.812302) (xy 239.592299 -111.862799)
			(xy 239.608367 -111.916206) (xy 239.616487 -111.971382) (xy 239.616996 -111.999268) (xy 239.616487 -112.027154)
			(xy 239.608367 -112.08233) (xy 239.592299 -112.135737) (xy 239.568627 -112.186234) (xy 239.537854 -112.232747)
			(xy 239.500637 -112.274284) (xy 239.457769 -112.309959) (xy 239.410163 -112.339013) (xy 239.358834 -112.360825)
			(xy 239.304877 -112.374931) (xy 239.24944 -112.381031) (xy 239.193706 -112.378994) (xy 239.138863 -112.368864)
			(xy 239.086079 -112.350857) (xy 239.036479 -112.325356) (xy 238.991121 -112.292905) (xy 238.950972 -112.254196)
			(xy 238.916886 -112.210053) (xy 238.88959 -112.161418) (xy 238.869667 -112.109327) (xy 238.857541 -112.05489)
			(xy 238.85347 -111.999268) (xy 233.427314 -111.999268) (xy 233.42868 -112.003921) (xy 233.436436 -112.057869)
			(xy 233.436922 -112.08512) (xy 233.436487 -112.112492) (xy 233.428664 -112.166673) (xy 233.413169 -112.219177)
			(xy 233.39032 -112.268923) (xy 233.360587 -112.314888) (xy 233.342942 -112.335818) (xy 233.342688 -112.336072)
			(xy 233.337106 -112.343161) (xy 233.330857 -112.360076) (xy 233.330496 -112.369092) (xy 233.330496 -112.436148)
			(xy 233.330879 -112.445162) (xy 233.337109 -112.462079) (xy 233.342688 -112.469168) (xy 233.342942 -112.469168)
			(xy 233.342942 -112.469422) (xy 233.360565 -112.490367) (xy 233.390278 -112.536337) (xy 233.413116 -112.586081)
			(xy 233.428611 -112.638579) (xy 233.436445 -112.692752) (xy 233.436922 -112.72012) (xy 233.436436 -112.747371)
			(xy 233.42868 -112.801319) (xy 233.413325 -112.853614) (xy 233.390683 -112.903191) (xy 233.361217 -112.949041)
			(xy 233.325526 -112.990232) (xy 233.284335 -113.025923) (xy 233.238485 -113.055389) (xy 233.188908 -113.078031)
			(xy 233.136613 -113.093386) (xy 233.082665 -113.101142) (xy 233.028163 -113.101142) (xy 232.974215 -113.093386)
			(xy 232.92192 -113.078031) (xy 232.872343 -113.055389) (xy 232.826493 -113.025923) (xy 232.785302 -112.990232)
			(xy 232.749611 -112.949041) (xy 232.720145 -112.903191) (xy 232.697503 -112.853614) (xy 232.682148 -112.801319)
			(xy 232.674392 -112.747371) (xy 232.673906 -112.72012) (xy 220.430344 -112.72012) (xy 221.363286 -113.653062)
			(xy 235.227366 -113.653062) (xy 235.231437 -113.59744) (xy 235.243563 -113.543003) (xy 235.263486 -113.490912)
			(xy 235.290782 -113.442277) (xy 235.324868 -113.398134) (xy 235.365017 -113.359425) (xy 235.410375 -113.326974)
			(xy 235.459975 -113.301473) (xy 235.512759 -113.283466) (xy 235.567602 -113.273336) (xy 235.623336 -113.271299)
			(xy 235.678773 -113.277399) (xy 235.73273 -113.291505) (xy 235.784059 -113.313317) (xy 235.831665 -113.342371)
			(xy 235.874533 -113.378046) (xy 235.91175 -113.419583) (xy 235.942523 -113.466096) (xy 235.966195 -113.516593)
			(xy 235.982263 -113.57) (xy 235.990383 -113.625176) (xy 235.990892 -113.653062) (xy 235.990383 -113.680948)
			(xy 235.982263 -113.736124) (xy 235.966195 -113.789531) (xy 235.942523 -113.840028) (xy 235.91175 -113.886541)
			(xy 235.874533 -113.928078) (xy 235.831665 -113.963753) (xy 235.784059 -113.992807) (xy 235.73273 -114.014619)
			(xy 235.678773 -114.028725) (xy 235.623336 -114.034825) (xy 235.567602 -114.032788) (xy 235.512759 -114.022658)
			(xy 235.459975 -114.004651) (xy 235.410375 -113.97915) (xy 235.365017 -113.946699) (xy 235.324868 -113.90799)
			(xy 235.290782 -113.863847) (xy 235.263486 -113.815212) (xy 235.243563 -113.763121) (xy 235.231437 -113.708684)
			(xy 235.227366 -113.653062) (xy 221.363286 -113.653062) (xy 222.297752 -114.587528) (xy 222.3207 -114.611081)
			(xy 222.361725 -114.662479) (xy 222.396733 -114.71815) (xy 222.425284 -114.777392) (xy 222.447017 -114.83946)
			(xy 222.46166 -114.903572) (xy 222.469028 -114.968921) (xy 222.469456 -115.001802) (xy 222.469456 -116.188224)
			(xy 223.368955 -116.188224) (xy 223.373268 -116.130954) (xy 223.386114 -116.074977) (xy 223.407204 -116.021557)
			(xy 223.436062 -115.971901) (xy 223.472035 -115.927131) (xy 223.492822 -115.907312) (xy 223.500224 -115.899791)
			(xy 223.508747 -115.88051) (xy 223.509332 -115.869974) (xy 223.509332 -115.795298) (xy 223.508808 -115.784748)
			(xy 223.500268 -115.765453) (xy 223.492822 -115.75796) (xy 223.473758 -115.739813) (xy 223.440301 -115.699182)
			(xy 223.412743 -115.65434) (xy 223.391605 -115.606137) (xy 223.37729 -115.555488) (xy 223.370069 -115.503353)
			(xy 223.369632 -115.477036) (xy 223.370118 -115.449785) (xy 223.377874 -115.395837) (xy 223.393229 -115.343542)
			(xy 223.415871 -115.293965) (xy 223.445337 -115.248115) (xy 223.481028 -115.206924) (xy 223.522219 -115.171233)
			(xy 223.568069 -115.141767) (xy 223.617646 -115.119125) (xy 223.669941 -115.10377) (xy 223.723889 -115.096014)
			(xy 223.778391 -115.096014) (xy 223.832339 -115.10377) (xy 223.884634 -115.119125) (xy 223.934211 -115.141767)
			(xy 223.980061 -115.171233) (xy 224.021252 -115.206924) (xy 224.056943 -115.248115) (xy 224.086409 -115.293965)
			(xy 224.109051 -115.343542) (xy 224.124406 -115.395837) (xy 224.132162 -115.449785) (xy 224.132648 -115.477036)
			(xy 224.132221 -115.503352) (xy 224.12498 -115.555482) (xy 224.110654 -115.606127) (xy 224.089514 -115.654326)
			(xy 224.06196 -115.699168) (xy 224.028514 -115.739805) (xy 224.009458 -115.75796) (xy 224.002081 -115.765502)
			(xy 223.99354 -115.784766) (xy 223.992948 -115.795298) (xy 223.992948 -115.869974) (xy 223.993464 -115.880526)
			(xy 224.002007 -115.899822) (xy 224.009458 -115.907312) (xy 224.03028 -115.927097) (xy 224.066251 -115.971876)
			(xy 224.095107 -116.021539) (xy 224.116195 -116.074966) (xy 224.12904 -116.130949) (xy 224.133352 -116.188224)
			(xy 225.907203 -116.188224) (xy 225.911514 -116.130957) (xy 225.924357 -116.074981) (xy 225.945443 -116.021562)
			(xy 225.974294 -115.971906) (xy 226.010261 -115.927133) (xy 226.031044 -115.907312) (xy 226.038434 -115.89978)
			(xy 226.046967 -115.880508) (xy 226.047554 -115.869974) (xy 226.047554 -115.795298) (xy 226.047053 -115.784745)
			(xy 226.0385 -115.765449) (xy 226.031044 -115.75796) (xy 226.011965 -115.739828) (xy 225.978512 -115.699192)
			(xy 225.950958 -115.654346) (xy 225.929824 -115.606141) (xy 225.915511 -115.55549) (xy 225.90829 -115.503353)
			(xy 225.907854 -115.477036) (xy 225.90834 -115.449785) (xy 225.916096 -115.395837) (xy 225.931451 -115.343542)
			(xy 225.954093 -115.293965) (xy 225.983559 -115.248115) (xy 226.01925 -115.206924) (xy 226.060441 -115.171233)
			(xy 226.106291 -115.141767) (xy 226.155868 -115.119125) (xy 226.208163 -115.10377) (xy 226.262111 -115.096014)
			(xy 226.316613 -115.096014) (xy 226.370561 -115.10377) (xy 226.422856 -115.119125) (xy 226.472433 -115.141767)
			(xy 226.518283 -115.171233) (xy 226.559474 -115.206924) (xy 226.595165 -115.248115) (xy 226.624631 -115.293965)
			(xy 226.647273 -115.343542) (xy 226.662628 -115.395837) (xy 226.670384 -115.449785) (xy 226.67087 -115.477036)
			(xy 226.670436 -115.503351) (xy 226.663196 -115.555482) (xy 226.648871 -115.606125) (xy 226.627732 -115.654324)
			(xy 226.60018 -115.699167) (xy 226.566735 -115.739805) (xy 226.54768 -115.75796) (xy 226.540291 -115.765492)
			(xy 226.53176 -115.784764) (xy 226.53117 -115.795298) (xy 226.53117 -115.869974) (xy 226.531708 -115.880522)
			(xy 226.540238 -115.899817) (xy 226.54768 -115.907312) (xy 226.568506 -115.927095) (xy 226.604484 -115.971871)
			(xy 226.633345 -116.021534) (xy 226.654438 -116.074961) (xy 226.667286 -116.130946) (xy 226.668309 -116.144533)
			(xy 230.110137 -116.144533) (xy 230.114448 -116.087265) (xy 230.127291 -116.03129) (xy 230.148377 -115.977871)
			(xy 230.17723 -115.928215) (xy 230.213198 -115.883444) (xy 230.233982 -115.863624) (xy 230.241372 -115.856093)
			(xy 230.249904 -115.83682) (xy 230.250492 -115.826286) (xy 230.250492 -115.75161) (xy 230.249973 -115.741059)
			(xy 230.241431 -115.721764) (xy 230.233982 -115.714272) (xy 230.213242 -115.694404) (xy 230.177267 -115.649638)
			(xy 230.148405 -115.599988) (xy 230.12731 -115.546573) (xy 230.114457 -115.4906) (xy 230.110137 -115.433333)
			(xy 230.114448 -115.376065) (xy 230.127291 -115.32009) (xy 230.148377 -115.266671) (xy 230.17723 -115.217015)
			(xy 230.213198 -115.172244) (xy 230.233982 -115.152424) (xy 230.241372 -115.144893) (xy 230.249904 -115.12562)
			(xy 230.250492 -115.115086) (xy 230.250492 -115.04041) (xy 230.249973 -115.029859) (xy 230.241431 -115.010564)
			(xy 230.233982 -115.003072) (xy 230.214916 -114.984927) (xy 230.181461 -114.944294) (xy 230.153904 -114.899452)
			(xy 230.132767 -114.851249) (xy 230.118452 -114.8006) (xy 230.111229 -114.748465) (xy 230.110792 -114.722148)
			(xy 230.1113 -114.694896) (xy 230.11905 -114.640947) (xy 230.1344 -114.58865) (xy 230.157037 -114.53907)
			(xy 230.1865 -114.493217) (xy 230.222189 -114.452023) (xy 230.263378 -114.416329) (xy 230.309228 -114.38686)
			(xy 230.358805 -114.364217) (xy 230.4111 -114.348861) (xy 230.465048 -114.341103) (xy 230.4923 -114.34064)
			(xy 230.518615 -114.341095) (xy 230.570744 -114.34833) (xy 230.621388 -114.362651) (xy 230.669587 -114.383786)
			(xy 230.71443 -114.411335) (xy 230.755068 -114.444777) (xy 230.773224 -114.46383) (xy 230.780744 -114.471234)
			(xy 230.800025 -114.479759) (xy 230.810562 -114.48034) (xy 230.885238 -114.48034) (xy 230.895784 -114.479779)
			(xy 230.915079 -114.471265) (xy 230.922576 -114.46383) (xy 230.940756 -114.444799) (xy 230.98138 -114.411338)
			(xy 231.026215 -114.383775) (xy 231.074411 -114.362632) (xy 231.125054 -114.34831) (xy 231.177185 -114.341081)
			(xy 231.2035 -114.34064) (xy 231.230755 -114.341055) (xy 231.28471 -114.348814) (xy 231.337012 -114.364172)
			(xy 231.386595 -114.386818) (xy 231.426389 -114.412395) (xy 232.727135 -114.412395) (xy 232.727135 -114.360405)
			(xy 232.735269 -114.309056) (xy 232.751336 -114.259612) (xy 232.774941 -114.21329) (xy 232.805502 -114.171231)
			(xy 232.842266 -114.134472) (xy 232.884329 -114.103917) (xy 232.930654 -114.080318) (xy 232.980101 -114.064258)
			(xy 233.031451 -114.056132) (xy 233.057446 -114.055652) (xy 233.084091 -114.056131) (xy 233.136694 -114.064663)
			(xy 233.187244 -114.081529) (xy 233.234431 -114.106293) (xy 233.277029 -114.138312) (xy 233.313934 -114.176754)
			(xy 233.32948 -114.1984) (xy 233.337844 -114.209686) (xy 233.359517 -114.227541) (xy 233.385231 -114.238824)
			(xy 233.413046 -114.242682) (xy 233.440861 -114.238824) (xy 233.466575 -114.227541) (xy 233.488248 -114.209686)
			(xy 233.496612 -114.1984) (xy 233.512202 -114.176793) (xy 233.549115 -114.138375) (xy 233.59171 -114.106373)
			(xy 233.638886 -114.081616) (xy 233.689421 -114.064743) (xy 233.742007 -114.056191) (xy 233.768646 -114.055652)
			(xy 233.794628 -114.056245) (xy 233.84595 -114.064381) (xy 233.895369 -114.080444) (xy 233.941666 -114.104039)
			(xy 233.983703 -114.134586) (xy 234.020444 -114.171332) (xy 234.050985 -114.213373) (xy 234.074574 -114.259674)
			(xy 234.09063 -114.309095) (xy 234.098758 -114.360418) (xy 234.098758 -114.412382) (xy 234.09063 -114.463705)
			(xy 234.074574 -114.513126) (xy 234.050985 -114.559427) (xy 234.020444 -114.601468) (xy 233.983703 -114.638214)
			(xy 233.945097 -114.666268) (xy 236.640876 -114.666268) (xy 236.644947 -114.610646) (xy 236.657073 -114.556209)
			(xy 236.676996 -114.504118) (xy 236.704292 -114.455483) (xy 236.738378 -114.41134) (xy 236.778527 -114.372631)
			(xy 236.823885 -114.34018) (xy 236.873485 -114.314679) (xy 236.926269 -114.296672) (xy 236.981112 -114.286542)
			(xy 237.036846 -114.284505) (xy 237.092283 -114.290605) (xy 237.14624 -114.304711) (xy 237.197569 -114.326523)
			(xy 237.245175 -114.355577) (xy 237.288043 -114.391252) (xy 237.32526 -114.432789) (xy 237.356033 -114.479302)
			(xy 237.379705 -114.529799) (xy 237.395773 -114.583206) (xy 237.403893 -114.638382) (xy 237.404402 -114.666268)
			(xy 237.403893 -114.694154) (xy 237.395773 -114.74933) (xy 237.379705 -114.802737) (xy 237.356033 -114.853234)
			(xy 237.32526 -114.899747) (xy 237.288043 -114.941284) (xy 237.245175 -114.976959) (xy 237.197569 -115.006013)
			(xy 237.14624 -115.027825) (xy 237.092283 -115.041931) (xy 237.036846 -115.048031) (xy 236.981112 -115.045994)
			(xy 236.926269 -115.035864) (xy 236.873485 -115.017857) (xy 236.823885 -114.992356) (xy 236.778527 -114.959905)
			(xy 236.738378 -114.921196) (xy 236.704292 -114.877053) (xy 236.676996 -114.828418) (xy 236.657073 -114.776327)
			(xy 236.644947 -114.72189) (xy 236.640876 -114.666268) (xy 233.945097 -114.666268) (xy 233.941666 -114.668761)
			(xy 233.895369 -114.692356) (xy 233.84595 -114.708419) (xy 233.794628 -114.716555) (xy 233.768646 -114.717068)
			(xy 233.742001 -114.716586) (xy 233.689399 -114.708054) (xy 233.638849 -114.691187) (xy 233.591663 -114.666424)
			(xy 233.549064 -114.634406) (xy 233.512158 -114.595965) (xy 233.496612 -114.57432) (xy 233.488248 -114.563034)
			(xy 233.466575 -114.545179) (xy 233.440861 -114.533896) (xy 233.413046 -114.530038) (xy 233.385231 -114.533896)
			(xy 233.359517 -114.545179) (xy 233.337844 -114.563034) (xy 233.32948 -114.57432) (xy 233.3139 -114.595935)
			(xy 233.276985 -114.634351) (xy 233.234387 -114.666352) (xy 233.18721 -114.691108) (xy 233.136673 -114.707979)
			(xy 233.084085 -114.716529) (xy 233.057446 -114.717068) (xy 233.031451 -114.716668) (xy 232.980101 -114.708542)
			(xy 232.930654 -114.692482) (xy 232.884329 -114.668883) (xy 232.842266 -114.638328) (xy 232.805502 -114.601569)
			(xy 232.774941 -114.55951) (xy 232.751336 -114.513188) (xy 232.735269 -114.463744) (xy 232.727135 -114.412395)
			(xy 231.426389 -114.412395) (xy 231.432451 -114.416291) (xy 231.473645 -114.451989) (xy 231.509338 -114.493188)
			(xy 231.538805 -114.539047) (xy 231.561445 -114.588633) (xy 231.576797 -114.640937) (xy 231.584548 -114.694893)
			(xy 231.585008 -114.722148) (xy 231.58457 -114.748463) (xy 231.577329 -114.800593) (xy 231.563004 -114.851236)
			(xy 231.541866 -114.899435) (xy 231.514315 -114.944277) (xy 231.480872 -114.984916) (xy 231.461818 -115.003072)
			(xy 231.454429 -115.010604) (xy 231.445897 -115.029876) (xy 231.445308 -115.04041) (xy 231.445308 -115.115086)
			(xy 231.445829 -115.125637) (xy 231.45437 -115.144932) (xy 231.461818 -115.152424) (xy 231.482654 -115.172196)
			(xy 231.518629 -115.216975) (xy 231.547487 -115.26664) (xy 231.565585 -115.312489) (xy 232.727211 -115.312489)
			(xy 232.727211 -115.260511) (xy 232.735343 -115.209174) (xy 232.751406 -115.159741) (xy 232.775005 -115.113429)
			(xy 232.805559 -115.071381) (xy 232.842316 -115.034629) (xy 232.884369 -115.004081) (xy 232.930683 -114.980489)
			(xy 232.980119 -114.964432) (xy 233.031457 -114.956308) (xy 233.057446 -114.955828) (xy 233.084091 -114.956318)
			(xy 233.136692 -114.964848) (xy 233.187242 -114.981713) (xy 233.234428 -115.006475) (xy 233.277027 -115.038492)
			(xy 233.313933 -115.076932) (xy 233.32948 -115.098576) (xy 233.337844 -115.109862) (xy 233.359517 -115.127717)
			(xy 233.385231 -115.139) (xy 233.413046 -115.142858) (xy 233.440861 -115.139) (xy 233.466575 -115.127717)
			(xy 233.488248 -115.109862) (xy 233.496612 -115.098576) (xy 233.512195 -115.076964) (xy 233.54911 -115.038547)
			(xy 233.591707 -115.006547) (xy 233.638884 -114.98179) (xy 233.68942 -114.964918) (xy 233.742007 -114.956367)
			(xy 233.768646 -114.955828) (xy 233.794634 -114.956269) (xy 233.845968 -114.964406) (xy 233.895398 -114.980473)
			(xy 233.941706 -115.004074) (xy 233.983753 -115.034628) (xy 234.020502 -115.071383) (xy 234.05105 -115.113433)
			(xy 234.074645 -115.159745) (xy 234.090705 -115.209177) (xy 234.098835 -115.260512) (xy 234.098835 -115.312488)
			(xy 234.090704 -115.363823) (xy 234.074645 -115.413255) (xy 234.05105 -115.459567) (xy 234.020502 -115.501617)
			(xy 233.983753 -115.538372) (xy 233.941706 -115.568926) (xy 233.895398 -115.592527) (xy 233.845968 -115.608594)
			(xy 233.794634 -115.616731) (xy 233.768646 -115.617244) (xy 233.742 -115.616772) (xy 233.689397 -115.608239)
			(xy 233.638847 -115.591372) (xy 233.59166 -115.566606) (xy 233.549062 -115.534586) (xy 233.512158 -115.496142)
			(xy 233.496612 -115.474496) (xy 233.488248 -115.46321) (xy 233.466575 -115.445355) (xy 233.440861 -115.434072)
			(xy 233.413046 -115.430214) (xy 233.385231 -115.434072) (xy 233.359517 -115.445355) (xy 233.337844 -115.46321)
			(xy 233.32948 -115.474496) (xy 233.313923 -115.496128) (xy 233.277 -115.53454) (xy 233.234397 -115.566536)
			(xy 233.187215 -115.591288) (xy 233.136676 -115.608157) (xy 233.084086 -115.616705) (xy 233.057446 -115.617244)
			(xy 233.031457 -115.616692) (xy 232.980119 -115.608568) (xy 232.930683 -115.592511) (xy 232.884369 -115.568919)
			(xy 232.842316 -115.538371) (xy 232.805559 -115.501619) (xy 232.775005 -115.45957) (xy 232.751406 -115.413259)
			(xy 232.735343 -115.363826) (xy 232.727211 -115.312489) (xy 231.565585 -115.312489) (xy 231.568577 -115.320069)
			(xy 231.581422 -115.376054) (xy 231.585733 -115.433333) (xy 231.581413 -115.49061) (xy 231.568557 -115.546594)
			(xy 231.547458 -115.600018) (xy 231.518592 -115.649678) (xy 231.482609 -115.694452) (xy 231.461818 -115.714272)
			(xy 231.454429 -115.721804) (xy 231.445897 -115.741076) (xy 231.445308 -115.75161) (xy 231.445308 -115.826286)
			(xy 231.445829 -115.836837) (xy 231.45437 -115.856132) (xy 231.461818 -115.863624) (xy 231.482654 -115.883396)
			(xy 231.518629 -115.928175) (xy 231.547487 -115.97784) (xy 231.568577 -116.031269) (xy 231.581422 -116.087254)
			(xy 231.585733 -116.144533) (xy 231.581413 -116.20181) (xy 231.578959 -116.212495) (xy 232.727133 -116.212495)
			(xy 232.727133 -116.160505) (xy 232.735267 -116.109156) (xy 232.751334 -116.059711) (xy 232.774939 -116.013389)
			(xy 232.8055 -115.97133) (xy 232.842265 -115.93457) (xy 232.884328 -115.904015) (xy 232.930653 -115.880417)
			(xy 232.9801 -115.864356) (xy 233.031451 -115.85623) (xy 233.057446 -115.85575) (xy 233.084091 -115.85623)
			(xy 233.136694 -115.864762) (xy 233.187244 -115.881628) (xy 233.23443 -115.906392) (xy 233.277029 -115.93841)
			(xy 233.313934 -115.976852) (xy 233.32948 -115.998498) (xy 233.337844 -116.009784) (xy 233.359517 -116.027639)
			(xy 233.385231 -116.038922) (xy 233.413046 -116.04278) (xy 233.440861 -116.038922) (xy 233.466575 -116.027639)
			(xy 233.488248 -116.009784) (xy 233.496612 -115.998498) (xy 233.512202 -115.976891) (xy 233.549115 -115.938473)
			(xy 233.59171 -115.906471) (xy 233.638886 -115.881714) (xy 233.689421 -115.864841) (xy 233.742007 -115.856289)
			(xy 233.768646 -115.85575) (xy 233.794627 -115.856347) (xy 233.84595 -115.864483) (xy 233.895368 -115.880546)
			(xy 233.941665 -115.904141) (xy 233.983702 -115.934687) (xy 233.985283 -115.936268) (xy 235.270546 -115.936268)
			(xy 235.274617 -115.880646) (xy 235.286743 -115.826209) (xy 235.306666 -115.774118) (xy 235.333962 -115.725483)
			(xy 235.368048 -115.68134) (xy 235.408197 -115.642631) (xy 235.453555 -115.61018) (xy 235.503155 -115.584679)
			(xy 235.555939 -115.566672) (xy 235.610782 -115.556542) (xy 235.666516 -115.554505) (xy 235.721953 -115.560605)
			(xy 235.77591 -115.574711) (xy 235.827239 -115.596523) (xy 235.874845 -115.625577) (xy 235.917713 -115.661252)
			(xy 235.95493 -115.702789) (xy 235.985703 -115.749302) (xy 236.009375 -115.799799) (xy 236.025443 -115.853206)
			(xy 236.033563 -115.908382) (xy 236.034072 -115.936268) (xy 236.033563 -115.964154) (xy 236.025443 -116.01933)
			(xy 236.009375 -116.072737) (xy 235.985703 -116.123234) (xy 235.95493 -116.169747) (xy 235.917713 -116.211284)
			(xy 235.874845 -116.246959) (xy 235.827239 -116.276013) (xy 235.77591 -116.297825) (xy 235.721953 -116.311931)
			(xy 235.666516 -116.318031) (xy 235.610782 -116.315994) (xy 235.555939 -116.305864) (xy 235.503155 -116.287857)
			(xy 235.453555 -116.262356) (xy 235.408197 -116.229905) (xy 235.368048 -116.191196) (xy 235.333962 -116.147053)
			(xy 235.306666 -116.098418) (xy 235.286743 -116.046327) (xy 235.274617 -115.99189) (xy 235.270546 -115.936268)
			(xy 233.985283 -115.936268) (xy 234.020442 -115.971434) (xy 234.050983 -116.013474) (xy 234.074572 -116.059775)
			(xy 234.090628 -116.109195) (xy 234.098756 -116.160518) (xy 234.098756 -116.212482) (xy 234.090628 -116.263805)
			(xy 234.074572 -116.313225) (xy 234.050983 -116.359526) (xy 234.020442 -116.401566) (xy 233.983702 -116.438313)
			(xy 233.970963 -116.44757) (xy 236.707678 -116.44757) (xy 236.711749 -116.391948) (xy 236.723875 -116.337511)
			(xy 236.743798 -116.28542) (xy 236.771094 -116.236785) (xy 236.80518 -116.192642) (xy 236.845329 -116.153933)
			(xy 236.890687 -116.121482) (xy 236.940287 -116.095981) (xy 236.993071 -116.077974) (xy 237.047914 -116.067844)
			(xy 237.103648 -116.065807) (xy 237.159085 -116.071907) (xy 237.213042 -116.086013) (xy 237.264371 -116.107825)
			(xy 237.311977 -116.136879) (xy 237.354845 -116.172554) (xy 237.392062 -116.214091) (xy 237.422835 -116.260604)
			(xy 237.446507 -116.311101) (xy 237.462575 -116.364508) (xy 237.470695 -116.419684) (xy 237.471204 -116.44757)
			(xy 237.470695 -116.475456) (xy 237.462575 -116.530632) (xy 237.446507 -116.584039) (xy 237.422835 -116.634536)
			(xy 237.392062 -116.681049) (xy 237.354845 -116.722586) (xy 237.311977 -116.758261) (xy 237.264371 -116.787315)
			(xy 237.213042 -116.809127) (xy 237.159085 -116.823233) (xy 237.103648 -116.829333) (xy 237.047914 -116.827296)
			(xy 236.993071 -116.817166) (xy 236.940287 -116.799159) (xy 236.890687 -116.773658) (xy 236.845329 -116.741207)
			(xy 236.80518 -116.702498) (xy 236.771094 -116.658355) (xy 236.743798 -116.60972) (xy 236.723875 -116.557629)
			(xy 236.711749 -116.503192) (xy 236.707678 -116.44757) (xy 233.970963 -116.44757) (xy 233.941665 -116.468859)
			(xy 233.895368 -116.492454) (xy 233.84595 -116.508517) (xy 233.794627 -116.516653) (xy 233.768646 -116.517166)
			(xy 233.742001 -116.516685) (xy 233.689399 -116.508153) (xy 233.638849 -116.491286) (xy 233.591663 -116.466523)
			(xy 233.549064 -116.434505) (xy 233.512158 -116.396063) (xy 233.496612 -116.374418) (xy 233.488248 -116.363132)
			(xy 233.466575 -116.345277) (xy 233.440861 -116.333994) (xy 233.413046 -116.330136) (xy 233.385231 -116.333994)
			(xy 233.359517 -116.345277) (xy 233.337844 -116.363132) (xy 233.32948 -116.374418) (xy 233.3139 -116.396033)
			(xy 233.276984 -116.434449) (xy 233.234387 -116.46645) (xy 233.187209 -116.491206) (xy 233.136673 -116.508077)
			(xy 233.084085 -116.516627) (xy 233.057446 -116.517166) (xy 233.031451 -116.51677) (xy 232.9801 -116.508644)
			(xy 232.930654 -116.492583) (xy 232.884328 -116.468985) (xy 232.842265 -116.43843) (xy 232.8055 -116.40167)
			(xy 232.774939 -116.359611) (xy 232.751334 -116.313289) (xy 232.735267 -116.263844) (xy 232.727133 -116.212495)
			(xy 231.578959 -116.212495) (xy 231.568557 -116.257794) (xy 231.547458 -116.311218) (xy 231.518592 -116.360878)
			(xy 231.482609 -116.405652) (xy 231.461818 -116.425472) (xy 231.454429 -116.433004) (xy 231.445897 -116.452276)
			(xy 231.445308 -116.46281) (xy 231.445308 -116.537486) (xy 231.445829 -116.548037) (xy 231.45437 -116.567332)
			(xy 231.461818 -116.574824) (xy 231.480882 -116.592971) (xy 231.514337 -116.633603) (xy 231.541895 -116.678445)
			(xy 231.563032 -116.726648) (xy 231.577347 -116.777296) (xy 231.58457 -116.829431) (xy 231.585008 -116.855748)
			(xy 231.584567 -116.883) (xy 231.576804 -116.93695) (xy 231.561443 -116.989245) (xy 231.538796 -117.038823)
			(xy 231.509325 -117.084673) (xy 231.485302 -117.112393) (xy 232.727155 -117.112393) (xy 232.727155 -117.060407)
			(xy 232.735289 -117.009061) (xy 232.751355 -116.959619) (xy 232.774958 -116.9133) (xy 232.805517 -116.871244)
			(xy 232.842279 -116.834487) (xy 232.88434 -116.803934) (xy 232.930662 -116.780337) (xy 232.980106 -116.764278)
			(xy 233.031453 -116.756152) (xy 233.057446 -116.755672) (xy 233.084092 -116.756143) (xy 233.136695 -116.764675)
			(xy 233.187246 -116.781542) (xy 233.234433 -116.806308) (xy 233.277031 -116.838328) (xy 233.313935 -116.876773)
			(xy 233.32948 -116.89842) (xy 233.337844 -116.909706) (xy 233.359517 -116.927561) (xy 233.385231 -116.938844)
			(xy 233.413046 -116.942702) (xy 233.440861 -116.938844) (xy 233.466575 -116.927561) (xy 233.488248 -116.909706)
			(xy 233.496612 -116.89842) (xy 233.512179 -116.876796) (xy 233.549099 -116.838383) (xy 233.5917 -116.806385)
			(xy 233.63888 -116.781631) (xy 233.689418 -116.764761) (xy 233.742006 -116.756211) (xy 233.768646 -116.755672)
			(xy 233.794629 -116.756225) (xy 233.845955 -116.764361) (xy 233.895376 -116.780425) (xy 233.941677 -116.804022)
			(xy 233.983716 -116.83457) (xy 234.02046 -116.871319) (xy 234.051002 -116.913362) (xy 234.074593 -116.959666)
			(xy 234.09065 -117.00909) (xy 234.098779 -117.060417) (xy 234.098779 -117.112383) (xy 234.09065 -117.16371)
			(xy 234.074593 -117.213134) (xy 234.051002 -117.259438) (xy 234.02046 -117.301481) (xy 233.983716 -117.33823)
			(xy 233.941677 -117.368778) (xy 233.895376 -117.392375) (xy 233.845955 -117.408439) (xy 233.794629 -117.416575)
			(xy 233.768646 -117.417088) (xy 233.742001 -117.416597) (xy 233.6894 -117.408066) (xy 233.638851 -117.391201)
			(xy 233.591665 -117.366439) (xy 233.549066 -117.334423) (xy 233.512159 -117.295984) (xy 233.496612 -117.27434)
			(xy 233.488248 -117.263054) (xy 233.466575 -117.245199) (xy 233.440861 -117.233916) (xy 233.413046 -117.230058)
			(xy 233.385231 -117.233916) (xy 233.359517 -117.245199) (xy 233.337844 -117.263054) (xy 233.32948 -117.27434)
			(xy 233.313906 -117.295959) (xy 233.276989 -117.334375) (xy 233.23439 -117.366374) (xy 233.187211 -117.391129)
			(xy 233.136674 -117.408) (xy 233.084085 -117.416549) (xy 233.057446 -117.417088) (xy 233.031453 -117.416648)
			(xy 232.980106 -117.408522) (xy 232.930662 -117.392463) (xy 232.88434 -117.368866) (xy 232.842279 -117.338313)
			(xy 232.805517 -117.301556) (xy 232.774958 -117.2595) (xy 232.751355 -117.213181) (xy 232.735289 -117.163739)
			(xy 232.727155 -117.112393) (xy 231.485302 -117.112393) (xy 231.473629 -117.125863) (xy 231.432434 -117.161553)
			(xy 231.386581 -117.191019) (xy 231.337 -117.213659) (xy 231.284703 -117.229014) (xy 231.230752 -117.23677)
			(xy 231.2035 -117.237256) (xy 231.177185 -117.236803) (xy 231.125056 -117.229567) (xy 231.074412 -117.215246)
			(xy 231.026213 -117.194111) (xy 230.98137 -117.166562) (xy 230.940732 -117.133119) (xy 230.922576 -117.114066)
			(xy 230.915056 -117.106662) (xy 230.895775 -117.098136) (xy 230.885238 -117.097556) (xy 230.810562 -117.097556)
			(xy 230.800017 -117.098118) (xy 230.780722 -117.106632) (xy 230.773224 -117.114066) (xy 230.755063 -117.133116)
			(xy 230.714433 -117.166571) (xy 230.669593 -117.194129) (xy 230.621394 -117.215268) (xy 230.570748 -117.229587)
			(xy 230.518616 -117.236815) (xy 230.4923 -117.237256) (xy 230.465051 -117.236722) (xy 230.411107 -117.228967)
			(xy 230.358816 -117.213614) (xy 230.309242 -117.190977) (xy 230.263394 -117.161515) (xy 230.222205 -117.125829)
			(xy 230.186514 -117.084644) (xy 230.157046 -117.0388) (xy 230.134402 -116.989229) (xy 230.119043 -116.93694)
			(xy 230.111281 -116.882997) (xy 230.110792 -116.855748) (xy 230.111227 -116.829433) (xy 230.118469 -116.777303)
			(xy 230.132795 -116.72666) (xy 230.153933 -116.678461) (xy 230.181485 -116.633618) (xy 230.214928 -116.59298)
			(xy 230.233982 -116.574824) (xy 230.241372 -116.567293) (xy 230.249904 -116.54802) (xy 230.250492 -116.537486)
			(xy 230.250492 -116.46281) (xy 230.249973 -116.452259) (xy 230.241431 -116.432964) (xy 230.233982 -116.425472)
			(xy 230.213242 -116.405604) (xy 230.177267 -116.360838) (xy 230.148405 -116.311188) (xy 230.12731 -116.257773)
			(xy 230.114457 -116.2018) (xy 230.110137 -116.144533) (xy 226.668309 -116.144533) (xy 226.671599 -116.188224)
			(xy 226.667279 -116.245502) (xy 226.654424 -116.301485) (xy 226.633324 -116.35491) (xy 226.604456 -116.404569)
			(xy 226.568472 -116.449341) (xy 226.54768 -116.46916) (xy 226.540291 -116.476692) (xy 226.53176 -116.495964)
			(xy 226.53117 -116.506498) (xy 226.53117 -116.581174) (xy 226.531708 -116.591722) (xy 226.540238 -116.611017)
			(xy 226.54768 -116.618512) (xy 226.566731 -116.636673) (xy 226.600189 -116.677301) (xy 226.627749 -116.72214)
			(xy 226.648889 -116.77034) (xy 226.663207 -116.820987) (xy 226.670432 -116.87312) (xy 226.67087 -116.899436)
			(xy 226.670384 -116.926687) (xy 226.662628 -116.980635) (xy 226.647273 -117.03293) (xy 226.624631 -117.082507)
			(xy 226.595165 -117.128357) (xy 226.559474 -117.169548) (xy 226.518283 -117.205239) (xy 226.472433 -117.234705)
			(xy 226.422856 -117.257347) (xy 226.370561 -117.272702) (xy 226.316613 -117.280458) (xy 226.262111 -117.280458)
			(xy 226.208163 -117.272702) (xy 226.155868 -117.257347) (xy 226.106291 -117.234705) (xy 226.060441 -117.205239)
			(xy 226.01925 -117.169548) (xy 225.983559 -117.128357) (xy 225.954093 -117.082507) (xy 225.931451 -117.03293)
			(xy 225.916096 -116.980635) (xy 225.90834 -116.926687) (xy 225.907854 -116.899436) (xy 225.908262 -116.87312)
			(xy 225.915506 -116.820988) (xy 225.929836 -116.770343) (xy 225.950979 -116.722144) (xy 225.978537 -116.677302)
			(xy 226.011987 -116.636666) (xy 226.031044 -116.618512) (xy 226.038434 -116.61098) (xy 226.046967 -116.591708)
			(xy 226.047554 -116.581174) (xy 226.047554 -116.506498) (xy 226.047053 -116.495945) (xy 226.0385 -116.476649)
			(xy 226.031044 -116.46916) (xy 226.010294 -116.449303) (xy 225.974322 -116.404534) (xy 225.945464 -116.354882)
			(xy 225.924372 -116.301465) (xy 225.911521 -116.245492) (xy 225.907203 -116.188224) (xy 224.133352 -116.188224)
			(xy 224.129033 -116.2455) (xy 224.11618 -116.301481) (xy 224.095085 -116.354905) (xy 224.066223 -116.404564)
			(xy 224.030247 -116.449339) (xy 224.009458 -116.46916) (xy 224.002081 -116.476702) (xy 223.99354 -116.495966)
			(xy 223.992948 -116.506498) (xy 223.992948 -116.581174) (xy 223.993464 -116.591726) (xy 224.002007 -116.611022)
			(xy 224.009458 -116.618512) (xy 224.028523 -116.636657) (xy 224.061977 -116.677291) (xy 224.089534 -116.722133)
			(xy 224.11067 -116.770336) (xy 224.124986 -116.820985) (xy 224.13221 -116.873119) (xy 224.132648 -116.899436)
			(xy 224.132162 -116.926687) (xy 224.124406 -116.980635) (xy 224.109051 -117.03293) (xy 224.086409 -117.082507)
			(xy 224.056943 -117.128357) (xy 224.021252 -117.169548) (xy 223.980061 -117.205239) (xy 223.934211 -117.234705)
			(xy 223.884634 -117.257347) (xy 223.832339 -117.272702) (xy 223.778391 -117.280458) (xy 223.723889 -117.280458)
			(xy 223.669941 -117.272702) (xy 223.617646 -117.257347) (xy 223.568069 -117.234705) (xy 223.522219 -117.205239)
			(xy 223.481028 -117.169548) (xy 223.445337 -117.128357) (xy 223.415871 -117.082507) (xy 223.393229 -117.03293)
			(xy 223.377874 -116.980635) (xy 223.370118 -116.926687) (xy 223.369632 -116.899436) (xy 223.370047 -116.87312)
			(xy 223.377291 -116.820989) (xy 223.39162 -116.770345) (xy 223.412762 -116.722146) (xy 223.440318 -116.677304)
			(xy 223.473766 -116.636667) (xy 223.492822 -116.618512) (xy 223.500224 -116.610991) (xy 223.508747 -116.59171)
			(xy 223.509332 -116.581174) (xy 223.509332 -116.506498) (xy 223.508808 -116.495948) (xy 223.500268 -116.476653)
			(xy 223.492822 -116.46916) (xy 223.472068 -116.449305) (xy 223.436089 -116.404539) (xy 223.407225 -116.354887)
			(xy 223.386128 -116.30147) (xy 223.373275 -116.245494) (xy 223.368955 -116.188224) (xy 222.469456 -116.188224)
			(xy 222.469456 -117.719348) (xy 236.702598 -117.719348) (xy 236.706669 -117.663726) (xy 236.718795 -117.609289)
			(xy 236.738718 -117.557198) (xy 236.766014 -117.508563) (xy 236.8001 -117.46442) (xy 236.840249 -117.425711)
			(xy 236.885607 -117.39326) (xy 236.935207 -117.367759) (xy 236.987991 -117.349752) (xy 237.042834 -117.339622)
			(xy 237.098568 -117.337585) (xy 237.154005 -117.343685) (xy 237.207962 -117.357791) (xy 237.259291 -117.379603)
			(xy 237.306897 -117.408657) (xy 237.349765 -117.444332) (xy 237.386982 -117.485869) (xy 237.417755 -117.532382)
			(xy 237.441427 -117.582879) (xy 237.457495 -117.636286) (xy 237.465615 -117.691462) (xy 237.466124 -117.719348)
			(xy 237.465615 -117.747234) (xy 237.457495 -117.80241) (xy 237.441427 -117.855817) (xy 237.417755 -117.906314)
			(xy 237.386982 -117.952827) (xy 237.349765 -117.994364) (xy 237.306897 -118.030039) (xy 237.259291 -118.059093)
			(xy 237.207962 -118.080905) (xy 237.154005 -118.095011) (xy 237.098568 -118.101111) (xy 237.042834 -118.099074)
			(xy 236.987991 -118.088944) (xy 236.935207 -118.070937) (xy 236.885607 -118.045436) (xy 236.840249 -118.012985)
			(xy 236.8001 -117.974276) (xy 236.766014 -117.930133) (xy 236.738718 -117.881498) (xy 236.718795 -117.829407)
			(xy 236.706669 -117.77497) (xy 236.702598 -117.719348) (xy 222.469456 -117.719348) (xy 222.469456 -118.179088)
			(xy 230.817926 -118.179088) (xy 230.821997 -118.123466) (xy 230.834123 -118.069029) (xy 230.854046 -118.016938)
			(xy 230.881342 -117.968303) (xy 230.915428 -117.92416) (xy 230.955577 -117.885451) (xy 231.000935 -117.853)
			(xy 231.050535 -117.827499) (xy 231.103319 -117.809492) (xy 231.158162 -117.799362) (xy 231.213896 -117.797325)
			(xy 231.269333 -117.803425) (xy 231.32329 -117.817531) (xy 231.374619 -117.839343) (xy 231.422225 -117.868397)
			(xy 231.465093 -117.904072) (xy 231.50231 -117.945609) (xy 231.533083 -117.992122) (xy 231.556755 -118.042619)
			(xy 231.572823 -118.096026) (xy 231.580943 -118.151202) (xy 231.581452 -118.179088) (xy 231.580943 -118.206974)
			(xy 231.572823 -118.26215) (xy 231.556755 -118.315557) (xy 231.533083 -118.366054) (xy 231.50231 -118.412567)
			(xy 231.465093 -118.454104) (xy 231.422225 -118.489779) (xy 231.374619 -118.518833) (xy 231.32329 -118.540645)
			(xy 231.269333 -118.554751) (xy 231.213896 -118.560851) (xy 231.158162 -118.558814) (xy 231.103319 -118.548684)
			(xy 231.050535 -118.530677) (xy 231.000935 -118.505176) (xy 230.955577 -118.472725) (xy 230.915428 -118.434016)
			(xy 230.881342 -118.389873) (xy 230.854046 -118.341238) (xy 230.834123 -118.289147) (xy 230.821997 -118.23471)
			(xy 230.817926 -118.179088) (xy 222.469456 -118.179088) (xy 222.469456 -119.16156) (xy 232.432604 -119.16156)
			(xy 232.436675 -119.105938) (xy 232.448801 -119.051501) (xy 232.468724 -118.99941) (xy 232.49602 -118.950775)
			(xy 232.530106 -118.906632) (xy 232.570255 -118.867923) (xy 232.615613 -118.835472) (xy 232.665213 -118.809971)
			(xy 232.717997 -118.791964) (xy 232.77284 -118.781834) (xy 232.828574 -118.779797) (xy 232.884011 -118.785897)
			(xy 232.937968 -118.800003) (xy 232.989297 -118.821815) (xy 233.036903 -118.850869) (xy 233.079771 -118.886544)
			(xy 233.116988 -118.928081) (xy 233.147761 -118.974594) (xy 233.171433 -119.025091) (xy 233.187501 -119.078498)
			(xy 233.195621 -119.133674) (xy 233.19613 -119.16156) (xy 233.195621 -119.189446) (xy 233.192697 -119.209312)
			(xy 233.799124 -119.209312) (xy 233.803195 -119.15369) (xy 233.815321 -119.099253) (xy 233.835244 -119.047162)
			(xy 233.86254 -118.998527) (xy 233.896626 -118.954384) (xy 233.936775 -118.915675) (xy 233.982133 -118.883224)
			(xy 234.031733 -118.857723) (xy 234.084517 -118.839716) (xy 234.13936 -118.829586) (xy 234.195094 -118.827549)
			(xy 234.250531 -118.833649) (xy 234.304488 -118.847755) (xy 234.355817 -118.869567) (xy 234.403423 -118.898621)
			(xy 234.446291 -118.934296) (xy 234.483508 -118.975833) (xy 234.514281 -119.022346) (xy 234.537953 -119.072843)
			(xy 234.554021 -119.12625) (xy 234.55619 -119.140986) (xy 235.177836 -119.140986) (xy 235.181907 -119.085364)
			(xy 235.194033 -119.030927) (xy 235.213956 -118.978836) (xy 235.241252 -118.930201) (xy 235.275338 -118.886058)
			(xy 235.315487 -118.847349) (xy 235.360845 -118.814898) (xy 235.410445 -118.789397) (xy 235.463229 -118.77139)
			(xy 235.518072 -118.76126) (xy 235.573806 -118.759223) (xy 235.629243 -118.765323) (xy 235.6832 -118.779429)
			(xy 235.734529 -118.801241) (xy 235.782135 -118.830295) (xy 235.825003 -118.86597) (xy 235.86222 -118.907507)
			(xy 235.892993 -118.95402) (xy 235.916665 -119.004517) (xy 235.932733 -119.057924) (xy 235.940583 -119.111268)
			(xy 236.70463 -119.111268) (xy 236.708701 -119.055646) (xy 236.720827 -119.001209) (xy 236.74075 -118.949118)
			(xy 236.768046 -118.900483) (xy 236.802132 -118.85634) (xy 236.842281 -118.817631) (xy 236.887639 -118.78518)
			(xy 236.937239 -118.759679) (xy 236.990023 -118.741672) (xy 237.044866 -118.731542) (xy 237.1006 -118.729505)
			(xy 237.156037 -118.735605) (xy 237.209994 -118.749711) (xy 237.261323 -118.771523) (xy 237.308929 -118.800577)
			(xy 237.351797 -118.836252) (xy 237.389014 -118.877789) (xy 237.419787 -118.924302) (xy 237.443459 -118.974799)
			(xy 237.459527 -119.028206) (xy 237.467647 -119.083382) (xy 237.468156 -119.111268) (xy 237.467647 -119.139154)
			(xy 237.459527 -119.19433) (xy 237.443459 -119.247737) (xy 237.419787 -119.298234) (xy 237.389014 -119.344747)
			(xy 237.351797 -119.386284) (xy 237.308929 -119.421959) (xy 237.261323 -119.451013) (xy 237.209994 -119.472825)
			(xy 237.156037 -119.486931) (xy 237.1006 -119.493031) (xy 237.044866 -119.490994) (xy 236.990023 -119.480864)
			(xy 236.937239 -119.462857) (xy 236.887639 -119.437356) (xy 236.842281 -119.404905) (xy 236.802132 -119.366196)
			(xy 236.768046 -119.322053) (xy 236.74075 -119.273418) (xy 236.720827 -119.221327) (xy 236.708701 -119.16689)
			(xy 236.70463 -119.111268) (xy 235.940583 -119.111268) (xy 235.940853 -119.1131) (xy 235.941362 -119.140986)
			(xy 235.940853 -119.168872) (xy 235.932733 -119.224048) (xy 235.916665 -119.277455) (xy 235.892993 -119.327952)
			(xy 235.86222 -119.374465) (xy 235.825003 -119.416002) (xy 235.782135 -119.451677) (xy 235.734529 -119.480731)
			(xy 235.6832 -119.502543) (xy 235.629243 -119.516649) (xy 235.573806 -119.522749) (xy 235.518072 -119.520712)
			(xy 235.463229 -119.510582) (xy 235.410445 -119.492575) (xy 235.360845 -119.467074) (xy 235.315487 -119.434623)
			(xy 235.275338 -119.395914) (xy 235.241252 -119.351771) (xy 235.213956 -119.303136) (xy 235.194033 -119.251045)
			(xy 235.181907 -119.196608) (xy 235.177836 -119.140986) (xy 234.55619 -119.140986) (xy 234.562141 -119.181426)
			(xy 234.56265 -119.209312) (xy 234.562141 -119.237198) (xy 234.554021 -119.292374) (xy 234.537953 -119.345781)
			(xy 234.514281 -119.396278) (xy 234.483508 -119.442791) (xy 234.446291 -119.484328) (xy 234.403423 -119.520003)
			(xy 234.355817 -119.549057) (xy 234.304488 -119.570869) (xy 234.250531 -119.584975) (xy 234.195094 -119.591075)
			(xy 234.13936 -119.589038) (xy 234.084517 -119.578908) (xy 234.031733 -119.560901) (xy 233.982133 -119.5354)
			(xy 233.936775 -119.502949) (xy 233.896626 -119.46424) (xy 233.86254 -119.420097) (xy 233.835244 -119.371462)
			(xy 233.815321 -119.319371) (xy 233.803195 -119.264934) (xy 233.799124 -119.209312) (xy 233.192697 -119.209312)
			(xy 233.187501 -119.244622) (xy 233.171433 -119.298029) (xy 233.147761 -119.348526) (xy 233.116988 -119.395039)
			(xy 233.079771 -119.436576) (xy 233.036903 -119.472251) (xy 232.989297 -119.501305) (xy 232.937968 -119.523117)
			(xy 232.884011 -119.537223) (xy 232.828574 -119.543323) (xy 232.77284 -119.541286) (xy 232.717997 -119.531156)
			(xy 232.665213 -119.513149) (xy 232.615613 -119.487648) (xy 232.570255 -119.455197) (xy 232.530106 -119.416488)
			(xy 232.49602 -119.372345) (xy 232.468724 -119.32371) (xy 232.448801 -119.271619) (xy 232.436675 -119.217182)
			(xy 232.432604 -119.16156) (xy 222.469456 -119.16156) (xy 222.469456 -120.779794) (xy 230.950768 -120.779794)
			(xy 230.954839 -120.724172) (xy 230.966965 -120.669735) (xy 230.986888 -120.617644) (xy 231.014184 -120.569009)
			(xy 231.04827 -120.524866) (xy 231.088419 -120.486157) (xy 231.133777 -120.453706) (xy 231.183377 -120.428205)
			(xy 231.236161 -120.410198) (xy 231.291004 -120.400068) (xy 231.346738 -120.398031) (xy 231.402175 -120.404131)
			(xy 231.456132 -120.418237) (xy 231.507461 -120.440049) (xy 231.555067 -120.469103) (xy 231.597935 -120.504778)
			(xy 231.635152 -120.546315) (xy 231.665925 -120.592828) (xy 231.689597 -120.643325) (xy 231.705665 -120.696732)
			(xy 231.713785 -120.751908) (xy 231.714294 -120.779794) (xy 231.713785 -120.80768) (xy 231.705665 -120.862856)
			(xy 231.689597 -120.916263) (xy 231.665925 -120.96676) (xy 231.635152 -121.013273) (xy 231.597935 -121.05481)
			(xy 231.555067 -121.090485) (xy 231.507461 -121.119539) (xy 231.456132 -121.141351) (xy 231.402175 -121.155457)
			(xy 231.346738 -121.161557) (xy 231.291004 -121.15952) (xy 231.236161 -121.14939) (xy 231.183377 -121.131383)
			(xy 231.133777 -121.105882) (xy 231.088419 -121.073431) (xy 231.04827 -121.034722) (xy 231.014184 -120.990579)
			(xy 230.986888 -120.941944) (xy 230.966965 -120.889853) (xy 230.954839 -120.835416) (xy 230.950768 -120.779794)
			(xy 222.469456 -120.779794) (xy 222.469456 -121.398792) (xy 233.551728 -121.398792) (xy 233.555799 -121.34317)
			(xy 233.567925 -121.288733) (xy 233.587848 -121.236642) (xy 233.615144 -121.188007) (xy 233.64923 -121.143864)
			(xy 233.689379 -121.105155) (xy 233.734737 -121.072704) (xy 233.784337 -121.047203) (xy 233.837121 -121.029196)
			(xy 233.891964 -121.019066) (xy 233.947698 -121.017029) (xy 234.003135 -121.023129) (xy 234.057092 -121.037235)
			(xy 234.108421 -121.059047) (xy 234.156027 -121.088101) (xy 234.198895 -121.123776) (xy 234.236112 -121.165313)
			(xy 234.266885 -121.211826) (xy 234.290557 -121.262323) (xy 234.306625 -121.31573) (xy 234.314745 -121.370906)
			(xy 234.315254 -121.398792) (xy 234.314745 -121.426678) (xy 234.306625 -121.481854) (xy 234.290557 -121.535261)
			(xy 234.266885 -121.585758) (xy 234.236112 -121.632271) (xy 234.198895 -121.673808) (xy 234.156027 -121.709483)
			(xy 234.108421 -121.738537) (xy 234.057092 -121.760349) (xy 234.003135 -121.774455) (xy 233.947698 -121.780555)
			(xy 233.891964 -121.778518) (xy 233.837121 -121.768388) (xy 233.784337 -121.750381) (xy 233.734737 -121.72488)
			(xy 233.689379 -121.692429) (xy 233.64923 -121.65372) (xy 233.615144 -121.609577) (xy 233.587848 -121.560942)
			(xy 233.567925 -121.508851) (xy 233.555799 -121.454414) (xy 233.551728 -121.398792) (xy 222.469456 -121.398792)
			(xy 222.469456 -123.509024) (xy 223.888298 -123.509024) (xy 223.892369 -123.453402) (xy 223.904495 -123.398965)
			(xy 223.924418 -123.346874) (xy 223.951714 -123.298239) (xy 223.9858 -123.254096) (xy 224.025949 -123.215387)
			(xy 224.071307 -123.182936) (xy 224.120907 -123.157435) (xy 224.173691 -123.139428) (xy 224.228534 -123.129298)
			(xy 224.284268 -123.127261) (xy 224.339705 -123.133361) (xy 224.393662 -123.147467) (xy 224.444991 -123.169279)
			(xy 224.492597 -123.198333) (xy 224.535465 -123.234008) (xy 224.572682 -123.275545) (xy 224.603455 -123.322058)
			(xy 224.627127 -123.372555) (xy 224.643195 -123.425962) (xy 224.651315 -123.481138) (xy 224.651824 -123.509024)
			(xy 224.651606 -123.520962) (xy 226.047298 -123.520962) (xy 226.051369 -123.46534) (xy 226.063495 -123.410903)
			(xy 226.083418 -123.358812) (xy 226.110714 -123.310177) (xy 226.1448 -123.266034) (xy 226.184949 -123.227325)
			(xy 226.230307 -123.194874) (xy 226.279907 -123.169373) (xy 226.332691 -123.151366) (xy 226.387534 -123.141236)
			(xy 226.443268 -123.139199) (xy 226.498705 -123.145299) (xy 226.552662 -123.159405) (xy 226.603991 -123.181217)
			(xy 226.651597 -123.210271) (xy 226.694465 -123.245946) (xy 226.731682 -123.287483) (xy 226.762455 -123.333996)
			(xy 226.786127 -123.384493) (xy 226.802195 -123.4379) (xy 226.810315 -123.493076) (xy 226.810824 -123.520962)
			(xy 226.810315 -123.548848) (xy 226.802195 -123.604024) (xy 226.786127 -123.657431) (xy 226.762455 -123.707928)
			(xy 226.731682 -123.754441) (xy 226.694465 -123.795978) (xy 226.651597 -123.831653) (xy 226.603991 -123.860707)
			(xy 226.552662 -123.882519) (xy 226.498705 -123.896625) (xy 226.443268 -123.902725) (xy 226.387534 -123.900688)
			(xy 226.332691 -123.890558) (xy 226.279907 -123.872551) (xy 226.230307 -123.84705) (xy 226.184949 -123.814599)
			(xy 226.1448 -123.77589) (xy 226.110714 -123.731747) (xy 226.083418 -123.683112) (xy 226.063495 -123.631021)
			(xy 226.051369 -123.576584) (xy 226.047298 -123.520962) (xy 224.651606 -123.520962) (xy 224.651315 -123.53691)
			(xy 224.643195 -123.592086) (xy 224.627127 -123.645493) (xy 224.603455 -123.69599) (xy 224.572682 -123.742503)
			(xy 224.535465 -123.78404) (xy 224.492597 -123.819715) (xy 224.444991 -123.848769) (xy 224.393662 -123.870581)
			(xy 224.339705 -123.884687) (xy 224.284268 -123.890787) (xy 224.228534 -123.88875) (xy 224.173691 -123.87862)
			(xy 224.120907 -123.860613) (xy 224.071307 -123.835112) (xy 224.025949 -123.802661) (xy 223.9858 -123.763952)
			(xy 223.951714 -123.719809) (xy 223.924418 -123.671174) (xy 223.904495 -123.619083) (xy 223.892369 -123.564646)
			(xy 223.888298 -123.509024) (xy 222.469456 -123.509024) (xy 222.469456 -130.338068) (xy 222.469124 -130.36412)
			(xy 222.464414 -130.416012) (xy 222.460058 -130.4417) (xy 222.459296 -130.446018) (xy 222.459296 -131.266692)
			(xy 222.45886 -131.299005) (xy 222.451625 -131.363224) (xy 222.437245 -131.426229) (xy 222.4159 -131.487229)
			(xy 222.38786 -131.545454) (xy 222.353477 -131.600174) (xy 222.313183 -131.6507) (xy 222.29064 -131.673854)
			(xy 217.006519 -136.957816) (xy 223.695512 -136.957816) (xy 223.699583 -136.902194) (xy 223.711709 -136.847757)
			(xy 223.731632 -136.795666) (xy 223.758928 -136.747031) (xy 223.793014 -136.702888) (xy 223.833163 -136.664179)
			(xy 223.878521 -136.631728) (xy 223.928121 -136.606227) (xy 223.980905 -136.58822) (xy 224.035748 -136.57809)
			(xy 224.091482 -136.576053) (xy 224.146919 -136.582153) (xy 224.200876 -136.596259) (xy 224.252205 -136.618071)
			(xy 224.299811 -136.647125) (xy 224.342679 -136.6828) (xy 224.379896 -136.724337) (xy 224.410669 -136.77085)
			(xy 224.434341 -136.821347) (xy 224.450409 -136.874754) (xy 224.458529 -136.92993) (xy 224.459038 -136.957816)
			(xy 224.458529 -136.985702) (xy 224.450409 -137.040878) (xy 224.434341 -137.094285) (xy 224.410669 -137.144782)
			(xy 224.379896 -137.191295) (xy 224.342679 -137.232832) (xy 224.299811 -137.268507) (xy 224.252205 -137.297561)
			(xy 224.200876 -137.319373) (xy 224.146919 -137.333479) (xy 224.091482 -137.339579) (xy 224.035748 -137.337542)
			(xy 223.980905 -137.327412) (xy 223.928121 -137.309405) (xy 223.878521 -137.283904) (xy 223.833163 -137.251453)
			(xy 223.793014 -137.212744) (xy 223.758928 -137.168601) (xy 223.731632 -137.119966) (xy 223.711709 -137.067875)
			(xy 223.699583 -137.013438) (xy 223.695512 -136.957816) (xy 217.006519 -136.957816) (xy 215.459104 -138.505184)
			(xy 221.778828 -138.505184) (xy 221.782899 -138.449562) (xy 221.795025 -138.395125) (xy 221.814948 -138.343034)
			(xy 221.842244 -138.294399) (xy 221.87633 -138.250256) (xy 221.916479 -138.211547) (xy 221.961837 -138.179096)
			(xy 222.011437 -138.153595) (xy 222.064221 -138.135588) (xy 222.119064 -138.125458) (xy 222.174798 -138.123421)
			(xy 222.230235 -138.129521) (xy 222.284192 -138.143627) (xy 222.335521 -138.165439) (xy 222.383127 -138.194493)
			(xy 222.425995 -138.230168) (xy 222.463212 -138.271705) (xy 222.493985 -138.318218) (xy 222.517657 -138.368715)
			(xy 222.533725 -138.422122) (xy 222.541845 -138.477298) (xy 222.542354 -138.505184) (xy 222.541845 -138.53307)
			(xy 222.533725 -138.588246) (xy 222.517657 -138.641653) (xy 222.493985 -138.69215) (xy 222.463212 -138.738663)
			(xy 222.425995 -138.7802) (xy 222.383127 -138.815875) (xy 222.335521 -138.844929) (xy 222.284192 -138.866741)
			(xy 222.230235 -138.880847) (xy 222.174798 -138.886947) (xy 222.119064 -138.88491) (xy 222.064221 -138.87478)
			(xy 222.011437 -138.856773) (xy 221.961837 -138.831272) (xy 221.916479 -138.798821) (xy 221.87633 -138.760112)
			(xy 221.842244 -138.715969) (xy 221.814948 -138.667334) (xy 221.795025 -138.615243) (xy 221.782899 -138.560806)
			(xy 221.778828 -138.505184) (xy 215.459104 -138.505184) (xy 214.32242 -139.641834) (xy 219.820234 -139.641834)
			(xy 219.824305 -139.586212) (xy 219.836431 -139.531775) (xy 219.856354 -139.479684) (xy 219.88365 -139.431049)
			(xy 219.917736 -139.386906) (xy 219.957885 -139.348197) (xy 220.003243 -139.315746) (xy 220.052843 -139.290245)
			(xy 220.105627 -139.272238) (xy 220.16047 -139.262108) (xy 220.216204 -139.260071) (xy 220.271641 -139.266171)
			(xy 220.325598 -139.280277) (xy 220.376927 -139.302089) (xy 220.424533 -139.331143) (xy 220.467401 -139.366818)
			(xy 220.504618 -139.408355) (xy 220.535391 -139.454868) (xy 220.559063 -139.505365) (xy 220.575131 -139.558772)
			(xy 220.583251 -139.613948) (xy 220.58376 -139.641834) (xy 220.583251 -139.66972) (xy 220.575131 -139.724896)
			(xy 220.559063 -139.778303) (xy 220.535391 -139.8288) (xy 220.504618 -139.875313) (xy 220.467401 -139.91685)
			(xy 220.424533 -139.952525) (xy 220.376927 -139.981579) (xy 220.325598 -140.003391) (xy 220.271641 -140.017497)
			(xy 220.216204 -140.023597) (xy 220.16047 -140.02156) (xy 220.105627 -140.01143) (xy 220.052843 -139.993423)
			(xy 220.003243 -139.967922) (xy 219.957885 -139.935471) (xy 219.917736 -139.896762) (xy 219.88365 -139.852619)
			(xy 219.856354 -139.803984) (xy 219.836431 -139.751893) (xy 219.824305 -139.697456) (xy 219.820234 -139.641834)
			(xy 214.32242 -139.641834) (xy 213.843108 -140.121132) (xy 213.840405 -140.123985) (xy 213.835818 -140.130366)
			(xy 213.833964 -140.133832) (xy 213.831377 -140.139258) (xy 213.828547 -140.150938) (xy 213.828376 -140.156946)
			(xy 213.828376 -140.894562) (xy 219.859604 -140.894562) (xy 219.863675 -140.83894) (xy 219.875801 -140.784503)
			(xy 219.895724 -140.732412) (xy 219.92302 -140.683777) (xy 219.957106 -140.639634) (xy 219.997255 -140.600925)
			(xy 220.042613 -140.568474) (xy 220.092213 -140.542973) (xy 220.144997 -140.524966) (xy 220.19984 -140.514836)
			(xy 220.255574 -140.512799) (xy 220.311011 -140.518899) (xy 220.364968 -140.533005) (xy 220.416297 -140.554817)
			(xy 220.463903 -140.583871) (xy 220.506771 -140.619546) (xy 220.543988 -140.661083) (xy 220.574761 -140.707596)
			(xy 220.598433 -140.758093) (xy 220.614501 -140.8115) (xy 220.622621 -140.866676) (xy 220.62313 -140.894562)
			(xy 220.622621 -140.922448) (xy 220.614501 -140.977624) (xy 220.598433 -141.031031) (xy 220.574761 -141.081528)
			(xy 220.543988 -141.128041) (xy 220.506771 -141.169578) (xy 220.463903 -141.205253) (xy 220.416297 -141.234307)
			(xy 220.364968 -141.256119) (xy 220.311011 -141.270225) (xy 220.255574 -141.276325) (xy 220.19984 -141.274288)
			(xy 220.144997 -141.264158) (xy 220.092213 -141.246151) (xy 220.042613 -141.22065) (xy 219.997255 -141.188199)
			(xy 219.957106 -141.14949) (xy 219.92302 -141.105347) (xy 219.895724 -141.056712) (xy 219.875801 -141.004621)
			(xy 219.863675 -140.950184) (xy 219.859604 -140.894562) (xy 213.828376 -140.894562) (xy 213.828376 -145.974562)
			(xy 219.859604 -145.974562) (xy 219.863675 -145.91894) (xy 219.875801 -145.864503) (xy 219.895724 -145.812412)
			(xy 219.92302 -145.763777) (xy 219.957106 -145.719634) (xy 219.997255 -145.680925) (xy 220.042613 -145.648474)
			(xy 220.092213 -145.622973) (xy 220.144997 -145.604966) (xy 220.19984 -145.594836) (xy 220.255574 -145.592799)
			(xy 220.311011 -145.598899) (xy 220.364968 -145.613005) (xy 220.416297 -145.634817) (xy 220.463903 -145.663871)
			(xy 220.506771 -145.699546) (xy 220.543988 -145.741083) (xy 220.574761 -145.787596) (xy 220.598433 -145.838093)
			(xy 220.614501 -145.8915) (xy 220.622621 -145.946676) (xy 220.62313 -145.974562) (xy 220.622621 -146.002448)
			(xy 220.614501 -146.057624) (xy 220.598433 -146.111031) (xy 220.574761 -146.161528) (xy 220.543988 -146.208041)
			(xy 220.506771 -146.249578) (xy 220.463903 -146.285253) (xy 220.416297 -146.314307) (xy 220.364968 -146.336119)
			(xy 220.311011 -146.350225) (xy 220.255574 -146.356325) (xy 220.19984 -146.354288) (xy 220.144997 -146.344158)
			(xy 220.092213 -146.326151) (xy 220.042613 -146.30065) (xy 219.997255 -146.268199) (xy 219.957106 -146.22949)
			(xy 219.92302 -146.185347) (xy 219.895724 -146.136712) (xy 219.875801 -146.084621) (xy 219.863675 -146.030184)
			(xy 219.859604 -145.974562) (xy 213.828376 -145.974562) (xy 213.828376 -146.990582) (xy 221.941621 -146.990582)
			(xy 221.945638 -146.935329) (xy 221.957598 -146.881236) (xy 221.977252 -146.829441) (xy 222.004185 -146.781029)
			(xy 222.037833 -146.737019) (xy 222.077489 -146.698335) (xy 222.12232 -146.665788) (xy 222.146622 -146.652488)
			(xy 222.159068 -146.645884) (xy 222.1738 -146.621754) (xy 222.1738 -145.572734) (xy 222.174362 -145.546916)
			(xy 222.183107 -145.496023) (xy 222.200286 -145.447327) (xy 222.22541 -145.402213) (xy 222.257763 -145.361966)
			(xy 222.296423 -145.327734) (xy 222.318072 -145.313654) (xy 222.353378 -145.29181) (xy 222.36225 -145.285653)
			(xy 222.374292 -145.267756) (xy 222.377945 -145.246497) (xy 222.37573 -145.23593) (xy 222.37004 -145.212465)
			(xy 222.363926 -145.164568) (xy 222.363538 -145.140426) (xy 222.363921 -145.116283) (xy 222.370031 -145.068386)
			(xy 222.37573 -145.044922) (xy 222.377952 -145.034351) (xy 222.374315 -145.013077) (xy 222.362279 -144.995162)
			(xy 222.353378 -144.989042) (xy 222.318072 -144.967198) (xy 222.296428 -144.953108) (xy 222.257753 -144.91889)
			(xy 222.225389 -144.878649) (xy 222.200263 -144.833535) (xy 222.183089 -144.784834) (xy 222.174359 -144.733938)
			(xy 222.1738 -144.708118) (xy 222.1738 -142.777972) (xy 222.173944 -142.773082) (xy 222.175858 -142.763489)
			(xy 222.17761 -142.758922) (xy 222.216472 -142.663164) (xy 222.218568 -142.658341) (xy 222.224457 -142.64963)
			(xy 222.228156 -142.645892) (xy 222.264732 -142.610586) (xy 222.26524 -142.610078) (xy 223.241108 -141.63421)
			(xy 223.248183 -141.626512) (xy 223.255894 -141.607099) (xy 223.255255 -141.586219) (xy 223.251268 -141.576552)
			(xy 223.203262 -141.47546) (xy 223.175322 -141.459712) (xy 223.15932 -141.461236) (xy 223.14678 -141.462416)
			(xy 223.121623 -141.463685) (xy 223.109028 -141.463776) (xy 223.078295 -141.463336) (xy 223.017278 -141.45593)
			(xy 222.957598 -141.441222) (xy 222.900126 -141.419428) (xy 222.8457 -141.390865) (xy 222.795115 -141.355949)
			(xy 222.749107 -141.31519) (xy 222.708349 -141.269182) (xy 222.673433 -141.218596) (xy 222.64487 -141.16417)
			(xy 222.623076 -141.106698) (xy 222.608369 -141.047018) (xy 222.600964 -140.986001) (xy 222.60052 -140.955268)
			(xy 222.601091 -140.921983) (xy 222.609829 -140.85599) (xy 222.6271 -140.791699) (xy 222.652608 -140.73021)
			(xy 222.685918 -140.672573) (xy 222.72646 -140.619773) (xy 222.749618 -140.595858) (xy 224.76333 -138.581892)
			(xy 224.771211 -138.573173) (xy 224.778745 -138.550936) (xy 224.777808 -138.53922) (xy 224.765616 -138.447526)
			(xy 224.752408 -138.427714) (xy 224.741994 -138.421872) (xy 224.71736 -138.407186) (xy 224.672372 -138.371622)
			(xy 224.633217 -138.32972) (xy 224.600779 -138.282428) (xy 224.575789 -138.23081) (xy 224.558812 -138.176033)
			(xy 224.55023 -138.11933) (xy 224.549716 -138.090656) (xy 224.550137 -138.063403) (xy 224.5579 -138.009451)
			(xy 224.573262 -137.957154) (xy 224.59591 -137.907575) (xy 224.625383 -137.861724) (xy 224.661081 -137.820533)
			(xy 224.702278 -137.784842) (xy 224.748135 -137.755377) (xy 224.797718 -137.732738) (xy 224.850018 -137.717386)
			(xy 224.90397 -137.709632) (xy 224.931224 -137.709148) (xy 224.960606 -137.709706) (xy 225.018674 -137.71872)
			(xy 225.074674 -137.73653) (xy 225.127281 -137.762717) (xy 225.175251 -137.796659) (xy 225.217449 -137.837555)
			(xy 225.252878 -137.884438) (xy 225.267266 -137.910062) (xy 225.272811 -137.919132) (xy 225.289605 -137.932125)
			(xy 225.299778 -137.935208) (xy 225.372676 -137.953496) (xy 225.383034 -137.955446) (xy 225.403763 -137.95179)
			(xy 225.412808 -137.946384) (xy 225.413062 -137.946384) (xy 225.438116 -137.930286) (xy 225.491241 -137.903368)
			(xy 225.547146 -137.88284) (xy 225.605066 -137.868985) (xy 225.664209 -137.861991) (xy 225.693986 -137.861548)
			(xy 228.186996 -137.861548) (xy 228.220277 -137.862049) (xy 228.28627 -137.870727) (xy 228.350565 -137.887948)
			(xy 228.412061 -137.913418) (xy 228.469704 -137.9467) (xy 228.522507 -137.987224) (xy 228.546406 -138.010392)
			(xy 228.794564 -138.25855) (xy 232.741976 -138.25855) (xy 232.746047 -138.202928) (xy 232.758173 -138.148491)
			(xy 232.778096 -138.0964) (xy 232.805392 -138.047765) (xy 232.839478 -138.003622) (xy 232.879627 -137.964913)
			(xy 232.924985 -137.932462) (xy 232.974585 -137.906961) (xy 233.027369 -137.888954) (xy 233.082212 -137.878824)
			(xy 233.137946 -137.876787) (xy 233.193383 -137.882887) (xy 233.24734 -137.896993) (xy 233.298669 -137.918805)
			(xy 233.346275 -137.947859) (xy 233.389143 -137.983534) (xy 233.42636 -138.025071) (xy 233.457133 -138.071584)
			(xy 233.480805 -138.122081) (xy 233.496873 -138.175488) (xy 233.504993 -138.230664) (xy 233.505502 -138.25855)
			(xy 233.504993 -138.286436) (xy 233.496873 -138.341612) (xy 233.480805 -138.395019) (xy 233.457133 -138.445516)
			(xy 233.42636 -138.492029) (xy 233.389143 -138.533566) (xy 233.346275 -138.569241) (xy 233.298669 -138.598295)
			(xy 233.24734 -138.620107) (xy 233.193383 -138.634213) (xy 233.137946 -138.640313) (xy 233.082212 -138.638276)
			(xy 233.027369 -138.628146) (xy 232.974585 -138.610139) (xy 232.924985 -138.584638) (xy 232.879627 -138.552187)
			(xy 232.839478 -138.513478) (xy 232.805392 -138.469335) (xy 232.778096 -138.4207) (xy 232.758173 -138.368609)
			(xy 232.746047 -138.314172) (xy 232.741976 -138.25855) (xy 228.794564 -138.25855) (xy 230.361744 -139.82573)
			(xy 231.704894 -139.82573) (xy 231.708965 -139.770108) (xy 231.721091 -139.715671) (xy 231.741014 -139.66358)
			(xy 231.76831 -139.614945) (xy 231.802396 -139.570802) (xy 231.842545 -139.532093) (xy 231.887903 -139.499642)
			(xy 231.937503 -139.474141) (xy 231.990287 -139.456134) (xy 232.04513 -139.446004) (xy 232.100864 -139.443967)
			(xy 232.156301 -139.450067) (xy 232.210258 -139.464173) (xy 232.261587 -139.485985) (xy 232.309193 -139.515039)
			(xy 232.352061 -139.550714) (xy 232.389278 -139.592251) (xy 232.420051 -139.638764) (xy 232.443723 -139.689261)
			(xy 232.459791 -139.742668) (xy 232.467911 -139.797844) (xy 232.46842 -139.82573) (xy 232.467911 -139.853616)
			(xy 232.459791 -139.908792) (xy 232.443723 -139.962199) (xy 232.420051 -140.012696) (xy 232.389278 -140.059209)
			(xy 232.352061 -140.100746) (xy 232.309193 -140.136421) (xy 232.261587 -140.165475) (xy 232.210258 -140.187287)
			(xy 232.156301 -140.201393) (xy 232.100864 -140.207493) (xy 232.04513 -140.205456) (xy 231.990287 -140.195326)
			(xy 231.937503 -140.177319) (xy 231.887903 -140.151818) (xy 231.842545 -140.119367) (xy 231.802396 -140.080658)
			(xy 231.76831 -140.036515) (xy 231.741014 -139.98788) (xy 231.721091 -139.935789) (xy 231.708965 -139.881352)
			(xy 231.704894 -139.82573) (xy 230.361744 -139.82573) (xy 230.37419 -139.838176) (xy 230.397363 -139.86208)
			(xy 230.437928 -139.91487) (xy 230.471253 -139.972505) (xy 230.496766 -140.033998) (xy 230.514031 -140.098296)
			(xy 230.522752 -140.164298) (xy 230.523288 -140.197586) (xy 230.523288 -141.207744) (xy 230.523667 -141.217819)
			(xy 230.531418 -141.236418) (xy 230.538274 -141.243812) (xy 231.062585 -141.768322) (xy 231.849166 -141.768322)
			(xy 231.853237 -141.7127) (xy 231.865363 -141.658263) (xy 231.885286 -141.606172) (xy 231.912582 -141.557537)
			(xy 231.946668 -141.513394) (xy 231.986817 -141.474685) (xy 232.032175 -141.442234) (xy 232.081775 -141.416733)
			(xy 232.134559 -141.398726) (xy 232.189402 -141.388596) (xy 232.245136 -141.386559) (xy 232.300573 -141.392659)
			(xy 232.35453 -141.406765) (xy 232.405859 -141.428577) (xy 232.453465 -141.457631) (xy 232.496333 -141.493306)
			(xy 232.53355 -141.534843) (xy 232.564323 -141.581356) (xy 232.587995 -141.631853) (xy 232.604063 -141.68526)
			(xy 232.612183 -141.740436) (xy 232.612692 -141.768322) (xy 232.612183 -141.796208) (xy 232.604063 -141.851384)
			(xy 232.587995 -141.904791) (xy 232.564323 -141.955288) (xy 232.53355 -142.001801) (xy 232.496333 -142.043338)
			(xy 232.453465 -142.079013) (xy 232.405859 -142.108067) (xy 232.35453 -142.129879) (xy 232.300573 -142.143985)
			(xy 232.245136 -142.150085) (xy 232.189402 -142.148048) (xy 232.134559 -142.137918) (xy 232.081775 -142.119911)
			(xy 232.032175 -142.09441) (xy 231.986817 -142.061959) (xy 231.946668 -142.02325) (xy 231.912582 -141.979107)
			(xy 231.885286 -141.930472) (xy 231.865363 -141.878381) (xy 231.853237 -141.823944) (xy 231.849166 -141.768322)
			(xy 231.062585 -141.768322) (xy 231.206294 -141.912086) (xy 231.229473 -141.935984) (xy 231.270037 -141.988776)
			(xy 231.303361 -142.046412) (xy 231.328873 -142.107906) (xy 231.346137 -142.172205) (xy 231.354857 -142.238208)
			(xy 231.355392 -142.271496) (xy 231.354959 -142.302229) (xy 231.34755 -142.363246) (xy 231.332841 -142.422925)
			(xy 231.311045 -142.480396) (xy 231.28248 -142.534821) (xy 231.247563 -142.585405) (xy 231.206804 -142.631412)
			(xy 231.196193 -142.640812) (xy 234.22305 -142.640812) (xy 234.227121 -142.58519) (xy 234.239247 -142.530753)
			(xy 234.25917 -142.478662) (xy 234.286466 -142.430027) (xy 234.320552 -142.385884) (xy 234.360701 -142.347175)
			(xy 234.406059 -142.314724) (xy 234.455659 -142.289223) (xy 234.508443 -142.271216) (xy 234.563286 -142.261086)
			(xy 234.61902 -142.259049) (xy 234.674457 -142.265149) (xy 234.728414 -142.279255) (xy 234.779743 -142.301067)
			(xy 234.827349 -142.330121) (xy 234.870217 -142.365796) (xy 234.907434 -142.407333) (xy 234.938207 -142.453846)
			(xy 234.961879 -142.504343) (xy 234.977947 -142.55775) (xy 234.986067 -142.612926) (xy 234.986576 -142.640812)
			(xy 234.986067 -142.668698) (xy 234.977947 -142.723874) (xy 234.961879 -142.777281) (xy 234.938207 -142.827778)
			(xy 234.907434 -142.874291) (xy 234.870217 -142.915828) (xy 234.827349 -142.951503) (xy 234.779743 -142.980557)
			(xy 234.728414 -143.002369) (xy 234.674457 -143.016475) (xy 234.61902 -143.022575) (xy 234.563286 -143.020538)
			(xy 234.508443 -143.010408) (xy 234.455659 -142.992401) (xy 234.406059 -142.9669) (xy 234.360701 -142.934449)
			(xy 234.320552 -142.89574) (xy 234.286466 -142.851597) (xy 234.25917 -142.802962) (xy 234.239247 -142.750871)
			(xy 234.227121 -142.696434) (xy 234.22305 -142.640812) (xy 231.196193 -142.640812) (xy 231.160796 -142.672171)
			(xy 231.11021 -142.707086) (xy 231.055785 -142.73565) (xy 230.998314 -142.757444) (xy 230.938634 -142.772152)
			(xy 230.877617 -142.779559) (xy 230.846884 -142.780004) (xy 230.8136 -142.779416) (xy 230.747607 -142.77068)
			(xy 230.683317 -142.753412) (xy 230.621828 -142.727907) (xy 230.564191 -142.694601) (xy 230.511389 -142.654062)
			(xy 230.487474 -142.630906) (xy 229.65537 -141.798802) (xy 229.632179 -141.774915) (xy 229.591617 -141.72212)
			(xy 229.558296 -141.664482) (xy 229.532786 -141.602985) (xy 229.515524 -141.538685) (xy 229.506806 -141.47268)
			(xy 229.506272 -141.439392) (xy 229.506272 -140.429234) (xy 229.505836 -140.419166) (xy 229.498123 -140.400568)
			(xy 229.491286 -140.393166) (xy 227.991416 -138.893042) (xy 227.984 -138.886222) (xy 227.965413 -138.878489)
			(xy 227.955348 -138.878056) (xy 227.543614 -138.878056) (xy 227.532889 -138.878465) (xy 227.513284 -138.887157)
			(xy 227.505768 -138.89482) (xy 227.44811 -138.959336) (xy 227.441506 -138.979656) (xy 227.442522 -138.990324)
			(xy 227.443487 -139.000265) (xy 227.444502 -139.020214) (xy 227.444554 -139.030202) (xy 227.444024 -139.057451)
			(xy 227.436269 -139.111395) (xy 227.420916 -139.163686) (xy 227.398278 -139.21326) (xy 227.368815 -139.259108)
			(xy 227.333129 -139.300297) (xy 227.291944 -139.335989) (xy 227.246099 -139.365456) (xy 227.196527 -139.3881)
			(xy 227.144238 -139.403459) (xy 227.090295 -139.411221) (xy 227.063046 -139.41171) (xy 227.035677 -139.411215)
			(xy 226.981499 -139.403403) (xy 226.928996 -139.387921) (xy 226.879249 -139.365086) (xy 226.833281 -139.335368)
			(xy 226.812348 -139.31773) (xy 226.812094 -139.317476) (xy 226.805015 -139.311878) (xy 226.788092 -139.305639)
			(xy 226.779074 -139.305284) (xy 226.712018 -139.305284) (xy 226.703002 -139.305653) (xy 226.686086 -139.311893)
			(xy 226.678998 -139.317476) (xy 226.678998 -139.31773) (xy 226.678744 -139.31773) (xy 226.65781 -139.335367)
			(xy 226.611837 -139.365078) (xy 226.56209 -139.387914) (xy 226.50959 -139.403405) (xy 226.455415 -139.411235)
			(xy 226.428046 -139.41171) (xy 226.400794 -139.411202) (xy 226.346845 -139.403451) (xy 226.294548 -139.388101)
			(xy 226.244968 -139.365464) (xy 226.199115 -139.336001) (xy 226.157922 -139.300312) (xy 226.122228 -139.259123)
			(xy 226.092759 -139.213274) (xy 226.070116 -139.163697) (xy 226.054759 -139.111402) (xy 226.047002 -139.057454)
			(xy 226.046538 -139.030202) (xy 226.046585 -139.020214) (xy 226.047603 -139.000265) (xy 226.04857 -138.990324)
			(xy 226.049586 -138.979656) (xy 226.042982 -138.959336) (xy 225.985324 -138.89482) (xy 225.977734 -138.887266)
			(xy 225.958173 -138.878612) (xy 225.947478 -138.878056) (xy 225.926142 -138.878056) (xy 225.916073 -138.878488)
			(xy 225.897474 -138.886203) (xy 225.890074 -138.893042) (xy 224.975928 -139.807188) (xy 224.969243 -139.814598)
			(xy 224.961646 -139.833032) (xy 224.961647 -139.85297) (xy 224.969244 -139.871404) (xy 224.975928 -139.878816)
			(xy 224.986596 -139.889484) (xy 225.014536 -139.895834) (xy 225.028252 -139.891262) (xy 225.052106 -139.883611)
			(xy 225.101506 -139.875317) (xy 225.12655 -139.874752) (xy 225.99015 -139.874752) (xy 225.99504 -139.874893)
			(xy 226.004633 -139.876809) (xy 226.0092 -139.878562) (xy 226.104958 -139.917424) (xy 226.10978 -139.919523)
			(xy 226.118491 -139.92541) (xy 226.12223 -139.929108) (xy 226.157536 -139.965684) (xy 226.158044 -139.966192)
			(xy 226.832668 -140.640562) (xy 226.849267 -140.657854) (xy 226.877433 -140.696635) (xy 226.899201 -140.739336)
			(xy 226.914037 -140.784911) (xy 226.921578 -140.832244) (xy 226.922076 -140.856208) (xy 226.922076 -142.244826)
			(xy 228.06736 -142.244826) (xy 228.071431 -142.189204) (xy 228.083557 -142.134767) (xy 228.10348 -142.082676)
			(xy 228.130776 -142.034041) (xy 228.164862 -141.989898) (xy 228.205011 -141.951189) (xy 228.250369 -141.918738)
			(xy 228.299969 -141.893237) (xy 228.352753 -141.87523) (xy 228.407596 -141.8651) (xy 228.46333 -141.863063)
			(xy 228.518767 -141.869163) (xy 228.572724 -141.883269) (xy 228.624053 -141.905081) (xy 228.671659 -141.934135)
			(xy 228.714527 -141.96981) (xy 228.751744 -142.011347) (xy 228.782517 -142.05786) (xy 228.806189 -142.108357)
			(xy 228.822257 -142.161764) (xy 228.830377 -142.21694) (xy 228.830886 -142.244826) (xy 228.830377 -142.272712)
			(xy 228.822257 -142.327888) (xy 228.806189 -142.381295) (xy 228.782517 -142.431792) (xy 228.751744 -142.478305)
			(xy 228.714527 -142.519842) (xy 228.671659 -142.555517) (xy 228.624053 -142.584571) (xy 228.572724 -142.606383)
			(xy 228.518767 -142.620489) (xy 228.46333 -142.626589) (xy 228.407596 -142.624552) (xy 228.352753 -142.614422)
			(xy 228.299969 -142.596415) (xy 228.250369 -142.570914) (xy 228.205011 -142.538463) (xy 228.164862 -142.499754)
			(xy 228.130776 -142.455611) (xy 228.10348 -142.406976) (xy 228.083557 -142.354885) (xy 228.071431 -142.300448)
			(xy 228.06736 -142.244826) (xy 226.922076 -142.244826) (xy 226.922076 -143.604234) (xy 226.921671 -143.628208)
			(xy 226.914168 -143.675564) (xy 226.899336 -143.721159) (xy 226.877541 -143.763867) (xy 226.849324 -143.802631)
			(xy 226.832668 -143.81988) (xy 225.970338 -144.68221) (xy 225.963506 -144.689617) (xy 225.955781 -144.708211)
			(xy 225.955352 -144.718278) (xy 225.955352 -147.189248) (xy 233.05469 -147.189248) (xy 233.05469 -147.134752)
			(xy 233.062445 -147.08081) (xy 233.077797 -147.028521) (xy 233.100434 -146.978948) (xy 233.129895 -146.933102)
			(xy 233.16558 -146.891914) (xy 233.206763 -146.856224) (xy 233.252606 -146.826757) (xy 233.302176 -146.804114)
			(xy 233.354463 -146.788755) (xy 233.408404 -146.780994) (xy 233.435652 -146.780504) (xy 233.467273 -146.781113)
			(xy 233.529646 -146.791567) (xy 233.589436 -146.812179) (xy 233.617516 -146.826732) (xy 233.625869 -146.830746)
			(xy 233.644237 -146.833091) (xy 233.65333 -146.831304) (xy 233.728514 -146.813524) (xy 233.744262 -146.802856)
			(xy 233.749342 -146.795236) (xy 233.764731 -146.773932) (xy 233.80036 -146.735302) (xy 233.840952 -146.701925)
			(xy 233.885739 -146.674433) (xy 233.933874 -146.653344) (xy 233.984447 -146.639058) (xy 234.036502 -146.631846)
			(xy 234.062778 -146.631406) (xy 234.090033 -146.631839) (xy 234.143988 -146.639594) (xy 234.196291 -146.654949)
			(xy 234.245876 -146.677591) (xy 234.291733 -146.707059) (xy 234.33293 -146.742754) (xy 234.368627 -146.783949)
			(xy 234.398099 -146.829805) (xy 234.420743 -146.879389) (xy 234.436101 -146.93169) (xy 234.443859 -146.985645)
			(xy 234.443859 -147.040155) (xy 234.436101 -147.09411) (xy 234.420743 -147.146411) (xy 234.398099 -147.195995)
			(xy 234.368627 -147.241851) (xy 234.33293 -147.283046) (xy 234.291733 -147.318741) (xy 234.245876 -147.348209)
			(xy 234.196291 -147.370851) (xy 234.143988 -147.386206) (xy 234.090033 -147.393961) (xy 234.062778 -147.394422)
			(xy 234.031157 -147.393809) (xy 233.968784 -147.383359) (xy 233.908994 -147.362748) (xy 233.880914 -147.348194)
			(xy 233.872555 -147.344195) (xy 233.854192 -147.34184) (xy 233.8451 -147.343622) (xy 233.769916 -147.361402)
			(xy 233.754168 -147.37207) (xy 233.749088 -147.37969) (xy 233.733751 -147.401032) (xy 233.698112 -147.43966)
			(xy 233.657511 -147.473033) (xy 233.612715 -147.500521) (xy 233.564572 -147.521603) (xy 233.513991 -147.535881)
			(xy 233.461931 -147.543085) (xy 233.435652 -147.54352) (xy 233.408404 -147.543006) (xy 233.354463 -147.535245)
			(xy 233.302176 -147.519886) (xy 233.252606 -147.497243) (xy 233.206763 -147.467776) (xy 233.16558 -147.432086)
			(xy 233.129895 -147.390898) (xy 233.100434 -147.345052) (xy 233.077797 -147.295479) (xy 233.062445 -147.24319)
			(xy 233.05469 -147.189248) (xy 225.955352 -147.189248) (xy 225.955352 -147.720812) (xy 234.212128 -147.720812)
			(xy 234.216199 -147.66519) (xy 234.228325 -147.610753) (xy 234.248248 -147.558662) (xy 234.275544 -147.510027)
			(xy 234.30963 -147.465884) (xy 234.349779 -147.427175) (xy 234.395137 -147.394724) (xy 234.444737 -147.369223)
			(xy 234.497521 -147.351216) (xy 234.552364 -147.341086) (xy 234.608098 -147.339049) (xy 234.663535 -147.345149)
			(xy 234.717492 -147.359255) (xy 234.768821 -147.381067) (xy 234.816427 -147.410121) (xy 234.859295 -147.445796)
			(xy 234.896512 -147.487333) (xy 234.927285 -147.533846) (xy 234.950957 -147.584343) (xy 234.967025 -147.63775)
			(xy 234.975145 -147.692926) (xy 234.975654 -147.720812) (xy 234.975145 -147.748698) (xy 234.967025 -147.803874)
			(xy 234.950957 -147.857281) (xy 234.927285 -147.907778) (xy 234.896512 -147.954291) (xy 234.859295 -147.995828)
			(xy 234.816427 -148.031503) (xy 234.768821 -148.060557) (xy 234.717492 -148.082369) (xy 234.663535 -148.096475)
			(xy 234.608098 -148.102575) (xy 234.552364 -148.100538) (xy 234.497521 -148.090408) (xy 234.444737 -148.072401)
			(xy 234.395137 -148.0469) (xy 234.349779 -148.014449) (xy 234.30963 -147.97574) (xy 234.275544 -147.931597)
			(xy 234.248248 -147.882962) (xy 234.228325 -147.830871) (xy 234.216199 -147.776434) (xy 234.212128 -147.720812)
			(xy 225.955352 -147.720812) (xy 225.955352 -149.44852) (xy 225.955753 -149.458592) (xy 225.963489 -149.477191)
			(xy 225.970338 -149.484588) (xy 226.683824 -150.198074) (xy 226.691225 -150.204913) (xy 226.709823 -150.212634)
			(xy 226.719892 -150.21306) (xy 230.210868 -150.21306) (xy 230.215759 -150.213196) (xy 230.225351 -150.215115)
			(xy 230.229918 -150.21687) (xy 230.325676 -150.255732) (xy 230.3305 -150.257825) (xy 230.33921 -150.263717)
			(xy 230.342948 -150.267416) (xy 230.378254 -150.303992) (xy 230.378762 -150.3045) (xy 230.439976 -150.36546)
			(xy 230.456575 -150.382751) (xy 230.484741 -150.421532) (xy 230.506508 -150.464234) (xy 230.521345 -150.509809)
			(xy 230.528886 -150.557142) (xy 230.529384 -150.581106) (xy 230.529384 -152.076404) (xy 230.958388 -152.076404)
			(xy 230.962459 -152.020782) (xy 230.974585 -151.966345) (xy 230.994508 -151.914254) (xy 231.021804 -151.865619)
			(xy 231.05589 -151.821476) (xy 231.096039 -151.782767) (xy 231.141397 -151.750316) (xy 231.190997 -151.724815)
			(xy 231.243781 -151.706808) (xy 231.298624 -151.696678) (xy 231.354358 -151.694641) (xy 231.409795 -151.700741)
			(xy 231.463752 -151.714847) (xy 231.515081 -151.736659) (xy 231.562687 -151.765713) (xy 231.605555 -151.801388)
			(xy 231.642772 -151.842925) (xy 231.673545 -151.889438) (xy 231.697217 -151.939935) (xy 231.713285 -151.993342)
			(xy 231.721405 -152.048518) (xy 231.721914 -152.076404) (xy 231.721405 -152.10429) (xy 231.713285 -152.159466)
			(xy 231.697217 -152.212873) (xy 231.673545 -152.26337) (xy 231.642772 -152.309883) (xy 231.605555 -152.35142)
			(xy 231.562687 -152.387095) (xy 231.515081 -152.416149) (xy 231.463752 -152.437961) (xy 231.409795 -152.452067)
			(xy 231.354358 -152.458167) (xy 231.298624 -152.45613) (xy 231.243781 -152.446) (xy 231.190997 -152.427993)
			(xy 231.141397 -152.402492) (xy 231.096039 -152.370041) (xy 231.05589 -152.331332) (xy 231.021804 -152.287189)
			(xy 230.994508 -152.238554) (xy 230.974585 -152.186463) (xy 230.962459 -152.132026) (xy 230.958388 -152.076404)
			(xy 230.529384 -152.076404) (xy 230.529384 -152.603962) (xy 230.528932 -152.627934) (xy 230.521439 -152.675288)
			(xy 230.506618 -152.720882) (xy 230.484835 -152.763591) (xy 230.456627 -152.802357) (xy 230.439976 -152.819608)
			(xy 230.172514 -153.08707) (xy 230.155208 -153.103707) (xy 230.116403 -153.131962) (xy 230.073655 -153.153798)
			(xy 230.028018 -153.168678) (xy 229.980614 -153.176236) (xy 229.956614 -153.176732) (xy 224.56902 -153.176732)
			(xy 224.545016 -153.176261) (xy 224.497603 -153.168717) (xy 224.451956 -153.153844) (xy 224.4092 -153.132008)
			(xy 224.37039 -153.103748) (xy 224.35312 -153.08707) (xy 222.263462 -150.997412) (xy 222.246811 -150.980118)
			(xy 222.218552 -150.941311) (xy 222.196712 -150.898561) (xy 222.18183 -150.852921) (xy 222.174271 -150.805514)
			(xy 222.1738 -150.781512) (xy 222.1738 -147.35937) (xy 222.159068 -147.33524) (xy 222.146622 -147.328636)
			(xy 222.12229 -147.315393) (xy 222.077462 -147.282842) (xy 222.03781 -147.244154) (xy 222.004166 -147.200141)
			(xy 221.977237 -147.151727) (xy 221.957588 -147.09993) (xy 221.945633 -147.045836) (xy 221.941621 -146.990582)
			(xy 213.828376 -146.990582) (xy 213.828376 -149.054312) (xy 219.859604 -149.054312) (xy 219.863675 -148.99869)
			(xy 219.875801 -148.944253) (xy 219.895724 -148.892162) (xy 219.92302 -148.843527) (xy 219.957106 -148.799384)
			(xy 219.997255 -148.760675) (xy 220.042613 -148.728224) (xy 220.092213 -148.702723) (xy 220.144997 -148.684716)
			(xy 220.19984 -148.674586) (xy 220.255574 -148.672549) (xy 220.311011 -148.678649) (xy 220.364968 -148.692755)
			(xy 220.416297 -148.714567) (xy 220.463903 -148.743621) (xy 220.506771 -148.779296) (xy 220.543988 -148.820833)
			(xy 220.574761 -148.867346) (xy 220.598433 -148.917843) (xy 220.614501 -148.97125) (xy 220.622621 -149.026426)
			(xy 220.62313 -149.054312) (xy 220.622621 -149.082198) (xy 220.614501 -149.137374) (xy 220.598433 -149.190781)
			(xy 220.574761 -149.241278) (xy 220.543988 -149.287791) (xy 220.506771 -149.329328) (xy 220.463903 -149.365003)
			(xy 220.416297 -149.394057) (xy 220.364968 -149.415869) (xy 220.311011 -149.429975) (xy 220.255574 -149.436075)
			(xy 220.19984 -149.434038) (xy 220.144997 -149.423908) (xy 220.092213 -149.405901) (xy 220.042613 -149.3804)
			(xy 219.997255 -149.347949) (xy 219.957106 -149.30924) (xy 219.92302 -149.265097) (xy 219.895724 -149.216462)
			(xy 219.875801 -149.164371) (xy 219.863675 -149.109934) (xy 219.859604 -149.054312) (xy 213.828376 -149.054312)
			(xy 213.828376 -153.675842) (xy 222.211136 -153.675842) (xy 222.215207 -153.62022) (xy 222.227333 -153.565783)
			(xy 222.247256 -153.513692) (xy 222.274552 -153.465057) (xy 222.308638 -153.420914) (xy 222.348787 -153.382205)
			(xy 222.394145 -153.349754) (xy 222.443745 -153.324253) (xy 222.496529 -153.306246) (xy 222.551372 -153.296116)
			(xy 222.607106 -153.294079) (xy 222.662543 -153.300179) (xy 222.7165 -153.314285) (xy 222.767829 -153.336097)
			(xy 222.815435 -153.365151) (xy 222.858303 -153.400826) (xy 222.89552 -153.442363) (xy 222.926293 -153.488876)
			(xy 222.949965 -153.539373) (xy 222.966033 -153.59278) (xy 222.974153 -153.647956) (xy 222.974662 -153.675842)
			(xy 222.974153 -153.703728) (xy 222.966033 -153.758904) (xy 222.949965 -153.812311) (xy 222.926293 -153.862808)
			(xy 222.89552 -153.909321) (xy 222.858303 -153.950858) (xy 222.815435 -153.986533) (xy 222.767829 -154.015587)
			(xy 222.7165 -154.037399) (xy 222.662543 -154.051505) (xy 222.607106 -154.057605) (xy 222.551372 -154.055568)
			(xy 222.496529 -154.045438) (xy 222.443745 -154.027431) (xy 222.394145 -154.00193) (xy 222.348787 -153.969479)
			(xy 222.308638 -153.93077) (xy 222.274552 -153.886627) (xy 222.247256 -153.837992) (xy 222.227333 -153.785901)
			(xy 222.215207 -153.731464) (xy 222.211136 -153.675842) (xy 213.828376 -153.675842) (xy 213.828376 -154.564842)
			(xy 222.211136 -154.564842) (xy 222.215207 -154.50922) (xy 222.227333 -154.454783) (xy 222.247256 -154.402692)
			(xy 222.274552 -154.354057) (xy 222.308638 -154.309914) (xy 222.348787 -154.271205) (xy 222.394145 -154.238754)
			(xy 222.443745 -154.213253) (xy 222.496529 -154.195246) (xy 222.551372 -154.185116) (xy 222.607106 -154.183079)
			(xy 222.662543 -154.189179) (xy 222.7165 -154.203285) (xy 222.767829 -154.225097) (xy 222.815435 -154.254151)
			(xy 222.858303 -154.289826) (xy 222.89552 -154.331363) (xy 222.926293 -154.377876) (xy 222.949965 -154.428373)
			(xy 222.966033 -154.48178) (xy 222.974153 -154.536956) (xy 222.974662 -154.564842) (xy 222.974153 -154.592728)
			(xy 222.966033 -154.647904) (xy 222.949965 -154.701311) (xy 222.926293 -154.751808) (xy 222.89552 -154.798321)
			(xy 222.858303 -154.839858) (xy 222.830755 -154.862784) (xy 227.185474 -154.862784) (xy 227.185978 -154.835875)
			(xy 227.193556 -154.782593) (xy 227.208545 -154.730905) (xy 227.230648 -154.681835) (xy 227.259426 -154.636357)
			(xy 227.294309 -154.595375) (xy 227.334604 -154.5597) (xy 227.379512 -154.530041) (xy 227.428142 -154.506985)
			(xy 227.453698 -154.498548) (xy 227.453952 -154.498548) (xy 227.459646 -154.496572) (xy 227.469921 -154.490273)
			(xy 227.474272 -154.486102) (xy 228.087936 -153.872438) (xy 228.106704 -153.854311) (xy 228.148905 -153.823629)
			(xy 228.195389 -153.799931) (xy 228.24501 -153.783802) (xy 228.296544 -153.77564) (xy 228.322632 -153.775156)
			(xy 230.921306 -153.775156) (xy 230.931377 -153.774745) (xy 230.949976 -153.767016) (xy 230.957374 -153.76017)
			(xy 231.808782 -152.909016) (xy 231.815605 -152.901602) (xy 231.823335 -152.883014) (xy 231.823768 -152.872948)
			(xy 231.823768 -151.86533) (xy 231.823565 -151.859181) (xy 231.820618 -151.84724) (xy 231.817926 -151.841708)
			(xy 231.804091 -151.814181) (xy 231.784526 -151.755764) (xy 231.774593 -151.694965) (xy 231.773984 -151.664162)
			(xy 231.774442 -151.63691) (xy 231.782204 -151.582962) (xy 231.797563 -151.530667) (xy 231.820208 -151.48109)
			(xy 231.849678 -151.43524) (xy 231.885372 -151.394051) (xy 231.926565 -151.35836) (xy 231.972417 -151.328894)
			(xy 232.021995 -151.306253) (xy 232.074291 -151.290898) (xy 232.12824 -151.28314) (xy 232.155492 -151.282654)
			(xy 232.186295 -151.283267) (xy 232.247096 -151.29319) (xy 232.30551 -151.312763) (xy 232.333038 -151.326596)
			(xy 232.333546 -151.32685) (xy 232.338866 -151.329327) (xy 232.350286 -151.33202) (xy 232.356152 -151.332184)
			(xy 232.675684 -151.332184) (xy 232.685753 -151.331754) (xy 232.704351 -151.324037) (xy 232.711752 -151.317198)
			(xy 233.642154 -150.386796) (xy 233.648982 -150.379386) (xy 233.65671 -150.360795) (xy 233.65714 -150.350728)
			(xy 233.65714 -149.855428) (xy 233.6546 -149.844252) (xy 233.651806 -149.838918) (xy 233.651298 -149.837902)
			(xy 233.637649 -149.810566) (xy 233.61825 -149.75263) (xy 233.61269 -149.722586) (xy 233.611166 -149.71268)
			(xy 233.600752 -149.695916) (xy 233.535474 -149.64791) (xy 233.527334 -149.642476) (xy 233.508391 -149.637632)
			(xy 233.498644 -149.638512) (xy 233.49839 -149.638512) (xy 233.4855 -149.640167) (xy 233.45957 -149.641948)
			(xy 233.446574 -149.642068) (xy 233.44632 -149.642068) (xy 233.419063 -149.641686) (xy 233.365105 -149.633931)
			(xy 233.312799 -149.618575) (xy 233.263211 -149.595931) (xy 233.21735 -149.566461) (xy 233.176151 -149.530763)
			(xy 233.140451 -149.489566) (xy 233.110978 -149.443707) (xy 233.088332 -149.39412) (xy 233.072973 -149.341815)
			(xy 233.065215 -149.287857) (xy 233.065215 -149.233343) (xy 233.072973 -149.179385) (xy 233.088332 -149.12708)
			(xy 233.110978 -149.077493) (xy 233.140451 -149.031634) (xy 233.176151 -148.990437) (xy 233.21735 -148.954739)
			(xy 233.263211 -148.925269) (xy 233.312799 -148.902625) (xy 233.365105 -148.887269) (xy 233.419063 -148.879514)
			(xy 233.44632 -148.879052) (xy 233.473193 -148.879488) (xy 233.526406 -148.887047) (xy 233.578032 -148.901998)
			(xy 233.627049 -148.924046) (xy 233.672487 -148.952753) (xy 233.713447 -148.987553) (xy 233.749118 -149.027757)
			(xy 233.778795 -149.072568) (xy 233.80189 -149.1211) (xy 233.817946 -149.172393) (xy 233.822748 -149.198838)
			(xy 233.824272 -149.208744) (xy 233.834686 -149.225508) (xy 233.899964 -149.273514) (xy 233.908092 -149.278969)
			(xy 233.927045 -149.283799) (xy 233.936794 -149.282912) (xy 233.937048 -149.282912) (xy 233.949938 -149.281253)
			(xy 233.975868 -149.279475) (xy 233.988864 -149.279356) (xy 233.989118 -149.279356) (xy 234.016368 -149.279861)
			(xy 234.070313 -149.287619) (xy 234.122605 -149.302975) (xy 234.17218 -149.325615) (xy 234.218029 -149.35508)
			(xy 234.259218 -149.390769) (xy 234.294909 -149.431957) (xy 234.324376 -149.477804) (xy 234.347019 -149.527378)
			(xy 234.362377 -149.579669) (xy 234.370138 -149.633614) (xy 234.370626 -149.660864) (xy 234.370032 -149.691667)
			(xy 234.3601 -149.752469) (xy 234.34052 -149.810882) (xy 234.326684 -149.83841) (xy 234.32643 -149.838918)
			(xy 234.323954 -149.844239) (xy 234.321251 -149.855657) (xy 234.321096 -149.861524) (xy 234.321096 -150.509224)
			(xy 234.320577 -150.53531) (xy 234.31242 -150.586841) (xy 234.296296 -150.636458) (xy 234.272603 -150.68294)
			(xy 234.241924 -150.725139) (xy 234.223814 -150.74392) (xy 233.068876 -151.898858) (xy 233.050102 -151.916978)
			(xy 233.007903 -151.947662) (xy 232.96142 -151.971361) (xy 232.911801 -151.987491) (xy 232.860268 -151.995655)
			(xy 232.83418 -151.99614) (xy 232.538016 -151.99614) (xy 232.527991 -151.996533) (xy 232.509466 -152.004206)
			(xy 232.495292 -152.018387) (xy 232.487629 -152.036915) (xy 232.487216 -152.04694) (xy 232.487216 -153.031952)
			(xy 232.486696 -153.057976) (xy 232.478528 -153.10938) (xy 232.462432 -153.158877) (xy 232.438803 -153.205253)
			(xy 232.408221 -153.247369) (xy 232.390188 -153.26614) (xy 231.314498 -154.34183) (xy 231.295727 -154.359952)
			(xy 231.253525 -154.390632) (xy 231.207041 -154.41433) (xy 231.157422 -154.43046) (xy 231.10589 -154.438626)
			(xy 231.079802 -154.439112) (xy 228.481128 -154.439112) (xy 228.47106 -154.439549) (xy 228.452462 -154.447261)
			(xy 228.44506 -154.454098) (xy 227.943664 -154.955494) (xy 227.939553 -154.959891) (xy 227.933265 -154.970153)
			(xy 227.931218 -154.975814) (xy 227.931218 -154.976322) (xy 227.922765 -155.001865) (xy 227.899698 -155.05047)
			(xy 227.87003 -155.095353) (xy 227.83435 -155.135622) (xy 227.793367 -155.170478) (xy 227.747893 -155.199231)
			(xy 227.69883 -155.221309) (xy 227.647151 -155.236275) (xy 227.593883 -155.243832) (xy 227.566982 -155.244292)
			(xy 227.53973 -155.243839) (xy 227.48578 -155.23608) (xy 227.433484 -155.220721) (xy 227.383905 -155.198077)
			(xy 227.338054 -155.168607) (xy 227.296864 -155.132912) (xy 227.261172 -155.091719) (xy 227.231707 -155.045865)
			(xy 227.209067 -154.996285) (xy 227.193713 -154.943987) (xy 227.185959 -154.890036) (xy 227.185474 -154.862784)
			(xy 222.830755 -154.862784) (xy 222.815435 -154.875533) (xy 222.767829 -154.904587) (xy 222.7165 -154.926399)
			(xy 222.662543 -154.940505) (xy 222.607106 -154.946605) (xy 222.551372 -154.944568) (xy 222.496529 -154.934438)
			(xy 222.443745 -154.916431) (xy 222.394145 -154.89093) (xy 222.348787 -154.858479) (xy 222.308638 -154.81977)
			(xy 222.274552 -154.775627) (xy 222.247256 -154.726992) (xy 222.227333 -154.674901) (xy 222.215207 -154.620464)
			(xy 222.211136 -154.564842) (xy 213.828376 -154.564842) (xy 213.828376 -157.008322) (xy 226.168964 -157.008322)
			(xy 226.173035 -156.9527) (xy 226.185161 -156.898263) (xy 226.205084 -156.846172) (xy 226.23238 -156.797537)
			(xy 226.266466 -156.753394) (xy 226.306615 -156.714685) (xy 226.351973 -156.682234) (xy 226.401573 -156.656733)
			(xy 226.454357 -156.638726) (xy 226.5092 -156.628596) (xy 226.564934 -156.626559) (xy 226.620371 -156.632659)
			(xy 226.674328 -156.646765) (xy 226.725657 -156.668577) (xy 226.773263 -156.697631) (xy 226.816131 -156.733306)
			(xy 226.853348 -156.774843) (xy 226.884121 -156.821356) (xy 226.907793 -156.871853) (xy 226.923861 -156.92526)
			(xy 226.931981 -156.980436) (xy 226.93249 -157.008322) (xy 226.931981 -157.036208) (xy 226.923861 -157.091384)
			(xy 226.907793 -157.144791) (xy 226.884121 -157.195288) (xy 226.853348 -157.241801) (xy 226.816131 -157.283338)
			(xy 226.773263 -157.319013) (xy 226.725657 -157.348067) (xy 226.674328 -157.369879) (xy 226.620371 -157.383985)
			(xy 226.564934 -157.390085) (xy 226.5092 -157.388048) (xy 226.454357 -157.377918) (xy 226.401573 -157.359911)
			(xy 226.351973 -157.33441) (xy 226.306615 -157.301959) (xy 226.266466 -157.26325) (xy 226.23238 -157.219107)
			(xy 226.205084 -157.170472) (xy 226.185161 -157.118381) (xy 226.173035 -157.063944) (xy 226.168964 -157.008322)
			(xy 213.828376 -157.008322) (xy 213.828376 -157.900066) (xy 228.314505 -157.900066) (xy 228.314505 -157.840134)
			(xy 228.322328 -157.780714) (xy 228.33784 -157.722823) (xy 228.360775 -157.667453) (xy 228.390741 -157.61555)
			(xy 228.427226 -157.568002) (xy 228.469605 -157.525624) (xy 228.517153 -157.489139) (xy 228.569056 -157.459173)
			(xy 228.624427 -157.436238) (xy 228.682318 -157.420727) (xy 228.741738 -157.412905) (xy 228.771704 -157.412436)
			(xy 229.635304 -157.412436) (xy 229.665274 -157.412838) (xy 229.724702 -157.420663) (xy 229.7826 -157.436177)
			(xy 229.837978 -157.459116) (xy 229.889888 -157.489086) (xy 229.937442 -157.525576) (xy 229.979827 -157.567961)
			(xy 230.016316 -157.615515) (xy 230.046286 -157.667425) (xy 230.069224 -157.722803) (xy 230.084738 -157.780702)
			(xy 230.092562 -157.84013) (xy 230.092562 -157.90007) (xy 230.089876 -157.920473) (xy 230.557725 -157.920473)
			(xy 230.557725 -157.860527) (xy 230.56555 -157.801095) (xy 230.581066 -157.743192) (xy 230.604007 -157.68781)
			(xy 230.633981 -157.635897) (xy 230.670475 -157.58834) (xy 230.712864 -157.545953) (xy 230.760423 -157.509463)
			(xy 230.812339 -157.479493) (xy 230.867722 -157.456555) (xy 230.925626 -157.441044) (xy 230.985059 -157.433223)
			(xy 231.015032 -157.432756) (xy 231.878632 -157.432756) (xy 231.908596 -157.43332) (xy 231.968011 -157.441146)
			(xy 232.025896 -157.45666) (xy 232.081261 -157.479596) (xy 232.133158 -157.509563) (xy 232.180701 -157.546046)
			(xy 232.223075 -157.588423) (xy 232.259555 -157.635968) (xy 232.289518 -157.687868) (xy 232.31245 -157.743235)
			(xy 232.32796 -157.801121) (xy 232.335782 -157.860536) (xy 232.335782 -157.920464) (xy 232.32796 -157.979879)
			(xy 232.31245 -158.037765) (xy 232.289518 -158.093132) (xy 232.259555 -158.145032) (xy 232.223075 -158.192577)
			(xy 232.180701 -158.234954) (xy 232.133158 -158.271437) (xy 232.081261 -158.301404) (xy 232.025896 -158.32434)
			(xy 231.968011 -158.339854) (xy 231.908596 -158.34768) (xy 231.878632 -158.348172) (xy 231.015032 -158.348172)
			(xy 230.985059 -158.347777) (xy 230.925626 -158.339956) (xy 230.867722 -158.324445) (xy 230.812339 -158.301507)
			(xy 230.760423 -158.271537) (xy 230.712864 -158.235047) (xy 230.670475 -158.19266) (xy 230.633981 -158.145103)
			(xy 230.604007 -158.09319) (xy 230.581066 -158.037808) (xy 230.56555 -157.979905) (xy 230.557725 -157.920473)
			(xy 230.089876 -157.920473) (xy 230.084738 -157.959498) (xy 230.069224 -158.017397) (xy 230.046286 -158.072775)
			(xy 230.016316 -158.124685) (xy 229.979827 -158.172239) (xy 229.937442 -158.214624) (xy 229.889888 -158.251114)
			(xy 229.837978 -158.281084) (xy 229.7826 -158.304023) (xy 229.724702 -158.319537) (xy 229.665274 -158.327362)
			(xy 229.635304 -158.327852) (xy 228.771704 -158.327852) (xy 228.741738 -158.327295) (xy 228.682318 -158.319473)
			(xy 228.624427 -158.303962) (xy 228.569056 -158.281027) (xy 228.517153 -158.251061) (xy 228.469605 -158.214576)
			(xy 228.427226 -158.172198) (xy 228.390741 -158.12465) (xy 228.360775 -158.072747) (xy 228.33784 -158.017377)
			(xy 228.322328 -157.959486) (xy 228.314505 -157.900066) (xy 213.828376 -157.900066) (xy 213.828376 -159.492696)
			(xy 213.829392 -159.502348) (xy 213.831018 -159.509593) (xy 213.837855 -159.522767) (xy 213.842854 -159.528256)
			(xy 215.69045 -161.375852) (xy 215.699065 -161.383978) (xy 215.719206 -161.396422) (xy 215.730328 -161.40049)
			(xy 215.734223 -161.401668) (xy 215.742261 -161.402941) (xy 215.74633 -161.40303) (xy 215.785192 -161.40303)
			(xy 215.796876 -161.399728) (xy 215.796876 -160.502346) (xy 215.797334 -160.469491) (xy 215.804685 -160.404194)
			(xy 215.819301 -160.340131) (xy 215.840998 -160.278107) (xy 215.869502 -160.218902) (xy 215.904455 -160.16326)
			(xy 215.945419 -160.111882) (xy 215.968326 -160.088326) (xy 216.335864 -159.720788) (xy 216.359419 -159.697843)
			(xy 216.410819 -159.656826) (xy 216.466491 -159.621825) (xy 216.525733 -159.593281) (xy 216.5878 -159.571553)
			(xy 216.651911 -159.556916) (xy 216.717258 -159.549553) (xy 216.750138 -159.549084) (xy 216.913206 -159.549084)
			(xy 216.948619 -159.549619) (xy 217.01893 -159.558156) (xy 217.087699 -159.575106) (xy 217.153923 -159.600221)
			(xy 217.216637 -159.633135) (xy 217.274927 -159.673369) (xy 217.327943 -159.720334) (xy 217.374912 -159.773347)
			(xy 217.415148 -159.831635) (xy 217.448065 -159.894348) (xy 217.473184 -159.960571) (xy 217.475768 -159.971051)
			(xy 232.232178 -159.971051) (xy 232.232178 -159.916549) (xy 232.239934 -159.862601) (xy 232.255289 -159.810306)
			(xy 232.277931 -159.760729) (xy 232.307397 -159.714879) (xy 232.343088 -159.673688) (xy 232.384279 -159.637997)
			(xy 232.430129 -159.608531) (xy 232.479706 -159.585889) (xy 232.532001 -159.570534) (xy 232.585949 -159.562778)
			(xy 232.6132 -159.562292) (xy 232.64057 -159.56276) (xy 232.694749 -159.570578) (xy 232.747252 -159.586066)
			(xy 232.796999 -159.608908) (xy 232.842966 -159.638631) (xy 232.863898 -159.656272) (xy 232.864152 -159.656526)
			(xy 232.871246 -159.662102) (xy 232.888157 -159.668354) (xy 232.897172 -159.668718) (xy 232.964228 -159.668718)
			(xy 232.973246 -159.668371) (xy 232.990163 -159.662116) (xy 232.997248 -159.656526) (xy 232.997248 -159.656272)
			(xy 232.997502 -159.656272) (xy 233.018419 -159.638614) (xy 233.064396 -159.608906) (xy 233.114148 -159.586074)
			(xy 233.166652 -159.570587) (xy 233.22083 -159.562764) (xy 233.2482 -159.562292) (xy 233.275451 -159.562778)
			(xy 233.329399 -159.570534) (xy 233.381694 -159.585889) (xy 233.431271 -159.608531) (xy 233.477121 -159.637997)
			(xy 233.518312 -159.673688) (xy 233.554003 -159.714879) (xy 233.583469 -159.760729) (xy 233.606111 -159.810306)
			(xy 233.621466 -159.862601) (xy 233.629222 -159.916549) (xy 233.629222 -159.971051) (xy 233.621466 -160.024999)
			(xy 233.606111 -160.077294) (xy 233.583469 -160.126871) (xy 233.554003 -160.172721) (xy 233.518312 -160.213912)
			(xy 233.477121 -160.249603) (xy 233.431271 -160.279069) (xy 233.381694 -160.301711) (xy 233.329399 -160.317066)
			(xy 233.275451 -160.324822) (xy 233.2482 -160.325308) (xy 233.22083 -160.32484) (xy 233.166651 -160.317022)
			(xy 233.114148 -160.301534) (xy 233.064401 -160.278692) (xy 233.018434 -160.248969) (xy 232.997502 -160.231328)
			(xy 232.997248 -160.231074) (xy 232.990154 -160.225498) (xy 232.973243 -160.219246) (xy 232.964228 -160.218882)
			(xy 232.897172 -160.218882) (xy 232.888154 -160.219229) (xy 232.871237 -160.225484) (xy 232.864152 -160.231074)
			(xy 232.864152 -160.231328) (xy 232.863898 -160.231328) (xy 232.842981 -160.248986) (xy 232.797004 -160.278694)
			(xy 232.747252 -160.301526) (xy 232.694748 -160.317013) (xy 232.64057 -160.324836) (xy 232.6132 -160.325308)
			(xy 232.585949 -160.324822) (xy 232.532001 -160.317066) (xy 232.479706 -160.301711) (xy 232.430129 -160.279069)
			(xy 232.384279 -160.249603) (xy 232.343088 -160.213912) (xy 232.307397 -160.172721) (xy 232.277931 -160.126871)
			(xy 232.255289 -160.077294) (xy 232.239934 -160.024999) (xy 232.232178 -159.971051) (xy 217.475768 -159.971051)
			(xy 217.490138 -160.029339) (xy 217.498679 -160.099649) (xy 217.499184 -160.135062) (xy 217.49853 -160.173307)
			(xy 217.488517 -160.249139) (xy 217.468733 -160.323027) (xy 217.439514 -160.393718) (xy 217.420952 -160.427162)
			(xy 217.416786 -160.435036) (xy 217.413681 -160.452567) (xy 217.416764 -160.470101) (xy 217.420952 -160.477962)
			(xy 217.439514 -160.511408) (xy 217.468757 -160.58209) (xy 217.488544 -160.655979) (xy 217.490156 -160.668208)
			(xy 222.918272 -160.668208) (xy 222.922343 -160.612586) (xy 222.934469 -160.558149) (xy 222.954392 -160.506058)
			(xy 222.981688 -160.457423) (xy 223.015774 -160.41328) (xy 223.055923 -160.374571) (xy 223.101281 -160.34212)
			(xy 223.150881 -160.316619) (xy 223.203665 -160.298612) (xy 223.258508 -160.288482) (xy 223.314242 -160.286445)
			(xy 223.369679 -160.292545) (xy 223.423636 -160.306651) (xy 223.474965 -160.328463) (xy 223.522571 -160.357517)
			(xy 223.565439 -160.393192) (xy 223.602656 -160.434729) (xy 223.633429 -160.481242) (xy 223.657101 -160.531739)
			(xy 223.673169 -160.585146) (xy 223.681289 -160.640322) (xy 223.681798 -160.668208) (xy 223.681289 -160.696094)
			(xy 223.673169 -160.75127) (xy 223.657101 -160.804677) (xy 223.633429 -160.855174) (xy 223.602656 -160.901687)
			(xy 223.565439 -160.943224) (xy 223.522571 -160.978899) (xy 223.474965 -161.007953) (xy 223.423636 -161.029765)
			(xy 223.369679 -161.043871) (xy 223.314242 -161.049971) (xy 223.258508 -161.047934) (xy 223.203665 -161.037804)
			(xy 223.150881 -161.019797) (xy 223.101281 -160.994296) (xy 223.055923 -160.961845) (xy 223.015774 -160.923136)
			(xy 222.981688 -160.878993) (xy 222.954392 -160.830358) (xy 222.934469 -160.778267) (xy 222.922343 -160.72383)
			(xy 222.918272 -160.668208) (xy 217.490156 -160.668208) (xy 217.498539 -160.731816) (xy 217.499184 -160.770062)
			(xy 217.499184 -161.253932) (xy 217.499612 -161.264) (xy 217.507333 -161.282598) (xy 217.51417 -161.29)
			(xy 218.411806 -162.18789) (xy 218.419205 -162.194736) (xy 218.437802 -162.20247) (xy 218.447874 -162.202876)
			(xy 219.204794 -162.202876) (xy 219.237648 -162.203336) (xy 219.302943 -162.210692) (xy 219.367003 -162.225311)
			(xy 219.429025 -162.247011) (xy 219.488226 -162.275518) (xy 219.543865 -162.310473) (xy 219.59524 -162.351438)
			(xy 219.618814 -162.374326) (xy 220.35008 -163.105846) (xy 220.35748 -163.112686) (xy 220.376079 -163.1204)
			(xy 220.386148 -163.120832)
		)
		(stroke
			(width 0)
			(type solid)
		)
		(fill yes)
		(layer "In5.Cu")
		(net "GND")
	)
	(gr_poly
		(pts
			(xy 50.245772 -304.283872) (xy 50.254565 -304.283507) (xy 50.271115 -304.277562) (xy 50.284674 -304.266364)
			(xy 50.28946 -304.25898) (xy 50.341022 -304.172366) (xy 50.34153 -304.145442) (xy 50.334926 -304.133504)
			(xy 50.322148 -304.109015) (xy 50.304037 -304.056835) (xy 50.294849 -304.002371) (xy 50.294286 -303.974754)
			(xy 50.294796 -303.948767) (xy 50.302926 -303.897432) (xy 50.318987 -303.848002) (xy 50.342583 -303.801692)
			(xy 50.373133 -303.759644) (xy 50.409884 -303.722893) (xy 50.451932 -303.692343) (xy 50.498242 -303.668747)
			(xy 50.547672 -303.652686) (xy 50.599007 -303.644556) (xy 50.650981 -303.644556) (xy 50.702316 -303.652686)
			(xy 50.751746 -303.668747) (xy 50.798056 -303.692343) (xy 50.840104 -303.722893) (xy 50.876855 -303.759644)
			(xy 50.907405 -303.801692) (xy 50.931001 -303.848002) (xy 50.947062 -303.897432) (xy 50.955192 -303.948767)
			(xy 50.955702 -303.974754) (xy 50.955148 -304.002372) (xy 50.945968 -304.05684) (xy 50.927855 -304.109021)
			(xy 50.915062 -304.133504) (xy 50.908458 -304.145442) (xy 50.908966 -304.172366) (xy 50.960528 -304.25898)
			(xy 50.965327 -304.266354) (xy 50.978881 -304.277551) (xy 50.995426 -304.283498) (xy 51.004216 -304.283872)
			(xy 51.195732 -304.283872) (xy 51.20452 -304.283498) (xy 51.221054 -304.277539) (xy 51.234597 -304.266337)
			(xy 51.23942 -304.25898) (xy 51.290982 -304.172366) (xy 51.29149 -304.145442) (xy 51.284886 -304.133504)
			(xy 51.272106 -304.109015) (xy 51.253992 -304.056836) (xy 51.244802 -304.002371) (xy 51.244246 -303.974754)
			(xy 51.244756 -303.948767) (xy 51.252886 -303.897432) (xy 51.268947 -303.848002) (xy 51.292543 -303.801692)
			(xy 51.323093 -303.759644) (xy 51.359844 -303.722893) (xy 51.401892 -303.692343) (xy 51.448202 -303.668747)
			(xy 51.497632 -303.652686) (xy 51.548967 -303.644556) (xy 51.600941 -303.644556) (xy 51.652276 -303.652686)
			(xy 51.701706 -303.668747) (xy 51.748016 -303.692343) (xy 51.790064 -303.722893) (xy 51.826815 -303.759644)
			(xy 51.857365 -303.801692) (xy 51.880961 -303.848002) (xy 51.897022 -303.897432) (xy 51.905152 -303.948767)
			(xy 51.905662 -303.974754) (xy 51.905108 -304.002372) (xy 51.895927 -304.056839) (xy 51.877812 -304.10902)
			(xy 51.865022 -304.133504) (xy 51.858418 -304.145442) (xy 51.858926 -304.172366) (xy 51.910488 -304.25898)
			(xy 51.915285 -304.266358) (xy 51.928837 -304.277566) (xy 51.945383 -304.283526) (xy 51.954176 -304.283872)
			(xy 52.145692 -304.283872) (xy 52.154483 -304.283504) (xy 52.171028 -304.277554) (xy 52.184582 -304.266355)
			(xy 52.18938 -304.25898) (xy 52.240942 -304.172366) (xy 52.24145 -304.145442) (xy 52.234846 -304.133504)
			(xy 52.222068 -304.109015) (xy 52.203955 -304.056835) (xy 52.194767 -304.002371) (xy 52.194206 -303.974754)
			(xy 52.194716 -303.948767) (xy 52.202846 -303.897432) (xy 52.218907 -303.848002) (xy 52.242503 -303.801692)
			(xy 52.273053 -303.759644) (xy 52.309804 -303.722893) (xy 52.351852 -303.692343) (xy 52.398162 -303.668747)
			(xy 52.447592 -303.652686) (xy 52.498927 -303.644556) (xy 52.550901 -303.644556) (xy 52.602236 -303.652686)
			(xy 52.651666 -303.668747) (xy 52.697976 -303.692343) (xy 52.740024 -303.722893) (xy 52.776775 -303.759644)
			(xy 52.807325 -303.801692) (xy 52.830921 -303.848002) (xy 52.846982 -303.897432) (xy 52.855112 -303.948767)
			(xy 52.855622 -303.974754) (xy 52.855068 -304.002372) (xy 52.845888 -304.05684) (xy 52.827776 -304.109022)
			(xy 52.814982 -304.133504) (xy 52.808378 -304.145442) (xy 52.808886 -304.172366) (xy 52.860448 -304.25898)
			(xy 52.865243 -304.266363) (xy 52.878794 -304.277581) (xy 52.895341 -304.283553) (xy 52.904136 -304.283872)
			(xy 53.095652 -304.283872) (xy 53.104447 -304.28351) (xy 53.121001 -304.27757) (xy 53.134566 -304.266373)
			(xy 53.13934 -304.25898) (xy 53.190902 -304.172366) (xy 53.19141 -304.145442) (xy 53.184806 -304.133504)
			(xy 53.172029 -304.109014) (xy 53.153919 -304.056834) (xy 53.144732 -304.002371) (xy 53.144166 -303.974754)
			(xy 53.144676 -303.948767) (xy 53.152806 -303.897432) (xy 53.168867 -303.848002) (xy 53.192463 -303.801692)
			(xy 53.223013 -303.759644) (xy 53.259764 -303.722893) (xy 53.301812 -303.692343) (xy 53.348122 -303.668747)
			(xy 53.397552 -303.652686) (xy 53.448887 -303.644556) (xy 53.500861 -303.644556) (xy 53.552196 -303.652686)
			(xy 53.601626 -303.668747) (xy 53.647936 -303.692343) (xy 53.689984 -303.722893) (xy 53.726735 -303.759644)
			(xy 53.757285 -303.801692) (xy 53.780881 -303.848002) (xy 53.796942 -303.897432) (xy 53.805072 -303.948767)
			(xy 53.805582 -303.974754) (xy 53.805028 -304.002372) (xy 53.795847 -304.056839) (xy 53.777733 -304.109021)
			(xy 53.764942 -304.133504) (xy 53.758338 -304.145442) (xy 53.758846 -304.172366) (xy 53.810408 -304.25898)
			(xy 53.815206 -304.266356) (xy 53.828759 -304.277558) (xy 53.845304 -304.283511) (xy 53.854096 -304.283872)
			(xy 54.045612 -304.283872) (xy 54.054401 -304.283501) (xy 54.070941 -304.277547) (xy 54.084489 -304.266346)
			(xy 54.0893 -304.25898) (xy 54.140862 -304.172366) (xy 54.14137 -304.145442) (xy 54.134766 -304.133504)
			(xy 54.121987 -304.109015) (xy 54.103874 -304.056835) (xy 54.094685 -304.002371) (xy 54.094126 -303.974754)
			(xy 54.094636 -303.948767) (xy 54.102766 -303.897432) (xy 54.118827 -303.848002) (xy 54.142423 -303.801692)
			(xy 54.172973 -303.759644) (xy 54.209724 -303.722893) (xy 54.251772 -303.692343) (xy 54.298082 -303.668747)
			(xy 54.347512 -303.652686) (xy 54.398847 -303.644556) (xy 54.450821 -303.644556) (xy 54.502156 -303.652686)
			(xy 54.551586 -303.668747) (xy 54.597896 -303.692343) (xy 54.639944 -303.722893) (xy 54.676695 -303.759644)
			(xy 54.707245 -303.801692) (xy 54.730841 -303.848002) (xy 54.746902 -303.897432) (xy 54.755032 -303.948767)
			(xy 54.755542 -303.974754) (xy 54.754988 -304.002372) (xy 54.745809 -304.05684) (xy 54.727698 -304.109023)
			(xy 54.714902 -304.133504) (xy 54.708298 -304.145442) (xy 54.708806 -304.172366) (xy 54.760368 -304.25898)
			(xy 54.765164 -304.266361) (xy 54.778716 -304.277574) (xy 54.795262 -304.283539) (xy 54.804056 -304.283872)
			(xy 54.995572 -304.283872) (xy 55.004365 -304.283507) (xy 55.020915 -304.277562) (xy 55.034474 -304.266364)
			(xy 55.03926 -304.25898) (xy 55.090822 -304.172366) (xy 55.09133 -304.145442) (xy 55.084726 -304.133504)
			(xy 55.071948 -304.109015) (xy 55.053837 -304.056835) (xy 55.044649 -304.002371) (xy 55.044086 -303.974754)
			(xy 55.044596 -303.948767) (xy 55.052726 -303.897432) (xy 55.068787 -303.848002) (xy 55.092383 -303.801692)
			(xy 55.122933 -303.759644) (xy 55.159684 -303.722893) (xy 55.201732 -303.692343) (xy 55.248042 -303.668747)
			(xy 55.297472 -303.652686) (xy 55.348807 -303.644556) (xy 55.400781 -303.644556) (xy 55.452116 -303.652686)
			(xy 55.501546 -303.668747) (xy 55.547856 -303.692343) (xy 55.589904 -303.722893) (xy 55.626655 -303.759644)
			(xy 55.657205 -303.801692) (xy 55.680801 -303.848002) (xy 55.696862 -303.897432) (xy 55.704992 -303.948767)
			(xy 55.705502 -303.974754) (xy 55.704948 -304.002372) (xy 55.695768 -304.05684) (xy 55.677655 -304.109021)
			(xy 55.664862 -304.133504) (xy 55.658258 -304.145442) (xy 55.658766 -304.172366) (xy 55.710328 -304.25898)
			(xy 55.715127 -304.266354) (xy 55.728681 -304.277551) (xy 55.745226 -304.283498) (xy 55.754016 -304.283872)
			(xy 55.945532 -304.283872) (xy 55.95432 -304.283498) (xy 55.970854 -304.277539) (xy 55.984397 -304.266337)
			(xy 55.98922 -304.25898) (xy 56.040782 -304.172366) (xy 56.04129 -304.145442) (xy 56.034686 -304.133504)
			(xy 56.021906 -304.109015) (xy 56.003792 -304.056836) (xy 55.994602 -304.002371) (xy 55.994046 -303.974754)
			(xy 55.994556 -303.948767) (xy 56.002686 -303.897432) (xy 56.018747 -303.848002) (xy 56.042343 -303.801692)
			(xy 56.072893 -303.759644) (xy 56.109644 -303.722893) (xy 56.151692 -303.692343) (xy 56.198002 -303.668747)
			(xy 56.247432 -303.652686) (xy 56.298767 -303.644556) (xy 56.350741 -303.644556) (xy 56.402076 -303.652686)
			(xy 56.451506 -303.668747) (xy 56.497816 -303.692343) (xy 56.539864 -303.722893) (xy 56.576615 -303.759644)
			(xy 56.607165 -303.801692) (xy 56.630761 -303.848002) (xy 56.646822 -303.897432) (xy 56.654952 -303.948767)
			(xy 56.655462 -303.974754) (xy 56.654908 -304.002372) (xy 56.645727 -304.056839) (xy 56.627612 -304.10902)
			(xy 56.614822 -304.133504) (xy 56.608218 -304.145442) (xy 56.608726 -304.172366) (xy 56.660288 -304.25898)
			(xy 56.665085 -304.266358) (xy 56.678637 -304.277566) (xy 56.695183 -304.283526) (xy 56.703976 -304.283872)
			(xy 56.895746 -304.283872) (xy 56.904541 -304.283511) (xy 56.921098 -304.277572) (xy 56.934664 -304.266376)
			(xy 56.939434 -304.25898) (xy 56.990996 -304.172366) (xy 56.991504 -304.145442) (xy 56.9849 -304.133504)
			(xy 56.97212 -304.109016) (xy 56.954004 -304.056836) (xy 56.944815 -304.002371) (xy 56.94426 -303.974754)
			(xy 56.94477 -303.948767) (xy 56.9529 -303.897432) (xy 56.968961 -303.848002) (xy 56.992557 -303.801692)
			(xy 57.023107 -303.759644) (xy 57.059858 -303.722893) (xy 57.101906 -303.692343) (xy 57.148216 -303.668747)
			(xy 57.197646 -303.652686) (xy 57.248981 -303.644556) (xy 57.300955 -303.644556) (xy 57.35229 -303.652686)
			(xy 57.40172 -303.668747) (xy 57.44803 -303.692343) (xy 57.490078 -303.722893) (xy 57.526829 -303.759644)
			(xy 57.557379 -303.801692) (xy 57.580975 -303.848002) (xy 57.597036 -303.897432) (xy 57.605166 -303.948767)
			(xy 57.605676 -303.974754) (xy 57.605122 -304.002372) (xy 57.595941 -304.056839) (xy 57.577827 -304.10902)
			(xy 57.565036 -304.133504) (xy 57.558432 -304.145442) (xy 57.55894 -304.172366) (xy 57.610502 -304.25898)
			(xy 57.6153 -304.266357) (xy 57.628853 -304.27756) (xy 57.645398 -304.283516) (xy 57.65419 -304.283872)
			(xy 57.845706 -304.283872) (xy 57.854496 -304.283502) (xy 57.871037 -304.277549) (xy 57.884587 -304.266349)
			(xy 57.889394 -304.25898) (xy 57.940956 -304.172366) (xy 57.941464 -304.145442) (xy 57.93486 -304.133504)
			(xy 57.922081 -304.109015) (xy 57.903968 -304.056835) (xy 57.894779 -304.002371) (xy 57.89422 -303.974754)
			(xy 57.89473 -303.948767) (xy 57.90286 -303.897432) (xy 57.918921 -303.848002) (xy 57.942517 -303.801692)
			(xy 57.973067 -303.759644) (xy 58.009818 -303.722893) (xy 58.051866 -303.692343) (xy 58.098176 -303.668747)
			(xy 58.147606 -303.652686) (xy 58.198941 -303.644556) (xy 58.250915 -303.644556) (xy 58.30225 -303.652686)
			(xy 58.35168 -303.668747) (xy 58.39799 -303.692343) (xy 58.440038 -303.722893) (xy 58.476789 -303.759644)
			(xy 58.507339 -303.801692) (xy 58.530935 -303.848002) (xy 58.546996 -303.897432) (xy 58.555126 -303.948767)
			(xy 58.555636 -303.974754) (xy 58.555082 -304.002372) (xy 58.545903 -304.05684) (xy 58.527791 -304.109023)
			(xy 58.514996 -304.133504) (xy 58.508392 -304.145442) (xy 58.5089 -304.172366) (xy 58.560462 -304.25898)
			(xy 58.565258 -304.266361) (xy 58.578809 -304.277576) (xy 58.595355 -304.283544) (xy 58.60415 -304.283872)
			(xy 59.745626 -304.283872) (xy 59.754414 -304.283499) (xy 59.77095 -304.277542) (xy 59.784495 -304.26634)
			(xy 59.789314 -304.25898) (xy 59.840876 -304.172366) (xy 59.841384 -304.145442) (xy 59.83478 -304.133504)
			(xy 59.822 -304.109015) (xy 59.803886 -304.056836) (xy 59.794697 -304.002371) (xy 59.79414 -303.974754)
			(xy 59.79465 -303.948767) (xy 59.80278 -303.897432) (xy 59.818841 -303.848002) (xy 59.842437 -303.801692)
			(xy 59.872987 -303.759644) (xy 59.909738 -303.722893) (xy 59.951786 -303.692343) (xy 59.998096 -303.668747)
			(xy 60.047526 -303.652686) (xy 60.098861 -303.644556) (xy 60.150835 -303.644556) (xy 60.20217 -303.652686)
			(xy 60.2516 -303.668747) (xy 60.29791 -303.692343) (xy 60.339958 -303.722893) (xy 60.376709 -303.759644)
			(xy 60.407259 -303.801692) (xy 60.430855 -303.848002) (xy 60.446916 -303.897432) (xy 60.455046 -303.948767)
			(xy 60.455556 -303.974754) (xy 60.455002 -304.002372) (xy 60.44582 -304.056839) (xy 60.427705 -304.10902)
			(xy 60.414916 -304.133504) (xy 60.408312 -304.145442) (xy 60.40882 -304.172366) (xy 60.460382 -304.25898)
			(xy 60.465179 -304.266359) (xy 60.478731 -304.277568) (xy 60.495277 -304.28353) (xy 60.50407 -304.283872)
			(xy 60.695586 -304.283872) (xy 60.704378 -304.283505) (xy 60.720924 -304.277557) (xy 60.734479 -304.266358)
			(xy 60.739274 -304.25898) (xy 60.790836 -304.172366) (xy 60.791344 -304.145442) (xy 60.78474 -304.133504)
			(xy 60.771962 -304.109015) (xy 60.75385 -304.056835) (xy 60.744662 -304.002371) (xy 60.7441 -303.974754)
			(xy 60.74461 -303.948767) (xy 60.75274 -303.897432) (xy 60.768801 -303.848002) (xy 60.792397 -303.801692)
			(xy 60.822947 -303.759644) (xy 60.859698 -303.722893) (xy 60.901746 -303.692343) (xy 60.948056 -303.668747)
			(xy 60.997486 -303.652686) (xy 61.048821 -303.644556) (xy 61.100795 -303.644556) (xy 61.15213 -303.652686)
			(xy 61.20156 -303.668747) (xy 61.24787 -303.692343) (xy 61.289918 -303.722893) (xy 61.326669 -303.759644)
			(xy 61.357219 -303.801692) (xy 61.380815 -303.848002) (xy 61.396876 -303.897432) (xy 61.405006 -303.948767)
			(xy 61.405516 -303.974754) (xy 61.404962 -304.002372) (xy 61.395782 -304.05684) (xy 61.37767 -304.109022)
			(xy 61.364876 -304.133504) (xy 61.358272 -304.145442) (xy 61.35878 -304.172366) (xy 61.410342 -304.25898)
			(xy 61.415137 -304.266363) (xy 61.428687 -304.277583) (xy 61.445234 -304.283557) (xy 61.45403 -304.283872)
			(xy 61.645546 -304.283872) (xy 61.654341 -304.283511) (xy 61.670898 -304.277572) (xy 61.684464 -304.266376)
			(xy 61.689234 -304.25898) (xy 61.740796 -304.172366) (xy 61.741304 -304.145442) (xy 61.7347 -304.133504)
			(xy 61.72192 -304.109016) (xy 61.703804 -304.056836) (xy 61.694615 -304.002371) (xy 61.69406 -303.974754)
			(xy 61.69457 -303.948767) (xy 61.7027 -303.897432) (xy 61.718761 -303.848002) (xy 61.742357 -303.801692)
			(xy 61.772907 -303.759644) (xy 61.809658 -303.722893) (xy 61.851706 -303.692343) (xy 61.898016 -303.668747)
			(xy 61.947446 -303.652686) (xy 61.998781 -303.644556) (xy 62.050755 -303.644556) (xy 62.10209 -303.652686)
			(xy 62.15152 -303.668747) (xy 62.19783 -303.692343) (xy 62.239878 -303.722893) (xy 62.276629 -303.759644)
			(xy 62.307179 -303.801692) (xy 62.330775 -303.848002) (xy 62.346836 -303.897432) (xy 62.354966 -303.948767)
			(xy 62.355476 -303.974754) (xy 62.354922 -304.002372) (xy 62.345741 -304.056839) (xy 62.327627 -304.10902)
			(xy 62.314836 -304.133504) (xy 62.308232 -304.145442) (xy 62.30874 -304.172366) (xy 62.360302 -304.25898)
			(xy 62.3651 -304.266357) (xy 62.378653 -304.27756) (xy 62.395198 -304.283516) (xy 62.40399 -304.283872)
			(xy 62.59576 -304.283872) (xy 62.604554 -304.283509) (xy 62.621107 -304.277567) (xy 62.634669 -304.26637)
			(xy 62.639448 -304.25898) (xy 62.69101 -304.172366) (xy 62.691518 -304.145442) (xy 62.684914 -304.133504)
			(xy 62.672137 -304.109015) (xy 62.654026 -304.056835) (xy 62.644839 -304.002371) (xy 62.644274 -303.974754)
			(xy 62.644784 -303.948767) (xy 62.652914 -303.897432) (xy 62.668975 -303.848002) (xy 62.692571 -303.801692)
			(xy 62.723121 -303.759644) (xy 62.759872 -303.722893) (xy 62.80192 -303.692343) (xy 62.84823 -303.668747)
			(xy 62.89766 -303.652686) (xy 62.948995 -303.644556) (xy 63.000969 -303.644556) (xy 63.052304 -303.652686)
			(xy 63.101734 -303.668747) (xy 63.148044 -303.692343) (xy 63.190092 -303.722893) (xy 63.226843 -303.759644)
			(xy 63.257393 -303.801692) (xy 63.280989 -303.848002) (xy 63.29705 -303.897432) (xy 63.30518 -303.948767)
			(xy 63.30569 -303.974754) (xy 63.305136 -304.002372) (xy 63.295955 -304.05684) (xy 63.277842 -304.109021)
			(xy 63.26505 -304.133504) (xy 63.258446 -304.145442) (xy 63.258954 -304.172366) (xy 63.310516 -304.25898)
			(xy 63.315315 -304.266355) (xy 63.328868 -304.277555) (xy 63.345413 -304.283506) (xy 63.354204 -304.283872)
			(xy 63.54572 -304.283872) (xy 63.554509 -304.2835) (xy 63.571046 -304.277544) (xy 63.584593 -304.266343)
			(xy 63.589408 -304.25898) (xy 63.64097 -304.172366) (xy 63.641478 -304.145442) (xy 63.634874 -304.133504)
			(xy 63.622095 -304.109015) (xy 63.603981 -304.056836) (xy 63.594792 -304.002371) (xy 63.594234 -303.974754)
			(xy 63.594744 -303.948767) (xy 63.602874 -303.897432) (xy 63.618935 -303.848002) (xy 63.642531 -303.801692)
			(xy 63.673081 -303.759644) (xy 63.709832 -303.722893) (xy 63.75188 -303.692343) (xy 63.79819 -303.668747)
			(xy 63.84762 -303.652686) (xy 63.898955 -303.644556) (xy 63.950929 -303.644556) (xy 64.002264 -303.652686)
			(xy 64.051694 -303.668747) (xy 64.098004 -303.692343) (xy 64.140052 -303.722893) (xy 64.176803 -303.759644)
			(xy 64.207353 -303.801692) (xy 64.230949 -303.848002) (xy 64.24701 -303.897432) (xy 64.25514 -303.948767)
			(xy 64.25565 -303.974754) (xy 64.255096 -304.002372) (xy 64.245917 -304.05684) (xy 64.227806 -304.109023)
			(xy 64.21501 -304.133504) (xy 64.208406 -304.145442) (xy 64.208914 -304.172366) (xy 64.260476 -304.25898)
			(xy 64.265273 -304.26636) (xy 64.278824 -304.277571) (xy 64.29537 -304.283534) (xy 64.304164 -304.283872)
			(xy 64.49568 -304.283872) (xy 64.504472 -304.283506) (xy 64.52102 -304.277559) (xy 64.534577 -304.266361)
			(xy 64.539368 -304.25898) (xy 64.59093 -304.172366) (xy 64.591438 -304.145442) (xy 64.584834 -304.133504)
			(xy 64.572056 -304.109015) (xy 64.553944 -304.056835) (xy 64.544756 -304.002371) (xy 64.544194 -303.974754)
			(xy 64.544704 -303.948767) (xy 64.552834 -303.897432) (xy 64.568895 -303.848002) (xy 64.592491 -303.801692)
			(xy 64.623041 -303.759644) (xy 64.659792 -303.722893) (xy 64.70184 -303.692343) (xy 64.74815 -303.668747)
			(xy 64.79758 -303.652686) (xy 64.848915 -303.644556) (xy 64.900889 -303.644556) (xy 64.952224 -303.652686)
			(xy 65.001654 -303.668747) (xy 65.047964 -303.692343) (xy 65.090012 -303.722893) (xy 65.126763 -303.759644)
			(xy 65.157313 -303.801692) (xy 65.180909 -303.848002) (xy 65.19697 -303.897432) (xy 65.2051 -303.948767)
			(xy 65.20561 -303.974754) (xy 65.205056 -304.002372) (xy 65.195876 -304.05684) (xy 65.177763 -304.109022)
			(xy 65.16497 -304.133504) (xy 65.158366 -304.145442) (xy 65.158874 -304.172366) (xy 65.210436 -304.25898)
			(xy 65.215236 -304.266353) (xy 65.22879 -304.277548) (xy 65.245334 -304.283492) (xy 65.254124 -304.283872)
			(xy 65.44564 -304.283872) (xy 65.454427 -304.283496) (xy 65.47096 -304.277536) (xy 65.4845 -304.266334)
			(xy 65.489328 -304.25898) (xy 65.54089 -304.172366) (xy 65.541398 -304.145442) (xy 65.534794 -304.133504)
			(xy 65.522014 -304.109015) (xy 65.503899 -304.056836) (xy 65.494709 -304.002371) (xy 65.494154 -303.974754)
			(xy 65.494664 -303.948767) (xy 65.502794 -303.897432) (xy 65.518855 -303.848002) (xy 65.542451 -303.801692)
			(xy 65.573001 -303.759644) (xy 65.609752 -303.722893) (xy 65.6518 -303.692343) (xy 65.69811 -303.668747)
			(xy 65.74754 -303.652686) (xy 65.798875 -303.644556) (xy 65.850849 -303.644556) (xy 65.902184 -303.652686)
			(xy 65.951614 -303.668747) (xy 65.997924 -303.692343) (xy 66.039972 -303.722893) (xy 66.076723 -303.759644)
			(xy 66.107273 -303.801692) (xy 66.130869 -303.848002) (xy 66.14693 -303.897432) (xy 66.15506 -303.948767)
			(xy 66.15557 -303.974754) (xy 66.155016 -304.002372) (xy 66.145835 -304.056839) (xy 66.12772 -304.10902)
			(xy 66.11493 -304.133504) (xy 66.108326 -304.145442) (xy 66.108834 -304.172366) (xy 66.160396 -304.25898)
			(xy 66.165193 -304.266358) (xy 66.178746 -304.277563) (xy 66.195292 -304.28352) (xy 66.204084 -304.283872)
			(xy 66.3956 -304.283872) (xy 66.40439 -304.283503) (xy 66.420933 -304.277551) (xy 66.434485 -304.266352)
			(xy 66.439288 -304.25898) (xy 66.49085 -304.172366) (xy 66.491358 -304.145442) (xy 66.484754 -304.133504)
			(xy 66.471975 -304.109015) (xy 66.453863 -304.056835) (xy 66.444674 -304.002371) (xy 66.444114 -303.974754)
			(xy 66.444624 -303.948767) (xy 66.452754 -303.897432) (xy 66.468815 -303.848002) (xy 66.492411 -303.801692)
			(xy 66.522961 -303.759644) (xy 66.559712 -303.722893) (xy 66.60176 -303.692343) (xy 66.64807 -303.668747)
			(xy 66.6975 -303.652686) (xy 66.748835 -303.644556) (xy 66.800809 -303.644556) (xy 66.852144 -303.652686)
			(xy 66.901574 -303.668747) (xy 66.947884 -303.692343) (xy 66.989932 -303.722893) (xy 67.026683 -303.759644)
			(xy 67.057233 -303.801692) (xy 67.080829 -303.848002) (xy 67.09689 -303.897432) (xy 67.10502 -303.948767)
			(xy 67.10553 -303.974754) (xy 67.104976 -304.002372) (xy 67.095796 -304.05684) (xy 67.077685 -304.109022)
			(xy 67.06489 -304.133504) (xy 67.058286 -304.145442) (xy 67.058794 -304.172366) (xy 67.110356 -304.25898)
			(xy 67.115152 -304.266362) (xy 67.128703 -304.277578) (xy 67.145249 -304.283548) (xy 67.154044 -304.283872)
			(xy 67.34556 -304.283872) (xy 67.354354 -304.283509) (xy 67.370907 -304.277567) (xy 67.384469 -304.26637)
			(xy 67.389248 -304.25898) (xy 67.44081 -304.172366) (xy 67.441318 -304.145442) (xy 67.434714 -304.133504)
			(xy 67.421937 -304.109015) (xy 67.403826 -304.056835) (xy 67.394639 -304.002371) (xy 67.394074 -303.974754)
			(xy 67.394584 -303.948767) (xy 67.402714 -303.897432) (xy 67.418775 -303.848002) (xy 67.442371 -303.801692)
			(xy 67.472921 -303.759644) (xy 67.509672 -303.722893) (xy 67.55172 -303.692343) (xy 67.59803 -303.668747)
			(xy 67.64746 -303.652686) (xy 67.698795 -303.644556) (xy 67.750769 -303.644556) (xy 67.802104 -303.652686)
			(xy 67.851534 -303.668747) (xy 67.897844 -303.692343) (xy 67.939892 -303.722893) (xy 67.976643 -303.759644)
			(xy 68.007193 -303.801692) (xy 68.030789 -303.848002) (xy 68.04685 -303.897432) (xy 68.05498 -303.948767)
			(xy 68.05549 -303.974754) (xy 68.054936 -304.002372) (xy 68.045755 -304.05684) (xy 68.027642 -304.109021)
			(xy 68.01485 -304.133504) (xy 68.008246 -304.145442) (xy 68.008754 -304.172366) (xy 68.060316 -304.25898)
			(xy 68.065115 -304.266355) (xy 68.078668 -304.277555) (xy 68.095213 -304.283506) (xy 68.104004 -304.283872)
			(xy 68.30314 -304.283872) (xy 68.311994 -304.283492) (xy 68.328649 -304.277477) (xy 68.342279 -304.266173)
			(xy 68.347082 -304.258726) (xy 68.39839 -304.17135) (xy 68.39839 -304.144426) (xy 68.391786 -304.132488)
			(xy 68.378371 -304.107516) (xy 68.359343 -304.054123) (xy 68.349685 -303.998269) (xy 68.349114 -303.969928)
			(xy 68.349624 -303.943941) (xy 68.357754 -303.892606) (xy 68.373815 -303.843176) (xy 68.397411 -303.796866)
			(xy 68.427961 -303.754818) (xy 68.464712 -303.718067) (xy 68.50676 -303.687517) (xy 68.55307 -303.663921)
			(xy 68.6025 -303.64786) (xy 68.653835 -303.63973) (xy 68.705809 -303.63973) (xy 68.757144 -303.64786)
			(xy 68.806574 -303.663921) (xy 68.852884 -303.687517) (xy 68.894932 -303.718067) (xy 68.931683 -303.754818)
			(xy 68.962233 -303.796866) (xy 68.985829 -303.843176) (xy 69.00189 -303.892606) (xy 69.01002 -303.943941)
			(xy 69.01053 -303.969928) (xy 69.009947 -303.998268) (xy 69.000291 -304.05412) (xy 68.981265 -304.107513)
			(xy 68.967858 -304.132488) (xy 68.961254 -304.144426) (xy 68.961254 -304.17135) (xy 69.012562 -304.258726)
			(xy 69.017313 -304.266224) (xy 69.03094 -304.277582) (xy 69.047633 -304.283588) (xy 69.056504 -304.283872)
			(xy 69.245734 -304.283872) (xy 69.254521 -304.283497) (xy 69.271056 -304.277539) (xy 69.284598 -304.266336)
			(xy 69.289422 -304.25898) (xy 69.340984 -304.172366) (xy 69.341492 -304.145442) (xy 69.334888 -304.133504)
			(xy 69.322108 -304.109015) (xy 69.303994 -304.056836) (xy 69.294804 -304.002371) (xy 69.294248 -303.974754)
			(xy 69.294761 -303.948768) (xy 69.302897 -303.897436) (xy 69.318961 -303.848009) (xy 69.342559 -303.801703)
			(xy 69.373109 -303.759657) (xy 69.409859 -303.722908) (xy 69.451905 -303.692358) (xy 69.498211 -303.668761)
			(xy 69.547638 -303.652696) (xy 69.59897 -303.644561) (xy 69.624956 -303.644046) (xy 69.648225 -303.64444)
			(xy 69.694304 -303.650961) (xy 69.739013 -303.663881) (xy 69.781468 -303.682945) (xy 69.820829 -303.707774)
			(xy 69.838824 -303.722532) (xy 69.839078 -303.722786) (xy 69.846738 -303.72865) (xy 69.865037 -303.734706)
			(xy 69.884282 -303.733618) (xy 69.89318 -303.729898) (xy 69.976746 -303.69129) (xy 69.978524 -303.690528)
			(xy 69.985995 -303.686345) (xy 69.997812 -303.673968) (xy 70.004875 -303.658382) (xy 70.005956 -303.649888)
			(xy 70.00621 -303.645062) (xy 70.00621 -300.978062) (xy 70.00578 -300.967995) (xy 69.998057 -300.949399)
			(xy 69.991224 -300.941994) (xy 69.667628 -300.618398) (xy 69.660516 -300.611032) (xy 69.64172 -300.603412)
			(xy 68.313046 -300.603412) (xy 68.30298 -300.60298) (xy 68.284388 -300.595253) (xy 68.276978 -300.588426)
			(xy 68.25488 -300.566328) (xy 68.248036 -300.558929) (xy 68.240315 -300.54033) (xy 68.239894 -300.53026)
			(xy 68.239894 -297.41114) (xy 68.240328 -297.401074) (xy 68.248057 -297.382485) (xy 68.25488 -297.375072)
			(xy 68.340224 -297.289728) (xy 68.34759 -297.275758) (xy 68.34886 -297.268138) (xy 68.353741 -297.242885)
			(xy 68.370281 -297.194187) (xy 68.394162 -297.148637) (xy 68.424808 -297.107334) (xy 68.461481 -297.071275)
			(xy 68.503295 -297.04133) (xy 68.549242 -297.018221) (xy 68.598213 -297.002506) (xy 68.649026 -296.994564)
			(xy 68.674742 -296.994072) (xy 68.701782 -296.994606) (xy 68.755141 -297.003398) (xy 68.806359 -297.020756)
			(xy 68.854069 -297.046218) (xy 68.897 -297.079105) (xy 68.934006 -297.118539) (xy 68.964101 -297.163471)
			(xy 68.986483 -297.212701) (xy 68.99402 -297.238674) (xy 68.99402 -297.238928) (xy 68.99749 -297.249478)
			(xy 69.01182 -297.266414) (xy 69.031949 -297.275739) (xy 69.043042 -297.276266) (xy 69.256656 -297.276266)
			(xy 69.267737 -297.275702) (xy 69.287839 -297.266368) (xy 69.30216 -297.249453) (xy 69.305678 -297.238928)
			(xy 69.305678 -297.238674) (xy 69.312755 -297.214228) (xy 69.333377 -297.167703) (xy 69.360884 -297.124887)
			(xy 69.394626 -297.08679) (xy 69.433806 -297.054312) (xy 69.477499 -297.02822) (xy 69.524673 -297.00913)
			(xy 69.574216 -296.997493) (xy 69.624956 -296.993583) (xy 69.675696 -296.997493) (xy 69.725239 -297.00913)
			(xy 69.772413 -297.02822) (xy 69.816106 -297.054312) (xy 69.855286 -297.08679) (xy 69.889028 -297.124887)
			(xy 69.916535 -297.167703) (xy 69.937157 -297.214228) (xy 69.944234 -297.238674) (xy 69.944234 -297.238928)
			(xy 69.947705 -297.249477) (xy 69.962035 -297.266408) (xy 69.982164 -297.275729) (xy 69.993256 -297.276266)
			(xy 70.206616 -297.276266) (xy 70.217702 -297.27571) (xy 70.237819 -297.266384) (xy 70.252153 -297.249467)
			(xy 70.255638 -297.238928) (xy 70.255638 -297.238674) (xy 70.262444 -297.215133) (xy 70.282042 -297.17022)
			(xy 70.308056 -297.128692) (xy 70.339916 -297.09146) (xy 70.376923 -297.059339) (xy 70.418267 -297.033034)
			(xy 70.463041 -297.013121) (xy 70.510265 -297.000036) (xy 70.53453 -296.996612) (xy 70.535292 -296.996612)
			(xy 70.544305 -296.995036) (xy 70.560443 -296.986441) (xy 70.566788 -296.979848) (xy 70.572601 -296.972638)
			(xy 70.579125 -296.955319) (xy 70.579488 -296.946066) (xy 70.579488 -296.753534) (xy 70.579136 -296.744276)
			(xy 70.572622 -296.726949) (xy 70.566788 -296.719752) (xy 70.560461 -296.713135) (xy 70.544316 -296.704531)
			(xy 70.535292 -296.702988) (xy 70.53453 -296.702988) (xy 70.509557 -296.699437) (xy 70.461012 -296.685748)
			(xy 70.415108 -296.664844) (xy 70.372912 -296.637212) (xy 70.335402 -296.603491) (xy 70.303448 -296.564465)
			(xy 70.277792 -296.521039) (xy 70.259029 -296.47422) (xy 70.247594 -296.425095) (xy 70.243752 -296.374802)
			(xy 70.247593 -296.32451) (xy 70.259027 -296.275384) (xy 70.27779 -296.228565) (xy 70.303445 -296.185139)
			(xy 70.335399 -296.146112) (xy 70.372908 -296.112391) (xy 70.415104 -296.084758) (xy 70.461007 -296.063854)
			(xy 70.509552 -296.050164) (xy 70.53453 -296.046652) (xy 70.535292 -296.046652) (xy 70.544306 -296.045078)
			(xy 70.560449 -296.036487) (xy 70.566788 -296.029888) (xy 70.572592 -296.022675) (xy 70.579096 -296.005357)
			(xy 70.579488 -295.996106) (xy 70.579488 -294.853614) (xy 70.579133 -294.844357) (xy 70.572613 -294.827035)
			(xy 70.566788 -294.819832) (xy 70.56046 -294.813217) (xy 70.544314 -294.804617) (xy 70.535292 -294.803068)
			(xy 70.53453 -294.803068) (xy 70.509559 -294.799517) (xy 70.461016 -294.785828) (xy 70.415116 -294.764926)
			(xy 70.372922 -294.737295) (xy 70.335415 -294.703576) (xy 70.303463 -294.664552) (xy 70.277809 -294.621128)
			(xy 70.259047 -294.574312) (xy 70.247613 -294.525189) (xy 70.243772 -294.4749) (xy 70.247613 -294.424611)
			(xy 70.259047 -294.375488) (xy 70.277809 -294.328672) (xy 70.303463 -294.285248) (xy 70.335415 -294.246224)
			(xy 70.372922 -294.212505) (xy 70.415116 -294.184874) (xy 70.461016 -294.163972) (xy 70.509559 -294.150283)
			(xy 70.53453 -294.146732) (xy 70.535292 -294.146732) (xy 70.544306 -294.145157) (xy 70.560446 -294.136564)
			(xy 70.566788 -294.129968) (xy 70.572604 -294.122759) (xy 70.579135 -294.105441) (xy 70.579488 -294.096186)
			(xy 70.579488 -293.903654) (xy 70.579139 -293.894395) (xy 70.57263 -293.877063) (xy 70.566788 -293.869872)
			(xy 70.560462 -293.863253) (xy 70.544317 -293.854646) (xy 70.535292 -293.853108) (xy 70.53453 -293.853108)
			(xy 70.509556 -293.849557) (xy 70.461007 -293.835867) (xy 70.415101 -293.814963) (xy 70.372902 -293.787329)
			(xy 70.335389 -293.753607) (xy 70.303433 -293.714579) (xy 70.277775 -293.67115) (xy 70.25901 -293.624329)
			(xy 70.247574 -293.5752) (xy 70.243732 -293.524905) (xy 70.247573 -293.474609) (xy 70.259008 -293.425481)
			(xy 70.277771 -293.378659) (xy 70.303428 -293.335229) (xy 70.335383 -293.2962) (xy 70.372894 -293.262477)
			(xy 70.415092 -293.234842) (xy 70.460998 -293.213936) (xy 70.509546 -293.200245) (xy 70.53453 -293.196772)
			(xy 70.535292 -293.196772) (xy 70.544304 -293.195195) (xy 70.560437 -293.186595) (xy 70.566788 -293.180008)
			(xy 70.572595 -293.172796) (xy 70.579106 -293.155477) (xy 70.579488 -293.146226) (xy 70.579488 -292.953694)
			(xy 70.579129 -292.944439) (xy 70.572605 -292.927121) (xy 70.566788 -292.919912) (xy 70.560458 -292.913299)
			(xy 70.544313 -292.904703) (xy 70.535292 -292.903148) (xy 70.53453 -292.903148) (xy 70.50956 -292.899597)
			(xy 70.461021 -292.885909) (xy 70.415123 -292.865007) (xy 70.372932 -292.837377) (xy 70.335427 -292.80366)
			(xy 70.303478 -292.764639) (xy 70.277825 -292.721217) (xy 70.259065 -292.674404) (xy 70.247632 -292.625284)
			(xy 70.243792 -292.574998) (xy 70.247633 -292.524711) (xy 70.259067 -292.475592) (xy 70.277828 -292.428778)
			(xy 70.303481 -292.385357) (xy 70.335431 -292.346336) (xy 70.372936 -292.31262) (xy 70.415127 -292.28499)
			(xy 70.461025 -292.264089) (xy 70.509565 -292.250402) (xy 70.53453 -292.246812) (xy 70.535292 -292.246812)
			(xy 70.544305 -292.245236) (xy 70.560443 -292.236641) (xy 70.566788 -292.230048) (xy 70.572601 -292.222838)
			(xy 70.579125 -292.205519) (xy 70.579488 -292.196266) (xy 70.579488 -292.00348) (xy 70.579127 -291.994226)
			(xy 70.572599 -291.976912) (xy 70.566788 -291.969698) (xy 70.560458 -291.963086) (xy 70.544312 -291.954493)
			(xy 70.535292 -291.952934) (xy 70.53453 -291.952934) (xy 70.509561 -291.949383) (xy 70.461024 -291.935695)
			(xy 70.415128 -291.914794) (xy 70.37294 -291.887165) (xy 70.335436 -291.85345) (xy 70.303488 -291.814429)
			(xy 70.277837 -291.77101) (xy 70.259078 -291.724198) (xy 70.247646 -291.67508) (xy 70.243805 -291.624796)
			(xy 70.247647 -291.574512) (xy 70.25908 -291.525394) (xy 70.277841 -291.478583) (xy 70.303493 -291.435164)
			(xy 70.335442 -291.396144) (xy 70.372946 -291.36243) (xy 70.415136 -291.334802) (xy 70.461032 -291.313902)
			(xy 70.50957 -291.300215) (xy 70.53453 -291.296598) (xy 70.535292 -291.296598) (xy 70.544305 -291.295022)
			(xy 70.560441 -291.286425) (xy 70.566788 -291.279834) (xy 70.572599 -291.272623) (xy 70.579118 -291.255305)
			(xy 70.579488 -291.246052) (xy 70.579488 -291.05352) (xy 70.579134 -291.044263) (xy 70.572616 -291.02694)
			(xy 70.566788 -291.019738) (xy 70.56046 -291.013122) (xy 70.544315 -291.004521) (xy 70.535292 -291.002974)
			(xy 70.53453 -291.002974) (xy 70.509558 -290.999423) (xy 70.461015 -290.985734) (xy 70.415114 -290.964831)
			(xy 70.372919 -290.9372) (xy 70.335411 -290.903481) (xy 70.303459 -290.864456) (xy 70.277804 -290.821032)
			(xy 70.259041 -290.774214) (xy 70.247607 -290.725091) (xy 70.243766 -290.674801) (xy 70.247607 -290.62451)
			(xy 70.259041 -290.575387) (xy 70.277803 -290.52857) (xy 70.303458 -290.485145) (xy 70.33541 -290.44612)
			(xy 70.372918 -290.412401) (xy 70.415112 -290.384769) (xy 70.461013 -290.363866) (xy 70.509557 -290.350177)
			(xy 70.53453 -290.346638) (xy 70.535292 -290.346638) (xy 70.544306 -290.345063) (xy 70.560447 -290.336471)
			(xy 70.566788 -290.329874) (xy 70.572605 -290.322665) (xy 70.579138 -290.305347) (xy 70.579488 -290.296092)
			(xy 70.579488 -290.10356) (xy 70.579141 -290.0943) (xy 70.572633 -290.076967) (xy 70.566788 -290.069778)
			(xy 70.560462 -290.063158) (xy 70.544317 -290.05455) (xy 70.535292 -290.053014) (xy 70.53453 -290.053014)
			(xy 70.509555 -290.049463) (xy 70.461006 -290.035773) (xy 70.415099 -290.014868) (xy 70.372899 -289.987234)
			(xy 70.335386 -289.953512) (xy 70.303429 -289.914483) (xy 70.27777 -289.871053) (xy 70.259005 -289.824231)
			(xy 70.247569 -289.775102) (xy 70.243726 -289.724806) (xy 70.247567 -289.674509) (xy 70.259002 -289.62538)
			(xy 70.277765 -289.578557) (xy 70.303422 -289.535126) (xy 70.335378 -289.496097) (xy 70.37289 -289.462373)
			(xy 70.415089 -289.434737) (xy 70.460995 -289.413831) (xy 70.509544 -289.400139) (xy 70.53453 -289.396678)
			(xy 70.535292 -289.396678) (xy 70.544304 -289.395101) (xy 70.560438 -289.386502) (xy 70.566788 -289.379914)
			(xy 70.572596 -289.372702) (xy 70.579108 -289.355384) (xy 70.579488 -289.346132) (xy 70.579488 -289.1536)
			(xy 70.57913 -289.144344) (xy 70.572607 -289.127026) (xy 70.566788 -289.119818) (xy 70.560459 -289.113204)
			(xy 70.544313 -289.104607) (xy 70.535292 -289.103054) (xy 70.53453 -289.103054) (xy 70.508354 -289.099305)
			(xy 70.457571 -289.084573) (xy 70.409779 -289.06195) (xy 70.366193 -289.032013) (xy 70.327924 -288.995525)
			(xy 70.295945 -288.953415) (xy 70.271072 -288.906754) (xy 70.253937 -288.856731) (xy 70.244977 -288.80462)
			(xy 70.244208 -288.778188) (xy 70.244208 -288.774632) (xy 70.244553 -288.751528) (xy 70.250923 -288.705764)
			(xy 70.256908 -288.683446) (xy 70.257924 -288.680398) (xy 70.25894 -288.672778) (xy 70.260047 -288.660961)
			(xy 70.252628 -288.638445) (xy 70.244716 -288.629598) (xy 70.028562 -288.413444) (xy 70.021163 -288.406599)
			(xy 70.002565 -288.398871) (xy 69.992494 -288.398458) (xy 69.008498 -288.398458) (xy 69.005196 -288.398458)
			(xy 68.993922 -288.399802) (xy 68.974145 -288.410892) (xy 68.967096 -288.419794) (xy 68.962524 -288.427668)
			(xy 68.925186 -288.506916) (xy 68.921334 -288.516171) (xy 68.920294 -288.53617) (xy 68.923154 -288.545778)
			(xy 68.930012 -288.56432) (xy 68.935092 -288.57067) (xy 68.951622 -288.59268) (xy 68.977909 -288.641039)
			(xy 68.99584 -288.693078) (xy 69.004924 -288.747365) (xy 69.00545 -288.774886) (xy 69.00494 -288.800873)
			(xy 68.99681 -288.852208) (xy 68.980749 -288.901638) (xy 68.957153 -288.947948) (xy 68.926603 -288.989996)
			(xy 68.889852 -289.026747) (xy 68.847804 -289.057297) (xy 68.801494 -289.080893) (xy 68.752064 -289.096954)
			(xy 68.700729 -289.105084) (xy 68.648755 -289.105084) (xy 68.59742 -289.096954) (xy 68.54799 -289.080893)
			(xy 68.50168 -289.057297) (xy 68.459632 -289.026747) (xy 68.422881 -288.989996) (xy 68.392331 -288.947948)
			(xy 68.368735 -288.901638) (xy 68.352674 -288.852208) (xy 68.344544 -288.800873) (xy 68.344034 -288.774886)
			(xy 68.344125 -288.762136) (xy 68.346031 -288.736707) (xy 68.347844 -288.724086) (xy 68.352696 -288.696262)
			(xy 68.370632 -288.64271) (xy 68.397422 -288.592993) (xy 68.414392 -288.570416) (xy 68.419472 -288.564066)
			(xy 68.42633 -288.545524) (xy 68.429296 -288.535929) (xy 68.428263 -288.515888) (xy 68.424298 -288.506662)
			(xy 68.38696 -288.427668) (xy 68.382388 -288.419794) (xy 68.375318 -288.410923) (xy 68.355545 -288.399862)
			(xy 68.344288 -288.398458) (xy 68.058538 -288.398458) (xy 68.04895 -288.398867) (xy 68.031104 -288.405885)
			(xy 68.017049 -288.418932) (xy 68.012564 -288.427414) (xy 67.973448 -288.510472) (xy 67.969685 -288.519337)
			(xy 67.968401 -288.538538) (xy 67.974284 -288.55686) (xy 67.980052 -288.564574) (xy 67.99771 -288.586963)
			(xy 68.025872 -288.63654) (xy 68.045128 -288.690206) (xy 68.05491 -288.746378) (xy 68.05549 -288.774886)
			(xy 68.05498 -288.800873) (xy 68.04685 -288.852208) (xy 68.030789 -288.901638) (xy 68.007193 -288.947948)
			(xy 67.976643 -288.989996) (xy 67.939892 -289.026747) (xy 67.897844 -289.057297) (xy 67.851534 -289.080893)
			(xy 67.802104 -289.096954) (xy 67.750769 -289.105084) (xy 67.698795 -289.105084) (xy 67.64746 -289.096954)
			(xy 67.59803 -289.080893) (xy 67.55172 -289.057297) (xy 67.509672 -289.026747) (xy 67.472921 -288.989996)
			(xy 67.442371 -288.947948) (xy 67.418775 -288.901638) (xy 67.402714 -288.852208) (xy 67.394584 -288.800873)
			(xy 67.394074 -288.774886) (xy 67.394671 -288.746379) (xy 67.404445 -288.690208) (xy 67.423699 -288.636543)
			(xy 67.451866 -288.586972) (xy 67.469512 -288.564574) (xy 67.475312 -288.556882) (xy 67.481191 -288.538552)
			(xy 67.479867 -288.519348) (xy 67.476116 -288.510472) (xy 67.437 -288.427414) (xy 67.432526 -288.418914)
			(xy 67.418498 -288.405815) (xy 67.400625 -288.398823) (xy 67.391026 -288.398458) (xy 67.108578 -288.398458)
			(xy 67.098996 -288.398877) (xy 67.081167 -288.405908) (xy 67.06713 -288.418958) (xy 67.062604 -288.427414)
			(xy 67.023488 -288.510472) (xy 67.019723 -288.519337) (xy 67.018438 -288.538537) (xy 67.024325 -288.556859)
			(xy 67.030092 -288.564574) (xy 67.047748 -288.586964) (xy 67.075906 -288.636541) (xy 67.09516 -288.690208)
			(xy 67.104941 -288.746378) (xy 67.10553 -288.774886) (xy 67.10502 -288.800873) (xy 67.09689 -288.852208)
			(xy 67.080829 -288.901638) (xy 67.057233 -288.947948) (xy 67.026683 -288.989996) (xy 66.989932 -289.026747)
			(xy 66.947884 -289.057297) (xy 66.901574 -289.080893) (xy 66.852144 -289.096954) (xy 66.800809 -289.105084)
			(xy 66.748835 -289.105084) (xy 66.6975 -289.096954) (xy 66.64807 -289.080893) (xy 66.60176 -289.057297)
			(xy 66.559712 -289.026747) (xy 66.522961 -288.989996) (xy 66.492411 -288.947948) (xy 66.468815 -288.901638)
			(xy 66.452754 -288.852208) (xy 66.444624 -288.800873) (xy 66.444114 -288.774886) (xy 66.444712 -288.746379)
			(xy 66.454486 -288.690209) (xy 66.473742 -288.636545) (xy 66.501912 -288.586976) (xy 66.519552 -288.564574)
			(xy 66.525348 -288.55688) (xy 66.531223 -288.538552) (xy 66.5299 -288.51935) (xy 66.526156 -288.510472)
			(xy 66.48704 -288.427414) (xy 66.482568 -288.41891) (xy 66.468542 -288.405799) (xy 66.450667 -288.398793)
			(xy 66.441066 -288.398458) (xy 66.158618 -288.398458) (xy 66.149032 -288.39887) (xy 66.131192 -288.405893)
			(xy 66.117143 -288.41894) (xy 66.112644 -288.427414) (xy 66.073528 -288.510472) (xy 66.069767 -288.519338)
			(xy 66.068483 -288.538538) (xy 66.074364 -288.556861) (xy 66.080132 -288.564574) (xy 66.097791 -288.586963)
			(xy 66.125954 -288.636539) (xy 66.145212 -288.690206) (xy 66.154995 -288.746378) (xy 66.15557 -288.774886)
			(xy 66.15506 -288.800873) (xy 66.14693 -288.852208) (xy 66.130869 -288.901638) (xy 66.107273 -288.947948)
			(xy 66.076723 -288.989996) (xy 66.039972 -289.026747) (xy 65.997924 -289.057297) (xy 65.951614 -289.080893)
			(xy 65.902184 -289.096954) (xy 65.850849 -289.105084) (xy 65.798875 -289.105084) (xy 65.74754 -289.096954)
			(xy 65.69811 -289.080893) (xy 65.6518 -289.057297) (xy 65.609752 -289.026747) (xy 65.573001 -288.989996)
			(xy 65.542451 -288.947948) (xy 65.518855 -288.901638) (xy 65.502794 -288.852208) (xy 65.494664 -288.800873)
			(xy 65.494154 -288.774886) (xy 65.494751 -288.746379) (xy 65.504524 -288.690208) (xy 65.523778 -288.636542)
			(xy 65.551943 -288.58697) (xy 65.569592 -288.564574) (xy 65.575394 -288.556882) (xy 65.581275 -288.538552)
			(xy 65.57995 -288.519347) (xy 65.576196 -288.510472) (xy 65.53708 -288.427414) (xy 65.532605 -288.418916)
			(xy 65.518577 -288.405822) (xy 65.500703 -288.398837) (xy 65.491106 -288.398458) (xy 65.208658 -288.398458)
			(xy 65.199078 -288.39888) (xy 65.181255 -288.405916) (xy 65.167224 -288.418966) (xy 65.162684 -288.427414)
			(xy 65.123568 -288.510472) (xy 65.119804 -288.519337) (xy 65.118519 -288.538538) (xy 65.124404 -288.55686)
			(xy 65.130172 -288.564574) (xy 65.147829 -288.586964) (xy 65.175989 -288.636541) (xy 65.195244 -288.690207)
			(xy 65.205026 -288.746378) (xy 65.20561 -288.774886) (xy 65.2051 -288.800873) (xy 65.19697 -288.852208)
			(xy 65.180909 -288.901638) (xy 65.157313 -288.947948) (xy 65.126763 -288.989996) (xy 65.090012 -289.026747)
			(xy 65.047964 -289.057297) (xy 65.001654 -289.080893) (xy 64.952224 -289.096954) (xy 64.900889 -289.105084)
			(xy 64.848915 -289.105084) (xy 64.79758 -289.096954) (xy 64.74815 -289.080893) (xy 64.70184 -289.057297)
			(xy 64.659792 -289.026747) (xy 64.623041 -288.989996) (xy 64.592491 -288.947948) (xy 64.568895 -288.901638)
			(xy 64.552834 -288.852208) (xy 64.544704 -288.800873) (xy 64.544194 -288.774886) (xy 64.544791 -288.746379)
			(xy 64.554565 -288.690209) (xy 64.573821 -288.636544) (xy 64.601989 -288.586974) (xy 64.619632 -288.564574)
			(xy 64.62543 -288.556881) (xy 64.631307 -288.538552) (xy 64.629983 -288.519349) (xy 64.626236 -288.510472)
			(xy 64.58712 -288.427414) (xy 64.582647 -288.418912) (xy 64.568621 -288.405807) (xy 64.550746 -288.398808)
			(xy 64.541146 -288.398458) (xy 64.258698 -288.398458) (xy 64.249114 -288.398873) (xy 64.231279 -288.405901)
			(xy 64.217237 -288.418949) (xy 64.212724 -288.427414) (xy 64.173608 -288.510472) (xy 64.169842 -288.519336)
			(xy 64.168556 -288.538537) (xy 64.174445 -288.556858) (xy 64.180212 -288.564574) (xy 64.197872 -288.586962)
			(xy 64.226037 -288.636538) (xy 64.245296 -288.690205) (xy 64.255079 -288.746377) (xy 64.25565 -288.774886)
			(xy 64.25514 -288.800873) (xy 64.24701 -288.852208) (xy 64.230949 -288.901638) (xy 64.207353 -288.947948)
			(xy 64.176803 -288.989996) (xy 64.140052 -289.026747) (xy 64.098004 -289.057297) (xy 64.051694 -289.080893)
			(xy 64.002264 -289.096954) (xy 63.950929 -289.105084) (xy 63.898955 -289.105084) (xy 63.84762 -289.096954)
			(xy 63.79819 -289.080893) (xy 63.75188 -289.057297) (xy 63.709832 -289.026747) (xy 63.673081 -288.989996)
			(xy 63.642531 -288.947948) (xy 63.618935 -288.901638) (xy 63.602874 -288.852208) (xy 63.594744 -288.800873)
			(xy 63.594234 -288.774886) (xy 63.594832 -288.746379) (xy 63.604607 -288.69021) (xy 63.623864 -288.636547)
			(xy 63.652035 -288.586979) (xy 63.669672 -288.564574) (xy 63.675476 -288.556883) (xy 63.68136 -288.538552)
			(xy 63.680034 -288.519346) (xy 63.676276 -288.510472) (xy 63.63716 -288.427414) (xy 63.632689 -288.418908)
			(xy 63.618664 -288.405791) (xy 63.600788 -288.398779) (xy 63.591186 -288.398458) (xy 63.308738 -288.398458)
			(xy 63.29915 -288.398867) (xy 63.281304 -288.405885) (xy 63.267249 -288.418932) (xy 63.262764 -288.427414)
			(xy 63.223648 -288.510472) (xy 63.219885 -288.519337) (xy 63.218601 -288.538538) (xy 63.224484 -288.55686)
			(xy 63.230252 -288.564574) (xy 63.24791 -288.586963) (xy 63.276072 -288.63654) (xy 63.295328 -288.690206)
			(xy 63.30511 -288.746378) (xy 63.30569 -288.774886) (xy 63.30518 -288.800873) (xy 63.29705 -288.852208)
			(xy 63.280989 -288.901638) (xy 63.257393 -288.947948) (xy 63.226843 -288.989996) (xy 63.190092 -289.026747)
			(xy 63.148044 -289.057297) (xy 63.101734 -289.080893) (xy 63.052304 -289.096954) (xy 63.000969 -289.105084)
			(xy 62.948995 -289.105084) (xy 62.89766 -289.096954) (xy 62.84823 -289.080893) (xy 62.80192 -289.057297)
			(xy 62.759872 -289.026747) (xy 62.723121 -288.989996) (xy 62.692571 -288.947948) (xy 62.668975 -288.901638)
			(xy 62.652914 -288.852208) (xy 62.644784 -288.800873) (xy 62.644274 -288.774886) (xy 62.644871 -288.746379)
			(xy 62.654645 -288.690208) (xy 62.673899 -288.636543) (xy 62.702066 -288.586972) (xy 62.719712 -288.564574)
			(xy 62.725512 -288.556882) (xy 62.731391 -288.538552) (xy 62.730067 -288.519348) (xy 62.726316 -288.510472)
			(xy 62.6872 -288.427414) (xy 62.682726 -288.418914) (xy 62.668698 -288.405815) (xy 62.650825 -288.398823)
			(xy 62.641226 -288.398458) (xy 62.358524 -288.398458) (xy 62.348938 -288.398869) (xy 62.331095 -288.405891)
			(xy 62.317045 -288.418938) (xy 62.31255 -288.427414) (xy 62.273434 -288.510472) (xy 62.269672 -288.519337)
			(xy 62.268388 -288.538538) (xy 62.27427 -288.55686) (xy 62.280038 -288.564574) (xy 62.297697 -288.586963)
			(xy 62.325859 -288.636539) (xy 62.345117 -288.690206) (xy 62.354899 -288.746378) (xy 62.355476 -288.774886)
			(xy 62.354966 -288.800873) (xy 62.346836 -288.852208) (xy 62.330775 -288.901638) (xy 62.307179 -288.947948)
			(xy 62.276629 -288.989996) (xy 62.239878 -289.026747) (xy 62.19783 -289.057297) (xy 62.15152 -289.080893)
			(xy 62.10209 -289.096954) (xy 62.050755 -289.105084) (xy 61.998781 -289.105084) (xy 61.947446 -289.096954)
			(xy 61.898016 -289.080893) (xy 61.851706 -289.057297) (xy 61.809658 -289.026747) (xy 61.772907 -288.989996)
			(xy 61.742357 -288.947948) (xy 61.718761 -288.901638) (xy 61.7027 -288.852208) (xy 61.69457 -288.800873)
			(xy 61.69406 -288.774886) (xy 61.694657 -288.746379) (xy 61.70443 -288.690208) (xy 61.723684 -288.636542)
			(xy 61.75185 -288.586971) (xy 61.769498 -288.564574) (xy 61.775299 -288.556882) (xy 61.78118 -288.538552)
			(xy 61.779855 -288.519347) (xy 61.776102 -288.510472) (xy 61.736986 -288.427414) (xy 61.732511 -288.418916)
			(xy 61.718483 -288.40582) (xy 61.70061 -288.398833) (xy 61.691012 -288.398458) (xy 61.408564 -288.398458)
			(xy 61.398984 -288.398879) (xy 61.381159 -288.405914) (xy 61.367126 -288.418963) (xy 61.36259 -288.427414)
			(xy 61.323474 -288.510472) (xy 61.31971 -288.519337) (xy 61.318425 -288.538538) (xy 61.324311 -288.556859)
			(xy 61.330078 -288.564574) (xy 61.347735 -288.586964) (xy 61.375894 -288.636541) (xy 61.395149 -288.690207)
			(xy 61.404931 -288.746378) (xy 61.405516 -288.774886) (xy 61.405006 -288.800873) (xy 61.396876 -288.852208)
			(xy 61.380815 -288.901638) (xy 61.357219 -288.947948) (xy 61.326669 -288.989996) (xy 61.289918 -289.026747)
			(xy 61.24787 -289.057297) (xy 61.20156 -289.080893) (xy 61.15213 -289.096954) (xy 61.100795 -289.105084)
			(xy 61.048821 -289.105084) (xy 60.997486 -289.096954) (xy 60.948056 -289.080893) (xy 60.901746 -289.057297)
			(xy 60.859698 -289.026747) (xy 60.822947 -288.989996) (xy 60.792397 -288.947948) (xy 60.768801 -288.901638)
			(xy 60.75274 -288.852208) (xy 60.74461 -288.800873) (xy 60.7441 -288.774886) (xy 60.744697 -288.746379)
			(xy 60.754471 -288.690209) (xy 60.773727 -288.636545) (xy 60.801896 -288.586975) (xy 60.819538 -288.564574)
			(xy 60.825335 -288.556881) (xy 60.831212 -288.538552) (xy 60.829888 -288.519349) (xy 60.826142 -288.510472)
			(xy 60.787026 -288.427414) (xy 60.782553 -288.418911) (xy 60.768527 -288.405804) (xy 60.750652 -288.398803)
			(xy 60.741052 -288.398458) (xy 60.458604 -288.398458) (xy 60.44902 -288.398872) (xy 60.431183 -288.405898)
			(xy 60.417138 -288.418946) (xy 60.41263 -288.427414) (xy 60.373514 -288.510472) (xy 60.369748 -288.519336)
			(xy 60.368461 -288.538537) (xy 60.374351 -288.556858) (xy 60.380118 -288.564574) (xy 60.397778 -288.586962)
			(xy 60.425942 -288.636538) (xy 60.4452 -288.690205) (xy 60.454984 -288.746377) (xy 60.455556 -288.774886)
			(xy 60.455046 -288.800873) (xy 60.446916 -288.852208) (xy 60.430855 -288.901638) (xy 60.407259 -288.947948)
			(xy 60.376709 -288.989996) (xy 60.339958 -289.026747) (xy 60.29791 -289.057297) (xy 60.2516 -289.080893)
			(xy 60.20217 -289.096954) (xy 60.150835 -289.105084) (xy 60.098861 -289.105084) (xy 60.047526 -289.096954)
			(xy 59.998096 -289.080893) (xy 59.951786 -289.057297) (xy 59.909738 -289.026747) (xy 59.872987 -288.989996)
			(xy 59.842437 -288.947948) (xy 59.818841 -288.901638) (xy 59.80278 -288.852208) (xy 59.79465 -288.800873)
			(xy 59.79414 -288.774886) (xy 59.794738 -288.746379) (xy 59.804513 -288.69021) (xy 59.823771 -288.636547)
			(xy 59.851942 -288.586979) (xy 59.869578 -288.564574) (xy 59.875381 -288.556883) (xy 59.881264 -288.538552)
			(xy 59.879939 -288.519346) (xy 59.876182 -288.510472) (xy 59.837066 -288.427414) (xy 59.832595 -288.418907)
			(xy 59.818571 -288.405789) (xy 59.800695 -288.398774) (xy 59.791092 -288.398458) (xy 58.558684 -288.398458)
			(xy 58.549102 -288.398876) (xy 58.531271 -288.405906) (xy 58.517232 -288.418955) (xy 58.51271 -288.427414)
			(xy 58.473594 -288.510472) (xy 58.469829 -288.519337) (xy 58.468543 -288.538537) (xy 58.474431 -288.556859)
			(xy 58.480198 -288.564574) (xy 58.497854 -288.586964) (xy 58.526011 -288.636542) (xy 58.545265 -288.690208)
			(xy 58.555046 -288.746378) (xy 58.555636 -288.774886) (xy 58.555126 -288.800873) (xy 58.546996 -288.852208)
			(xy 58.530935 -288.901638) (xy 58.507339 -288.947948) (xy 58.476789 -288.989996) (xy 58.440038 -289.026747)
			(xy 58.39799 -289.057297) (xy 58.35168 -289.080893) (xy 58.30225 -289.096954) (xy 58.250915 -289.105084)
			(xy 58.198941 -289.105084) (xy 58.147606 -289.096954) (xy 58.098176 -289.080893) (xy 58.051866 -289.057297)
			(xy 58.009818 -289.026747) (xy 57.973067 -288.989996) (xy 57.942517 -288.947948) (xy 57.918921 -288.901638)
			(xy 57.90286 -288.852208) (xy 57.89473 -288.800873) (xy 57.89422 -288.774886) (xy 57.894818 -288.746379)
			(xy 57.904592 -288.690209) (xy 57.923849 -288.636546) (xy 57.952019 -288.586977) (xy 57.969658 -288.564574)
			(xy 57.975453 -288.55688) (xy 57.981327 -288.538551) (xy 57.980004 -288.51935) (xy 57.976262 -288.510472)
			(xy 57.937146 -288.427414) (xy 57.932674 -288.418909) (xy 57.918649 -288.405797) (xy 57.900774 -288.398789)
			(xy 57.891172 -288.398458) (xy 57.608724 -288.398458) (xy 57.599138 -288.398869) (xy 57.581295 -288.405891)
			(xy 57.567245 -288.418938) (xy 57.56275 -288.427414) (xy 57.523634 -288.510472) (xy 57.519872 -288.519337)
			(xy 57.518588 -288.538538) (xy 57.52447 -288.55686) (xy 57.530238 -288.564574) (xy 57.547897 -288.586963)
			(xy 57.576059 -288.636539) (xy 57.595317 -288.690206) (xy 57.605099 -288.746378) (xy 57.605676 -288.774886)
			(xy 57.605166 -288.800873) (xy 57.597036 -288.852208) (xy 57.580975 -288.901638) (xy 57.557379 -288.947948)
			(xy 57.526829 -288.989996) (xy 57.490078 -289.026747) (xy 57.44803 -289.057297) (xy 57.40172 -289.080893)
			(xy 57.35229 -289.096954) (xy 57.300955 -289.105084) (xy 57.248981 -289.105084) (xy 57.197646 -289.096954)
			(xy 57.148216 -289.080893) (xy 57.101906 -289.057297) (xy 57.059858 -289.026747) (xy 57.023107 -288.989996)
			(xy 56.992557 -288.947948) (xy 56.968961 -288.901638) (xy 56.9529 -288.852208) (xy 56.94477 -288.800873)
			(xy 56.94426 -288.774886) (xy 56.944857 -288.746379) (xy 56.95463 -288.690208) (xy 56.973884 -288.636542)
			(xy 57.00205 -288.586971) (xy 57.019698 -288.564574) (xy 57.025499 -288.556882) (xy 57.03138 -288.538552)
			(xy 57.030055 -288.519347) (xy 57.026302 -288.510472) (xy 56.987186 -288.427414) (xy 56.982711 -288.418916)
			(xy 56.968683 -288.40582) (xy 56.95081 -288.398833) (xy 56.941212 -288.398458) (xy 56.65851 -288.398458)
			(xy 56.648925 -288.398871) (xy 56.631087 -288.405896) (xy 56.61704 -288.418944) (xy 56.612536 -288.427414)
			(xy 56.57342 -288.510472) (xy 56.569653 -288.519336) (xy 56.568367 -288.538537) (xy 56.574257 -288.556858)
			(xy 56.580024 -288.564574) (xy 56.597683 -288.586963) (xy 56.625847 -288.636539) (xy 56.645105 -288.690206)
			(xy 56.654889 -288.746377) (xy 56.655462 -288.774886) (xy 56.654952 -288.800873) (xy 56.646822 -288.852208)
			(xy 56.630761 -288.901638) (xy 56.607165 -288.947948) (xy 56.576615 -288.989996) (xy 56.539864 -289.026747)
			(xy 56.497816 -289.057297) (xy 56.451506 -289.080893) (xy 56.402076 -289.096954) (xy 56.350741 -289.105084)
			(xy 56.298767 -289.105084) (xy 56.247432 -289.096954) (xy 56.198002 -289.080893) (xy 56.151692 -289.057297)
			(xy 56.109644 -289.026747) (xy 56.072893 -288.989996) (xy 56.042343 -288.947948) (xy 56.018747 -288.901638)
			(xy 56.002686 -288.852208) (xy 55.994556 -288.800873) (xy 55.994046 -288.774886) (xy 55.994643 -288.746379)
			(xy 56.004416 -288.690207) (xy 56.023669 -288.636542) (xy 56.051834 -288.586969) (xy 56.069484 -288.564574)
			(xy 56.075286 -288.556882) (xy 56.081169 -288.538552) (xy 56.079844 -288.519347) (xy 56.076088 -288.510472)
			(xy 56.036972 -288.427414) (xy 56.032501 -288.418906) (xy 56.018477 -288.405787) (xy 56.000601 -288.39877)
			(xy 55.990998 -288.398458) (xy 55.70855 -288.398458) (xy 55.698961 -288.398865) (xy 55.681111 -288.405881)
			(xy 55.667053 -288.418927) (xy 55.662576 -288.427414) (xy 55.62346 -288.510472) (xy 55.619697 -288.519337)
			(xy 55.618412 -288.538538) (xy 55.624296 -288.55686) (xy 55.630064 -288.564574) (xy 55.647722 -288.586963)
			(xy 55.675882 -288.63654) (xy 55.695138 -288.690207) (xy 55.70492 -288.746378) (xy 55.705502 -288.774886)
			(xy 55.704992 -288.800873) (xy 55.696862 -288.852208) (xy 55.680801 -288.901638) (xy 55.657205 -288.947948)
			(xy 55.626655 -288.989996) (xy 55.589904 -289.026747) (xy 55.547856 -289.057297) (xy 55.501546 -289.080893)
			(xy 55.452116 -289.096954) (xy 55.400781 -289.105084) (xy 55.348807 -289.105084) (xy 55.297472 -289.096954)
			(xy 55.248042 -289.080893) (xy 55.201732 -289.057297) (xy 55.159684 -289.026747) (xy 55.122933 -288.989996)
			(xy 55.092383 -288.947948) (xy 55.068787 -288.901638) (xy 55.052726 -288.852208) (xy 55.044596 -288.800873)
			(xy 55.044086 -288.774886) (xy 55.044683 -288.746379) (xy 55.054457 -288.690208) (xy 55.073712 -288.636544)
			(xy 55.10188 -288.586973) (xy 55.119524 -288.564574) (xy 55.125323 -288.556881) (xy 55.131201 -288.538552)
			(xy 55.129877 -288.519349) (xy 55.126128 -288.510472) (xy 55.087012 -288.427414) (xy 55.082538 -288.418913)
			(xy 55.068512 -288.40581) (xy 55.050637 -288.398814) (xy 55.041038 -288.398458) (xy 54.75859 -288.398458)
			(xy 54.749007 -288.398875) (xy 54.731175 -288.405904) (xy 54.717134 -288.418952) (xy 54.712616 -288.427414)
			(xy 54.6735 -288.510472) (xy 54.669735 -288.519336) (xy 54.668449 -288.538537) (xy 54.674337 -288.556858)
			(xy 54.680104 -288.564574) (xy 54.69776 -288.586964) (xy 54.725917 -288.636542) (xy 54.74517 -288.690208)
			(xy 54.754951 -288.746378) (xy 54.755542 -288.774886) (xy 54.755032 -288.800873) (xy 54.746902 -288.852208)
			(xy 54.730841 -288.901638) (xy 54.707245 -288.947948) (xy 54.676695 -288.989996) (xy 54.639944 -289.026747)
			(xy 54.597896 -289.057297) (xy 54.551586 -289.080893) (xy 54.502156 -289.096954) (xy 54.450821 -289.105084)
			(xy 54.398847 -289.105084) (xy 54.347512 -289.096954) (xy 54.298082 -289.080893) (xy 54.251772 -289.057297)
			(xy 54.209724 -289.026747) (xy 54.172973 -288.989996) (xy 54.142423 -288.947948) (xy 54.118827 -288.901638)
			(xy 54.102766 -288.852208) (xy 54.094636 -288.800873) (xy 54.094126 -288.774886) (xy 54.094724 -288.746379)
			(xy 54.104498 -288.690209) (xy 54.123755 -288.636546) (xy 54.151925 -288.586978) (xy 54.169564 -288.564574)
			(xy 54.175359 -288.55688) (xy 54.181232 -288.538551) (xy 54.179909 -288.519351) (xy 54.176168 -288.510472)
			(xy 54.137052 -288.427414) (xy 54.13258 -288.418908) (xy 54.118555 -288.405794) (xy 54.10068 -288.398785)
			(xy 54.091078 -288.398458) (xy 53.80863 -288.398458) (xy 53.799043 -288.398868) (xy 53.781199 -288.405888)
			(xy 53.767147 -288.418935) (xy 53.762656 -288.427414) (xy 53.72354 -288.510472) (xy 53.719778 -288.519337)
			(xy 53.718493 -288.538538) (xy 53.724376 -288.55686) (xy 53.730144 -288.564574) (xy 53.747803 -288.586963)
			(xy 53.775965 -288.63654) (xy 53.795221 -288.690206) (xy 53.805004 -288.746378) (xy 53.805582 -288.774886)
			(xy 53.805072 -288.800873) (xy 53.796942 -288.852208) (xy 53.780881 -288.901638) (xy 53.757285 -288.947948)
			(xy 53.726735 -288.989996) (xy 53.689984 -289.026747) (xy 53.647936 -289.057297) (xy 53.601626 -289.080893)
			(xy 53.552196 -289.096954) (xy 53.500861 -289.105084) (xy 53.448887 -289.105084) (xy 53.397552 -289.096954)
			(xy 53.348122 -289.080893) (xy 53.301812 -289.057297) (xy 53.259764 -289.026747) (xy 53.223013 -288.989996)
			(xy 53.192463 -288.947948) (xy 53.168867 -288.901638) (xy 53.152806 -288.852208) (xy 53.144676 -288.800873)
			(xy 53.144166 -288.774886) (xy 53.144763 -288.746379) (xy 53.154536 -288.690208) (xy 53.173791 -288.636543)
			(xy 53.201957 -288.586971) (xy 53.219604 -288.564574) (xy 53.225405 -288.556882) (xy 53.231285 -288.538552)
			(xy 53.229961 -288.519348) (xy 53.226208 -288.510472) (xy 53.187092 -288.427414) (xy 53.182618 -288.418915)
			(xy 53.16859 -288.405818) (xy 53.150716 -288.398828) (xy 53.141118 -288.398458) (xy 52.85867 -288.398458)
			(xy 52.849089 -288.398878) (xy 52.831262 -288.405911) (xy 52.817228 -288.418961) (xy 52.812696 -288.427414)
			(xy 52.77358 -288.510472) (xy 52.769816 -288.519337) (xy 52.76853 -288.538538) (xy 52.774417 -288.556859)
			(xy 52.780184 -288.564574) (xy 52.797841 -288.586964) (xy 52.825999 -288.636541) (xy 52.845254 -288.690208)
			(xy 52.855035 -288.746378) (xy 52.855622 -288.774886) (xy 52.855112 -288.800873) (xy 52.846982 -288.852208)
			(xy 52.830921 -288.901638) (xy 52.807325 -288.947948) (xy 52.776775 -288.989996) (xy 52.740024 -289.026747)
			(xy 52.697976 -289.057297) (xy 52.651666 -289.080893) (xy 52.602236 -289.096954) (xy 52.550901 -289.105084)
			(xy 52.498927 -289.105084) (xy 52.447592 -289.096954) (xy 52.398162 -289.080893) (xy 52.351852 -289.057297)
			(xy 52.309804 -289.026747) (xy 52.273053 -288.989996) (xy 52.242503 -288.947948) (xy 52.218907 -288.901638)
			(xy 52.202846 -288.852208) (xy 52.194716 -288.800873) (xy 52.194206 -288.774886) (xy 52.194803 -288.746379)
			(xy 52.204577 -288.690209) (xy 52.223834 -288.636545) (xy 52.252003 -288.586975) (xy 52.269644 -288.564574)
			(xy 52.275441 -288.55688) (xy 52.281316 -288.538552) (xy 52.279993 -288.51935) (xy 52.276248 -288.510472)
			(xy 52.237132 -288.427414) (xy 52.23266 -288.418911) (xy 52.218634 -288.405802) (xy 52.200759 -288.398799)
			(xy 52.191158 -288.398458) (xy 51.90871 -288.398458) (xy 51.899125 -288.398871) (xy 51.881287 -288.405896)
			(xy 51.86724 -288.418944) (xy 51.862736 -288.427414) (xy 51.82362 -288.510472) (xy 51.819853 -288.519336)
			(xy 51.818567 -288.538537) (xy 51.824457 -288.556858) (xy 51.830224 -288.564574) (xy 51.847883 -288.586963)
			(xy 51.876047 -288.636539) (xy 51.895305 -288.690206) (xy 51.905089 -288.746377) (xy 51.905662 -288.774886)
			(xy 51.905152 -288.800873) (xy 51.897022 -288.852208) (xy 51.880961 -288.901638) (xy 51.857365 -288.947948)
			(xy 51.826815 -288.989996) (xy 51.790064 -289.026747) (xy 51.748016 -289.057297) (xy 51.701706 -289.080893)
			(xy 51.652276 -289.096954) (xy 51.600941 -289.105084) (xy 51.548967 -289.105084) (xy 51.497632 -289.096954)
			(xy 51.448202 -289.080893) (xy 51.401892 -289.057297) (xy 51.359844 -289.026747) (xy 51.323093 -288.989996)
			(xy 51.292543 -288.947948) (xy 51.268947 -288.901638) (xy 51.252886 -288.852208) (xy 51.244756 -288.800873)
			(xy 51.244246 -288.774886) (xy 51.244843 -288.746379) (xy 51.254616 -288.690207) (xy 51.273869 -288.636542)
			(xy 51.302034 -288.586969) (xy 51.319684 -288.564574) (xy 51.325486 -288.556882) (xy 51.331369 -288.538552)
			(xy 51.330044 -288.519347) (xy 51.326288 -288.510472) (xy 51.287172 -288.427414) (xy 51.282701 -288.418906)
			(xy 51.268677 -288.405787) (xy 51.250801 -288.39877) (xy 51.241198 -288.398458) (xy 50.95875 -288.398458)
			(xy 50.949161 -288.398865) (xy 50.931311 -288.405881) (xy 50.917253 -288.418927) (xy 50.912776 -288.427414)
			(xy 50.87366 -288.510472) (xy 50.869897 -288.519337) (xy 50.868612 -288.538538) (xy 50.874496 -288.55686)
			(xy 50.880264 -288.564574) (xy 50.897922 -288.586963) (xy 50.926082 -288.63654) (xy 50.945338 -288.690207)
			(xy 50.95512 -288.746378) (xy 50.955702 -288.774886) (xy 50.955192 -288.800873) (xy 50.947062 -288.852208)
			(xy 50.931001 -288.901638) (xy 50.907405 -288.947948) (xy 50.876855 -288.989996) (xy 50.840104 -289.026747)
			(xy 50.798056 -289.057297) (xy 50.751746 -289.080893) (xy 50.702316 -289.096954) (xy 50.650981 -289.105084)
			(xy 50.599007 -289.105084) (xy 50.547672 -289.096954) (xy 50.498242 -289.080893) (xy 50.451932 -289.057297)
			(xy 50.409884 -289.026747) (xy 50.373133 -288.989996) (xy 50.342583 -288.947948) (xy 50.318987 -288.901638)
			(xy 50.302926 -288.852208) (xy 50.294796 -288.800873) (xy 50.294286 -288.774886) (xy 50.294883 -288.746379)
			(xy 50.304657 -288.690208) (xy 50.323912 -288.636544) (xy 50.35208 -288.586973) (xy 50.369724 -288.564574)
			(xy 50.375523 -288.556881) (xy 50.381401 -288.538552) (xy 50.380077 -288.519349) (xy 50.376328 -288.510472)
			(xy 50.337212 -288.427414) (xy 50.332738 -288.418913) (xy 50.318712 -288.40581) (xy 50.300837 -288.398814)
			(xy 50.291238 -288.398458) (xy 50.082704 -288.398458) (xy 50.072635 -288.398882) (xy 50.054035 -288.406602)
			(xy 50.046636 -288.413444) (xy 49.933352 -288.526728) (xy 49.930304 -288.564066) (xy 49.94148 -288.579306)
			(xy 49.95656 -288.600705) (xy 49.980484 -288.647266) (xy 49.996768 -288.697017) (xy 50.005007 -288.748712)
			(xy 50.005488 -288.774886) (xy 50.005006 -288.800875) (xy 49.996876 -288.852215) (xy 49.980815 -288.90165)
			(xy 49.957218 -288.947963) (xy 49.926665 -288.990015) (xy 49.88991 -289.026769) (xy 49.847858 -289.057321)
			(xy 49.801544 -289.080917) (xy 49.752109 -289.096978) (xy 49.700769 -289.105106) (xy 49.67478 -289.105594)
			(xy 49.648607 -289.105095) (xy 49.596916 -289.096851) (xy 49.547166 -289.080571) (xy 49.500601 -289.056661)
			(xy 49.4792 -289.041586) (xy 49.46396 -289.03041) (xy 49.426622 -289.033458) (xy 49.116234 -289.343846)
			(xy 49.108835 -289.350688) (xy 49.090236 -289.358407) (xy 49.080166 -289.358832) (xy 49.066958 -289.358832)
			(xy 49.057465 -289.359221) (xy 49.039771 -289.366107) (xy 49.025768 -289.378929) (xy 49.021238 -289.38728)
			(xy 48.981106 -289.469068) (xy 48.977357 -289.477681) (xy 48.975697 -289.496376) (xy 48.980855 -289.514421)
			(xy 48.986186 -289.522154) (xy 48.98644 -289.522662) (xy 48.98644 -289.522916) (xy 49.002648 -289.544745)
			(xy 49.028442 -289.5926) (xy 49.046039 -289.644037) (xy 49.054963 -289.697664) (xy 49.055528 -289.724846)
			(xy 49.368976 -289.724846) (xy 49.372936 -289.675792) (xy 49.384713 -289.628008) (xy 49.404004 -289.582732)
			(xy 49.430307 -289.541136) (xy 49.462942 -289.504299) (xy 49.501063 -289.473174) (xy 49.543684 -289.448567)
			(xy 49.5897 -289.431115) (xy 49.637919 -289.421271) (xy 49.687094 -289.41929) (xy 49.735949 -289.425222)
			(xy 49.78322 -289.438914) (xy 49.827682 -289.460012) (xy 49.868185 -289.487968) (xy 49.903678 -289.52206)
			(xy 49.933243 -289.561404) (xy 49.956114 -289.604981) (xy 49.971698 -289.651662) (xy 49.979593 -289.700239)
			(xy 49.980088 -289.724846) (xy 50.31919 -289.724846) (xy 50.32315 -289.675792) (xy 50.334927 -289.628008)
			(xy 50.354218 -289.582732) (xy 50.380521 -289.541136) (xy 50.413156 -289.504299) (xy 50.451277 -289.473174)
			(xy 50.493898 -289.448567) (xy 50.539914 -289.431115) (xy 50.588133 -289.421271) (xy 50.637308 -289.41929)
			(xy 50.686163 -289.425222) (xy 50.733434 -289.438914) (xy 50.777896 -289.460012) (xy 50.818399 -289.487968)
			(xy 50.853892 -289.52206) (xy 50.883457 -289.561404) (xy 50.906328 -289.604981) (xy 50.921912 -289.651662)
			(xy 50.929807 -289.700239) (xy 50.930302 -289.724846) (xy 51.26915 -289.724846) (xy 51.27311 -289.675792)
			(xy 51.284887 -289.628008) (xy 51.304178 -289.582732) (xy 51.330481 -289.541136) (xy 51.363116 -289.504299)
			(xy 51.401237 -289.473174) (xy 51.443858 -289.448567) (xy 51.489874 -289.431115) (xy 51.538093 -289.421271)
			(xy 51.587268 -289.41929) (xy 51.636123 -289.425222) (xy 51.683394 -289.438914) (xy 51.727856 -289.460012)
			(xy 51.768359 -289.487968) (xy 51.803852 -289.52206) (xy 51.833417 -289.561404) (xy 51.856288 -289.604981)
			(xy 51.871872 -289.651662) (xy 51.879767 -289.700239) (xy 51.880262 -289.724846) (xy 52.21911 -289.724846)
			(xy 52.22307 -289.675792) (xy 52.234847 -289.628008) (xy 52.254138 -289.582732) (xy 52.280441 -289.541136)
			(xy 52.313076 -289.504299) (xy 52.351197 -289.473174) (xy 52.393818 -289.448567) (xy 52.439834 -289.431115)
			(xy 52.488053 -289.421271) (xy 52.537228 -289.41929) (xy 52.586083 -289.425222) (xy 52.633354 -289.438914)
			(xy 52.677816 -289.460012) (xy 52.718319 -289.487968) (xy 52.753812 -289.52206) (xy 52.783377 -289.561404)
			(xy 52.806248 -289.604981) (xy 52.821832 -289.651662) (xy 52.829727 -289.700239) (xy 52.830222 -289.724846)
			(xy 53.16907 -289.724846) (xy 53.17303 -289.675792) (xy 53.184807 -289.628008) (xy 53.204098 -289.582732)
			(xy 53.230401 -289.541136) (xy 53.263036 -289.504299) (xy 53.301157 -289.473174) (xy 53.343778 -289.448567)
			(xy 53.389794 -289.431115) (xy 53.438013 -289.421271) (xy 53.487188 -289.41929) (xy 53.536043 -289.425222)
			(xy 53.583314 -289.438914) (xy 53.627776 -289.460012) (xy 53.668279 -289.487968) (xy 53.703772 -289.52206)
			(xy 53.733337 -289.561404) (xy 53.756208 -289.604981) (xy 53.771792 -289.651662) (xy 53.779687 -289.700239)
			(xy 53.780182 -289.724846) (xy 54.11903 -289.724846) (xy 54.12299 -289.675792) (xy 54.134767 -289.628008)
			(xy 54.154058 -289.582732) (xy 54.180361 -289.541136) (xy 54.212996 -289.504299) (xy 54.251117 -289.473174)
			(xy 54.293738 -289.448567) (xy 54.339754 -289.431115) (xy 54.387973 -289.421271) (xy 54.437148 -289.41929)
			(xy 54.486003 -289.425222) (xy 54.533274 -289.438914) (xy 54.577736 -289.460012) (xy 54.618239 -289.487968)
			(xy 54.653732 -289.52206) (xy 54.683297 -289.561404) (xy 54.706168 -289.604981) (xy 54.721752 -289.651662)
			(xy 54.729647 -289.700239) (xy 54.730142 -289.724846) (xy 55.06899 -289.724846) (xy 55.07295 -289.675792)
			(xy 55.084727 -289.628008) (xy 55.104018 -289.582732) (xy 55.130321 -289.541136) (xy 55.162956 -289.504299)
			(xy 55.201077 -289.473174) (xy 55.243698 -289.448567) (xy 55.289714 -289.431115) (xy 55.337933 -289.421271)
			(xy 55.387108 -289.41929) (xy 55.435963 -289.425222) (xy 55.483234 -289.438914) (xy 55.527696 -289.460012)
			(xy 55.568199 -289.487968) (xy 55.603692 -289.52206) (xy 55.633257 -289.561404) (xy 55.656128 -289.604981)
			(xy 55.671712 -289.651662) (xy 55.679607 -289.700239) (xy 55.680102 -289.724846) (xy 56.01895 -289.724846)
			(xy 56.02291 -289.675792) (xy 56.034687 -289.628008) (xy 56.053978 -289.582732) (xy 56.080281 -289.541136)
			(xy 56.112916 -289.504299) (xy 56.151037 -289.473174) (xy 56.193658 -289.448567) (xy 56.239674 -289.431115)
			(xy 56.287893 -289.421271) (xy 56.337068 -289.41929) (xy 56.385923 -289.425222) (xy 56.433194 -289.438914)
			(xy 56.477656 -289.460012) (xy 56.518159 -289.487968) (xy 56.553652 -289.52206) (xy 56.583217 -289.561404)
			(xy 56.606088 -289.604981) (xy 56.621672 -289.651662) (xy 56.629567 -289.700239) (xy 56.630062 -289.724846)
			(xy 56.969164 -289.724846) (xy 56.973124 -289.675792) (xy 56.984901 -289.628008) (xy 57.004192 -289.582732)
			(xy 57.030495 -289.541136) (xy 57.06313 -289.504299) (xy 57.101251 -289.473174) (xy 57.143872 -289.448567)
			(xy 57.189888 -289.431115) (xy 57.238107 -289.421271) (xy 57.287282 -289.41929) (xy 57.336137 -289.425222)
			(xy 57.383408 -289.438914) (xy 57.42787 -289.460012) (xy 57.468373 -289.487968) (xy 57.503866 -289.52206)
			(xy 57.533431 -289.561404) (xy 57.556302 -289.604981) (xy 57.571886 -289.651662) (xy 57.579781 -289.700239)
			(xy 57.580276 -289.724846) (xy 57.919124 -289.724846) (xy 57.923084 -289.675792) (xy 57.934861 -289.628008)
			(xy 57.954152 -289.582732) (xy 57.980455 -289.541136) (xy 58.01309 -289.504299) (xy 58.051211 -289.473174)
			(xy 58.093832 -289.448567) (xy 58.139848 -289.431115) (xy 58.188067 -289.421271) (xy 58.237242 -289.41929)
			(xy 58.286097 -289.425222) (xy 58.333368 -289.438914) (xy 58.37783 -289.460012) (xy 58.418333 -289.487968)
			(xy 58.453826 -289.52206) (xy 58.483391 -289.561404) (xy 58.506262 -289.604981) (xy 58.521846 -289.651662)
			(xy 58.529741 -289.700239) (xy 58.530236 -289.724846) (xy 59.819044 -289.724846) (xy 59.823004 -289.675792)
			(xy 59.834781 -289.628008) (xy 59.854072 -289.582732) (xy 59.880375 -289.541136) (xy 59.91301 -289.504299)
			(xy 59.951131 -289.473174) (xy 59.993752 -289.448567) (xy 60.039768 -289.431115) (xy 60.087987 -289.421271)
			(xy 60.137162 -289.41929) (xy 60.186017 -289.425222) (xy 60.233288 -289.438914) (xy 60.27775 -289.460012)
			(xy 60.318253 -289.487968) (xy 60.353746 -289.52206) (xy 60.383311 -289.561404) (xy 60.406182 -289.604981)
			(xy 60.421766 -289.651662) (xy 60.429661 -289.700239) (xy 60.430156 -289.724846) (xy 60.769004 -289.724846)
			(xy 60.772964 -289.675792) (xy 60.784741 -289.628008) (xy 60.804032 -289.582732) (xy 60.830335 -289.541136)
			(xy 60.86297 -289.504299) (xy 60.901091 -289.473174) (xy 60.943712 -289.448567) (xy 60.989728 -289.431115)
			(xy 61.037947 -289.421271) (xy 61.087122 -289.41929) (xy 61.135977 -289.425222) (xy 61.183248 -289.438914)
			(xy 61.22771 -289.460012) (xy 61.268213 -289.487968) (xy 61.303706 -289.52206) (xy 61.333271 -289.561404)
			(xy 61.356142 -289.604981) (xy 61.371726 -289.651662) (xy 61.379621 -289.700239) (xy 61.380116 -289.724846)
			(xy 61.718964 -289.724846) (xy 61.722924 -289.675792) (xy 61.734701 -289.628008) (xy 61.753992 -289.582732)
			(xy 61.780295 -289.541136) (xy 61.81293 -289.504299) (xy 61.851051 -289.473174) (xy 61.893672 -289.448567)
			(xy 61.939688 -289.431115) (xy 61.987907 -289.421271) (xy 62.037082 -289.41929) (xy 62.085937 -289.425222)
			(xy 62.133208 -289.438914) (xy 62.17767 -289.460012) (xy 62.218173 -289.487968) (xy 62.253666 -289.52206)
			(xy 62.283231 -289.561404) (xy 62.306102 -289.604981) (xy 62.321686 -289.651662) (xy 62.329581 -289.700239)
			(xy 62.330076 -289.724846) (xy 62.669178 -289.724846) (xy 62.673138 -289.675792) (xy 62.684915 -289.628008)
			(xy 62.704206 -289.582732) (xy 62.730509 -289.541136) (xy 62.763144 -289.504299) (xy 62.801265 -289.473174)
			(xy 62.843886 -289.448567) (xy 62.889902 -289.431115) (xy 62.938121 -289.421271) (xy 62.987296 -289.41929)
			(xy 63.036151 -289.425222) (xy 63.083422 -289.438914) (xy 63.127884 -289.460012) (xy 63.168387 -289.487968)
			(xy 63.20388 -289.52206) (xy 63.233445 -289.561404) (xy 63.256316 -289.604981) (xy 63.2719 -289.651662)
			(xy 63.279795 -289.700239) (xy 63.28029 -289.724846) (xy 63.619138 -289.724846) (xy 63.623098 -289.675792)
			(xy 63.634875 -289.628008) (xy 63.654166 -289.582732) (xy 63.680469 -289.541136) (xy 63.713104 -289.504299)
			(xy 63.751225 -289.473174) (xy 63.793846 -289.448567) (xy 63.839862 -289.431115) (xy 63.888081 -289.421271)
			(xy 63.937256 -289.41929) (xy 63.986111 -289.425222) (xy 64.033382 -289.438914) (xy 64.077844 -289.460012)
			(xy 64.118347 -289.487968) (xy 64.15384 -289.52206) (xy 64.183405 -289.561404) (xy 64.206276 -289.604981)
			(xy 64.22186 -289.651662) (xy 64.229755 -289.700239) (xy 64.23025 -289.724846) (xy 64.569098 -289.724846)
			(xy 64.573058 -289.675792) (xy 64.584835 -289.628008) (xy 64.604126 -289.582732) (xy 64.630429 -289.541136)
			(xy 64.663064 -289.504299) (xy 64.701185 -289.473174) (xy 64.743806 -289.448567) (xy 64.789822 -289.431115)
			(xy 64.838041 -289.421271) (xy 64.887216 -289.41929) (xy 64.936071 -289.425222) (xy 64.983342 -289.438914)
			(xy 65.027804 -289.460012) (xy 65.068307 -289.487968) (xy 65.1038 -289.52206) (xy 65.133365 -289.561404)
			(xy 65.156236 -289.604981) (xy 65.17182 -289.651662) (xy 65.179715 -289.700239) (xy 65.18021 -289.724846)
			(xy 65.519058 -289.724846) (xy 65.523018 -289.675792) (xy 65.534795 -289.628008) (xy 65.554086 -289.582732)
			(xy 65.580389 -289.541136) (xy 65.613024 -289.504299) (xy 65.651145 -289.473174) (xy 65.693766 -289.448567)
			(xy 65.739782 -289.431115) (xy 65.788001 -289.421271) (xy 65.837176 -289.41929) (xy 65.886031 -289.425222)
			(xy 65.933302 -289.438914) (xy 65.977764 -289.460012) (xy 66.018267 -289.487968) (xy 66.05376 -289.52206)
			(xy 66.083325 -289.561404) (xy 66.106196 -289.604981) (xy 66.12178 -289.651662) (xy 66.129675 -289.700239)
			(xy 66.13017 -289.724846) (xy 66.469018 -289.724846) (xy 66.472978 -289.675792) (xy 66.484755 -289.628008)
			(xy 66.504046 -289.582732) (xy 66.530349 -289.541136) (xy 66.562984 -289.504299) (xy 66.601105 -289.473174)
			(xy 66.643726 -289.448567) (xy 66.689742 -289.431115) (xy 66.737961 -289.421271) (xy 66.787136 -289.41929)
			(xy 66.835991 -289.425222) (xy 66.883262 -289.438914) (xy 66.927724 -289.460012) (xy 66.968227 -289.487968)
			(xy 67.00372 -289.52206) (xy 67.033285 -289.561404) (xy 67.056156 -289.604981) (xy 67.07174 -289.651662)
			(xy 67.079635 -289.700239) (xy 67.08013 -289.724846) (xy 67.418978 -289.724846) (xy 67.422938 -289.675792)
			(xy 67.434715 -289.628008) (xy 67.454006 -289.582732) (xy 67.480309 -289.541136) (xy 67.512944 -289.504299)
			(xy 67.551065 -289.473174) (xy 67.593686 -289.448567) (xy 67.639702 -289.431115) (xy 67.687921 -289.421271)
			(xy 67.737096 -289.41929) (xy 67.785951 -289.425222) (xy 67.833222 -289.438914) (xy 67.877684 -289.460012)
			(xy 67.918187 -289.487968) (xy 67.95368 -289.52206) (xy 67.983245 -289.561404) (xy 68.006116 -289.604981)
			(xy 68.0217 -289.651662) (xy 68.029595 -289.700239) (xy 68.03009 -289.724846) (xy 68.368938 -289.724846)
			(xy 68.372898 -289.675792) (xy 68.384675 -289.628008) (xy 68.403966 -289.582732) (xy 68.430269 -289.541136)
			(xy 68.462904 -289.504299) (xy 68.501025 -289.473174) (xy 68.543646 -289.448567) (xy 68.589662 -289.431115)
			(xy 68.637881 -289.421271) (xy 68.687056 -289.41929) (xy 68.735911 -289.425222) (xy 68.783182 -289.438914)
			(xy 68.827644 -289.460012) (xy 68.868147 -289.487968) (xy 68.90364 -289.52206) (xy 68.933205 -289.561404)
			(xy 68.956076 -289.604981) (xy 68.97166 -289.651662) (xy 68.979555 -289.700239) (xy 68.98005 -289.724846)
			(xy 68.979555 -289.749453) (xy 68.97166 -289.79803) (xy 68.956076 -289.844711) (xy 68.933205 -289.888288)
			(xy 68.90364 -289.927632) (xy 68.868147 -289.961724) (xy 68.827644 -289.98968) (xy 68.783182 -290.010778)
			(xy 68.735911 -290.02447) (xy 68.687056 -290.030402) (xy 68.637881 -290.028421) (xy 68.589662 -290.018577)
			(xy 68.543646 -290.001125) (xy 68.501025 -289.976518) (xy 68.462904 -289.945393) (xy 68.430269 -289.908556)
			(xy 68.403966 -289.86696) (xy 68.384675 -289.821684) (xy 68.372898 -289.7739) (xy 68.368938 -289.724846)
			(xy 68.03009 -289.724846) (xy 68.029595 -289.749453) (xy 68.0217 -289.79803) (xy 68.006116 -289.844711)
			(xy 67.983245 -289.888288) (xy 67.95368 -289.927632) (xy 67.918187 -289.961724) (xy 67.877684 -289.98968)
			(xy 67.833222 -290.010778) (xy 67.785951 -290.02447) (xy 67.737096 -290.030402) (xy 67.687921 -290.028421)
			(xy 67.639702 -290.018577) (xy 67.593686 -290.001125) (xy 67.551065 -289.976518) (xy 67.512944 -289.945393)
			(xy 67.480309 -289.908556) (xy 67.454006 -289.86696) (xy 67.434715 -289.821684) (xy 67.422938 -289.7739)
			(xy 67.418978 -289.724846) (xy 67.08013 -289.724846) (xy 67.079635 -289.749453) (xy 67.07174 -289.79803)
			(xy 67.056156 -289.844711) (xy 67.033285 -289.888288) (xy 67.00372 -289.927632) (xy 66.968227 -289.961724)
			(xy 66.927724 -289.98968) (xy 66.883262 -290.010778) (xy 66.835991 -290.02447) (xy 66.787136 -290.030402)
			(xy 66.737961 -290.028421) (xy 66.689742 -290.018577) (xy 66.643726 -290.001125) (xy 66.601105 -289.976518)
			(xy 66.562984 -289.945393) (xy 66.530349 -289.908556) (xy 66.504046 -289.86696) (xy 66.484755 -289.821684)
			(xy 66.472978 -289.7739) (xy 66.469018 -289.724846) (xy 66.13017 -289.724846) (xy 66.129675 -289.749453)
			(xy 66.12178 -289.79803) (xy 66.106196 -289.844711) (xy 66.083325 -289.888288) (xy 66.05376 -289.927632)
			(xy 66.018267 -289.961724) (xy 65.977764 -289.98968) (xy 65.933302 -290.010778) (xy 65.886031 -290.02447)
			(xy 65.837176 -290.030402) (xy 65.788001 -290.028421) (xy 65.739782 -290.018577) (xy 65.693766 -290.001125)
			(xy 65.651145 -289.976518) (xy 65.613024 -289.945393) (xy 65.580389 -289.908556) (xy 65.554086 -289.86696)
			(xy 65.534795 -289.821684) (xy 65.523018 -289.7739) (xy 65.519058 -289.724846) (xy 65.18021 -289.724846)
			(xy 65.179715 -289.749453) (xy 65.17182 -289.79803) (xy 65.156236 -289.844711) (xy 65.133365 -289.888288)
			(xy 65.1038 -289.927632) (xy 65.068307 -289.961724) (xy 65.027804 -289.98968) (xy 64.983342 -290.010778)
			(xy 64.936071 -290.02447) (xy 64.887216 -290.030402) (xy 64.838041 -290.028421) (xy 64.789822 -290.018577)
			(xy 64.743806 -290.001125) (xy 64.701185 -289.976518) (xy 64.663064 -289.945393) (xy 64.630429 -289.908556)
			(xy 64.604126 -289.86696) (xy 64.584835 -289.821684) (xy 64.573058 -289.7739) (xy 64.569098 -289.724846)
			(xy 64.23025 -289.724846) (xy 64.229755 -289.749453) (xy 64.22186 -289.79803) (xy 64.206276 -289.844711)
			(xy 64.183405 -289.888288) (xy 64.15384 -289.927632) (xy 64.118347 -289.961724) (xy 64.077844 -289.98968)
			(xy 64.033382 -290.010778) (xy 63.986111 -290.02447) (xy 63.937256 -290.030402) (xy 63.888081 -290.028421)
			(xy 63.839862 -290.018577) (xy 63.793846 -290.001125) (xy 63.751225 -289.976518) (xy 63.713104 -289.945393)
			(xy 63.680469 -289.908556) (xy 63.654166 -289.86696) (xy 63.634875 -289.821684) (xy 63.623098 -289.7739)
			(xy 63.619138 -289.724846) (xy 63.28029 -289.724846) (xy 63.279795 -289.749453) (xy 63.2719 -289.79803)
			(xy 63.256316 -289.844711) (xy 63.233445 -289.888288) (xy 63.20388 -289.927632) (xy 63.168387 -289.961724)
			(xy 63.127884 -289.98968) (xy 63.083422 -290.010778) (xy 63.036151 -290.02447) (xy 62.987296 -290.030402)
			(xy 62.938121 -290.028421) (xy 62.889902 -290.018577) (xy 62.843886 -290.001125) (xy 62.801265 -289.976518)
			(xy 62.763144 -289.945393) (xy 62.730509 -289.908556) (xy 62.704206 -289.86696) (xy 62.684915 -289.821684)
			(xy 62.673138 -289.7739) (xy 62.669178 -289.724846) (xy 62.330076 -289.724846) (xy 62.329581 -289.749453)
			(xy 62.321686 -289.79803) (xy 62.306102 -289.844711) (xy 62.283231 -289.888288) (xy 62.253666 -289.927632)
			(xy 62.218173 -289.961724) (xy 62.17767 -289.98968) (xy 62.133208 -290.010778) (xy 62.085937 -290.02447)
			(xy 62.037082 -290.030402) (xy 61.987907 -290.028421) (xy 61.939688 -290.018577) (xy 61.893672 -290.001125)
			(xy 61.851051 -289.976518) (xy 61.81293 -289.945393) (xy 61.780295 -289.908556) (xy 61.753992 -289.86696)
			(xy 61.734701 -289.821684) (xy 61.722924 -289.7739) (xy 61.718964 -289.724846) (xy 61.380116 -289.724846)
			(xy 61.379621 -289.749453) (xy 61.371726 -289.79803) (xy 61.356142 -289.844711) (xy 61.333271 -289.888288)
			(xy 61.303706 -289.927632) (xy 61.268213 -289.961724) (xy 61.22771 -289.98968) (xy 61.183248 -290.010778)
			(xy 61.135977 -290.02447) (xy 61.087122 -290.030402) (xy 61.037947 -290.028421) (xy 60.989728 -290.018577)
			(xy 60.943712 -290.001125) (xy 60.901091 -289.976518) (xy 60.86297 -289.945393) (xy 60.830335 -289.908556)
			(xy 60.804032 -289.86696) (xy 60.784741 -289.821684) (xy 60.772964 -289.7739) (xy 60.769004 -289.724846)
			(xy 60.430156 -289.724846) (xy 60.429661 -289.749453) (xy 60.421766 -289.79803) (xy 60.406182 -289.844711)
			(xy 60.383311 -289.888288) (xy 60.353746 -289.927632) (xy 60.318253 -289.961724) (xy 60.27775 -289.98968)
			(xy 60.233288 -290.010778) (xy 60.186017 -290.02447) (xy 60.137162 -290.030402) (xy 60.087987 -290.028421)
			(xy 60.039768 -290.018577) (xy 59.993752 -290.001125) (xy 59.951131 -289.976518) (xy 59.91301 -289.945393)
			(xy 59.880375 -289.908556) (xy 59.854072 -289.86696) (xy 59.834781 -289.821684) (xy 59.823004 -289.7739)
			(xy 59.819044 -289.724846) (xy 58.530236 -289.724846) (xy 58.529741 -289.749453) (xy 58.521846 -289.79803)
			(xy 58.506262 -289.844711) (xy 58.483391 -289.888288) (xy 58.453826 -289.927632) (xy 58.418333 -289.961724)
			(xy 58.37783 -289.98968) (xy 58.333368 -290.010778) (xy 58.286097 -290.02447) (xy 58.237242 -290.030402)
			(xy 58.188067 -290.028421) (xy 58.139848 -290.018577) (xy 58.093832 -290.001125) (xy 58.051211 -289.976518)
			(xy 58.01309 -289.945393) (xy 57.980455 -289.908556) (xy 57.954152 -289.86696) (xy 57.934861 -289.821684)
			(xy 57.923084 -289.7739) (xy 57.919124 -289.724846) (xy 57.580276 -289.724846) (xy 57.579781 -289.749453)
			(xy 57.571886 -289.79803) (xy 57.556302 -289.844711) (xy 57.533431 -289.888288) (xy 57.503866 -289.927632)
			(xy 57.468373 -289.961724) (xy 57.42787 -289.98968) (xy 57.383408 -290.010778) (xy 57.336137 -290.02447)
			(xy 57.287282 -290.030402) (xy 57.238107 -290.028421) (xy 57.189888 -290.018577) (xy 57.143872 -290.001125)
			(xy 57.101251 -289.976518) (xy 57.06313 -289.945393) (xy 57.030495 -289.908556) (xy 57.004192 -289.86696)
			(xy 56.984901 -289.821684) (xy 56.973124 -289.7739) (xy 56.969164 -289.724846) (xy 56.630062 -289.724846)
			(xy 56.629567 -289.749453) (xy 56.621672 -289.79803) (xy 56.606088 -289.844711) (xy 56.583217 -289.888288)
			(xy 56.553652 -289.927632) (xy 56.518159 -289.961724) (xy 56.477656 -289.98968) (xy 56.433194 -290.010778)
			(xy 56.385923 -290.02447) (xy 56.337068 -290.030402) (xy 56.287893 -290.028421) (xy 56.239674 -290.018577)
			(xy 56.193658 -290.001125) (xy 56.151037 -289.976518) (xy 56.112916 -289.945393) (xy 56.080281 -289.908556)
			(xy 56.053978 -289.86696) (xy 56.034687 -289.821684) (xy 56.02291 -289.7739) (xy 56.01895 -289.724846)
			(xy 55.680102 -289.724846) (xy 55.679607 -289.749453) (xy 55.671712 -289.79803) (xy 55.656128 -289.844711)
			(xy 55.633257 -289.888288) (xy 55.603692 -289.927632) (xy 55.568199 -289.961724) (xy 55.527696 -289.98968)
			(xy 55.483234 -290.010778) (xy 55.435963 -290.02447) (xy 55.387108 -290.030402) (xy 55.337933 -290.028421)
			(xy 55.289714 -290.018577) (xy 55.243698 -290.001125) (xy 55.201077 -289.976518) (xy 55.162956 -289.945393)
			(xy 55.130321 -289.908556) (xy 55.104018 -289.86696) (xy 55.084727 -289.821684) (xy 55.07295 -289.7739)
			(xy 55.06899 -289.724846) (xy 54.730142 -289.724846) (xy 54.729647 -289.749453) (xy 54.721752 -289.79803)
			(xy 54.706168 -289.844711) (xy 54.683297 -289.888288) (xy 54.653732 -289.927632) (xy 54.618239 -289.961724)
			(xy 54.577736 -289.98968) (xy 54.533274 -290.010778) (xy 54.486003 -290.02447) (xy 54.437148 -290.030402)
			(xy 54.387973 -290.028421) (xy 54.339754 -290.018577) (xy 54.293738 -290.001125) (xy 54.251117 -289.976518)
			(xy 54.212996 -289.945393) (xy 54.180361 -289.908556) (xy 54.154058 -289.86696) (xy 54.134767 -289.821684)
			(xy 54.12299 -289.7739) (xy 54.11903 -289.724846) (xy 53.780182 -289.724846) (xy 53.779687 -289.749453)
			(xy 53.771792 -289.79803) (xy 53.756208 -289.844711) (xy 53.733337 -289.888288) (xy 53.703772 -289.927632)
			(xy 53.668279 -289.961724) (xy 53.627776 -289.98968) (xy 53.583314 -290.010778) (xy 53.536043 -290.02447)
			(xy 53.487188 -290.030402) (xy 53.438013 -290.028421) (xy 53.389794 -290.018577) (xy 53.343778 -290.001125)
			(xy 53.301157 -289.976518) (xy 53.263036 -289.945393) (xy 53.230401 -289.908556) (xy 53.204098 -289.86696)
			(xy 53.184807 -289.821684) (xy 53.17303 -289.7739) (xy 53.16907 -289.724846) (xy 52.830222 -289.724846)
			(xy 52.829727 -289.749453) (xy 52.821832 -289.79803) (xy 52.806248 -289.844711) (xy 52.783377 -289.888288)
			(xy 52.753812 -289.927632) (xy 52.718319 -289.961724) (xy 52.677816 -289.98968) (xy 52.633354 -290.010778)
			(xy 52.586083 -290.02447) (xy 52.537228 -290.030402) (xy 52.488053 -290.028421) (xy 52.439834 -290.018577)
			(xy 52.393818 -290.001125) (xy 52.351197 -289.976518) (xy 52.313076 -289.945393) (xy 52.280441 -289.908556)
			(xy 52.254138 -289.86696) (xy 52.234847 -289.821684) (xy 52.22307 -289.7739) (xy 52.21911 -289.724846)
			(xy 51.880262 -289.724846) (xy 51.879767 -289.749453) (xy 51.871872 -289.79803) (xy 51.856288 -289.844711)
			(xy 51.833417 -289.888288) (xy 51.803852 -289.927632) (xy 51.768359 -289.961724) (xy 51.727856 -289.98968)
			(xy 51.683394 -290.010778) (xy 51.636123 -290.02447) (xy 51.587268 -290.030402) (xy 51.538093 -290.028421)
			(xy 51.489874 -290.018577) (xy 51.443858 -290.001125) (xy 51.401237 -289.976518) (xy 51.363116 -289.945393)
			(xy 51.330481 -289.908556) (xy 51.304178 -289.86696) (xy 51.284887 -289.821684) (xy 51.27311 -289.7739)
			(xy 51.26915 -289.724846) (xy 50.930302 -289.724846) (xy 50.929807 -289.749453) (xy 50.921912 -289.79803)
			(xy 50.906328 -289.844711) (xy 50.883457 -289.888288) (xy 50.853892 -289.927632) (xy 50.818399 -289.961724)
			(xy 50.777896 -289.98968) (xy 50.733434 -290.010778) (xy 50.686163 -290.02447) (xy 50.637308 -290.030402)
			(xy 50.588133 -290.028421) (xy 50.539914 -290.018577) (xy 50.493898 -290.001125) (xy 50.451277 -289.976518)
			(xy 50.413156 -289.945393) (xy 50.380521 -289.908556) (xy 50.354218 -289.86696) (xy 50.334927 -289.821684)
			(xy 50.32315 -289.7739) (xy 50.31919 -289.724846) (xy 49.980088 -289.724846) (xy 49.979593 -289.749453)
			(xy 49.971698 -289.79803) (xy 49.956114 -289.844711) (xy 49.933243 -289.888288) (xy 49.903678 -289.927632)
			(xy 49.868185 -289.961724) (xy 49.827682 -289.98968) (xy 49.78322 -290.010778) (xy 49.735949 -290.02447)
			(xy 49.687094 -290.030402) (xy 49.637919 -290.028421) (xy 49.5897 -290.018577) (xy 49.543684 -290.001125)
			(xy 49.501063 -289.976518) (xy 49.462942 -289.945393) (xy 49.430307 -289.908556) (xy 49.404004 -289.86696)
			(xy 49.384713 -289.821684) (xy 49.372936 -289.7739) (xy 49.368976 -289.724846) (xy 49.055528 -289.724846)
			(xy 49.055018 -289.750833) (xy 49.046888 -289.802168) (xy 49.030827 -289.851598) (xy 49.007231 -289.897908)
			(xy 48.976681 -289.939956) (xy 48.93993 -289.976707) (xy 48.897882 -290.007257) (xy 48.851572 -290.030853)
			(xy 48.802142 -290.046914) (xy 48.750807 -290.055044) (xy 48.698833 -290.055044) (xy 48.647498 -290.046914)
			(xy 48.598068 -290.030853) (xy 48.551758 -290.007257) (xy 48.50971 -289.976707) (xy 48.472959 -289.939956)
			(xy 48.442409 -289.897908) (xy 48.418813 -289.851598) (xy 48.402752 -289.802168) (xy 48.394622 -289.750833)
			(xy 48.394112 -289.724846) (xy 48.394692 -289.697667) (xy 48.403642 -289.644051) (xy 48.421243 -289.59262)
			(xy 48.447021 -289.544763) (xy 48.4632 -289.522916) (xy 48.4632 -289.522662) (xy 48.463454 -289.522154)
			(xy 48.468859 -289.514449) (xy 48.474078 -289.496381) (xy 48.472396 -289.477649) (xy 48.468534 -289.469068)
			(xy 48.428402 -289.38728) (xy 48.423891 -289.378906) (xy 48.409908 -289.366033) (xy 48.392187 -289.359162)
			(xy 48.382682 -289.358832) (xy 48.116998 -289.358832) (xy 48.107511 -289.359231) (xy 48.089834 -289.36613)
			(xy 48.075848 -289.378955) (xy 48.071278 -289.38728) (xy 48.031146 -289.469068) (xy 48.027394 -289.47768)
			(xy 48.025733 -289.496375) (xy 48.030895 -289.514421) (xy 48.036226 -289.522154) (xy 48.03648 -289.522662)
			(xy 48.03648 -289.522916) (xy 48.052686 -289.544745) (xy 48.078477 -289.592601) (xy 48.096072 -289.644038)
			(xy 48.104995 -289.697664) (xy 48.105568 -289.724846) (xy 48.105058 -289.750833) (xy 48.096928 -289.802168)
			(xy 48.080867 -289.851598) (xy 48.057271 -289.897908) (xy 48.026721 -289.939956) (xy 47.98997 -289.976707)
			(xy 47.947922 -290.007257) (xy 47.901612 -290.030853) (xy 47.852182 -290.046914) (xy 47.800847 -290.055044)
			(xy 47.748873 -290.055044) (xy 47.697538 -290.046914) (xy 47.648108 -290.030853) (xy 47.601798 -290.007257)
			(xy 47.55975 -289.976707) (xy 47.522999 -289.939956) (xy 47.492449 -289.897908) (xy 47.468853 -289.851598)
			(xy 47.452792 -289.802168) (xy 47.444662 -289.750833) (xy 47.444152 -289.724846) (xy 47.444732 -289.697668)
			(xy 47.453683 -289.644051) (xy 47.471286 -289.592622) (xy 47.497066 -289.544766) (xy 47.51324 -289.522916)
			(xy 47.51324 -289.522662) (xy 47.513494 -289.522154) (xy 47.518904 -289.514451) (xy 47.52413 -289.496381)
			(xy 47.522445 -289.477647) (xy 47.518574 -289.469068) (xy 47.478442 -289.38728) (xy 47.473928 -289.378913)
			(xy 47.459942 -289.366056) (xy 47.442223 -289.359206) (xy 47.432722 -289.358832) (xy 47.167038 -289.358832)
			(xy 47.157547 -289.359225) (xy 47.139858 -289.366115) (xy 47.125861 -289.378938) (xy 47.121318 -289.38728)
			(xy 47.081186 -289.469068) (xy 47.077437 -289.477681) (xy 47.075779 -289.496376) (xy 47.080935 -289.514422)
			(xy 47.086266 -289.522154) (xy 47.08652 -289.522662) (xy 47.08652 -289.522916) (xy 47.102724 -289.544746)
			(xy 47.128512 -289.592602) (xy 47.146105 -289.644039) (xy 47.155027 -289.697665) (xy 47.155608 -289.724846)
			(xy 47.155098 -289.750833) (xy 47.146968 -289.802168) (xy 47.130907 -289.851598) (xy 47.107311 -289.897908)
			(xy 47.076761 -289.939956) (xy 47.04001 -289.976707) (xy 46.997962 -290.007257) (xy 46.951652 -290.030853)
			(xy 46.902222 -290.046914) (xy 46.850887 -290.055044) (xy 46.798913 -290.055044) (xy 46.747578 -290.046914)
			(xy 46.698148 -290.030853) (xy 46.651838 -290.007257) (xy 46.60979 -289.976707) (xy 46.573039 -289.939956)
			(xy 46.542489 -289.897908) (xy 46.518893 -289.851598) (xy 46.502832 -289.802168) (xy 46.494702 -289.750833)
			(xy 46.494192 -289.724846) (xy 46.494772 -289.697667) (xy 46.503722 -289.64405) (xy 46.521322 -289.592619)
			(xy 46.547098 -289.544761) (xy 46.56328 -289.522916) (xy 46.56328 -289.522662) (xy 46.563534 -289.522154)
			(xy 46.56894 -289.51445) (xy 46.574162 -289.496381) (xy 46.572479 -289.477648) (xy 46.568614 -289.469068)
			(xy 46.528482 -289.38728) (xy 46.52397 -289.378908) (xy 46.509986 -289.366041) (xy 46.492265 -289.359176)
			(xy 46.482762 -289.358832) (xy 46.217078 -289.358832) (xy 46.207593 -289.359235) (xy 46.189921 -289.366138)
			(xy 46.175942 -289.378964) (xy 46.171358 -289.38728) (xy 46.131226 -289.469068) (xy 46.127475 -289.477681)
			(xy 46.125815 -289.496376) (xy 46.130975 -289.514421) (xy 46.136306 -289.522154) (xy 46.13656 -289.522662)
			(xy 46.13656 -289.522916) (xy 46.152767 -289.544745) (xy 46.178559 -289.592601) (xy 46.196156 -289.644038)
			(xy 46.205079 -289.697664) (xy 46.205648 -289.724846) (xy 46.205138 -289.750833) (xy 46.197008 -289.802168)
			(xy 46.180947 -289.851598) (xy 46.157351 -289.897908) (xy 46.126801 -289.939956) (xy 46.09005 -289.976707)
			(xy 46.048002 -290.007257) (xy 46.001692 -290.030853) (xy 45.952262 -290.046914) (xy 45.900927 -290.055044)
			(xy 45.848953 -290.055044) (xy 45.797618 -290.046914) (xy 45.748188 -290.030853) (xy 45.701878 -290.007257)
			(xy 45.65983 -289.976707) (xy 45.623079 -289.939956) (xy 45.592529 -289.897908) (xy 45.568933 -289.851598)
			(xy 45.552872 -289.802168) (xy 45.544742 -289.750833) (xy 45.544232 -289.724846) (xy 45.544812 -289.697667)
			(xy 45.553763 -289.644051) (xy 45.571365 -289.592621) (xy 45.597143 -289.544764) (xy 45.61332 -289.522916)
			(xy 45.61332 -289.522662) (xy 45.613574 -289.522154) (xy 45.618985 -289.514451) (xy 45.624213 -289.496381)
			(xy 45.622528 -289.477646) (xy 45.618654 -289.469068) (xy 45.578522 -289.38728) (xy 45.574012 -289.378904)
			(xy 45.56003 -289.366025) (xy 45.542308 -289.359147) (xy 45.532802 -289.358832) (xy 45.267118 -289.358832)
			(xy 45.257629 -289.359228) (xy 45.239946 -289.366122) (xy 45.225955 -289.378947) (xy 45.221398 -289.38728)
			(xy 45.181266 -289.469068) (xy 45.177513 -289.47768) (xy 45.175852 -289.496375) (xy 45.181015 -289.51442)
			(xy 45.186346 -289.522154) (xy 45.1866 -289.522662) (xy 45.1866 -289.522916) (xy 45.202805 -289.544746)
			(xy 45.228595 -289.592602) (xy 45.246189 -289.644039) (xy 45.255111 -289.697665) (xy 45.255688 -289.724846)
			(xy 45.255178 -289.750833) (xy 45.247048 -289.802168) (xy 45.230987 -289.851598) (xy 45.207391 -289.897908)
			(xy 45.176841 -289.939956) (xy 45.14009 -289.976707) (xy 45.098042 -290.007257) (xy 45.051732 -290.030853)
			(xy 45.002302 -290.046914) (xy 44.950967 -290.055044) (xy 44.898993 -290.055044) (xy 44.847658 -290.046914)
			(xy 44.798228 -290.030853) (xy 44.751918 -290.007257) (xy 44.70987 -289.976707) (xy 44.673119 -289.939956)
			(xy 44.642569 -289.897908) (xy 44.618973 -289.851598) (xy 44.602912 -289.802168) (xy 44.594782 -289.750833)
			(xy 44.594272 -289.724846) (xy 44.594852 -289.697668) (xy 44.603804 -289.644052) (xy 44.621407 -289.592623)
			(xy 44.647189 -289.544768) (xy 44.66336 -289.522916) (xy 44.66336 -289.522662) (xy 44.663614 -289.522154)
			(xy 44.669022 -289.51445) (xy 44.674246 -289.496381) (xy 44.672562 -289.477647) (xy 44.668694 -289.469068)
			(xy 44.628562 -289.38728) (xy 44.624049 -289.378911) (xy 44.610064 -289.366049) (xy 44.592344 -289.359191)
			(xy 44.582842 -289.358832) (xy 44.316904 -289.358832) (xy 44.307416 -289.35923) (xy 44.289737 -289.366128)
			(xy 44.27575 -289.378953) (xy 44.271184 -289.38728) (xy 44.231052 -289.469068) (xy 44.2273 -289.47768)
			(xy 44.225639 -289.496375) (xy 44.230801 -289.51442) (xy 44.236132 -289.522154) (xy 44.236386 -289.522662)
			(xy 44.236386 -289.522916) (xy 44.252592 -289.544746) (xy 44.278382 -289.592601) (xy 44.295977 -289.644039)
			(xy 44.3049 -289.697665) (xy 44.305474 -289.724846) (xy 44.304964 -289.750833) (xy 44.296834 -289.802168)
			(xy 44.280773 -289.851598) (xy 44.257177 -289.897908) (xy 44.226627 -289.939956) (xy 44.189876 -289.976707)
			(xy 44.147828 -290.007257) (xy 44.101518 -290.030853) (xy 44.052088 -290.046914) (xy 44.000753 -290.055044)
			(xy 43.948779 -290.055044) (xy 43.897444 -290.046914) (xy 43.848014 -290.030853) (xy 43.801704 -290.007257)
			(xy 43.759656 -289.976707) (xy 43.722905 -289.939956) (xy 43.692355 -289.897908) (xy 43.668759 -289.851598)
			(xy 43.652698 -289.802168) (xy 43.644568 -289.750833) (xy 43.644058 -289.724846) (xy 43.644638 -289.697668)
			(xy 43.653589 -289.644052) (xy 43.671192 -289.592623) (xy 43.696973 -289.544767) (xy 43.713146 -289.522916)
			(xy 43.713146 -289.522662) (xy 43.7134 -289.522154) (xy 43.718809 -289.514451) (xy 43.724035 -289.496381)
			(xy 43.72235 -289.477647) (xy 43.71848 -289.469068) (xy 43.678348 -289.38728) (xy 43.673834 -289.378912)
			(xy 43.659849 -289.366054) (xy 43.642129 -289.359201) (xy 43.632628 -289.358832) (xy 43.252136 -289.358832)
			(xy 43.242072 -289.359267) (xy 43.223487 -289.367002) (xy 43.216068 -289.373818) (xy 43.210988 -289.378898)
			(xy 43.204311 -289.386312) (xy 43.196725 -289.404743) (xy 43.196729 -289.424674) (xy 43.204321 -289.443103)
			(xy 43.210988 -289.450526) (xy 43.214798 -289.454336) (xy 43.236133 -289.469937) (xy 43.274017 -289.506787)
			(xy 43.305558 -289.549195) (xy 43.32995 -289.596079) (xy 43.346574 -289.646247) (xy 43.355006 -289.698421)
			(xy 43.355514 -289.724846) (xy 43.354981 -289.752242) (xy 43.345954 -289.806286) (xy 43.328138 -289.8581)
			(xy 43.302021 -289.906268) (xy 43.268318 -289.949469) (xy 43.227953 -289.98652) (xy 43.18203 -290.016407)
			(xy 43.15714 -290.027868) (xy 43.148317 -290.03223) (xy 43.134591 -290.046314) (xy 43.127156 -290.064519)
			(xy 43.12666 -290.07435) (xy 43.12666 -290.145724) (xy 43.126435 -290.152763) (xy 43.122564 -290.166296)
			(xy 43.11904 -290.172394) (xy 43.115484 -290.17849) (xy 43.111674 -290.191698) (xy 43.111674 -290.318952)
			(xy 43.111936 -290.326684) (xy 43.116586 -290.341432) (xy 43.120818 -290.347908) (xy 43.125136 -290.354258)
			(xy 43.137074 -290.363656) (xy 43.144186 -290.36645) (xy 43.168707 -290.376506) (xy 43.214444 -290.403278)
			(xy 43.255324 -290.437003) (xy 43.290302 -290.476817) (xy 43.318482 -290.521699) (xy 43.339142 -290.570502)
			(xy 43.351753 -290.621976) (xy 43.355993 -290.674802) (xy 43.355993 -290.674806) (xy 43.668962 -290.674806)
			(xy 43.672922 -290.625752) (xy 43.684699 -290.577968) (xy 43.70399 -290.532692) (xy 43.730293 -290.491096)
			(xy 43.762928 -290.454259) (xy 43.801049 -290.423134) (xy 43.84367 -290.398527) (xy 43.889686 -290.381075)
			(xy 43.937905 -290.371231) (xy 43.98708 -290.36925) (xy 44.035935 -290.375182) (xy 44.083206 -290.388874)
			(xy 44.127668 -290.409972) (xy 44.168171 -290.437928) (xy 44.203664 -290.47202) (xy 44.233229 -290.511364)
			(xy 44.2561 -290.554941) (xy 44.271684 -290.601622) (xy 44.279579 -290.650199) (xy 44.280074 -290.674806)
			(xy 45.569136 -290.674806) (xy 45.573096 -290.625752) (xy 45.584873 -290.577968) (xy 45.604164 -290.532692)
			(xy 45.630467 -290.491096) (xy 45.663102 -290.454259) (xy 45.701223 -290.423134) (xy 45.743844 -290.398527)
			(xy 45.78986 -290.381075) (xy 45.838079 -290.371231) (xy 45.887254 -290.36925) (xy 45.936109 -290.375182)
			(xy 45.98338 -290.388874) (xy 46.027842 -290.409972) (xy 46.068345 -290.437928) (xy 46.103838 -290.47202)
			(xy 46.133403 -290.511364) (xy 46.156274 -290.554941) (xy 46.171858 -290.601622) (xy 46.179753 -290.650199)
			(xy 46.180248 -290.674806) (xy 47.469056 -290.674806) (xy 47.473016 -290.625752) (xy 47.484793 -290.577968)
			(xy 47.504084 -290.532692) (xy 47.530387 -290.491096) (xy 47.563022 -290.454259) (xy 47.601143 -290.423134)
			(xy 47.643764 -290.398527) (xy 47.68978 -290.381075) (xy 47.737999 -290.371231) (xy 47.787174 -290.36925)
			(xy 47.836029 -290.375182) (xy 47.8833 -290.388874) (xy 47.927762 -290.409972) (xy 47.968265 -290.437928)
			(xy 48.003758 -290.47202) (xy 48.033323 -290.511364) (xy 48.056194 -290.554941) (xy 48.071778 -290.601622)
			(xy 48.079673 -290.650199) (xy 48.080168 -290.674806) (xy 48.419016 -290.674806) (xy 48.422976 -290.625752)
			(xy 48.434753 -290.577968) (xy 48.454044 -290.532692) (xy 48.480347 -290.491096) (xy 48.512982 -290.454259)
			(xy 48.551103 -290.423134) (xy 48.593724 -290.398527) (xy 48.63974 -290.381075) (xy 48.687959 -290.371231)
			(xy 48.737134 -290.36925) (xy 48.785989 -290.375182) (xy 48.83326 -290.388874) (xy 48.877722 -290.409972)
			(xy 48.918225 -290.437928) (xy 48.953718 -290.47202) (xy 48.983283 -290.511364) (xy 49.006154 -290.554941)
			(xy 49.021738 -290.601622) (xy 49.029633 -290.650199) (xy 49.030128 -290.674806) (xy 49.368976 -290.674806)
			(xy 49.372936 -290.625752) (xy 49.384713 -290.577968) (xy 49.404004 -290.532692) (xy 49.430307 -290.491096)
			(xy 49.462942 -290.454259) (xy 49.501063 -290.423134) (xy 49.543684 -290.398527) (xy 49.5897 -290.381075)
			(xy 49.637919 -290.371231) (xy 49.687094 -290.36925) (xy 49.735949 -290.375182) (xy 49.78322 -290.388874)
			(xy 49.827682 -290.409972) (xy 49.868185 -290.437928) (xy 49.903678 -290.47202) (xy 49.933243 -290.511364)
			(xy 49.956114 -290.554941) (xy 49.971698 -290.601622) (xy 49.979593 -290.650199) (xy 49.980088 -290.674806)
			(xy 50.31919 -290.674806) (xy 50.32315 -290.625752) (xy 50.334927 -290.577968) (xy 50.354218 -290.532692)
			(xy 50.380521 -290.491096) (xy 50.413156 -290.454259) (xy 50.451277 -290.423134) (xy 50.493898 -290.398527)
			(xy 50.539914 -290.381075) (xy 50.588133 -290.371231) (xy 50.637308 -290.36925) (xy 50.686163 -290.375182)
			(xy 50.733434 -290.388874) (xy 50.777896 -290.409972) (xy 50.818399 -290.437928) (xy 50.853892 -290.47202)
			(xy 50.883457 -290.511364) (xy 50.906328 -290.554941) (xy 50.921912 -290.601622) (xy 50.929807 -290.650199)
			(xy 50.930302 -290.674806) (xy 51.26915 -290.674806) (xy 51.27311 -290.625752) (xy 51.284887 -290.577968)
			(xy 51.304178 -290.532692) (xy 51.330481 -290.491096) (xy 51.363116 -290.454259) (xy 51.401237 -290.423134)
			(xy 51.443858 -290.398527) (xy 51.489874 -290.381075) (xy 51.538093 -290.371231) (xy 51.587268 -290.36925)
			(xy 51.636123 -290.375182) (xy 51.683394 -290.388874) (xy 51.727856 -290.409972) (xy 51.768359 -290.437928)
			(xy 51.803852 -290.47202) (xy 51.833417 -290.511364) (xy 51.856288 -290.554941) (xy 51.871872 -290.601622)
			(xy 51.879767 -290.650199) (xy 51.880262 -290.674806) (xy 52.21911 -290.674806) (xy 52.22307 -290.625752)
			(xy 52.234847 -290.577968) (xy 52.254138 -290.532692) (xy 52.280441 -290.491096) (xy 52.313076 -290.454259)
			(xy 52.351197 -290.423134) (xy 52.393818 -290.398527) (xy 52.439834 -290.381075) (xy 52.488053 -290.371231)
			(xy 52.537228 -290.36925) (xy 52.586083 -290.375182) (xy 52.633354 -290.388874) (xy 52.677816 -290.409972)
			(xy 52.718319 -290.437928) (xy 52.753812 -290.47202) (xy 52.783377 -290.511364) (xy 52.806248 -290.554941)
			(xy 52.821832 -290.601622) (xy 52.829727 -290.650199) (xy 52.830222 -290.674806) (xy 53.16907 -290.674806)
			(xy 53.17303 -290.625752) (xy 53.184807 -290.577968) (xy 53.204098 -290.532692) (xy 53.230401 -290.491096)
			(xy 53.263036 -290.454259) (xy 53.301157 -290.423134) (xy 53.343778 -290.398527) (xy 53.389794 -290.381075)
			(xy 53.438013 -290.371231) (xy 53.487188 -290.36925) (xy 53.536043 -290.375182) (xy 53.583314 -290.388874)
			(xy 53.627776 -290.409972) (xy 53.668279 -290.437928) (xy 53.703772 -290.47202) (xy 53.733337 -290.511364)
			(xy 53.756208 -290.554941) (xy 53.771792 -290.601622) (xy 53.779687 -290.650199) (xy 53.780182 -290.674806)
			(xy 54.11903 -290.674806) (xy 54.12299 -290.625752) (xy 54.134767 -290.577968) (xy 54.154058 -290.532692)
			(xy 54.180361 -290.491096) (xy 54.212996 -290.454259) (xy 54.251117 -290.423134) (xy 54.293738 -290.398527)
			(xy 54.339754 -290.381075) (xy 54.387973 -290.371231) (xy 54.437148 -290.36925) (xy 54.486003 -290.375182)
			(xy 54.533274 -290.388874) (xy 54.577736 -290.409972) (xy 54.618239 -290.437928) (xy 54.653732 -290.47202)
			(xy 54.683297 -290.511364) (xy 54.706168 -290.554941) (xy 54.721752 -290.601622) (xy 54.729647 -290.650199)
			(xy 54.730142 -290.674806) (xy 55.06899 -290.674806) (xy 55.07295 -290.625752) (xy 55.084727 -290.577968)
			(xy 55.104018 -290.532692) (xy 55.130321 -290.491096) (xy 55.162956 -290.454259) (xy 55.201077 -290.423134)
			(xy 55.243698 -290.398527) (xy 55.289714 -290.381075) (xy 55.337933 -290.371231) (xy 55.387108 -290.36925)
			(xy 55.435963 -290.375182) (xy 55.483234 -290.388874) (xy 55.527696 -290.409972) (xy 55.568199 -290.437928)
			(xy 55.603692 -290.47202) (xy 55.633257 -290.511364) (xy 55.656128 -290.554941) (xy 55.671712 -290.601622)
			(xy 55.679607 -290.650199) (xy 55.680102 -290.674806) (xy 56.01895 -290.674806) (xy 56.02291 -290.625752)
			(xy 56.034687 -290.577968) (xy 56.053978 -290.532692) (xy 56.080281 -290.491096) (xy 56.112916 -290.454259)
			(xy 56.151037 -290.423134) (xy 56.193658 -290.398527) (xy 56.239674 -290.381075) (xy 56.287893 -290.371231)
			(xy 56.337068 -290.36925) (xy 56.385923 -290.375182) (xy 56.433194 -290.388874) (xy 56.477656 -290.409972)
			(xy 56.518159 -290.437928) (xy 56.553652 -290.47202) (xy 56.583217 -290.511364) (xy 56.606088 -290.554941)
			(xy 56.621672 -290.601622) (xy 56.629567 -290.650199) (xy 56.630062 -290.674806) (xy 56.969164 -290.674806)
			(xy 56.973124 -290.625752) (xy 56.984901 -290.577968) (xy 57.004192 -290.532692) (xy 57.030495 -290.491096)
			(xy 57.06313 -290.454259) (xy 57.101251 -290.423134) (xy 57.143872 -290.398527) (xy 57.189888 -290.381075)
			(xy 57.238107 -290.371231) (xy 57.287282 -290.36925) (xy 57.336137 -290.375182) (xy 57.383408 -290.388874)
			(xy 57.42787 -290.409972) (xy 57.468373 -290.437928) (xy 57.503866 -290.47202) (xy 57.533431 -290.511364)
			(xy 57.556302 -290.554941) (xy 57.571886 -290.601622) (xy 57.579781 -290.650199) (xy 57.580276 -290.674806)
			(xy 57.919124 -290.674806) (xy 57.923084 -290.625752) (xy 57.934861 -290.577968) (xy 57.954152 -290.532692)
			(xy 57.980455 -290.491096) (xy 58.01309 -290.454259) (xy 58.051211 -290.423134) (xy 58.093832 -290.398527)
			(xy 58.139848 -290.381075) (xy 58.188067 -290.371231) (xy 58.237242 -290.36925) (xy 58.286097 -290.375182)
			(xy 58.333368 -290.388874) (xy 58.37783 -290.409972) (xy 58.418333 -290.437928) (xy 58.453826 -290.47202)
			(xy 58.483391 -290.511364) (xy 58.506262 -290.554941) (xy 58.521846 -290.601622) (xy 58.529741 -290.650199)
			(xy 58.530236 -290.674806) (xy 59.819044 -290.674806) (xy 59.823004 -290.625752) (xy 59.834781 -290.577968)
			(xy 59.854072 -290.532692) (xy 59.880375 -290.491096) (xy 59.91301 -290.454259) (xy 59.951131 -290.423134)
			(xy 59.993752 -290.398527) (xy 60.039768 -290.381075) (xy 60.087987 -290.371231) (xy 60.137162 -290.36925)
			(xy 60.186017 -290.375182) (xy 60.233288 -290.388874) (xy 60.27775 -290.409972) (xy 60.318253 -290.437928)
			(xy 60.353746 -290.47202) (xy 60.383311 -290.511364) (xy 60.406182 -290.554941) (xy 60.421766 -290.601622)
			(xy 60.429661 -290.650199) (xy 60.430156 -290.674806) (xy 60.769004 -290.674806) (xy 60.772964 -290.625752)
			(xy 60.784741 -290.577968) (xy 60.804032 -290.532692) (xy 60.830335 -290.491096) (xy 60.86297 -290.454259)
			(xy 60.901091 -290.423134) (xy 60.943712 -290.398527) (xy 60.989728 -290.381075) (xy 61.037947 -290.371231)
			(xy 61.087122 -290.36925) (xy 61.135977 -290.375182) (xy 61.183248 -290.388874) (xy 61.22771 -290.409972)
			(xy 61.268213 -290.437928) (xy 61.303706 -290.47202) (xy 61.333271 -290.511364) (xy 61.356142 -290.554941)
			(xy 61.371726 -290.601622) (xy 61.379621 -290.650199) (xy 61.380116 -290.674806) (xy 61.718964 -290.674806)
			(xy 61.722924 -290.625752) (xy 61.734701 -290.577968) (xy 61.753992 -290.532692) (xy 61.780295 -290.491096)
			(xy 61.81293 -290.454259) (xy 61.851051 -290.423134) (xy 61.893672 -290.398527) (xy 61.939688 -290.381075)
			(xy 61.987907 -290.371231) (xy 62.037082 -290.36925) (xy 62.085937 -290.375182) (xy 62.133208 -290.388874)
			(xy 62.17767 -290.409972) (xy 62.218173 -290.437928) (xy 62.253666 -290.47202) (xy 62.283231 -290.511364)
			(xy 62.306102 -290.554941) (xy 62.321686 -290.601622) (xy 62.329581 -290.650199) (xy 62.330076 -290.674806)
			(xy 62.669178 -290.674806) (xy 62.673138 -290.625752) (xy 62.684915 -290.577968) (xy 62.704206 -290.532692)
			(xy 62.730509 -290.491096) (xy 62.763144 -290.454259) (xy 62.801265 -290.423134) (xy 62.843886 -290.398527)
			(xy 62.889902 -290.381075) (xy 62.938121 -290.371231) (xy 62.987296 -290.36925) (xy 63.036151 -290.375182)
			(xy 63.083422 -290.388874) (xy 63.127884 -290.409972) (xy 63.168387 -290.437928) (xy 63.20388 -290.47202)
			(xy 63.233445 -290.511364) (xy 63.256316 -290.554941) (xy 63.2719 -290.601622) (xy 63.279795 -290.650199)
			(xy 63.28029 -290.674806) (xy 63.619138 -290.674806) (xy 63.623098 -290.625752) (xy 63.634875 -290.577968)
			(xy 63.654166 -290.532692) (xy 63.680469 -290.491096) (xy 63.713104 -290.454259) (xy 63.751225 -290.423134)
			(xy 63.793846 -290.398527) (xy 63.839862 -290.381075) (xy 63.888081 -290.371231) (xy 63.937256 -290.36925)
			(xy 63.986111 -290.375182) (xy 64.033382 -290.388874) (xy 64.077844 -290.409972) (xy 64.118347 -290.437928)
			(xy 64.15384 -290.47202) (xy 64.183405 -290.511364) (xy 64.206276 -290.554941) (xy 64.22186 -290.601622)
			(xy 64.229755 -290.650199) (xy 64.23025 -290.674806) (xy 64.569098 -290.674806) (xy 64.573058 -290.625752)
			(xy 64.584835 -290.577968) (xy 64.604126 -290.532692) (xy 64.630429 -290.491096) (xy 64.663064 -290.454259)
			(xy 64.701185 -290.423134) (xy 64.743806 -290.398527) (xy 64.789822 -290.381075) (xy 64.838041 -290.371231)
			(xy 64.887216 -290.36925) (xy 64.936071 -290.375182) (xy 64.983342 -290.388874) (xy 65.027804 -290.409972)
			(xy 65.068307 -290.437928) (xy 65.1038 -290.47202) (xy 65.133365 -290.511364) (xy 65.156236 -290.554941)
			(xy 65.17182 -290.601622) (xy 65.179715 -290.650199) (xy 65.18021 -290.674806) (xy 65.519058 -290.674806)
			(xy 65.523018 -290.625752) (xy 65.534795 -290.577968) (xy 65.554086 -290.532692) (xy 65.580389 -290.491096)
			(xy 65.613024 -290.454259) (xy 65.651145 -290.423134) (xy 65.693766 -290.398527) (xy 65.739782 -290.381075)
			(xy 65.788001 -290.371231) (xy 65.837176 -290.36925) (xy 65.886031 -290.375182) (xy 65.933302 -290.388874)
			(xy 65.977764 -290.409972) (xy 66.018267 -290.437928) (xy 66.05376 -290.47202) (xy 66.083325 -290.511364)
			(xy 66.106196 -290.554941) (xy 66.12178 -290.601622) (xy 66.129675 -290.650199) (xy 66.13017 -290.674806)
			(xy 66.469018 -290.674806) (xy 66.472978 -290.625752) (xy 66.484755 -290.577968) (xy 66.504046 -290.532692)
			(xy 66.530349 -290.491096) (xy 66.562984 -290.454259) (xy 66.601105 -290.423134) (xy 66.643726 -290.398527)
			(xy 66.689742 -290.381075) (xy 66.737961 -290.371231) (xy 66.787136 -290.36925) (xy 66.835991 -290.375182)
			(xy 66.883262 -290.388874) (xy 66.927724 -290.409972) (xy 66.968227 -290.437928) (xy 67.00372 -290.47202)
			(xy 67.033285 -290.511364) (xy 67.056156 -290.554941) (xy 67.07174 -290.601622) (xy 67.079635 -290.650199)
			(xy 67.08013 -290.674806) (xy 67.418978 -290.674806) (xy 67.422938 -290.625752) (xy 67.434715 -290.577968)
			(xy 67.454006 -290.532692) (xy 67.480309 -290.491096) (xy 67.512944 -290.454259) (xy 67.551065 -290.423134)
			(xy 67.593686 -290.398527) (xy 67.639702 -290.381075) (xy 67.687921 -290.371231) (xy 67.737096 -290.36925)
			(xy 67.785951 -290.375182) (xy 67.833222 -290.388874) (xy 67.877684 -290.409972) (xy 67.918187 -290.437928)
			(xy 67.95368 -290.47202) (xy 67.983245 -290.511364) (xy 68.006116 -290.554941) (xy 68.0217 -290.601622)
			(xy 68.029595 -290.650199) (xy 68.03009 -290.674806) (xy 68.368938 -290.674806) (xy 68.372898 -290.625752)
			(xy 68.384675 -290.577968) (xy 68.403966 -290.532692) (xy 68.430269 -290.491096) (xy 68.462904 -290.454259)
			(xy 68.501025 -290.423134) (xy 68.543646 -290.398527) (xy 68.589662 -290.381075) (xy 68.637881 -290.371231)
			(xy 68.687056 -290.36925) (xy 68.735911 -290.375182) (xy 68.783182 -290.388874) (xy 68.827644 -290.409972)
			(xy 68.868147 -290.437928) (xy 68.90364 -290.47202) (xy 68.933205 -290.511364) (xy 68.956076 -290.554941)
			(xy 68.97166 -290.601622) (xy 68.979555 -290.650199) (xy 68.98005 -290.674806) (xy 68.979555 -290.699413)
			(xy 68.97166 -290.74799) (xy 68.956076 -290.794671) (xy 68.933205 -290.838248) (xy 68.90364 -290.877592)
			(xy 68.868147 -290.911684) (xy 68.827644 -290.93964) (xy 68.783182 -290.960738) (xy 68.735911 -290.97443)
			(xy 68.687056 -290.980362) (xy 68.637881 -290.978381) (xy 68.589662 -290.968537) (xy 68.543646 -290.951085)
			(xy 68.501025 -290.926478) (xy 68.462904 -290.895353) (xy 68.430269 -290.858516) (xy 68.403966 -290.81692)
			(xy 68.384675 -290.771644) (xy 68.372898 -290.72386) (xy 68.368938 -290.674806) (xy 68.03009 -290.674806)
			(xy 68.029595 -290.699413) (xy 68.0217 -290.74799) (xy 68.006116 -290.794671) (xy 67.983245 -290.838248)
			(xy 67.95368 -290.877592) (xy 67.918187 -290.911684) (xy 67.877684 -290.93964) (xy 67.833222 -290.960738)
			(xy 67.785951 -290.97443) (xy 67.737096 -290.980362) (xy 67.687921 -290.978381) (xy 67.639702 -290.968537)
			(xy 67.593686 -290.951085) (xy 67.551065 -290.926478) (xy 67.512944 -290.895353) (xy 67.480309 -290.858516)
			(xy 67.454006 -290.81692) (xy 67.434715 -290.771644) (xy 67.422938 -290.72386) (xy 67.418978 -290.674806)
			(xy 67.08013 -290.674806) (xy 67.079635 -290.699413) (xy 67.07174 -290.74799) (xy 67.056156 -290.794671)
			(xy 67.033285 -290.838248) (xy 67.00372 -290.877592) (xy 66.968227 -290.911684) (xy 66.927724 -290.93964)
			(xy 66.883262 -290.960738) (xy 66.835991 -290.97443) (xy 66.787136 -290.980362) (xy 66.737961 -290.978381)
			(xy 66.689742 -290.968537) (xy 66.643726 -290.951085) (xy 66.601105 -290.926478) (xy 66.562984 -290.895353)
			(xy 66.530349 -290.858516) (xy 66.504046 -290.81692) (xy 66.484755 -290.771644) (xy 66.472978 -290.72386)
			(xy 66.469018 -290.674806) (xy 66.13017 -290.674806) (xy 66.129675 -290.699413) (xy 66.12178 -290.74799)
			(xy 66.106196 -290.794671) (xy 66.083325 -290.838248) (xy 66.05376 -290.877592) (xy 66.018267 -290.911684)
			(xy 65.977764 -290.93964) (xy 65.933302 -290.960738) (xy 65.886031 -290.97443) (xy 65.837176 -290.980362)
			(xy 65.788001 -290.978381) (xy 65.739782 -290.968537) (xy 65.693766 -290.951085) (xy 65.651145 -290.926478)
			(xy 65.613024 -290.895353) (xy 65.580389 -290.858516) (xy 65.554086 -290.81692) (xy 65.534795 -290.771644)
			(xy 65.523018 -290.72386) (xy 65.519058 -290.674806) (xy 65.18021 -290.674806) (xy 65.179715 -290.699413)
			(xy 65.17182 -290.74799) (xy 65.156236 -290.794671) (xy 65.133365 -290.838248) (xy 65.1038 -290.877592)
			(xy 65.068307 -290.911684) (xy 65.027804 -290.93964) (xy 64.983342 -290.960738) (xy 64.936071 -290.97443)
			(xy 64.887216 -290.980362) (xy 64.838041 -290.978381) (xy 64.789822 -290.968537) (xy 64.743806 -290.951085)
			(xy 64.701185 -290.926478) (xy 64.663064 -290.895353) (xy 64.630429 -290.858516) (xy 64.604126 -290.81692)
			(xy 64.584835 -290.771644) (xy 64.573058 -290.72386) (xy 64.569098 -290.674806) (xy 64.23025 -290.674806)
			(xy 64.229755 -290.699413) (xy 64.22186 -290.74799) (xy 64.206276 -290.794671) (xy 64.183405 -290.838248)
			(xy 64.15384 -290.877592) (xy 64.118347 -290.911684) (xy 64.077844 -290.93964) (xy 64.033382 -290.960738)
			(xy 63.986111 -290.97443) (xy 63.937256 -290.980362) (xy 63.888081 -290.978381) (xy 63.839862 -290.968537)
			(xy 63.793846 -290.951085) (xy 63.751225 -290.926478) (xy 63.713104 -290.895353) (xy 63.680469 -290.858516)
			(xy 63.654166 -290.81692) (xy 63.634875 -290.771644) (xy 63.623098 -290.72386) (xy 63.619138 -290.674806)
			(xy 63.28029 -290.674806) (xy 63.279795 -290.699413) (xy 63.2719 -290.74799) (xy 63.256316 -290.794671)
			(xy 63.233445 -290.838248) (xy 63.20388 -290.877592) (xy 63.168387 -290.911684) (xy 63.127884 -290.93964)
			(xy 63.083422 -290.960738) (xy 63.036151 -290.97443) (xy 62.987296 -290.980362) (xy 62.938121 -290.978381)
			(xy 62.889902 -290.968537) (xy 62.843886 -290.951085) (xy 62.801265 -290.926478) (xy 62.763144 -290.895353)
			(xy 62.730509 -290.858516) (xy 62.704206 -290.81692) (xy 62.684915 -290.771644) (xy 62.673138 -290.72386)
			(xy 62.669178 -290.674806) (xy 62.330076 -290.674806) (xy 62.329581 -290.699413) (xy 62.321686 -290.74799)
			(xy 62.306102 -290.794671) (xy 62.283231 -290.838248) (xy 62.253666 -290.877592) (xy 62.218173 -290.911684)
			(xy 62.17767 -290.93964) (xy 62.133208 -290.960738) (xy 62.085937 -290.97443) (xy 62.037082 -290.980362)
			(xy 61.987907 -290.978381) (xy 61.939688 -290.968537) (xy 61.893672 -290.951085) (xy 61.851051 -290.926478)
			(xy 61.81293 -290.895353) (xy 61.780295 -290.858516) (xy 61.753992 -290.81692) (xy 61.734701 -290.771644)
			(xy 61.722924 -290.72386) (xy 61.718964 -290.674806) (xy 61.380116 -290.674806) (xy 61.379621 -290.699413)
			(xy 61.371726 -290.74799) (xy 61.356142 -290.794671) (xy 61.333271 -290.838248) (xy 61.303706 -290.877592)
			(xy 61.268213 -290.911684) (xy 61.22771 -290.93964) (xy 61.183248 -290.960738) (xy 61.135977 -290.97443)
			(xy 61.087122 -290.980362) (xy 61.037947 -290.978381) (xy 60.989728 -290.968537) (xy 60.943712 -290.951085)
			(xy 60.901091 -290.926478) (xy 60.86297 -290.895353) (xy 60.830335 -290.858516) (xy 60.804032 -290.81692)
			(xy 60.784741 -290.771644) (xy 60.772964 -290.72386) (xy 60.769004 -290.674806) (xy 60.430156 -290.674806)
			(xy 60.429661 -290.699413) (xy 60.421766 -290.74799) (xy 60.406182 -290.794671) (xy 60.383311 -290.838248)
			(xy 60.353746 -290.877592) (xy 60.318253 -290.911684) (xy 60.27775 -290.93964) (xy 60.233288 -290.960738)
			(xy 60.186017 -290.97443) (xy 60.137162 -290.980362) (xy 60.087987 -290.978381) (xy 60.039768 -290.968537)
			(xy 59.993752 -290.951085) (xy 59.951131 -290.926478) (xy 59.91301 -290.895353) (xy 59.880375 -290.858516)
			(xy 59.854072 -290.81692) (xy 59.834781 -290.771644) (xy 59.823004 -290.72386) (xy 59.819044 -290.674806)
			(xy 58.530236 -290.674806) (xy 58.529741 -290.699413) (xy 58.521846 -290.74799) (xy 58.506262 -290.794671)
			(xy 58.483391 -290.838248) (xy 58.453826 -290.877592) (xy 58.418333 -290.911684) (xy 58.37783 -290.93964)
			(xy 58.333368 -290.960738) (xy 58.286097 -290.97443) (xy 58.237242 -290.980362) (xy 58.188067 -290.978381)
			(xy 58.139848 -290.968537) (xy 58.093832 -290.951085) (xy 58.051211 -290.926478) (xy 58.01309 -290.895353)
			(xy 57.980455 -290.858516) (xy 57.954152 -290.81692) (xy 57.934861 -290.771644) (xy 57.923084 -290.72386)
			(xy 57.919124 -290.674806) (xy 57.580276 -290.674806) (xy 57.579781 -290.699413) (xy 57.571886 -290.74799)
			(xy 57.556302 -290.794671) (xy 57.533431 -290.838248) (xy 57.503866 -290.877592) (xy 57.468373 -290.911684)
			(xy 57.42787 -290.93964) (xy 57.383408 -290.960738) (xy 57.336137 -290.97443) (xy 57.287282 -290.980362)
			(xy 57.238107 -290.978381) (xy 57.189888 -290.968537) (xy 57.143872 -290.951085) (xy 57.101251 -290.926478)
			(xy 57.06313 -290.895353) (xy 57.030495 -290.858516) (xy 57.004192 -290.81692) (xy 56.984901 -290.771644)
			(xy 56.973124 -290.72386) (xy 56.969164 -290.674806) (xy 56.630062 -290.674806) (xy 56.629567 -290.699413)
			(xy 56.621672 -290.74799) (xy 56.606088 -290.794671) (xy 56.583217 -290.838248) (xy 56.553652 -290.877592)
			(xy 56.518159 -290.911684) (xy 56.477656 -290.93964) (xy 56.433194 -290.960738) (xy 56.385923 -290.97443)
			(xy 56.337068 -290.980362) (xy 56.287893 -290.978381) (xy 56.239674 -290.968537) (xy 56.193658 -290.951085)
			(xy 56.151037 -290.926478) (xy 56.112916 -290.895353) (xy 56.080281 -290.858516) (xy 56.053978 -290.81692)
			(xy 56.034687 -290.771644) (xy 56.02291 -290.72386) (xy 56.01895 -290.674806) (xy 55.680102 -290.674806)
			(xy 55.679607 -290.699413) (xy 55.671712 -290.74799) (xy 55.656128 -290.794671) (xy 55.633257 -290.838248)
			(xy 55.603692 -290.877592) (xy 55.568199 -290.911684) (xy 55.527696 -290.93964) (xy 55.483234 -290.960738)
			(xy 55.435963 -290.97443) (xy 55.387108 -290.980362) (xy 55.337933 -290.978381) (xy 55.289714 -290.968537)
			(xy 55.243698 -290.951085) (xy 55.201077 -290.926478) (xy 55.162956 -290.895353) (xy 55.130321 -290.858516)
			(xy 55.104018 -290.81692) (xy 55.084727 -290.771644) (xy 55.07295 -290.72386) (xy 55.06899 -290.674806)
			(xy 54.730142 -290.674806) (xy 54.729647 -290.699413) (xy 54.721752 -290.74799) (xy 54.706168 -290.794671)
			(xy 54.683297 -290.838248) (xy 54.653732 -290.877592) (xy 54.618239 -290.911684) (xy 54.577736 -290.93964)
			(xy 54.533274 -290.960738) (xy 54.486003 -290.97443) (xy 54.437148 -290.980362) (xy 54.387973 -290.978381)
			(xy 54.339754 -290.968537) (xy 54.293738 -290.951085) (xy 54.251117 -290.926478) (xy 54.212996 -290.895353)
			(xy 54.180361 -290.858516) (xy 54.154058 -290.81692) (xy 54.134767 -290.771644) (xy 54.12299 -290.72386)
			(xy 54.11903 -290.674806) (xy 53.780182 -290.674806) (xy 53.779687 -290.699413) (xy 53.771792 -290.74799)
			(xy 53.756208 -290.794671) (xy 53.733337 -290.838248) (xy 53.703772 -290.877592) (xy 53.668279 -290.911684)
			(xy 53.627776 -290.93964) (xy 53.583314 -290.960738) (xy 53.536043 -290.97443) (xy 53.487188 -290.980362)
			(xy 53.438013 -290.978381) (xy 53.389794 -290.968537) (xy 53.343778 -290.951085) (xy 53.301157 -290.926478)
			(xy 53.263036 -290.895353) (xy 53.230401 -290.858516) (xy 53.204098 -290.81692) (xy 53.184807 -290.771644)
			(xy 53.17303 -290.72386) (xy 53.16907 -290.674806) (xy 52.830222 -290.674806) (xy 52.829727 -290.699413)
			(xy 52.821832 -290.74799) (xy 52.806248 -290.794671) (xy 52.783377 -290.838248) (xy 52.753812 -290.877592)
			(xy 52.718319 -290.911684) (xy 52.677816 -290.93964) (xy 52.633354 -290.960738) (xy 52.586083 -290.97443)
			(xy 52.537228 -290.980362) (xy 52.488053 -290.978381) (xy 52.439834 -290.968537) (xy 52.393818 -290.951085)
			(xy 52.351197 -290.926478) (xy 52.313076 -290.895353) (xy 52.280441 -290.858516) (xy 52.254138 -290.81692)
			(xy 52.234847 -290.771644) (xy 52.22307 -290.72386) (xy 52.21911 -290.674806) (xy 51.880262 -290.674806)
			(xy 51.879767 -290.699413) (xy 51.871872 -290.74799) (xy 51.856288 -290.794671) (xy 51.833417 -290.838248)
			(xy 51.803852 -290.877592) (xy 51.768359 -290.911684) (xy 51.727856 -290.93964) (xy 51.683394 -290.960738)
			(xy 51.636123 -290.97443) (xy 51.587268 -290.980362) (xy 51.538093 -290.978381) (xy 51.489874 -290.968537)
			(xy 51.443858 -290.951085) (xy 51.401237 -290.926478) (xy 51.363116 -290.895353) (xy 51.330481 -290.858516)
			(xy 51.304178 -290.81692) (xy 51.284887 -290.771644) (xy 51.27311 -290.72386) (xy 51.26915 -290.674806)
			(xy 50.930302 -290.674806) (xy 50.929807 -290.699413) (xy 50.921912 -290.74799) (xy 50.906328 -290.794671)
			(xy 50.883457 -290.838248) (xy 50.853892 -290.877592) (xy 50.818399 -290.911684) (xy 50.777896 -290.93964)
			(xy 50.733434 -290.960738) (xy 50.686163 -290.97443) (xy 50.637308 -290.980362) (xy 50.588133 -290.978381)
			(xy 50.539914 -290.968537) (xy 50.493898 -290.951085) (xy 50.451277 -290.926478) (xy 50.413156 -290.895353)
			(xy 50.380521 -290.858516) (xy 50.354218 -290.81692) (xy 50.334927 -290.771644) (xy 50.32315 -290.72386)
			(xy 50.31919 -290.674806) (xy 49.980088 -290.674806) (xy 49.979593 -290.699413) (xy 49.971698 -290.74799)
			(xy 49.956114 -290.794671) (xy 49.933243 -290.838248) (xy 49.903678 -290.877592) (xy 49.868185 -290.911684)
			(xy 49.827682 -290.93964) (xy 49.78322 -290.960738) (xy 49.735949 -290.97443) (xy 49.687094 -290.980362)
			(xy 49.637919 -290.978381) (xy 49.5897 -290.968537) (xy 49.543684 -290.951085) (xy 49.501063 -290.926478)
			(xy 49.462942 -290.895353) (xy 49.430307 -290.858516) (xy 49.404004 -290.81692) (xy 49.384713 -290.771644)
			(xy 49.372936 -290.72386) (xy 49.368976 -290.674806) (xy 49.030128 -290.674806) (xy 49.029633 -290.699413)
			(xy 49.021738 -290.74799) (xy 49.006154 -290.794671) (xy 48.983283 -290.838248) (xy 48.953718 -290.877592)
			(xy 48.918225 -290.911684) (xy 48.877722 -290.93964) (xy 48.83326 -290.960738) (xy 48.785989 -290.97443)
			(xy 48.737134 -290.980362) (xy 48.687959 -290.978381) (xy 48.63974 -290.968537) (xy 48.593724 -290.951085)
			(xy 48.551103 -290.926478) (xy 48.512982 -290.895353) (xy 48.480347 -290.858516) (xy 48.454044 -290.81692)
			(xy 48.434753 -290.771644) (xy 48.422976 -290.72386) (xy 48.419016 -290.674806) (xy 48.080168 -290.674806)
			(xy 48.079673 -290.699413) (xy 48.071778 -290.74799) (xy 48.056194 -290.794671) (xy 48.033323 -290.838248)
			(xy 48.003758 -290.877592) (xy 47.968265 -290.911684) (xy 47.927762 -290.93964) (xy 47.8833 -290.960738)
			(xy 47.836029 -290.97443) (xy 47.787174 -290.980362) (xy 47.737999 -290.978381) (xy 47.68978 -290.968537)
			(xy 47.643764 -290.951085) (xy 47.601143 -290.926478) (xy 47.563022 -290.895353) (xy 47.530387 -290.858516)
			(xy 47.504084 -290.81692) (xy 47.484793 -290.771644) (xy 47.473016 -290.72386) (xy 47.469056 -290.674806)
			(xy 46.180248 -290.674806) (xy 46.179753 -290.699413) (xy 46.171858 -290.74799) (xy 46.156274 -290.794671)
			(xy 46.133403 -290.838248) (xy 46.103838 -290.877592) (xy 46.068345 -290.911684) (xy 46.027842 -290.93964)
			(xy 45.98338 -290.960738) (xy 45.936109 -290.97443) (xy 45.887254 -290.980362) (xy 45.838079 -290.978381)
			(xy 45.78986 -290.968537) (xy 45.743844 -290.951085) (xy 45.701223 -290.926478) (xy 45.663102 -290.895353)
			(xy 45.630467 -290.858516) (xy 45.604164 -290.81692) (xy 45.584873 -290.771644) (xy 45.573096 -290.72386)
			(xy 45.569136 -290.674806) (xy 44.280074 -290.674806) (xy 44.279579 -290.699413) (xy 44.271684 -290.74799)
			(xy 44.2561 -290.794671) (xy 44.233229 -290.838248) (xy 44.203664 -290.877592) (xy 44.168171 -290.911684)
			(xy 44.127668 -290.93964) (xy 44.083206 -290.960738) (xy 44.035935 -290.97443) (xy 43.98708 -290.980362)
			(xy 43.937905 -290.978381) (xy 43.889686 -290.968537) (xy 43.84367 -290.951085) (xy 43.801049 -290.926478)
			(xy 43.762928 -290.895353) (xy 43.730293 -290.858516) (xy 43.70399 -290.81692) (xy 43.684699 -290.771644)
			(xy 43.672922 -290.72386) (xy 43.668962 -290.674806) (xy 43.355993 -290.674806) (xy 43.351753 -290.727628)
			(xy 43.339141 -290.779102) (xy 43.31848 -290.827904) (xy 43.2903 -290.872787) (xy 43.255321 -290.9126)
			(xy 43.21444 -290.946324) (xy 43.168704 -290.973096) (xy 43.144186 -290.983162) (xy 43.137074 -290.985956)
			(xy 43.125136 -290.995354) (xy 43.120818 -291.001704) (xy 43.116665 -291.008218) (xy 43.112018 -291.022942)
			(xy 43.111674 -291.03066) (xy 43.111674 -291.268912) (xy 43.111945 -291.276641) (xy 43.11661 -291.291378)
			(xy 43.120818 -291.297868) (xy 43.125136 -291.304218) (xy 43.137074 -291.313616) (xy 43.144186 -291.31641)
			(xy 43.168711 -291.326466) (xy 43.214453 -291.353239) (xy 43.25534 -291.386966) (xy 43.290323 -291.426783)
			(xy 43.318508 -291.471669) (xy 43.339173 -291.520477) (xy 43.351788 -291.571956) (xy 43.356028 -291.624766)
			(xy 43.668962 -291.624766) (xy 43.672922 -291.575712) (xy 43.684699 -291.527928) (xy 43.70399 -291.482652)
			(xy 43.730293 -291.441056) (xy 43.762928 -291.404219) (xy 43.801049 -291.373094) (xy 43.84367 -291.348487)
			(xy 43.889686 -291.331035) (xy 43.937905 -291.321191) (xy 43.98708 -291.31921) (xy 44.035935 -291.325142)
			(xy 44.083206 -291.338834) (xy 44.127668 -291.359932) (xy 44.168171 -291.387888) (xy 44.203664 -291.42198)
			(xy 44.233229 -291.461324) (xy 44.2561 -291.504901) (xy 44.271684 -291.551582) (xy 44.279579 -291.600159)
			(xy 44.280074 -291.624766) (xy 45.569136 -291.624766) (xy 45.573096 -291.575712) (xy 45.584873 -291.527928)
			(xy 45.604164 -291.482652) (xy 45.630467 -291.441056) (xy 45.663102 -291.404219) (xy 45.701223 -291.373094)
			(xy 45.743844 -291.348487) (xy 45.78986 -291.331035) (xy 45.838079 -291.321191) (xy 45.887254 -291.31921)
			(xy 45.936109 -291.325142) (xy 45.98338 -291.338834) (xy 46.027842 -291.359932) (xy 46.068345 -291.387888)
			(xy 46.103838 -291.42198) (xy 46.133403 -291.461324) (xy 46.156274 -291.504901) (xy 46.171858 -291.551582)
			(xy 46.179753 -291.600159) (xy 46.180248 -291.624766) (xy 47.469056 -291.624766) (xy 47.473016 -291.575712)
			(xy 47.484793 -291.527928) (xy 47.504084 -291.482652) (xy 47.530387 -291.441056) (xy 47.563022 -291.404219)
			(xy 47.601143 -291.373094) (xy 47.643764 -291.348487) (xy 47.68978 -291.331035) (xy 47.737999 -291.321191)
			(xy 47.787174 -291.31921) (xy 47.836029 -291.325142) (xy 47.8833 -291.338834) (xy 47.927762 -291.359932)
			(xy 47.968265 -291.387888) (xy 48.003758 -291.42198) (xy 48.033323 -291.461324) (xy 48.056194 -291.504901)
			(xy 48.071778 -291.551582) (xy 48.079673 -291.600159) (xy 48.080168 -291.624766) (xy 48.419016 -291.624766)
			(xy 48.422976 -291.575712) (xy 48.434753 -291.527928) (xy 48.454044 -291.482652) (xy 48.480347 -291.441056)
			(xy 48.512982 -291.404219) (xy 48.551103 -291.373094) (xy 48.593724 -291.348487) (xy 48.63974 -291.331035)
			(xy 48.687959 -291.321191) (xy 48.737134 -291.31921) (xy 48.785989 -291.325142) (xy 48.83326 -291.338834)
			(xy 48.877722 -291.359932) (xy 48.918225 -291.387888) (xy 48.953718 -291.42198) (xy 48.983283 -291.461324)
			(xy 49.006154 -291.504901) (xy 49.021738 -291.551582) (xy 49.029633 -291.600159) (xy 49.030128 -291.624766)
			(xy 49.368976 -291.624766) (xy 49.372936 -291.575712) (xy 49.384713 -291.527928) (xy 49.404004 -291.482652)
			(xy 49.430307 -291.441056) (xy 49.462942 -291.404219) (xy 49.501063 -291.373094) (xy 49.543684 -291.348487)
			(xy 49.5897 -291.331035) (xy 49.637919 -291.321191) (xy 49.687094 -291.31921) (xy 49.735949 -291.325142)
			(xy 49.78322 -291.338834) (xy 49.827682 -291.359932) (xy 49.868185 -291.387888) (xy 49.903678 -291.42198)
			(xy 49.933243 -291.461324) (xy 49.956114 -291.504901) (xy 49.971698 -291.551582) (xy 49.979593 -291.600159)
			(xy 49.980088 -291.624766) (xy 50.31919 -291.624766) (xy 50.32315 -291.575712) (xy 50.334927 -291.527928)
			(xy 50.354218 -291.482652) (xy 50.380521 -291.441056) (xy 50.413156 -291.404219) (xy 50.451277 -291.373094)
			(xy 50.493898 -291.348487) (xy 50.539914 -291.331035) (xy 50.588133 -291.321191) (xy 50.637308 -291.31921)
			(xy 50.686163 -291.325142) (xy 50.733434 -291.338834) (xy 50.777896 -291.359932) (xy 50.818399 -291.387888)
			(xy 50.853892 -291.42198) (xy 50.883457 -291.461324) (xy 50.906328 -291.504901) (xy 50.921912 -291.551582)
			(xy 50.929807 -291.600159) (xy 50.930302 -291.624766) (xy 51.26915 -291.624766) (xy 51.27311 -291.575712)
			(xy 51.284887 -291.527928) (xy 51.304178 -291.482652) (xy 51.330481 -291.441056) (xy 51.363116 -291.404219)
			(xy 51.401237 -291.373094) (xy 51.443858 -291.348487) (xy 51.489874 -291.331035) (xy 51.538093 -291.321191)
			(xy 51.587268 -291.31921) (xy 51.636123 -291.325142) (xy 51.683394 -291.338834) (xy 51.727856 -291.359932)
			(xy 51.768359 -291.387888) (xy 51.803852 -291.42198) (xy 51.833417 -291.461324) (xy 51.856288 -291.504901)
			(xy 51.871872 -291.551582) (xy 51.879767 -291.600159) (xy 51.880262 -291.624766) (xy 52.21911 -291.624766)
			(xy 52.22307 -291.575712) (xy 52.234847 -291.527928) (xy 52.254138 -291.482652) (xy 52.280441 -291.441056)
			(xy 52.313076 -291.404219) (xy 52.351197 -291.373094) (xy 52.393818 -291.348487) (xy 52.439834 -291.331035)
			(xy 52.488053 -291.321191) (xy 52.537228 -291.31921) (xy 52.586083 -291.325142) (xy 52.633354 -291.338834)
			(xy 52.677816 -291.359932) (xy 52.718319 -291.387888) (xy 52.753812 -291.42198) (xy 52.783377 -291.461324)
			(xy 52.806248 -291.504901) (xy 52.821832 -291.551582) (xy 52.829727 -291.600159) (xy 52.830222 -291.624766)
			(xy 53.16907 -291.624766) (xy 53.17303 -291.575712) (xy 53.184807 -291.527928) (xy 53.204098 -291.482652)
			(xy 53.230401 -291.441056) (xy 53.263036 -291.404219) (xy 53.301157 -291.373094) (xy 53.343778 -291.348487)
			(xy 53.389794 -291.331035) (xy 53.438013 -291.321191) (xy 53.487188 -291.31921) (xy 53.536043 -291.325142)
			(xy 53.583314 -291.338834) (xy 53.627776 -291.359932) (xy 53.668279 -291.387888) (xy 53.703772 -291.42198)
			(xy 53.733337 -291.461324) (xy 53.756208 -291.504901) (xy 53.771792 -291.551582) (xy 53.779687 -291.600159)
			(xy 53.780182 -291.624766) (xy 54.11903 -291.624766) (xy 54.12299 -291.575712) (xy 54.134767 -291.527928)
			(xy 54.154058 -291.482652) (xy 54.180361 -291.441056) (xy 54.212996 -291.404219) (xy 54.251117 -291.373094)
			(xy 54.293738 -291.348487) (xy 54.339754 -291.331035) (xy 54.387973 -291.321191) (xy 54.437148 -291.31921)
			(xy 54.486003 -291.325142) (xy 54.533274 -291.338834) (xy 54.577736 -291.359932) (xy 54.618239 -291.387888)
			(xy 54.653732 -291.42198) (xy 54.683297 -291.461324) (xy 54.706168 -291.504901) (xy 54.721752 -291.551582)
			(xy 54.729647 -291.600159) (xy 54.730142 -291.624766) (xy 55.06899 -291.624766) (xy 55.07295 -291.575712)
			(xy 55.084727 -291.527928) (xy 55.104018 -291.482652) (xy 55.130321 -291.441056) (xy 55.162956 -291.404219)
			(xy 55.201077 -291.373094) (xy 55.243698 -291.348487) (xy 55.289714 -291.331035) (xy 55.337933 -291.321191)
			(xy 55.387108 -291.31921) (xy 55.435963 -291.325142) (xy 55.483234 -291.338834) (xy 55.527696 -291.359932)
			(xy 55.568199 -291.387888) (xy 55.603692 -291.42198) (xy 55.633257 -291.461324) (xy 55.656128 -291.504901)
			(xy 55.671712 -291.551582) (xy 55.679607 -291.600159) (xy 55.680102 -291.624766) (xy 56.01895 -291.624766)
			(xy 56.02291 -291.575712) (xy 56.034687 -291.527928) (xy 56.053978 -291.482652) (xy 56.080281 -291.441056)
			(xy 56.112916 -291.404219) (xy 56.151037 -291.373094) (xy 56.193658 -291.348487) (xy 56.239674 -291.331035)
			(xy 56.287893 -291.321191) (xy 56.337068 -291.31921) (xy 56.385923 -291.325142) (xy 56.433194 -291.338834)
			(xy 56.477656 -291.359932) (xy 56.518159 -291.387888) (xy 56.553652 -291.42198) (xy 56.583217 -291.461324)
			(xy 56.606088 -291.504901) (xy 56.621672 -291.551582) (xy 56.629567 -291.600159) (xy 56.630062 -291.624766)
			(xy 56.969164 -291.624766) (xy 56.973124 -291.575712) (xy 56.984901 -291.527928) (xy 57.004192 -291.482652)
			(xy 57.030495 -291.441056) (xy 57.06313 -291.404219) (xy 57.101251 -291.373094) (xy 57.143872 -291.348487)
			(xy 57.189888 -291.331035) (xy 57.238107 -291.321191) (xy 57.287282 -291.31921) (xy 57.336137 -291.325142)
			(xy 57.383408 -291.338834) (xy 57.42787 -291.359932) (xy 57.468373 -291.387888) (xy 57.503866 -291.42198)
			(xy 57.533431 -291.461324) (xy 57.556302 -291.504901) (xy 57.571886 -291.551582) (xy 57.579781 -291.600159)
			(xy 57.580276 -291.624766) (xy 57.919124 -291.624766) (xy 57.923084 -291.575712) (xy 57.934861 -291.527928)
			(xy 57.954152 -291.482652) (xy 57.980455 -291.441056) (xy 58.01309 -291.404219) (xy 58.051211 -291.373094)
			(xy 58.093832 -291.348487) (xy 58.139848 -291.331035) (xy 58.188067 -291.321191) (xy 58.237242 -291.31921)
			(xy 58.286097 -291.325142) (xy 58.333368 -291.338834) (xy 58.37783 -291.359932) (xy 58.418333 -291.387888)
			(xy 58.453826 -291.42198) (xy 58.483391 -291.461324) (xy 58.506262 -291.504901) (xy 58.521846 -291.551582)
			(xy 58.529741 -291.600159) (xy 58.530236 -291.624766) (xy 59.819044 -291.624766) (xy 59.823004 -291.575712)
			(xy 59.834781 -291.527928) (xy 59.854072 -291.482652) (xy 59.880375 -291.441056) (xy 59.91301 -291.404219)
			(xy 59.951131 -291.373094) (xy 59.993752 -291.348487) (xy 60.039768 -291.331035) (xy 60.087987 -291.321191)
			(xy 60.137162 -291.31921) (xy 60.186017 -291.325142) (xy 60.233288 -291.338834) (xy 60.27775 -291.359932)
			(xy 60.318253 -291.387888) (xy 60.353746 -291.42198) (xy 60.383311 -291.461324) (xy 60.406182 -291.504901)
			(xy 60.421766 -291.551582) (xy 60.429661 -291.600159) (xy 60.430156 -291.624766) (xy 60.769004 -291.624766)
			(xy 60.772964 -291.575712) (xy 60.784741 -291.527928) (xy 60.804032 -291.482652) (xy 60.830335 -291.441056)
			(xy 60.86297 -291.404219) (xy 60.901091 -291.373094) (xy 60.943712 -291.348487) (xy 60.989728 -291.331035)
			(xy 61.037947 -291.321191) (xy 61.087122 -291.31921) (xy 61.135977 -291.325142) (xy 61.183248 -291.338834)
			(xy 61.22771 -291.359932) (xy 61.268213 -291.387888) (xy 61.303706 -291.42198) (xy 61.333271 -291.461324)
			(xy 61.356142 -291.504901) (xy 61.371726 -291.551582) (xy 61.379621 -291.600159) (xy 61.380116 -291.624766)
			(xy 61.718964 -291.624766) (xy 61.722924 -291.575712) (xy 61.734701 -291.527928) (xy 61.753992 -291.482652)
			(xy 61.780295 -291.441056) (xy 61.81293 -291.404219) (xy 61.851051 -291.373094) (xy 61.893672 -291.348487)
			(xy 61.939688 -291.331035) (xy 61.987907 -291.321191) (xy 62.037082 -291.31921) (xy 62.085937 -291.325142)
			(xy 62.133208 -291.338834) (xy 62.17767 -291.359932) (xy 62.218173 -291.387888) (xy 62.253666 -291.42198)
			(xy 62.283231 -291.461324) (xy 62.306102 -291.504901) (xy 62.321686 -291.551582) (xy 62.329581 -291.600159)
			(xy 62.330076 -291.624766) (xy 62.669178 -291.624766) (xy 62.673138 -291.575712) (xy 62.684915 -291.527928)
			(xy 62.704206 -291.482652) (xy 62.730509 -291.441056) (xy 62.763144 -291.404219) (xy 62.801265 -291.373094)
			(xy 62.843886 -291.348487) (xy 62.889902 -291.331035) (xy 62.938121 -291.321191) (xy 62.987296 -291.31921)
			(xy 63.036151 -291.325142) (xy 63.083422 -291.338834) (xy 63.127884 -291.359932) (xy 63.168387 -291.387888)
			(xy 63.20388 -291.42198) (xy 63.233445 -291.461324) (xy 63.256316 -291.504901) (xy 63.2719 -291.551582)
			(xy 63.279795 -291.600159) (xy 63.28029 -291.624766) (xy 63.619138 -291.624766) (xy 63.623098 -291.575712)
			(xy 63.634875 -291.527928) (xy 63.654166 -291.482652) (xy 63.680469 -291.441056) (xy 63.713104 -291.404219)
			(xy 63.751225 -291.373094) (xy 63.793846 -291.348487) (xy 63.839862 -291.331035) (xy 63.888081 -291.321191)
			(xy 63.937256 -291.31921) (xy 63.986111 -291.325142) (xy 64.033382 -291.338834) (xy 64.077844 -291.359932)
			(xy 64.118347 -291.387888) (xy 64.15384 -291.42198) (xy 64.183405 -291.461324) (xy 64.206276 -291.504901)
			(xy 64.22186 -291.551582) (xy 64.229755 -291.600159) (xy 64.23025 -291.624766) (xy 64.569098 -291.624766)
			(xy 64.573058 -291.575712) (xy 64.584835 -291.527928) (xy 64.604126 -291.482652) (xy 64.630429 -291.441056)
			(xy 64.663064 -291.404219) (xy 64.701185 -291.373094) (xy 64.743806 -291.348487) (xy 64.789822 -291.331035)
			(xy 64.838041 -291.321191) (xy 64.887216 -291.31921) (xy 64.936071 -291.325142) (xy 64.983342 -291.338834)
			(xy 65.027804 -291.359932) (xy 65.068307 -291.387888) (xy 65.1038 -291.42198) (xy 65.133365 -291.461324)
			(xy 65.156236 -291.504901) (xy 65.17182 -291.551582) (xy 65.179715 -291.600159) (xy 65.18021 -291.624766)
			(xy 65.519058 -291.624766) (xy 65.523018 -291.575712) (xy 65.534795 -291.527928) (xy 65.554086 -291.482652)
			(xy 65.580389 -291.441056) (xy 65.613024 -291.404219) (xy 65.651145 -291.373094) (xy 65.693766 -291.348487)
			(xy 65.739782 -291.331035) (xy 65.788001 -291.321191) (xy 65.837176 -291.31921) (xy 65.886031 -291.325142)
			(xy 65.933302 -291.338834) (xy 65.977764 -291.359932) (xy 66.018267 -291.387888) (xy 66.05376 -291.42198)
			(xy 66.083325 -291.461324) (xy 66.106196 -291.504901) (xy 66.12178 -291.551582) (xy 66.129675 -291.600159)
			(xy 66.13017 -291.624766) (xy 66.469018 -291.624766) (xy 66.472978 -291.575712) (xy 66.484755 -291.527928)
			(xy 66.504046 -291.482652) (xy 66.530349 -291.441056) (xy 66.562984 -291.404219) (xy 66.601105 -291.373094)
			(xy 66.643726 -291.348487) (xy 66.689742 -291.331035) (xy 66.737961 -291.321191) (xy 66.787136 -291.31921)
			(xy 66.835991 -291.325142) (xy 66.883262 -291.338834) (xy 66.927724 -291.359932) (xy 66.968227 -291.387888)
			(xy 67.00372 -291.42198) (xy 67.033285 -291.461324) (xy 67.056156 -291.504901) (xy 67.07174 -291.551582)
			(xy 67.079635 -291.600159) (xy 67.08013 -291.624766) (xy 67.418978 -291.624766) (xy 67.422938 -291.575712)
			(xy 67.434715 -291.527928) (xy 67.454006 -291.482652) (xy 67.480309 -291.441056) (xy 67.512944 -291.404219)
			(xy 67.551065 -291.373094) (xy 67.593686 -291.348487) (xy 67.639702 -291.331035) (xy 67.687921 -291.321191)
			(xy 67.737096 -291.31921) (xy 67.785951 -291.325142) (xy 67.833222 -291.338834) (xy 67.877684 -291.359932)
			(xy 67.918187 -291.387888) (xy 67.95368 -291.42198) (xy 67.983245 -291.461324) (xy 68.006116 -291.504901)
			(xy 68.0217 -291.551582) (xy 68.029595 -291.600159) (xy 68.03009 -291.624766) (xy 68.368938 -291.624766)
			(xy 68.372898 -291.575712) (xy 68.384675 -291.527928) (xy 68.403966 -291.482652) (xy 68.430269 -291.441056)
			(xy 68.462904 -291.404219) (xy 68.501025 -291.373094) (xy 68.543646 -291.348487) (xy 68.589662 -291.331035)
			(xy 68.637881 -291.321191) (xy 68.687056 -291.31921) (xy 68.735911 -291.325142) (xy 68.783182 -291.338834)
			(xy 68.827644 -291.359932) (xy 68.868147 -291.387888) (xy 68.90364 -291.42198) (xy 68.933205 -291.461324)
			(xy 68.956076 -291.504901) (xy 68.97166 -291.551582) (xy 68.979555 -291.600159) (xy 68.98005 -291.624766)
			(xy 69.319152 -291.624766) (xy 69.323112 -291.575712) (xy 69.334889 -291.527928) (xy 69.35418 -291.482652)
			(xy 69.380483 -291.441056) (xy 69.413118 -291.404219) (xy 69.451239 -291.373094) (xy 69.49386 -291.348487)
			(xy 69.539876 -291.331035) (xy 69.588095 -291.321191) (xy 69.63727 -291.31921) (xy 69.686125 -291.325142)
			(xy 69.733396 -291.338834) (xy 69.777858 -291.359932) (xy 69.818361 -291.387888) (xy 69.853854 -291.42198)
			(xy 69.883419 -291.461324) (xy 69.90629 -291.504901) (xy 69.921874 -291.551582) (xy 69.929769 -291.600159)
			(xy 69.930264 -291.624766) (xy 69.929769 -291.649373) (xy 69.921874 -291.69795) (xy 69.90629 -291.744631)
			(xy 69.883419 -291.788208) (xy 69.853854 -291.827552) (xy 69.818361 -291.861644) (xy 69.777858 -291.8896)
			(xy 69.733396 -291.910698) (xy 69.686125 -291.92439) (xy 69.63727 -291.930322) (xy 69.588095 -291.928341)
			(xy 69.539876 -291.918497) (xy 69.49386 -291.901045) (xy 69.451239 -291.876438) (xy 69.413118 -291.845313)
			(xy 69.380483 -291.808476) (xy 69.35418 -291.76688) (xy 69.334889 -291.721604) (xy 69.323112 -291.67382)
			(xy 69.319152 -291.624766) (xy 68.98005 -291.624766) (xy 68.979555 -291.649373) (xy 68.97166 -291.69795)
			(xy 68.956076 -291.744631) (xy 68.933205 -291.788208) (xy 68.90364 -291.827552) (xy 68.868147 -291.861644)
			(xy 68.827644 -291.8896) (xy 68.783182 -291.910698) (xy 68.735911 -291.92439) (xy 68.687056 -291.930322)
			(xy 68.637881 -291.928341) (xy 68.589662 -291.918497) (xy 68.543646 -291.901045) (xy 68.501025 -291.876438)
			(xy 68.462904 -291.845313) (xy 68.430269 -291.808476) (xy 68.403966 -291.76688) (xy 68.384675 -291.721604)
			(xy 68.372898 -291.67382) (xy 68.368938 -291.624766) (xy 68.03009 -291.624766) (xy 68.029595 -291.649373)
			(xy 68.0217 -291.69795) (xy 68.006116 -291.744631) (xy 67.983245 -291.788208) (xy 67.95368 -291.827552)
			(xy 67.918187 -291.861644) (xy 67.877684 -291.8896) (xy 67.833222 -291.910698) (xy 67.785951 -291.92439)
			(xy 67.737096 -291.930322) (xy 67.687921 -291.928341) (xy 67.639702 -291.918497) (xy 67.593686 -291.901045)
			(xy 67.551065 -291.876438) (xy 67.512944 -291.845313) (xy 67.480309 -291.808476) (xy 67.454006 -291.76688)
			(xy 67.434715 -291.721604) (xy 67.422938 -291.67382) (xy 67.418978 -291.624766) (xy 67.08013 -291.624766)
			(xy 67.079635 -291.649373) (xy 67.07174 -291.69795) (xy 67.056156 -291.744631) (xy 67.033285 -291.788208)
			(xy 67.00372 -291.827552) (xy 66.968227 -291.861644) (xy 66.927724 -291.8896) (xy 66.883262 -291.910698)
			(xy 66.835991 -291.92439) (xy 66.787136 -291.930322) (xy 66.737961 -291.928341) (xy 66.689742 -291.918497)
			(xy 66.643726 -291.901045) (xy 66.601105 -291.876438) (xy 66.562984 -291.845313) (xy 66.530349 -291.808476)
			(xy 66.504046 -291.76688) (xy 66.484755 -291.721604) (xy 66.472978 -291.67382) (xy 66.469018 -291.624766)
			(xy 66.13017 -291.624766) (xy 66.129675 -291.649373) (xy 66.12178 -291.69795) (xy 66.106196 -291.744631)
			(xy 66.083325 -291.788208) (xy 66.05376 -291.827552) (xy 66.018267 -291.861644) (xy 65.977764 -291.8896)
			(xy 65.933302 -291.910698) (xy 65.886031 -291.92439) (xy 65.837176 -291.930322) (xy 65.788001 -291.928341)
			(xy 65.739782 -291.918497) (xy 65.693766 -291.901045) (xy 65.651145 -291.876438) (xy 65.613024 -291.845313)
			(xy 65.580389 -291.808476) (xy 65.554086 -291.76688) (xy 65.534795 -291.721604) (xy 65.523018 -291.67382)
			(xy 65.519058 -291.624766) (xy 65.18021 -291.624766) (xy 65.179715 -291.649373) (xy 65.17182 -291.69795)
			(xy 65.156236 -291.744631) (xy 65.133365 -291.788208) (xy 65.1038 -291.827552) (xy 65.068307 -291.861644)
			(xy 65.027804 -291.8896) (xy 64.983342 -291.910698) (xy 64.936071 -291.92439) (xy 64.887216 -291.930322)
			(xy 64.838041 -291.928341) (xy 64.789822 -291.918497) (xy 64.743806 -291.901045) (xy 64.701185 -291.876438)
			(xy 64.663064 -291.845313) (xy 64.630429 -291.808476) (xy 64.604126 -291.76688) (xy 64.584835 -291.721604)
			(xy 64.573058 -291.67382) (xy 64.569098 -291.624766) (xy 64.23025 -291.624766) (xy 64.229755 -291.649373)
			(xy 64.22186 -291.69795) (xy 64.206276 -291.744631) (xy 64.183405 -291.788208) (xy 64.15384 -291.827552)
			(xy 64.118347 -291.861644) (xy 64.077844 -291.8896) (xy 64.033382 -291.910698) (xy 63.986111 -291.92439)
			(xy 63.937256 -291.930322) (xy 63.888081 -291.928341) (xy 63.839862 -291.918497) (xy 63.793846 -291.901045)
			(xy 63.751225 -291.876438) (xy 63.713104 -291.845313) (xy 63.680469 -291.808476) (xy 63.654166 -291.76688)
			(xy 63.634875 -291.721604) (xy 63.623098 -291.67382) (xy 63.619138 -291.624766) (xy 63.28029 -291.624766)
			(xy 63.279795 -291.649373) (xy 63.2719 -291.69795) (xy 63.256316 -291.744631) (xy 63.233445 -291.788208)
			(xy 63.20388 -291.827552) (xy 63.168387 -291.861644) (xy 63.127884 -291.8896) (xy 63.083422 -291.910698)
			(xy 63.036151 -291.92439) (xy 62.987296 -291.930322) (xy 62.938121 -291.928341) (xy 62.889902 -291.918497)
			(xy 62.843886 -291.901045) (xy 62.801265 -291.876438) (xy 62.763144 -291.845313) (xy 62.730509 -291.808476)
			(xy 62.704206 -291.76688) (xy 62.684915 -291.721604) (xy 62.673138 -291.67382) (xy 62.669178 -291.624766)
			(xy 62.330076 -291.624766) (xy 62.329581 -291.649373) (xy 62.321686 -291.69795) (xy 62.306102 -291.744631)
			(xy 62.283231 -291.788208) (xy 62.253666 -291.827552) (xy 62.218173 -291.861644) (xy 62.17767 -291.8896)
			(xy 62.133208 -291.910698) (xy 62.085937 -291.92439) (xy 62.037082 -291.930322) (xy 61.987907 -291.928341)
			(xy 61.939688 -291.918497) (xy 61.893672 -291.901045) (xy 61.851051 -291.876438) (xy 61.81293 -291.845313)
			(xy 61.780295 -291.808476) (xy 61.753992 -291.76688) (xy 61.734701 -291.721604) (xy 61.722924 -291.67382)
			(xy 61.718964 -291.624766) (xy 61.380116 -291.624766) (xy 61.379621 -291.649373) (xy 61.371726 -291.69795)
			(xy 61.356142 -291.744631) (xy 61.333271 -291.788208) (xy 61.303706 -291.827552) (xy 61.268213 -291.861644)
			(xy 61.22771 -291.8896) (xy 61.183248 -291.910698) (xy 61.135977 -291.92439) (xy 61.087122 -291.930322)
			(xy 61.037947 -291.928341) (xy 60.989728 -291.918497) (xy 60.943712 -291.901045) (xy 60.901091 -291.876438)
			(xy 60.86297 -291.845313) (xy 60.830335 -291.808476) (xy 60.804032 -291.76688) (xy 60.784741 -291.721604)
			(xy 60.772964 -291.67382) (xy 60.769004 -291.624766) (xy 60.430156 -291.624766) (xy 60.429661 -291.649373)
			(xy 60.421766 -291.69795) (xy 60.406182 -291.744631) (xy 60.383311 -291.788208) (xy 60.353746 -291.827552)
			(xy 60.318253 -291.861644) (xy 60.27775 -291.8896) (xy 60.233288 -291.910698) (xy 60.186017 -291.92439)
			(xy 60.137162 -291.930322) (xy 60.087987 -291.928341) (xy 60.039768 -291.918497) (xy 59.993752 -291.901045)
			(xy 59.951131 -291.876438) (xy 59.91301 -291.845313) (xy 59.880375 -291.808476) (xy 59.854072 -291.76688)
			(xy 59.834781 -291.721604) (xy 59.823004 -291.67382) (xy 59.819044 -291.624766) (xy 58.530236 -291.624766)
			(xy 58.529741 -291.649373) (xy 58.521846 -291.69795) (xy 58.506262 -291.744631) (xy 58.483391 -291.788208)
			(xy 58.453826 -291.827552) (xy 58.418333 -291.861644) (xy 58.37783 -291.8896) (xy 58.333368 -291.910698)
			(xy 58.286097 -291.92439) (xy 58.237242 -291.930322) (xy 58.188067 -291.928341) (xy 58.139848 -291.918497)
			(xy 58.093832 -291.901045) (xy 58.051211 -291.876438) (xy 58.01309 -291.845313) (xy 57.980455 -291.808476)
			(xy 57.954152 -291.76688) (xy 57.934861 -291.721604) (xy 57.923084 -291.67382) (xy 57.919124 -291.624766)
			(xy 57.580276 -291.624766) (xy 57.579781 -291.649373) (xy 57.571886 -291.69795) (xy 57.556302 -291.744631)
			(xy 57.533431 -291.788208) (xy 57.503866 -291.827552) (xy 57.468373 -291.861644) (xy 57.42787 -291.8896)
			(xy 57.383408 -291.910698) (xy 57.336137 -291.92439) (xy 57.287282 -291.930322) (xy 57.238107 -291.928341)
			(xy 57.189888 -291.918497) (xy 57.143872 -291.901045) (xy 57.101251 -291.876438) (xy 57.06313 -291.845313)
			(xy 57.030495 -291.808476) (xy 57.004192 -291.76688) (xy 56.984901 -291.721604) (xy 56.973124 -291.67382)
			(xy 56.969164 -291.624766) (xy 56.630062 -291.624766) (xy 56.629567 -291.649373) (xy 56.621672 -291.69795)
			(xy 56.606088 -291.744631) (xy 56.583217 -291.788208) (xy 56.553652 -291.827552) (xy 56.518159 -291.861644)
			(xy 56.477656 -291.8896) (xy 56.433194 -291.910698) (xy 56.385923 -291.92439) (xy 56.337068 -291.930322)
			(xy 56.287893 -291.928341) (xy 56.239674 -291.918497) (xy 56.193658 -291.901045) (xy 56.151037 -291.876438)
			(xy 56.112916 -291.845313) (xy 56.080281 -291.808476) (xy 56.053978 -291.76688) (xy 56.034687 -291.721604)
			(xy 56.02291 -291.67382) (xy 56.01895 -291.624766) (xy 55.680102 -291.624766) (xy 55.679607 -291.649373)
			(xy 55.671712 -291.69795) (xy 55.656128 -291.744631) (xy 55.633257 -291.788208) (xy 55.603692 -291.827552)
			(xy 55.568199 -291.861644) (xy 55.527696 -291.8896) (xy 55.483234 -291.910698) (xy 55.435963 -291.92439)
			(xy 55.387108 -291.930322) (xy 55.337933 -291.928341) (xy 55.289714 -291.918497) (xy 55.243698 -291.901045)
			(xy 55.201077 -291.876438) (xy 55.162956 -291.845313) (xy 55.130321 -291.808476) (xy 55.104018 -291.76688)
			(xy 55.084727 -291.721604) (xy 55.07295 -291.67382) (xy 55.06899 -291.624766) (xy 54.730142 -291.624766)
			(xy 54.729647 -291.649373) (xy 54.721752 -291.69795) (xy 54.706168 -291.744631) (xy 54.683297 -291.788208)
			(xy 54.653732 -291.827552) (xy 54.618239 -291.861644) (xy 54.577736 -291.8896) (xy 54.533274 -291.910698)
			(xy 54.486003 -291.92439) (xy 54.437148 -291.930322) (xy 54.387973 -291.928341) (xy 54.339754 -291.918497)
			(xy 54.293738 -291.901045) (xy 54.251117 -291.876438) (xy 54.212996 -291.845313) (xy 54.180361 -291.808476)
			(xy 54.154058 -291.76688) (xy 54.134767 -291.721604) (xy 54.12299 -291.67382) (xy 54.11903 -291.624766)
			(xy 53.780182 -291.624766) (xy 53.779687 -291.649373) (xy 53.771792 -291.69795) (xy 53.756208 -291.744631)
			(xy 53.733337 -291.788208) (xy 53.703772 -291.827552) (xy 53.668279 -291.861644) (xy 53.627776 -291.8896)
			(xy 53.583314 -291.910698) (xy 53.536043 -291.92439) (xy 53.487188 -291.930322) (xy 53.438013 -291.928341)
			(xy 53.389794 -291.918497) (xy 53.343778 -291.901045) (xy 53.301157 -291.876438) (xy 53.263036 -291.845313)
			(xy 53.230401 -291.808476) (xy 53.204098 -291.76688) (xy 53.184807 -291.721604) (xy 53.17303 -291.67382)
			(xy 53.16907 -291.624766) (xy 52.830222 -291.624766) (xy 52.829727 -291.649373) (xy 52.821832 -291.69795)
			(xy 52.806248 -291.744631) (xy 52.783377 -291.788208) (xy 52.753812 -291.827552) (xy 52.718319 -291.861644)
			(xy 52.677816 -291.8896) (xy 52.633354 -291.910698) (xy 52.586083 -291.92439) (xy 52.537228 -291.930322)
			(xy 52.488053 -291.928341) (xy 52.439834 -291.918497) (xy 52.393818 -291.901045) (xy 52.351197 -291.876438)
			(xy 52.313076 -291.845313) (xy 52.280441 -291.808476) (xy 52.254138 -291.76688) (xy 52.234847 -291.721604)
			(xy 52.22307 -291.67382) (xy 52.21911 -291.624766) (xy 51.880262 -291.624766) (xy 51.879767 -291.649373)
			(xy 51.871872 -291.69795) (xy 51.856288 -291.744631) (xy 51.833417 -291.788208) (xy 51.803852 -291.827552)
			(xy 51.768359 -291.861644) (xy 51.727856 -291.8896) (xy 51.683394 -291.910698) (xy 51.636123 -291.92439)
			(xy 51.587268 -291.930322) (xy 51.538093 -291.928341) (xy 51.489874 -291.918497) (xy 51.443858 -291.901045)
			(xy 51.401237 -291.876438) (xy 51.363116 -291.845313) (xy 51.330481 -291.808476) (xy 51.304178 -291.76688)
			(xy 51.284887 -291.721604) (xy 51.27311 -291.67382) (xy 51.26915 -291.624766) (xy 50.930302 -291.624766)
			(xy 50.929807 -291.649373) (xy 50.921912 -291.69795) (xy 50.906328 -291.744631) (xy 50.883457 -291.788208)
			(xy 50.853892 -291.827552) (xy 50.818399 -291.861644) (xy 50.777896 -291.8896) (xy 50.733434 -291.910698)
			(xy 50.686163 -291.92439) (xy 50.637308 -291.930322) (xy 50.588133 -291.928341) (xy 50.539914 -291.918497)
			(xy 50.493898 -291.901045) (xy 50.451277 -291.876438) (xy 50.413156 -291.845313) (xy 50.380521 -291.808476)
			(xy 50.354218 -291.76688) (xy 50.334927 -291.721604) (xy 50.32315 -291.67382) (xy 50.31919 -291.624766)
			(xy 49.980088 -291.624766) (xy 49.979593 -291.649373) (xy 49.971698 -291.69795) (xy 49.956114 -291.744631)
			(xy 49.933243 -291.788208) (xy 49.903678 -291.827552) (xy 49.868185 -291.861644) (xy 49.827682 -291.8896)
			(xy 49.78322 -291.910698) (xy 49.735949 -291.92439) (xy 49.687094 -291.930322) (xy 49.637919 -291.928341)
			(xy 49.5897 -291.918497) (xy 49.543684 -291.901045) (xy 49.501063 -291.876438) (xy 49.462942 -291.845313)
			(xy 49.430307 -291.808476) (xy 49.404004 -291.76688) (xy 49.384713 -291.721604) (xy 49.372936 -291.67382)
			(xy 49.368976 -291.624766) (xy 49.030128 -291.624766) (xy 49.029633 -291.649373) (xy 49.021738 -291.69795)
			(xy 49.006154 -291.744631) (xy 48.983283 -291.788208) (xy 48.953718 -291.827552) (xy 48.918225 -291.861644)
			(xy 48.877722 -291.8896) (xy 48.83326 -291.910698) (xy 48.785989 -291.92439) (xy 48.737134 -291.930322)
			(xy 48.687959 -291.928341) (xy 48.63974 -291.918497) (xy 48.593724 -291.901045) (xy 48.551103 -291.876438)
			(xy 48.512982 -291.845313) (xy 48.480347 -291.808476) (xy 48.454044 -291.76688) (xy 48.434753 -291.721604)
			(xy 48.422976 -291.67382) (xy 48.419016 -291.624766) (xy 48.080168 -291.624766) (xy 48.079673 -291.649373)
			(xy 48.071778 -291.69795) (xy 48.056194 -291.744631) (xy 48.033323 -291.788208) (xy 48.003758 -291.827552)
			(xy 47.968265 -291.861644) (xy 47.927762 -291.8896) (xy 47.8833 -291.910698) (xy 47.836029 -291.92439)
			(xy 47.787174 -291.930322) (xy 47.737999 -291.928341) (xy 47.68978 -291.918497) (xy 47.643764 -291.901045)
			(xy 47.601143 -291.876438) (xy 47.563022 -291.845313) (xy 47.530387 -291.808476) (xy 47.504084 -291.76688)
			(xy 47.484793 -291.721604) (xy 47.473016 -291.67382) (xy 47.469056 -291.624766) (xy 46.180248 -291.624766)
			(xy 46.179753 -291.649373) (xy 46.171858 -291.69795) (xy 46.156274 -291.744631) (xy 46.133403 -291.788208)
			(xy 46.103838 -291.827552) (xy 46.068345 -291.861644) (xy 46.027842 -291.8896) (xy 45.98338 -291.910698)
			(xy 45.936109 -291.92439) (xy 45.887254 -291.930322) (xy 45.838079 -291.928341) (xy 45.78986 -291.918497)
			(xy 45.743844 -291.901045) (xy 45.701223 -291.876438) (xy 45.663102 -291.845313) (xy 45.630467 -291.808476)
			(xy 45.604164 -291.76688) (xy 45.584873 -291.721604) (xy 45.573096 -291.67382) (xy 45.569136 -291.624766)
			(xy 44.280074 -291.624766) (xy 44.279579 -291.649373) (xy 44.271684 -291.69795) (xy 44.2561 -291.744631)
			(xy 44.233229 -291.788208) (xy 44.203664 -291.827552) (xy 44.168171 -291.861644) (xy 44.127668 -291.8896)
			(xy 44.083206 -291.910698) (xy 44.035935 -291.92439) (xy 43.98708 -291.930322) (xy 43.937905 -291.928341)
			(xy 43.889686 -291.918497) (xy 43.84367 -291.901045) (xy 43.801049 -291.876438) (xy 43.762928 -291.845313)
			(xy 43.730293 -291.808476) (xy 43.70399 -291.76688) (xy 43.684699 -291.721604) (xy 43.672922 -291.67382)
			(xy 43.668962 -291.624766) (xy 43.356028 -291.624766) (xy 43.35603 -291.624788) (xy 43.351792 -291.67762)
			(xy 43.339181 -291.7291) (xy 43.31852 -291.777909) (xy 43.290338 -291.822798) (xy 43.255357 -291.862617)
			(xy 43.214473 -291.896347) (xy 43.168733 -291.923123) (xy 43.144186 -291.933122) (xy 43.137074 -291.935916)
			(xy 43.125136 -291.945314) (xy 43.120818 -291.951664) (xy 43.11666 -291.958177) (xy 43.112001 -291.972901)
			(xy 43.111674 -291.98062) (xy 43.111674 -292.219126) (xy 43.111947 -292.226855) (xy 43.116615 -292.241589)
			(xy 43.120818 -292.248082) (xy 43.125136 -292.254432) (xy 43.137074 -292.26383) (xy 43.144186 -292.266624)
			(xy 43.168709 -292.27668) (xy 43.21445 -292.303453) (xy 43.255334 -292.337179) (xy 43.290316 -292.376995)
			(xy 43.318499 -292.42188) (xy 43.339162 -292.470686) (xy 43.351776 -292.522163) (xy 43.356016 -292.57498)
			(xy 43.668962 -292.57498) (xy 43.672922 -292.525926) (xy 43.684699 -292.478142) (xy 43.70399 -292.432866)
			(xy 43.730293 -292.39127) (xy 43.762928 -292.354433) (xy 43.801049 -292.323308) (xy 43.84367 -292.298701)
			(xy 43.889686 -292.281249) (xy 43.937905 -292.271405) (xy 43.98708 -292.269424) (xy 44.035935 -292.275356)
			(xy 44.083206 -292.289048) (xy 44.127668 -292.310146) (xy 44.168171 -292.338102) (xy 44.203664 -292.372194)
			(xy 44.233229 -292.411538) (xy 44.2561 -292.455115) (xy 44.271684 -292.501796) (xy 44.279579 -292.550373)
			(xy 44.280074 -292.57498) (xy 45.569136 -292.57498) (xy 45.573096 -292.525926) (xy 45.584873 -292.478142)
			(xy 45.604164 -292.432866) (xy 45.630467 -292.39127) (xy 45.663102 -292.354433) (xy 45.701223 -292.323308)
			(xy 45.743844 -292.298701) (xy 45.78986 -292.281249) (xy 45.838079 -292.271405) (xy 45.887254 -292.269424)
			(xy 45.936109 -292.275356) (xy 45.98338 -292.289048) (xy 46.027842 -292.310146) (xy 46.068345 -292.338102)
			(xy 46.103838 -292.372194) (xy 46.133403 -292.411538) (xy 46.156274 -292.455115) (xy 46.171858 -292.501796)
			(xy 46.179753 -292.550373) (xy 46.180248 -292.57498) (xy 46.519096 -292.57498) (xy 46.523056 -292.525926)
			(xy 46.534833 -292.478142) (xy 46.554124 -292.432866) (xy 46.580427 -292.39127) (xy 46.613062 -292.354433)
			(xy 46.651183 -292.323308) (xy 46.693804 -292.298701) (xy 46.73982 -292.281249) (xy 46.788039 -292.271405)
			(xy 46.837214 -292.269424) (xy 46.886069 -292.275356) (xy 46.93334 -292.289048) (xy 46.977802 -292.310146)
			(xy 47.018305 -292.338102) (xy 47.053798 -292.372194) (xy 47.083363 -292.411538) (xy 47.106234 -292.455115)
			(xy 47.121818 -292.501796) (xy 47.129713 -292.550373) (xy 47.130208 -292.57498) (xy 47.469056 -292.57498)
			(xy 47.473016 -292.525926) (xy 47.484793 -292.478142) (xy 47.504084 -292.432866) (xy 47.530387 -292.39127)
			(xy 47.563022 -292.354433) (xy 47.601143 -292.323308) (xy 47.643764 -292.298701) (xy 47.68978 -292.281249)
			(xy 47.737999 -292.271405) (xy 47.787174 -292.269424) (xy 47.836029 -292.275356) (xy 47.8833 -292.289048)
			(xy 47.927762 -292.310146) (xy 47.968265 -292.338102) (xy 48.003758 -292.372194) (xy 48.033323 -292.411538)
			(xy 48.056194 -292.455115) (xy 48.071778 -292.501796) (xy 48.079673 -292.550373) (xy 48.080163 -292.574726)
			(xy 48.419016 -292.574726) (xy 48.422976 -292.525672) (xy 48.434753 -292.477888) (xy 48.454044 -292.432612)
			(xy 48.480347 -292.391016) (xy 48.512982 -292.354179) (xy 48.551103 -292.323054) (xy 48.593724 -292.298447)
			(xy 48.63974 -292.280995) (xy 48.687959 -292.271151) (xy 48.737134 -292.26917) (xy 48.785989 -292.275102)
			(xy 48.83326 -292.288794) (xy 48.877722 -292.309892) (xy 48.918225 -292.337848) (xy 48.953718 -292.37194)
			(xy 48.983283 -292.411284) (xy 49.006154 -292.454861) (xy 49.021738 -292.501542) (xy 49.029633 -292.550119)
			(xy 49.030128 -292.574726) (xy 49.368976 -292.574726) (xy 49.372936 -292.525672) (xy 49.384713 -292.477888)
			(xy 49.404004 -292.432612) (xy 49.430307 -292.391016) (xy 49.462942 -292.354179) (xy 49.501063 -292.323054)
			(xy 49.543684 -292.298447) (xy 49.5897 -292.280995) (xy 49.637919 -292.271151) (xy 49.687094 -292.26917)
			(xy 49.735949 -292.275102) (xy 49.78322 -292.288794) (xy 49.827682 -292.309892) (xy 49.868185 -292.337848)
			(xy 49.903678 -292.37194) (xy 49.933243 -292.411284) (xy 49.956114 -292.454861) (xy 49.971698 -292.501542)
			(xy 49.979593 -292.550119) (xy 49.980088 -292.574726) (xy 49.980083 -292.57498) (xy 50.31919 -292.57498)
			(xy 50.32315 -292.525926) (xy 50.334927 -292.478142) (xy 50.354218 -292.432866) (xy 50.380521 -292.39127)
			(xy 50.413156 -292.354433) (xy 50.451277 -292.323308) (xy 50.493898 -292.298701) (xy 50.539914 -292.281249)
			(xy 50.588133 -292.271405) (xy 50.637308 -292.269424) (xy 50.686163 -292.275356) (xy 50.733434 -292.289048)
			(xy 50.777896 -292.310146) (xy 50.818399 -292.338102) (xy 50.853892 -292.372194) (xy 50.883457 -292.411538)
			(xy 50.906328 -292.455115) (xy 50.921912 -292.501796) (xy 50.929807 -292.550373) (xy 50.930302 -292.57498)
			(xy 51.26915 -292.57498) (xy 51.27311 -292.525926) (xy 51.284887 -292.478142) (xy 51.304178 -292.432866)
			(xy 51.330481 -292.39127) (xy 51.363116 -292.354433) (xy 51.401237 -292.323308) (xy 51.443858 -292.298701)
			(xy 51.489874 -292.281249) (xy 51.538093 -292.271405) (xy 51.587268 -292.269424) (xy 51.636123 -292.275356)
			(xy 51.683394 -292.289048) (xy 51.727856 -292.310146) (xy 51.768359 -292.338102) (xy 51.803852 -292.372194)
			(xy 51.833417 -292.411538) (xy 51.856288 -292.455115) (xy 51.871872 -292.501796) (xy 51.879767 -292.550373)
			(xy 51.880262 -292.57498) (xy 52.21911 -292.57498) (xy 52.22307 -292.525926) (xy 52.234847 -292.478142)
			(xy 52.254138 -292.432866) (xy 52.280441 -292.39127) (xy 52.313076 -292.354433) (xy 52.351197 -292.323308)
			(xy 52.393818 -292.298701) (xy 52.439834 -292.281249) (xy 52.488053 -292.271405) (xy 52.537228 -292.269424)
			(xy 52.586083 -292.275356) (xy 52.633354 -292.289048) (xy 52.677816 -292.310146) (xy 52.718319 -292.338102)
			(xy 52.753812 -292.372194) (xy 52.783377 -292.411538) (xy 52.806248 -292.455115) (xy 52.821832 -292.501796)
			(xy 52.829727 -292.550373) (xy 52.830222 -292.57498) (xy 53.16907 -292.57498) (xy 53.17303 -292.525926)
			(xy 53.184807 -292.478142) (xy 53.204098 -292.432866) (xy 53.230401 -292.39127) (xy 53.263036 -292.354433)
			(xy 53.301157 -292.323308) (xy 53.343778 -292.298701) (xy 53.389794 -292.281249) (xy 53.438013 -292.271405)
			(xy 53.487188 -292.269424) (xy 53.536043 -292.275356) (xy 53.583314 -292.289048) (xy 53.627776 -292.310146)
			(xy 53.668279 -292.338102) (xy 53.703772 -292.372194) (xy 53.733337 -292.411538) (xy 53.756208 -292.455115)
			(xy 53.771792 -292.501796) (xy 53.779687 -292.550373) (xy 53.780182 -292.57498) (xy 54.11903 -292.57498)
			(xy 54.12299 -292.525926) (xy 54.134767 -292.478142) (xy 54.154058 -292.432866) (xy 54.180361 -292.39127)
			(xy 54.212996 -292.354433) (xy 54.251117 -292.323308) (xy 54.293738 -292.298701) (xy 54.339754 -292.281249)
			(xy 54.387973 -292.271405) (xy 54.437148 -292.269424) (xy 54.486003 -292.275356) (xy 54.533274 -292.289048)
			(xy 54.577736 -292.310146) (xy 54.618239 -292.338102) (xy 54.653732 -292.372194) (xy 54.683297 -292.411538)
			(xy 54.706168 -292.455115) (xy 54.721752 -292.501796) (xy 54.729647 -292.550373) (xy 54.730142 -292.57498)
			(xy 55.06899 -292.57498) (xy 55.07295 -292.525926) (xy 55.084727 -292.478142) (xy 55.104018 -292.432866)
			(xy 55.130321 -292.39127) (xy 55.162956 -292.354433) (xy 55.201077 -292.323308) (xy 55.243698 -292.298701)
			(xy 55.289714 -292.281249) (xy 55.337933 -292.271405) (xy 55.387108 -292.269424) (xy 55.435963 -292.275356)
			(xy 55.483234 -292.289048) (xy 55.527696 -292.310146) (xy 55.568199 -292.338102) (xy 55.603692 -292.372194)
			(xy 55.633257 -292.411538) (xy 55.656128 -292.455115) (xy 55.671712 -292.501796) (xy 55.679607 -292.550373)
			(xy 55.680102 -292.57498) (xy 56.019204 -292.57498) (xy 56.023164 -292.525926) (xy 56.034941 -292.478142)
			(xy 56.054232 -292.432866) (xy 56.080535 -292.39127) (xy 56.11317 -292.354433) (xy 56.151291 -292.323308)
			(xy 56.193912 -292.298701) (xy 56.239928 -292.281249) (xy 56.288147 -292.271405) (xy 56.337322 -292.269424)
			(xy 56.386177 -292.275356) (xy 56.433448 -292.289048) (xy 56.47791 -292.310146) (xy 56.518413 -292.338102)
			(xy 56.553906 -292.372194) (xy 56.583471 -292.411538) (xy 56.606342 -292.455115) (xy 56.621926 -292.501796)
			(xy 56.629821 -292.550373) (xy 56.630316 -292.57498) (xy 56.969164 -292.57498) (xy 56.973124 -292.525926)
			(xy 56.984901 -292.478142) (xy 57.004192 -292.432866) (xy 57.030495 -292.39127) (xy 57.06313 -292.354433)
			(xy 57.101251 -292.323308) (xy 57.143872 -292.298701) (xy 57.189888 -292.281249) (xy 57.238107 -292.271405)
			(xy 57.287282 -292.269424) (xy 57.336137 -292.275356) (xy 57.383408 -292.289048) (xy 57.42787 -292.310146)
			(xy 57.468373 -292.338102) (xy 57.503866 -292.372194) (xy 57.533431 -292.411538) (xy 57.556302 -292.455115)
			(xy 57.571886 -292.501796) (xy 57.579781 -292.550373) (xy 57.580276 -292.57498) (xy 57.919124 -292.57498)
			(xy 57.923084 -292.525926) (xy 57.934861 -292.478142) (xy 57.954152 -292.432866) (xy 57.980455 -292.39127)
			(xy 58.01309 -292.354433) (xy 58.051211 -292.323308) (xy 58.093832 -292.298701) (xy 58.139848 -292.281249)
			(xy 58.188067 -292.271405) (xy 58.237242 -292.269424) (xy 58.286097 -292.275356) (xy 58.333368 -292.289048)
			(xy 58.37783 -292.310146) (xy 58.418333 -292.338102) (xy 58.453826 -292.372194) (xy 58.483391 -292.411538)
			(xy 58.506262 -292.455115) (xy 58.521846 -292.501796) (xy 58.529741 -292.550373) (xy 58.530231 -292.574726)
			(xy 59.819044 -292.574726) (xy 59.823004 -292.525672) (xy 59.834781 -292.477888) (xy 59.854072 -292.432612)
			(xy 59.880375 -292.391016) (xy 59.91301 -292.354179) (xy 59.951131 -292.323054) (xy 59.993752 -292.298447)
			(xy 60.039768 -292.280995) (xy 60.087987 -292.271151) (xy 60.137162 -292.26917) (xy 60.186017 -292.275102)
			(xy 60.233288 -292.288794) (xy 60.27775 -292.309892) (xy 60.318253 -292.337848) (xy 60.353746 -292.37194)
			(xy 60.383311 -292.411284) (xy 60.406182 -292.454861) (xy 60.421766 -292.501542) (xy 60.429661 -292.550119)
			(xy 60.430156 -292.574726) (xy 60.769004 -292.574726) (xy 60.772964 -292.525672) (xy 60.784741 -292.477888)
			(xy 60.804032 -292.432612) (xy 60.830335 -292.391016) (xy 60.86297 -292.354179) (xy 60.901091 -292.323054)
			(xy 60.943712 -292.298447) (xy 60.989728 -292.280995) (xy 61.037947 -292.271151) (xy 61.087122 -292.26917)
			(xy 61.135977 -292.275102) (xy 61.183248 -292.288794) (xy 61.22771 -292.309892) (xy 61.268213 -292.337848)
			(xy 61.303706 -292.37194) (xy 61.333271 -292.411284) (xy 61.356142 -292.454861) (xy 61.371726 -292.501542)
			(xy 61.379621 -292.550119) (xy 61.380116 -292.574726) (xy 61.718964 -292.574726) (xy 61.722924 -292.525672)
			(xy 61.734701 -292.477888) (xy 61.753992 -292.432612) (xy 61.780295 -292.391016) (xy 61.81293 -292.354179)
			(xy 61.851051 -292.323054) (xy 61.893672 -292.298447) (xy 61.939688 -292.280995) (xy 61.987907 -292.271151)
			(xy 62.037082 -292.26917) (xy 62.085937 -292.275102) (xy 62.133208 -292.288794) (xy 62.17767 -292.309892)
			(xy 62.218173 -292.337848) (xy 62.253666 -292.37194) (xy 62.283231 -292.411284) (xy 62.306102 -292.454861)
			(xy 62.321686 -292.501542) (xy 62.329581 -292.550119) (xy 62.330076 -292.574726) (xy 62.669178 -292.574726)
			(xy 62.673138 -292.525672) (xy 62.684915 -292.477888) (xy 62.704206 -292.432612) (xy 62.730509 -292.391016)
			(xy 62.763144 -292.354179) (xy 62.801265 -292.323054) (xy 62.843886 -292.298447) (xy 62.889902 -292.280995)
			(xy 62.938121 -292.271151) (xy 62.987296 -292.26917) (xy 63.036151 -292.275102) (xy 63.083422 -292.288794)
			(xy 63.127884 -292.309892) (xy 63.168387 -292.337848) (xy 63.20388 -292.37194) (xy 63.233445 -292.411284)
			(xy 63.256316 -292.454861) (xy 63.2719 -292.501542) (xy 63.279795 -292.550119) (xy 63.28029 -292.574726)
			(xy 63.619138 -292.574726) (xy 63.623098 -292.525672) (xy 63.634875 -292.477888) (xy 63.654166 -292.432612)
			(xy 63.680469 -292.391016) (xy 63.713104 -292.354179) (xy 63.751225 -292.323054) (xy 63.793846 -292.298447)
			(xy 63.839862 -292.280995) (xy 63.888081 -292.271151) (xy 63.937256 -292.26917) (xy 63.986111 -292.275102)
			(xy 64.033382 -292.288794) (xy 64.077844 -292.309892) (xy 64.118347 -292.337848) (xy 64.15384 -292.37194)
			(xy 64.183405 -292.411284) (xy 64.206276 -292.454861) (xy 64.22186 -292.501542) (xy 64.229755 -292.550119)
			(xy 64.23025 -292.574726) (xy 64.569098 -292.574726) (xy 64.573058 -292.525672) (xy 64.584835 -292.477888)
			(xy 64.604126 -292.432612) (xy 64.630429 -292.391016) (xy 64.663064 -292.354179) (xy 64.701185 -292.323054)
			(xy 64.743806 -292.298447) (xy 64.789822 -292.280995) (xy 64.838041 -292.271151) (xy 64.887216 -292.26917)
			(xy 64.936071 -292.275102) (xy 64.983342 -292.288794) (xy 65.027804 -292.309892) (xy 65.068307 -292.337848)
			(xy 65.1038 -292.37194) (xy 65.133365 -292.411284) (xy 65.156236 -292.454861) (xy 65.17182 -292.501542)
			(xy 65.179715 -292.550119) (xy 65.18021 -292.574726) (xy 65.519058 -292.574726) (xy 65.523018 -292.525672)
			(xy 65.534795 -292.477888) (xy 65.554086 -292.432612) (xy 65.580389 -292.391016) (xy 65.613024 -292.354179)
			(xy 65.651145 -292.323054) (xy 65.693766 -292.298447) (xy 65.739782 -292.280995) (xy 65.788001 -292.271151)
			(xy 65.837176 -292.26917) (xy 65.886031 -292.275102) (xy 65.933302 -292.288794) (xy 65.977764 -292.309892)
			(xy 66.018267 -292.337848) (xy 66.05376 -292.37194) (xy 66.083325 -292.411284) (xy 66.106196 -292.454861)
			(xy 66.12178 -292.501542) (xy 66.129675 -292.550119) (xy 66.13017 -292.574726) (xy 66.469018 -292.574726)
			(xy 66.472978 -292.525672) (xy 66.484755 -292.477888) (xy 66.504046 -292.432612) (xy 66.530349 -292.391016)
			(xy 66.562984 -292.354179) (xy 66.601105 -292.323054) (xy 66.643726 -292.298447) (xy 66.689742 -292.280995)
			(xy 66.737961 -292.271151) (xy 66.787136 -292.26917) (xy 66.835991 -292.275102) (xy 66.883262 -292.288794)
			(xy 66.927724 -292.309892) (xy 66.968227 -292.337848) (xy 67.00372 -292.37194) (xy 67.033285 -292.411284)
			(xy 67.056156 -292.454861) (xy 67.07174 -292.501542) (xy 67.079635 -292.550119) (xy 67.08013 -292.574726)
			(xy 67.418978 -292.574726) (xy 67.422938 -292.525672) (xy 67.434715 -292.477888) (xy 67.454006 -292.432612)
			(xy 67.480309 -292.391016) (xy 67.512944 -292.354179) (xy 67.551065 -292.323054) (xy 67.593686 -292.298447)
			(xy 67.639702 -292.280995) (xy 67.687921 -292.271151) (xy 67.737096 -292.26917) (xy 67.785951 -292.275102)
			(xy 67.833222 -292.288794) (xy 67.877684 -292.309892) (xy 67.918187 -292.337848) (xy 67.95368 -292.37194)
			(xy 67.983245 -292.411284) (xy 68.006116 -292.454861) (xy 68.0217 -292.501542) (xy 68.029595 -292.550119)
			(xy 68.03009 -292.574726) (xy 68.368938 -292.574726) (xy 68.372898 -292.525672) (xy 68.384675 -292.477888)
			(xy 68.403966 -292.432612) (xy 68.430269 -292.391016) (xy 68.462904 -292.354179) (xy 68.501025 -292.323054)
			(xy 68.543646 -292.298447) (xy 68.589662 -292.280995) (xy 68.637881 -292.271151) (xy 68.687056 -292.26917)
			(xy 68.735911 -292.275102) (xy 68.783182 -292.288794) (xy 68.827644 -292.309892) (xy 68.868147 -292.337848)
			(xy 68.90364 -292.37194) (xy 68.933205 -292.411284) (xy 68.956076 -292.454861) (xy 68.97166 -292.501542)
			(xy 68.979555 -292.550119) (xy 68.98005 -292.574726) (xy 69.319152 -292.574726) (xy 69.323112 -292.525672)
			(xy 69.334889 -292.477888) (xy 69.35418 -292.432612) (xy 69.380483 -292.391016) (xy 69.413118 -292.354179)
			(xy 69.451239 -292.323054) (xy 69.49386 -292.298447) (xy 69.539876 -292.280995) (xy 69.588095 -292.271151)
			(xy 69.63727 -292.26917) (xy 69.686125 -292.275102) (xy 69.733396 -292.288794) (xy 69.777858 -292.309892)
			(xy 69.818361 -292.337848) (xy 69.853854 -292.37194) (xy 69.883419 -292.411284) (xy 69.90629 -292.454861)
			(xy 69.921874 -292.501542) (xy 69.929769 -292.550119) (xy 69.930264 -292.574726) (xy 69.929769 -292.599333)
			(xy 69.921874 -292.64791) (xy 69.90629 -292.694591) (xy 69.883419 -292.738168) (xy 69.853854 -292.777512)
			(xy 69.818361 -292.811604) (xy 69.777858 -292.83956) (xy 69.733396 -292.860658) (xy 69.686125 -292.87435)
			(xy 69.63727 -292.880282) (xy 69.588095 -292.878301) (xy 69.539876 -292.868457) (xy 69.49386 -292.851005)
			(xy 69.451239 -292.826398) (xy 69.413118 -292.795273) (xy 69.380483 -292.758436) (xy 69.35418 -292.71684)
			(xy 69.334889 -292.671564) (xy 69.323112 -292.62378) (xy 69.319152 -292.574726) (xy 68.98005 -292.574726)
			(xy 68.979555 -292.599333) (xy 68.97166 -292.64791) (xy 68.956076 -292.694591) (xy 68.933205 -292.738168)
			(xy 68.90364 -292.777512) (xy 68.868147 -292.811604) (xy 68.827644 -292.83956) (xy 68.783182 -292.860658)
			(xy 68.735911 -292.87435) (xy 68.687056 -292.880282) (xy 68.637881 -292.878301) (xy 68.589662 -292.868457)
			(xy 68.543646 -292.851005) (xy 68.501025 -292.826398) (xy 68.462904 -292.795273) (xy 68.430269 -292.758436)
			(xy 68.403966 -292.71684) (xy 68.384675 -292.671564) (xy 68.372898 -292.62378) (xy 68.368938 -292.574726)
			(xy 68.03009 -292.574726) (xy 68.029595 -292.599333) (xy 68.0217 -292.64791) (xy 68.006116 -292.694591)
			(xy 67.983245 -292.738168) (xy 67.95368 -292.777512) (xy 67.918187 -292.811604) (xy 67.877684 -292.83956)
			(xy 67.833222 -292.860658) (xy 67.785951 -292.87435) (xy 67.737096 -292.880282) (xy 67.687921 -292.878301)
			(xy 67.639702 -292.868457) (xy 67.593686 -292.851005) (xy 67.551065 -292.826398) (xy 67.512944 -292.795273)
			(xy 67.480309 -292.758436) (xy 67.454006 -292.71684) (xy 67.434715 -292.671564) (xy 67.422938 -292.62378)
			(xy 67.418978 -292.574726) (xy 67.08013 -292.574726) (xy 67.079635 -292.599333) (xy 67.07174 -292.64791)
			(xy 67.056156 -292.694591) (xy 67.033285 -292.738168) (xy 67.00372 -292.777512) (xy 66.968227 -292.811604)
			(xy 66.927724 -292.83956) (xy 66.883262 -292.860658) (xy 66.835991 -292.87435) (xy 66.787136 -292.880282)
			(xy 66.737961 -292.878301) (xy 66.689742 -292.868457) (xy 66.643726 -292.851005) (xy 66.601105 -292.826398)
			(xy 66.562984 -292.795273) (xy 66.530349 -292.758436) (xy 66.504046 -292.71684) (xy 66.484755 -292.671564)
			(xy 66.472978 -292.62378) (xy 66.469018 -292.574726) (xy 66.13017 -292.574726) (xy 66.129675 -292.599333)
			(xy 66.12178 -292.64791) (xy 66.106196 -292.694591) (xy 66.083325 -292.738168) (xy 66.05376 -292.777512)
			(xy 66.018267 -292.811604) (xy 65.977764 -292.83956) (xy 65.933302 -292.860658) (xy 65.886031 -292.87435)
			(xy 65.837176 -292.880282) (xy 65.788001 -292.878301) (xy 65.739782 -292.868457) (xy 65.693766 -292.851005)
			(xy 65.651145 -292.826398) (xy 65.613024 -292.795273) (xy 65.580389 -292.758436) (xy 65.554086 -292.71684)
			(xy 65.534795 -292.671564) (xy 65.523018 -292.62378) (xy 65.519058 -292.574726) (xy 65.18021 -292.574726)
			(xy 65.179715 -292.599333) (xy 65.17182 -292.64791) (xy 65.156236 -292.694591) (xy 65.133365 -292.738168)
			(xy 65.1038 -292.777512) (xy 65.068307 -292.811604) (xy 65.027804 -292.83956) (xy 64.983342 -292.860658)
			(xy 64.936071 -292.87435) (xy 64.887216 -292.880282) (xy 64.838041 -292.878301) (xy 64.789822 -292.868457)
			(xy 64.743806 -292.851005) (xy 64.701185 -292.826398) (xy 64.663064 -292.795273) (xy 64.630429 -292.758436)
			(xy 64.604126 -292.71684) (xy 64.584835 -292.671564) (xy 64.573058 -292.62378) (xy 64.569098 -292.574726)
			(xy 64.23025 -292.574726) (xy 64.229755 -292.599333) (xy 64.22186 -292.64791) (xy 64.206276 -292.694591)
			(xy 64.183405 -292.738168) (xy 64.15384 -292.777512) (xy 64.118347 -292.811604) (xy 64.077844 -292.83956)
			(xy 64.033382 -292.860658) (xy 63.986111 -292.87435) (xy 63.937256 -292.880282) (xy 63.888081 -292.878301)
			(xy 63.839862 -292.868457) (xy 63.793846 -292.851005) (xy 63.751225 -292.826398) (xy 63.713104 -292.795273)
			(xy 63.680469 -292.758436) (xy 63.654166 -292.71684) (xy 63.634875 -292.671564) (xy 63.623098 -292.62378)
			(xy 63.619138 -292.574726) (xy 63.28029 -292.574726) (xy 63.279795 -292.599333) (xy 63.2719 -292.64791)
			(xy 63.256316 -292.694591) (xy 63.233445 -292.738168) (xy 63.20388 -292.777512) (xy 63.168387 -292.811604)
			(xy 63.127884 -292.83956) (xy 63.083422 -292.860658) (xy 63.036151 -292.87435) (xy 62.987296 -292.880282)
			(xy 62.938121 -292.878301) (xy 62.889902 -292.868457) (xy 62.843886 -292.851005) (xy 62.801265 -292.826398)
			(xy 62.763144 -292.795273) (xy 62.730509 -292.758436) (xy 62.704206 -292.71684) (xy 62.684915 -292.671564)
			(xy 62.673138 -292.62378) (xy 62.669178 -292.574726) (xy 62.330076 -292.574726) (xy 62.329581 -292.599333)
			(xy 62.321686 -292.64791) (xy 62.306102 -292.694591) (xy 62.283231 -292.738168) (xy 62.253666 -292.777512)
			(xy 62.218173 -292.811604) (xy 62.17767 -292.83956) (xy 62.133208 -292.860658) (xy 62.085937 -292.87435)
			(xy 62.037082 -292.880282) (xy 61.987907 -292.878301) (xy 61.939688 -292.868457) (xy 61.893672 -292.851005)
			(xy 61.851051 -292.826398) (xy 61.81293 -292.795273) (xy 61.780295 -292.758436) (xy 61.753992 -292.71684)
			(xy 61.734701 -292.671564) (xy 61.722924 -292.62378) (xy 61.718964 -292.574726) (xy 61.380116 -292.574726)
			(xy 61.379621 -292.599333) (xy 61.371726 -292.64791) (xy 61.356142 -292.694591) (xy 61.333271 -292.738168)
			(xy 61.303706 -292.777512) (xy 61.268213 -292.811604) (xy 61.22771 -292.83956) (xy 61.183248 -292.860658)
			(xy 61.135977 -292.87435) (xy 61.087122 -292.880282) (xy 61.037947 -292.878301) (xy 60.989728 -292.868457)
			(xy 60.943712 -292.851005) (xy 60.901091 -292.826398) (xy 60.86297 -292.795273) (xy 60.830335 -292.758436)
			(xy 60.804032 -292.71684) (xy 60.784741 -292.671564) (xy 60.772964 -292.62378) (xy 60.769004 -292.574726)
			(xy 60.430156 -292.574726) (xy 60.429661 -292.599333) (xy 60.421766 -292.64791) (xy 60.406182 -292.694591)
			(xy 60.383311 -292.738168) (xy 60.353746 -292.777512) (xy 60.318253 -292.811604) (xy 60.27775 -292.83956)
			(xy 60.233288 -292.860658) (xy 60.186017 -292.87435) (xy 60.137162 -292.880282) (xy 60.087987 -292.878301)
			(xy 60.039768 -292.868457) (xy 59.993752 -292.851005) (xy 59.951131 -292.826398) (xy 59.91301 -292.795273)
			(xy 59.880375 -292.758436) (xy 59.854072 -292.71684) (xy 59.834781 -292.671564) (xy 59.823004 -292.62378)
			(xy 59.819044 -292.574726) (xy 58.530231 -292.574726) (xy 58.530236 -292.57498) (xy 58.529741 -292.599587)
			(xy 58.521846 -292.648164) (xy 58.506262 -292.694845) (xy 58.483391 -292.738422) (xy 58.453826 -292.777766)
			(xy 58.418333 -292.811858) (xy 58.37783 -292.839814) (xy 58.333368 -292.860912) (xy 58.286097 -292.874604)
			(xy 58.237242 -292.880536) (xy 58.188067 -292.878555) (xy 58.139848 -292.868711) (xy 58.093832 -292.851259)
			(xy 58.051211 -292.826652) (xy 58.01309 -292.795527) (xy 57.980455 -292.75869) (xy 57.954152 -292.717094)
			(xy 57.934861 -292.671818) (xy 57.923084 -292.624034) (xy 57.919124 -292.57498) (xy 57.580276 -292.57498)
			(xy 57.579781 -292.599587) (xy 57.571886 -292.648164) (xy 57.556302 -292.694845) (xy 57.533431 -292.738422)
			(xy 57.503866 -292.777766) (xy 57.468373 -292.811858) (xy 57.42787 -292.839814) (xy 57.383408 -292.860912)
			(xy 57.336137 -292.874604) (xy 57.287282 -292.880536) (xy 57.238107 -292.878555) (xy 57.189888 -292.868711)
			(xy 57.143872 -292.851259) (xy 57.101251 -292.826652) (xy 57.06313 -292.795527) (xy 57.030495 -292.75869)
			(xy 57.004192 -292.717094) (xy 56.984901 -292.671818) (xy 56.973124 -292.624034) (xy 56.969164 -292.57498)
			(xy 56.630316 -292.57498) (xy 56.629821 -292.599587) (xy 56.621926 -292.648164) (xy 56.606342 -292.694845)
			(xy 56.583471 -292.738422) (xy 56.553906 -292.777766) (xy 56.518413 -292.811858) (xy 56.47791 -292.839814)
			(xy 56.433448 -292.860912) (xy 56.386177 -292.874604) (xy 56.337322 -292.880536) (xy 56.288147 -292.878555)
			(xy 56.239928 -292.868711) (xy 56.193912 -292.851259) (xy 56.151291 -292.826652) (xy 56.11317 -292.795527)
			(xy 56.080535 -292.75869) (xy 56.054232 -292.717094) (xy 56.034941 -292.671818) (xy 56.023164 -292.624034)
			(xy 56.019204 -292.57498) (xy 55.680102 -292.57498) (xy 55.679607 -292.599587) (xy 55.671712 -292.648164)
			(xy 55.656128 -292.694845) (xy 55.633257 -292.738422) (xy 55.603692 -292.777766) (xy 55.568199 -292.811858)
			(xy 55.527696 -292.839814) (xy 55.483234 -292.860912) (xy 55.435963 -292.874604) (xy 55.387108 -292.880536)
			(xy 55.337933 -292.878555) (xy 55.289714 -292.868711) (xy 55.243698 -292.851259) (xy 55.201077 -292.826652)
			(xy 55.162956 -292.795527) (xy 55.130321 -292.75869) (xy 55.104018 -292.717094) (xy 55.084727 -292.671818)
			(xy 55.07295 -292.624034) (xy 55.06899 -292.57498) (xy 54.730142 -292.57498) (xy 54.729647 -292.599587)
			(xy 54.721752 -292.648164) (xy 54.706168 -292.694845) (xy 54.683297 -292.738422) (xy 54.653732 -292.777766)
			(xy 54.618239 -292.811858) (xy 54.577736 -292.839814) (xy 54.533274 -292.860912) (xy 54.486003 -292.874604)
			(xy 54.437148 -292.880536) (xy 54.387973 -292.878555) (xy 54.339754 -292.868711) (xy 54.293738 -292.851259)
			(xy 54.251117 -292.826652) (xy 54.212996 -292.795527) (xy 54.180361 -292.75869) (xy 54.154058 -292.717094)
			(xy 54.134767 -292.671818) (xy 54.12299 -292.624034) (xy 54.11903 -292.57498) (xy 53.780182 -292.57498)
			(xy 53.779687 -292.599587) (xy 53.771792 -292.648164) (xy 53.756208 -292.694845) (xy 53.733337 -292.738422)
			(xy 53.703772 -292.777766) (xy 53.668279 -292.811858) (xy 53.627776 -292.839814) (xy 53.583314 -292.860912)
			(xy 53.536043 -292.874604) (xy 53.487188 -292.880536) (xy 53.438013 -292.878555) (xy 53.389794 -292.868711)
			(xy 53.343778 -292.851259) (xy 53.301157 -292.826652) (xy 53.263036 -292.795527) (xy 53.230401 -292.75869)
			(xy 53.204098 -292.717094) (xy 53.184807 -292.671818) (xy 53.17303 -292.624034) (xy 53.16907 -292.57498)
			(xy 52.830222 -292.57498) (xy 52.829727 -292.599587) (xy 52.821832 -292.648164) (xy 52.806248 -292.694845)
			(xy 52.783377 -292.738422) (xy 52.753812 -292.777766) (xy 52.718319 -292.811858) (xy 52.677816 -292.839814)
			(xy 52.633354 -292.860912) (xy 52.586083 -292.874604) (xy 52.537228 -292.880536) (xy 52.488053 -292.878555)
			(xy 52.439834 -292.868711) (xy 52.393818 -292.851259) (xy 52.351197 -292.826652) (xy 52.313076 -292.795527)
			(xy 52.280441 -292.75869) (xy 52.254138 -292.717094) (xy 52.234847 -292.671818) (xy 52.22307 -292.624034)
			(xy 52.21911 -292.57498) (xy 51.880262 -292.57498) (xy 51.879767 -292.599587) (xy 51.871872 -292.648164)
			(xy 51.856288 -292.694845) (xy 51.833417 -292.738422) (xy 51.803852 -292.777766) (xy 51.768359 -292.811858)
			(xy 51.727856 -292.839814) (xy 51.683394 -292.860912) (xy 51.636123 -292.874604) (xy 51.587268 -292.880536)
			(xy 51.538093 -292.878555) (xy 51.489874 -292.868711) (xy 51.443858 -292.851259) (xy 51.401237 -292.826652)
			(xy 51.363116 -292.795527) (xy 51.330481 -292.75869) (xy 51.304178 -292.717094) (xy 51.284887 -292.671818)
			(xy 51.27311 -292.624034) (xy 51.26915 -292.57498) (xy 50.930302 -292.57498) (xy 50.929807 -292.599587)
			(xy 50.921912 -292.648164) (xy 50.906328 -292.694845) (xy 50.883457 -292.738422) (xy 50.853892 -292.777766)
			(xy 50.818399 -292.811858) (xy 50.777896 -292.839814) (xy 50.733434 -292.860912) (xy 50.686163 -292.874604)
			(xy 50.637308 -292.880536) (xy 50.588133 -292.878555) (xy 50.539914 -292.868711) (xy 50.493898 -292.851259)
			(xy 50.451277 -292.826652) (xy 50.413156 -292.795527) (xy 50.380521 -292.75869) (xy 50.354218 -292.717094)
			(xy 50.334927 -292.671818) (xy 50.32315 -292.624034) (xy 50.31919 -292.57498) (xy 49.980083 -292.57498)
			(xy 49.979593 -292.599333) (xy 49.971698 -292.64791) (xy 49.956114 -292.694591) (xy 49.933243 -292.738168)
			(xy 49.903678 -292.777512) (xy 49.868185 -292.811604) (xy 49.827682 -292.83956) (xy 49.78322 -292.860658)
			(xy 49.735949 -292.87435) (xy 49.687094 -292.880282) (xy 49.637919 -292.878301) (xy 49.5897 -292.868457)
			(xy 49.543684 -292.851005) (xy 49.501063 -292.826398) (xy 49.462942 -292.795273) (xy 49.430307 -292.758436)
			(xy 49.404004 -292.71684) (xy 49.384713 -292.671564) (xy 49.372936 -292.62378) (xy 49.368976 -292.574726)
			(xy 49.030128 -292.574726) (xy 49.029633 -292.599333) (xy 49.021738 -292.64791) (xy 49.006154 -292.694591)
			(xy 48.983283 -292.738168) (xy 48.953718 -292.777512) (xy 48.918225 -292.811604) (xy 48.877722 -292.83956)
			(xy 48.83326 -292.860658) (xy 48.785989 -292.87435) (xy 48.737134 -292.880282) (xy 48.687959 -292.878301)
			(xy 48.63974 -292.868457) (xy 48.593724 -292.851005) (xy 48.551103 -292.826398) (xy 48.512982 -292.795273)
			(xy 48.480347 -292.758436) (xy 48.454044 -292.71684) (xy 48.434753 -292.671564) (xy 48.422976 -292.62378)
			(xy 48.419016 -292.574726) (xy 48.080163 -292.574726) (xy 48.080168 -292.57498) (xy 48.079673 -292.599587)
			(xy 48.071778 -292.648164) (xy 48.056194 -292.694845) (xy 48.033323 -292.738422) (xy 48.003758 -292.777766)
			(xy 47.968265 -292.811858) (xy 47.927762 -292.839814) (xy 47.8833 -292.860912) (xy 47.836029 -292.874604)
			(xy 47.787174 -292.880536) (xy 47.737999 -292.878555) (xy 47.68978 -292.868711) (xy 47.643764 -292.851259)
			(xy 47.601143 -292.826652) (xy 47.563022 -292.795527) (xy 47.530387 -292.75869) (xy 47.504084 -292.717094)
			(xy 47.484793 -292.671818) (xy 47.473016 -292.624034) (xy 47.469056 -292.57498) (xy 47.130208 -292.57498)
			(xy 47.129713 -292.599587) (xy 47.121818 -292.648164) (xy 47.106234 -292.694845) (xy 47.083363 -292.738422)
			(xy 47.053798 -292.777766) (xy 47.018305 -292.811858) (xy 46.977802 -292.839814) (xy 46.93334 -292.860912)
			(xy 46.886069 -292.874604) (xy 46.837214 -292.880536) (xy 46.788039 -292.878555) (xy 46.73982 -292.868711)
			(xy 46.693804 -292.851259) (xy 46.651183 -292.826652) (xy 46.613062 -292.795527) (xy 46.580427 -292.75869)
			(xy 46.554124 -292.717094) (xy 46.534833 -292.671818) (xy 46.523056 -292.624034) (xy 46.519096 -292.57498)
			(xy 46.180248 -292.57498) (xy 46.179753 -292.599587) (xy 46.171858 -292.648164) (xy 46.156274 -292.694845)
			(xy 46.133403 -292.738422) (xy 46.103838 -292.777766) (xy 46.068345 -292.811858) (xy 46.027842 -292.839814)
			(xy 45.98338 -292.860912) (xy 45.936109 -292.874604) (xy 45.887254 -292.880536) (xy 45.838079 -292.878555)
			(xy 45.78986 -292.868711) (xy 45.743844 -292.851259) (xy 45.701223 -292.826652) (xy 45.663102 -292.795527)
			(xy 45.630467 -292.75869) (xy 45.604164 -292.717094) (xy 45.584873 -292.671818) (xy 45.573096 -292.624034)
			(xy 45.569136 -292.57498) (xy 44.280074 -292.57498) (xy 44.279579 -292.599587) (xy 44.271684 -292.648164)
			(xy 44.2561 -292.694845) (xy 44.233229 -292.738422) (xy 44.203664 -292.777766) (xy 44.168171 -292.811858)
			(xy 44.127668 -292.839814) (xy 44.083206 -292.860912) (xy 44.035935 -292.874604) (xy 43.98708 -292.880536)
			(xy 43.937905 -292.878555) (xy 43.889686 -292.868711) (xy 43.84367 -292.851259) (xy 43.801049 -292.826652)
			(xy 43.762928 -292.795527) (xy 43.730293 -292.75869) (xy 43.70399 -292.717094) (xy 43.684699 -292.671818)
			(xy 43.672922 -292.624034) (xy 43.668962 -292.57498) (xy 43.356016 -292.57498) (xy 43.356017 -292.574993)
			(xy 43.351778 -292.627823) (xy 43.339167 -292.6793) (xy 43.318506 -292.728107) (xy 43.290325 -292.772994)
			(xy 43.255345 -292.812811) (xy 43.214462 -292.846539) (xy 43.168723 -292.873314) (xy 43.144186 -292.883336)
			(xy 43.137074 -292.88613) (xy 43.125136 -292.895528) (xy 43.120818 -292.901878) (xy 43.116661 -292.908391)
			(xy 43.112007 -292.923115) (xy 43.111674 -292.930834) (xy 43.111674 -293.114984) (xy 43.111938 -293.122951)
			(xy 43.11685 -293.138107) (xy 43.121326 -293.144702) (xy 43.121326 -293.144956) (xy 43.12613 -293.15112)
			(xy 43.138675 -293.160425) (xy 43.145964 -293.163244) (xy 43.146218 -293.163244) (xy 43.172597 -293.172624)
			(xy 43.222494 -293.198014) (xy 43.268146 -293.230421) (xy 43.308574 -293.269152) (xy 43.342908 -293.313373)
			(xy 43.370414 -293.362136) (xy 43.390499 -293.414394) (xy 43.402734 -293.469027) (xy 43.406855 -293.52486)
			(xy 43.406849 -293.52494) (xy 43.668962 -293.52494) (xy 43.672922 -293.475886) (xy 43.684699 -293.428102)
			(xy 43.70399 -293.382826) (xy 43.730293 -293.34123) (xy 43.762928 -293.304393) (xy 43.801049 -293.273268)
			(xy 43.84367 -293.248661) (xy 43.889686 -293.231209) (xy 43.937905 -293.221365) (xy 43.98708 -293.219384)
			(xy 44.035935 -293.225316) (xy 44.083206 -293.239008) (xy 44.127668 -293.260106) (xy 44.168171 -293.288062)
			(xy 44.203664 -293.322154) (xy 44.233229 -293.361498) (xy 44.2561 -293.405075) (xy 44.271684 -293.451756)
			(xy 44.279579 -293.500333) (xy 44.280074 -293.52494) (xy 45.569136 -293.52494) (xy 45.573096 -293.475886)
			(xy 45.584873 -293.428102) (xy 45.604164 -293.382826) (xy 45.630467 -293.34123) (xy 45.663102 -293.304393)
			(xy 45.701223 -293.273268) (xy 45.743844 -293.248661) (xy 45.78986 -293.231209) (xy 45.838079 -293.221365)
			(xy 45.887254 -293.219384) (xy 45.936109 -293.225316) (xy 45.98338 -293.239008) (xy 46.027842 -293.260106)
			(xy 46.068345 -293.288062) (xy 46.103838 -293.322154) (xy 46.133403 -293.361498) (xy 46.156274 -293.405075)
			(xy 46.171858 -293.451756) (xy 46.179753 -293.500333) (xy 46.180248 -293.52494) (xy 47.469056 -293.52494)
			(xy 47.473016 -293.475886) (xy 47.484793 -293.428102) (xy 47.504084 -293.382826) (xy 47.530387 -293.34123)
			(xy 47.563022 -293.304393) (xy 47.601143 -293.273268) (xy 47.643764 -293.248661) (xy 47.68978 -293.231209)
			(xy 47.737999 -293.221365) (xy 47.787174 -293.219384) (xy 47.836029 -293.225316) (xy 47.8833 -293.239008)
			(xy 47.927762 -293.260106) (xy 47.968265 -293.288062) (xy 48.003758 -293.322154) (xy 48.033323 -293.361498)
			(xy 48.056194 -293.405075) (xy 48.071778 -293.451756) (xy 48.079673 -293.500333) (xy 48.080168 -293.52494)
			(xy 48.419016 -293.52494) (xy 48.422976 -293.475886) (xy 48.434753 -293.428102) (xy 48.454044 -293.382826)
			(xy 48.480347 -293.34123) (xy 48.512982 -293.304393) (xy 48.551103 -293.273268) (xy 48.593724 -293.248661)
			(xy 48.63974 -293.231209) (xy 48.687959 -293.221365) (xy 48.737134 -293.219384) (xy 48.785989 -293.225316)
			(xy 48.83326 -293.239008) (xy 48.877722 -293.260106) (xy 48.918225 -293.288062) (xy 48.953718 -293.322154)
			(xy 48.983283 -293.361498) (xy 49.006154 -293.405075) (xy 49.021738 -293.451756) (xy 49.029633 -293.500333)
			(xy 49.030128 -293.52494) (xy 49.368976 -293.52494) (xy 49.372936 -293.475886) (xy 49.384713 -293.428102)
			(xy 49.404004 -293.382826) (xy 49.430307 -293.34123) (xy 49.462942 -293.304393) (xy 49.501063 -293.273268)
			(xy 49.543684 -293.248661) (xy 49.5897 -293.231209) (xy 49.637919 -293.221365) (xy 49.687094 -293.219384)
			(xy 49.735949 -293.225316) (xy 49.78322 -293.239008) (xy 49.827682 -293.260106) (xy 49.868185 -293.288062)
			(xy 49.903678 -293.322154) (xy 49.933243 -293.361498) (xy 49.956114 -293.405075) (xy 49.971698 -293.451756)
			(xy 49.979593 -293.500333) (xy 49.980088 -293.52494) (xy 50.31919 -293.52494) (xy 50.32315 -293.475886)
			(xy 50.334927 -293.428102) (xy 50.354218 -293.382826) (xy 50.380521 -293.34123) (xy 50.413156 -293.304393)
			(xy 50.451277 -293.273268) (xy 50.493898 -293.248661) (xy 50.539914 -293.231209) (xy 50.588133 -293.221365)
			(xy 50.637308 -293.219384) (xy 50.686163 -293.225316) (xy 50.733434 -293.239008) (xy 50.777896 -293.260106)
			(xy 50.818399 -293.288062) (xy 50.853892 -293.322154) (xy 50.883457 -293.361498) (xy 50.906328 -293.405075)
			(xy 50.921912 -293.451756) (xy 50.929807 -293.500333) (xy 50.930302 -293.52494) (xy 51.26915 -293.52494)
			(xy 51.27311 -293.475886) (xy 51.284887 -293.428102) (xy 51.304178 -293.382826) (xy 51.330481 -293.34123)
			(xy 51.363116 -293.304393) (xy 51.401237 -293.273268) (xy 51.443858 -293.248661) (xy 51.489874 -293.231209)
			(xy 51.538093 -293.221365) (xy 51.587268 -293.219384) (xy 51.636123 -293.225316) (xy 51.683394 -293.239008)
			(xy 51.727856 -293.260106) (xy 51.768359 -293.288062) (xy 51.803852 -293.322154) (xy 51.833417 -293.361498)
			(xy 51.856288 -293.405075) (xy 51.871872 -293.451756) (xy 51.879767 -293.500333) (xy 51.880262 -293.52494)
			(xy 52.21911 -293.52494) (xy 52.22307 -293.475886) (xy 52.234847 -293.428102) (xy 52.254138 -293.382826)
			(xy 52.280441 -293.34123) (xy 52.313076 -293.304393) (xy 52.351197 -293.273268) (xy 52.393818 -293.248661)
			(xy 52.439834 -293.231209) (xy 52.488053 -293.221365) (xy 52.537228 -293.219384) (xy 52.586083 -293.225316)
			(xy 52.633354 -293.239008) (xy 52.677816 -293.260106) (xy 52.718319 -293.288062) (xy 52.753812 -293.322154)
			(xy 52.783377 -293.361498) (xy 52.806248 -293.405075) (xy 52.821832 -293.451756) (xy 52.829727 -293.500333)
			(xy 52.830222 -293.52494) (xy 53.16907 -293.52494) (xy 53.17303 -293.475886) (xy 53.184807 -293.428102)
			(xy 53.204098 -293.382826) (xy 53.230401 -293.34123) (xy 53.263036 -293.304393) (xy 53.301157 -293.273268)
			(xy 53.343778 -293.248661) (xy 53.389794 -293.231209) (xy 53.438013 -293.221365) (xy 53.487188 -293.219384)
			(xy 53.536043 -293.225316) (xy 53.583314 -293.239008) (xy 53.627776 -293.260106) (xy 53.668279 -293.288062)
			(xy 53.703772 -293.322154) (xy 53.733337 -293.361498) (xy 53.756208 -293.405075) (xy 53.771792 -293.451756)
			(xy 53.779687 -293.500333) (xy 53.780182 -293.52494) (xy 54.11903 -293.52494) (xy 54.12299 -293.475886)
			(xy 54.134767 -293.428102) (xy 54.154058 -293.382826) (xy 54.180361 -293.34123) (xy 54.212996 -293.304393)
			(xy 54.251117 -293.273268) (xy 54.293738 -293.248661) (xy 54.339754 -293.231209) (xy 54.387973 -293.221365)
			(xy 54.437148 -293.219384) (xy 54.486003 -293.225316) (xy 54.533274 -293.239008) (xy 54.577736 -293.260106)
			(xy 54.618239 -293.288062) (xy 54.653732 -293.322154) (xy 54.683297 -293.361498) (xy 54.706168 -293.405075)
			(xy 54.721752 -293.451756) (xy 54.729647 -293.500333) (xy 54.730142 -293.52494) (xy 55.06899 -293.52494)
			(xy 55.07295 -293.475886) (xy 55.084727 -293.428102) (xy 55.104018 -293.382826) (xy 55.130321 -293.34123)
			(xy 55.162956 -293.304393) (xy 55.201077 -293.273268) (xy 55.243698 -293.248661) (xy 55.289714 -293.231209)
			(xy 55.337933 -293.221365) (xy 55.387108 -293.219384) (xy 55.435963 -293.225316) (xy 55.483234 -293.239008)
			(xy 55.527696 -293.260106) (xy 55.568199 -293.288062) (xy 55.603692 -293.322154) (xy 55.633257 -293.361498)
			(xy 55.656128 -293.405075) (xy 55.671712 -293.451756) (xy 55.679607 -293.500333) (xy 55.680102 -293.52494)
			(xy 56.01895 -293.52494) (xy 56.02291 -293.475886) (xy 56.034687 -293.428102) (xy 56.053978 -293.382826)
			(xy 56.080281 -293.34123) (xy 56.112916 -293.304393) (xy 56.151037 -293.273268) (xy 56.193658 -293.248661)
			(xy 56.239674 -293.231209) (xy 56.287893 -293.221365) (xy 56.337068 -293.219384) (xy 56.385923 -293.225316)
			(xy 56.433194 -293.239008) (xy 56.477656 -293.260106) (xy 56.518159 -293.288062) (xy 56.553652 -293.322154)
			(xy 56.583217 -293.361498) (xy 56.606088 -293.405075) (xy 56.621672 -293.451756) (xy 56.629567 -293.500333)
			(xy 56.630062 -293.52494) (xy 56.969164 -293.52494) (xy 56.973124 -293.475886) (xy 56.984901 -293.428102)
			(xy 57.004192 -293.382826) (xy 57.030495 -293.34123) (xy 57.06313 -293.304393) (xy 57.101251 -293.273268)
			(xy 57.143872 -293.248661) (xy 57.189888 -293.231209) (xy 57.238107 -293.221365) (xy 57.287282 -293.219384)
			(xy 57.336137 -293.225316) (xy 57.383408 -293.239008) (xy 57.42787 -293.260106) (xy 57.468373 -293.288062)
			(xy 57.503866 -293.322154) (xy 57.533431 -293.361498) (xy 57.556302 -293.405075) (xy 57.571886 -293.451756)
			(xy 57.579781 -293.500333) (xy 57.580276 -293.52494) (xy 57.919124 -293.52494) (xy 57.923084 -293.475886)
			(xy 57.934861 -293.428102) (xy 57.954152 -293.382826) (xy 57.980455 -293.34123) (xy 58.01309 -293.304393)
			(xy 58.051211 -293.273268) (xy 58.093832 -293.248661) (xy 58.139848 -293.231209) (xy 58.188067 -293.221365)
			(xy 58.237242 -293.219384) (xy 58.286097 -293.225316) (xy 58.333368 -293.239008) (xy 58.37783 -293.260106)
			(xy 58.418333 -293.288062) (xy 58.453826 -293.322154) (xy 58.483391 -293.361498) (xy 58.506262 -293.405075)
			(xy 58.521846 -293.451756) (xy 58.529741 -293.500333) (xy 58.530236 -293.52494) (xy 59.819044 -293.52494)
			(xy 59.823004 -293.475886) (xy 59.834781 -293.428102) (xy 59.854072 -293.382826) (xy 59.880375 -293.34123)
			(xy 59.91301 -293.304393) (xy 59.951131 -293.273268) (xy 59.993752 -293.248661) (xy 60.039768 -293.231209)
			(xy 60.087987 -293.221365) (xy 60.137162 -293.219384) (xy 60.186017 -293.225316) (xy 60.233288 -293.239008)
			(xy 60.27775 -293.260106) (xy 60.318253 -293.288062) (xy 60.353746 -293.322154) (xy 60.383311 -293.361498)
			(xy 60.406182 -293.405075) (xy 60.421766 -293.451756) (xy 60.429661 -293.500333) (xy 60.430156 -293.52494)
			(xy 60.769004 -293.52494) (xy 60.772964 -293.475886) (xy 60.784741 -293.428102) (xy 60.804032 -293.382826)
			(xy 60.830335 -293.34123) (xy 60.86297 -293.304393) (xy 60.901091 -293.273268) (xy 60.943712 -293.248661)
			(xy 60.989728 -293.231209) (xy 61.037947 -293.221365) (xy 61.087122 -293.219384) (xy 61.135977 -293.225316)
			(xy 61.183248 -293.239008) (xy 61.22771 -293.260106) (xy 61.268213 -293.288062) (xy 61.303706 -293.322154)
			(xy 61.333271 -293.361498) (xy 61.356142 -293.405075) (xy 61.371726 -293.451756) (xy 61.379621 -293.500333)
			(xy 61.380116 -293.52494) (xy 61.718964 -293.52494) (xy 61.722924 -293.475886) (xy 61.734701 -293.428102)
			(xy 61.753992 -293.382826) (xy 61.780295 -293.34123) (xy 61.81293 -293.304393) (xy 61.851051 -293.273268)
			(xy 61.893672 -293.248661) (xy 61.939688 -293.231209) (xy 61.987907 -293.221365) (xy 62.037082 -293.219384)
			(xy 62.085937 -293.225316) (xy 62.133208 -293.239008) (xy 62.17767 -293.260106) (xy 62.218173 -293.288062)
			(xy 62.253666 -293.322154) (xy 62.283231 -293.361498) (xy 62.306102 -293.405075) (xy 62.321686 -293.451756)
			(xy 62.329581 -293.500333) (xy 62.330076 -293.52494) (xy 62.669178 -293.52494) (xy 62.673138 -293.475886)
			(xy 62.684915 -293.428102) (xy 62.704206 -293.382826) (xy 62.730509 -293.34123) (xy 62.763144 -293.304393)
			(xy 62.801265 -293.273268) (xy 62.843886 -293.248661) (xy 62.889902 -293.231209) (xy 62.938121 -293.221365)
			(xy 62.987296 -293.219384) (xy 63.036151 -293.225316) (xy 63.083422 -293.239008) (xy 63.127884 -293.260106)
			(xy 63.168387 -293.288062) (xy 63.20388 -293.322154) (xy 63.233445 -293.361498) (xy 63.256316 -293.405075)
			(xy 63.2719 -293.451756) (xy 63.279795 -293.500333) (xy 63.28029 -293.52494) (xy 63.619138 -293.52494)
			(xy 63.623098 -293.475886) (xy 63.634875 -293.428102) (xy 63.654166 -293.382826) (xy 63.680469 -293.34123)
			(xy 63.713104 -293.304393) (xy 63.751225 -293.273268) (xy 63.793846 -293.248661) (xy 63.839862 -293.231209)
			(xy 63.888081 -293.221365) (xy 63.937256 -293.219384) (xy 63.986111 -293.225316) (xy 64.033382 -293.239008)
			(xy 64.077844 -293.260106) (xy 64.118347 -293.288062) (xy 64.15384 -293.322154) (xy 64.183405 -293.361498)
			(xy 64.206276 -293.405075) (xy 64.22186 -293.451756) (xy 64.229755 -293.500333) (xy 64.23025 -293.52494)
			(xy 64.569098 -293.52494) (xy 64.573058 -293.475886) (xy 64.584835 -293.428102) (xy 64.604126 -293.382826)
			(xy 64.630429 -293.34123) (xy 64.663064 -293.304393) (xy 64.701185 -293.273268) (xy 64.743806 -293.248661)
			(xy 64.789822 -293.231209) (xy 64.838041 -293.221365) (xy 64.887216 -293.219384) (xy 64.936071 -293.225316)
			(xy 64.983342 -293.239008) (xy 65.027804 -293.260106) (xy 65.068307 -293.288062) (xy 65.1038 -293.322154)
			(xy 65.133365 -293.361498) (xy 65.156236 -293.405075) (xy 65.17182 -293.451756) (xy 65.179715 -293.500333)
			(xy 65.18021 -293.52494) (xy 65.519058 -293.52494) (xy 65.523018 -293.475886) (xy 65.534795 -293.428102)
			(xy 65.554086 -293.382826) (xy 65.580389 -293.34123) (xy 65.613024 -293.304393) (xy 65.651145 -293.273268)
			(xy 65.693766 -293.248661) (xy 65.739782 -293.231209) (xy 65.788001 -293.221365) (xy 65.837176 -293.219384)
			(xy 65.886031 -293.225316) (xy 65.933302 -293.239008) (xy 65.977764 -293.260106) (xy 66.018267 -293.288062)
			(xy 66.05376 -293.322154) (xy 66.083325 -293.361498) (xy 66.106196 -293.405075) (xy 66.12178 -293.451756)
			(xy 66.129675 -293.500333) (xy 66.13017 -293.52494) (xy 66.469018 -293.52494) (xy 66.472978 -293.475886)
			(xy 66.484755 -293.428102) (xy 66.504046 -293.382826) (xy 66.530349 -293.34123) (xy 66.562984 -293.304393)
			(xy 66.601105 -293.273268) (xy 66.643726 -293.248661) (xy 66.689742 -293.231209) (xy 66.737961 -293.221365)
			(xy 66.787136 -293.219384) (xy 66.835991 -293.225316) (xy 66.883262 -293.239008) (xy 66.927724 -293.260106)
			(xy 66.968227 -293.288062) (xy 67.00372 -293.322154) (xy 67.033285 -293.361498) (xy 67.056156 -293.405075)
			(xy 67.07174 -293.451756) (xy 67.079635 -293.500333) (xy 67.08013 -293.52494) (xy 67.418978 -293.52494)
			(xy 67.422938 -293.475886) (xy 67.434715 -293.428102) (xy 67.454006 -293.382826) (xy 67.480309 -293.34123)
			(xy 67.512944 -293.304393) (xy 67.551065 -293.273268) (xy 67.593686 -293.248661) (xy 67.639702 -293.231209)
			(xy 67.687921 -293.221365) (xy 67.737096 -293.219384) (xy 67.785951 -293.225316) (xy 67.833222 -293.239008)
			(xy 67.877684 -293.260106) (xy 67.918187 -293.288062) (xy 67.95368 -293.322154) (xy 67.983245 -293.361498)
			(xy 68.006116 -293.405075) (xy 68.0217 -293.451756) (xy 68.029595 -293.500333) (xy 68.03009 -293.52494)
			(xy 68.368938 -293.52494) (xy 68.372898 -293.475886) (xy 68.384675 -293.428102) (xy 68.403966 -293.382826)
			(xy 68.430269 -293.34123) (xy 68.462904 -293.304393) (xy 68.501025 -293.273268) (xy 68.543646 -293.248661)
			(xy 68.589662 -293.231209) (xy 68.637881 -293.221365) (xy 68.687056 -293.219384) (xy 68.735911 -293.225316)
			(xy 68.783182 -293.239008) (xy 68.827644 -293.260106) (xy 68.868147 -293.288062) (xy 68.90364 -293.322154)
			(xy 68.933205 -293.361498) (xy 68.956076 -293.405075) (xy 68.97166 -293.451756) (xy 68.979555 -293.500333)
			(xy 68.98005 -293.52494) (xy 69.319152 -293.52494) (xy 69.323112 -293.475886) (xy 69.334889 -293.428102)
			(xy 69.35418 -293.382826) (xy 69.380483 -293.34123) (xy 69.413118 -293.304393) (xy 69.451239 -293.273268)
			(xy 69.49386 -293.248661) (xy 69.539876 -293.231209) (xy 69.588095 -293.221365) (xy 69.63727 -293.219384)
			(xy 69.686125 -293.225316) (xy 69.733396 -293.239008) (xy 69.777858 -293.260106) (xy 69.818361 -293.288062)
			(xy 69.853854 -293.322154) (xy 69.883419 -293.361498) (xy 69.90629 -293.405075) (xy 69.921874 -293.451756)
			(xy 69.929769 -293.500333) (xy 69.930264 -293.52494) (xy 69.929769 -293.549547) (xy 69.921874 -293.598124)
			(xy 69.90629 -293.644805) (xy 69.883419 -293.688382) (xy 69.853854 -293.727726) (xy 69.818361 -293.761818)
			(xy 69.777858 -293.789774) (xy 69.733396 -293.810872) (xy 69.686125 -293.824564) (xy 69.63727 -293.830496)
			(xy 69.588095 -293.828515) (xy 69.539876 -293.818671) (xy 69.49386 -293.801219) (xy 69.451239 -293.776612)
			(xy 69.413118 -293.745487) (xy 69.380483 -293.70865) (xy 69.35418 -293.667054) (xy 69.334889 -293.621778)
			(xy 69.323112 -293.573994) (xy 69.319152 -293.52494) (xy 68.98005 -293.52494) (xy 68.979555 -293.549547)
			(xy 68.97166 -293.598124) (xy 68.956076 -293.644805) (xy 68.933205 -293.688382) (xy 68.90364 -293.727726)
			(xy 68.868147 -293.761818) (xy 68.827644 -293.789774) (xy 68.783182 -293.810872) (xy 68.735911 -293.824564)
			(xy 68.687056 -293.830496) (xy 68.637881 -293.828515) (xy 68.589662 -293.818671) (xy 68.543646 -293.801219)
			(xy 68.501025 -293.776612) (xy 68.462904 -293.745487) (xy 68.430269 -293.70865) (xy 68.403966 -293.667054)
			(xy 68.384675 -293.621778) (xy 68.372898 -293.573994) (xy 68.368938 -293.52494) (xy 68.03009 -293.52494)
			(xy 68.029595 -293.549547) (xy 68.0217 -293.598124) (xy 68.006116 -293.644805) (xy 67.983245 -293.688382)
			(xy 67.95368 -293.727726) (xy 67.918187 -293.761818) (xy 67.877684 -293.789774) (xy 67.833222 -293.810872)
			(xy 67.785951 -293.824564) (xy 67.737096 -293.830496) (xy 67.687921 -293.828515) (xy 67.639702 -293.818671)
			(xy 67.593686 -293.801219) (xy 67.551065 -293.776612) (xy 67.512944 -293.745487) (xy 67.480309 -293.70865)
			(xy 67.454006 -293.667054) (xy 67.434715 -293.621778) (xy 67.422938 -293.573994) (xy 67.418978 -293.52494)
			(xy 67.08013 -293.52494) (xy 67.079635 -293.549547) (xy 67.07174 -293.598124) (xy 67.056156 -293.644805)
			(xy 67.033285 -293.688382) (xy 67.00372 -293.727726) (xy 66.968227 -293.761818) (xy 66.927724 -293.789774)
			(xy 66.883262 -293.810872) (xy 66.835991 -293.824564) (xy 66.787136 -293.830496) (xy 66.737961 -293.828515)
			(xy 66.689742 -293.818671) (xy 66.643726 -293.801219) (xy 66.601105 -293.776612) (xy 66.562984 -293.745487)
			(xy 66.530349 -293.70865) (xy 66.504046 -293.667054) (xy 66.484755 -293.621778) (xy 66.472978 -293.573994)
			(xy 66.469018 -293.52494) (xy 66.13017 -293.52494) (xy 66.129675 -293.549547) (xy 66.12178 -293.598124)
			(xy 66.106196 -293.644805) (xy 66.083325 -293.688382) (xy 66.05376 -293.727726) (xy 66.018267 -293.761818)
			(xy 65.977764 -293.789774) (xy 65.933302 -293.810872) (xy 65.886031 -293.824564) (xy 65.837176 -293.830496)
			(xy 65.788001 -293.828515) (xy 65.739782 -293.818671) (xy 65.693766 -293.801219) (xy 65.651145 -293.776612)
			(xy 65.613024 -293.745487) (xy 65.580389 -293.70865) (xy 65.554086 -293.667054) (xy 65.534795 -293.621778)
			(xy 65.523018 -293.573994) (xy 65.519058 -293.52494) (xy 65.18021 -293.52494) (xy 65.179715 -293.549547)
			(xy 65.17182 -293.598124) (xy 65.156236 -293.644805) (xy 65.133365 -293.688382) (xy 65.1038 -293.727726)
			(xy 65.068307 -293.761818) (xy 65.027804 -293.789774) (xy 64.983342 -293.810872) (xy 64.936071 -293.824564)
			(xy 64.887216 -293.830496) (xy 64.838041 -293.828515) (xy 64.789822 -293.818671) (xy 64.743806 -293.801219)
			(xy 64.701185 -293.776612) (xy 64.663064 -293.745487) (xy 64.630429 -293.70865) (xy 64.604126 -293.667054)
			(xy 64.584835 -293.621778) (xy 64.573058 -293.573994) (xy 64.569098 -293.52494) (xy 64.23025 -293.52494)
			(xy 64.229755 -293.549547) (xy 64.22186 -293.598124) (xy 64.206276 -293.644805) (xy 64.183405 -293.688382)
			(xy 64.15384 -293.727726) (xy 64.118347 -293.761818) (xy 64.077844 -293.789774) (xy 64.033382 -293.810872)
			(xy 63.986111 -293.824564) (xy 63.937256 -293.830496) (xy 63.888081 -293.828515) (xy 63.839862 -293.818671)
			(xy 63.793846 -293.801219) (xy 63.751225 -293.776612) (xy 63.713104 -293.745487) (xy 63.680469 -293.70865)
			(xy 63.654166 -293.667054) (xy 63.634875 -293.621778) (xy 63.623098 -293.573994) (xy 63.619138 -293.52494)
			(xy 63.28029 -293.52494) (xy 63.279795 -293.549547) (xy 63.2719 -293.598124) (xy 63.256316 -293.644805)
			(xy 63.233445 -293.688382) (xy 63.20388 -293.727726) (xy 63.168387 -293.761818) (xy 63.127884 -293.789774)
			(xy 63.083422 -293.810872) (xy 63.036151 -293.824564) (xy 62.987296 -293.830496) (xy 62.938121 -293.828515)
			(xy 62.889902 -293.818671) (xy 62.843886 -293.801219) (xy 62.801265 -293.776612) (xy 62.763144 -293.745487)
			(xy 62.730509 -293.70865) (xy 62.704206 -293.667054) (xy 62.684915 -293.621778) (xy 62.673138 -293.573994)
			(xy 62.669178 -293.52494) (xy 62.330076 -293.52494) (xy 62.329581 -293.549547) (xy 62.321686 -293.598124)
			(xy 62.306102 -293.644805) (xy 62.283231 -293.688382) (xy 62.253666 -293.727726) (xy 62.218173 -293.761818)
			(xy 62.17767 -293.789774) (xy 62.133208 -293.810872) (xy 62.085937 -293.824564) (xy 62.037082 -293.830496)
			(xy 61.987907 -293.828515) (xy 61.939688 -293.818671) (xy 61.893672 -293.801219) (xy 61.851051 -293.776612)
			(xy 61.81293 -293.745487) (xy 61.780295 -293.70865) (xy 61.753992 -293.667054) (xy 61.734701 -293.621778)
			(xy 61.722924 -293.573994) (xy 61.718964 -293.52494) (xy 61.380116 -293.52494) (xy 61.379621 -293.549547)
			(xy 61.371726 -293.598124) (xy 61.356142 -293.644805) (xy 61.333271 -293.688382) (xy 61.303706 -293.727726)
			(xy 61.268213 -293.761818) (xy 61.22771 -293.789774) (xy 61.183248 -293.810872) (xy 61.135977 -293.824564)
			(xy 61.087122 -293.830496) (xy 61.037947 -293.828515) (xy 60.989728 -293.818671) (xy 60.943712 -293.801219)
			(xy 60.901091 -293.776612) (xy 60.86297 -293.745487) (xy 60.830335 -293.70865) (xy 60.804032 -293.667054)
			(xy 60.784741 -293.621778) (xy 60.772964 -293.573994) (xy 60.769004 -293.52494) (xy 60.430156 -293.52494)
			(xy 60.429661 -293.549547) (xy 60.421766 -293.598124) (xy 60.406182 -293.644805) (xy 60.383311 -293.688382)
			(xy 60.353746 -293.727726) (xy 60.318253 -293.761818) (xy 60.27775 -293.789774) (xy 60.233288 -293.810872)
			(xy 60.186017 -293.824564) (xy 60.137162 -293.830496) (xy 60.087987 -293.828515) (xy 60.039768 -293.818671)
			(xy 59.993752 -293.801219) (xy 59.951131 -293.776612) (xy 59.91301 -293.745487) (xy 59.880375 -293.70865)
			(xy 59.854072 -293.667054) (xy 59.834781 -293.621778) (xy 59.823004 -293.573994) (xy 59.819044 -293.52494)
			(xy 58.530236 -293.52494) (xy 58.529741 -293.549547) (xy 58.521846 -293.598124) (xy 58.506262 -293.644805)
			(xy 58.483391 -293.688382) (xy 58.453826 -293.727726) (xy 58.418333 -293.761818) (xy 58.37783 -293.789774)
			(xy 58.333368 -293.810872) (xy 58.286097 -293.824564) (xy 58.237242 -293.830496) (xy 58.188067 -293.828515)
			(xy 58.139848 -293.818671) (xy 58.093832 -293.801219) (xy 58.051211 -293.776612) (xy 58.01309 -293.745487)
			(xy 57.980455 -293.70865) (xy 57.954152 -293.667054) (xy 57.934861 -293.621778) (xy 57.923084 -293.573994)
			(xy 57.919124 -293.52494) (xy 57.580276 -293.52494) (xy 57.579781 -293.549547) (xy 57.571886 -293.598124)
			(xy 57.556302 -293.644805) (xy 57.533431 -293.688382) (xy 57.503866 -293.727726) (xy 57.468373 -293.761818)
			(xy 57.42787 -293.789774) (xy 57.383408 -293.810872) (xy 57.336137 -293.824564) (xy 57.287282 -293.830496)
			(xy 57.238107 -293.828515) (xy 57.189888 -293.818671) (xy 57.143872 -293.801219) (xy 57.101251 -293.776612)
			(xy 57.06313 -293.745487) (xy 57.030495 -293.70865) (xy 57.004192 -293.667054) (xy 56.984901 -293.621778)
			(xy 56.973124 -293.573994) (xy 56.969164 -293.52494) (xy 56.630062 -293.52494) (xy 56.629567 -293.549547)
			(xy 56.621672 -293.598124) (xy 56.606088 -293.644805) (xy 56.583217 -293.688382) (xy 56.553652 -293.727726)
			(xy 56.518159 -293.761818) (xy 56.477656 -293.789774) (xy 56.433194 -293.810872) (xy 56.385923 -293.824564)
			(xy 56.337068 -293.830496) (xy 56.287893 -293.828515) (xy 56.239674 -293.818671) (xy 56.193658 -293.801219)
			(xy 56.151037 -293.776612) (xy 56.112916 -293.745487) (xy 56.080281 -293.70865) (xy 56.053978 -293.667054)
			(xy 56.034687 -293.621778) (xy 56.02291 -293.573994) (xy 56.01895 -293.52494) (xy 55.680102 -293.52494)
			(xy 55.679607 -293.549547) (xy 55.671712 -293.598124) (xy 55.656128 -293.644805) (xy 55.633257 -293.688382)
			(xy 55.603692 -293.727726) (xy 55.568199 -293.761818) (xy 55.527696 -293.789774) (xy 55.483234 -293.810872)
			(xy 55.435963 -293.824564) (xy 55.387108 -293.830496) (xy 55.337933 -293.828515) (xy 55.289714 -293.818671)
			(xy 55.243698 -293.801219) (xy 55.201077 -293.776612) (xy 55.162956 -293.745487) (xy 55.130321 -293.70865)
			(xy 55.104018 -293.667054) (xy 55.084727 -293.621778) (xy 55.07295 -293.573994) (xy 55.06899 -293.52494)
			(xy 54.730142 -293.52494) (xy 54.729647 -293.549547) (xy 54.721752 -293.598124) (xy 54.706168 -293.644805)
			(xy 54.683297 -293.688382) (xy 54.653732 -293.727726) (xy 54.618239 -293.761818) (xy 54.577736 -293.789774)
			(xy 54.533274 -293.810872) (xy 54.486003 -293.824564) (xy 54.437148 -293.830496) (xy 54.387973 -293.828515)
			(xy 54.339754 -293.818671) (xy 54.293738 -293.801219) (xy 54.251117 -293.776612) (xy 54.212996 -293.745487)
			(xy 54.180361 -293.70865) (xy 54.154058 -293.667054) (xy 54.134767 -293.621778) (xy 54.12299 -293.573994)
			(xy 54.11903 -293.52494) (xy 53.780182 -293.52494) (xy 53.779687 -293.549547) (xy 53.771792 -293.598124)
			(xy 53.756208 -293.644805) (xy 53.733337 -293.688382) (xy 53.703772 -293.727726) (xy 53.668279 -293.761818)
			(xy 53.627776 -293.789774) (xy 53.583314 -293.810872) (xy 53.536043 -293.824564) (xy 53.487188 -293.830496)
			(xy 53.438013 -293.828515) (xy 53.389794 -293.818671) (xy 53.343778 -293.801219) (xy 53.301157 -293.776612)
			(xy 53.263036 -293.745487) (xy 53.230401 -293.70865) (xy 53.204098 -293.667054) (xy 53.184807 -293.621778)
			(xy 53.17303 -293.573994) (xy 53.16907 -293.52494) (xy 52.830222 -293.52494) (xy 52.829727 -293.549547)
			(xy 52.821832 -293.598124) (xy 52.806248 -293.644805) (xy 52.783377 -293.688382) (xy 52.753812 -293.727726)
			(xy 52.718319 -293.761818) (xy 52.677816 -293.789774) (xy 52.633354 -293.810872) (xy 52.586083 -293.824564)
			(xy 52.537228 -293.830496) (xy 52.488053 -293.828515) (xy 52.439834 -293.818671) (xy 52.393818 -293.801219)
			(xy 52.351197 -293.776612) (xy 52.313076 -293.745487) (xy 52.280441 -293.70865) (xy 52.254138 -293.667054)
			(xy 52.234847 -293.621778) (xy 52.22307 -293.573994) (xy 52.21911 -293.52494) (xy 51.880262 -293.52494)
			(xy 51.879767 -293.549547) (xy 51.871872 -293.598124) (xy 51.856288 -293.644805) (xy 51.833417 -293.688382)
			(xy 51.803852 -293.727726) (xy 51.768359 -293.761818) (xy 51.727856 -293.789774) (xy 51.683394 -293.810872)
			(xy 51.636123 -293.824564) (xy 51.587268 -293.830496) (xy 51.538093 -293.828515) (xy 51.489874 -293.818671)
			(xy 51.443858 -293.801219) (xy 51.401237 -293.776612) (xy 51.363116 -293.745487) (xy 51.330481 -293.70865)
			(xy 51.304178 -293.667054) (xy 51.284887 -293.621778) (xy 51.27311 -293.573994) (xy 51.26915 -293.52494)
			(xy 50.930302 -293.52494) (xy 50.929807 -293.549547) (xy 50.921912 -293.598124) (xy 50.906328 -293.644805)
			(xy 50.883457 -293.688382) (xy 50.853892 -293.727726) (xy 50.818399 -293.761818) (xy 50.777896 -293.789774)
			(xy 50.733434 -293.810872) (xy 50.686163 -293.824564) (xy 50.637308 -293.830496) (xy 50.588133 -293.828515)
			(xy 50.539914 -293.818671) (xy 50.493898 -293.801219) (xy 50.451277 -293.776612) (xy 50.413156 -293.745487)
			(xy 50.380521 -293.70865) (xy 50.354218 -293.667054) (xy 50.334927 -293.621778) (xy 50.32315 -293.573994)
			(xy 50.31919 -293.52494) (xy 49.980088 -293.52494) (xy 49.979593 -293.549547) (xy 49.971698 -293.598124)
			(xy 49.956114 -293.644805) (xy 49.933243 -293.688382) (xy 49.903678 -293.727726) (xy 49.868185 -293.761818)
			(xy 49.827682 -293.789774) (xy 49.78322 -293.810872) (xy 49.735949 -293.824564) (xy 49.687094 -293.830496)
			(xy 49.637919 -293.828515) (xy 49.5897 -293.818671) (xy 49.543684 -293.801219) (xy 49.501063 -293.776612)
			(xy 49.462942 -293.745487) (xy 49.430307 -293.70865) (xy 49.404004 -293.667054) (xy 49.384713 -293.621778)
			(xy 49.372936 -293.573994) (xy 49.368976 -293.52494) (xy 49.030128 -293.52494) (xy 49.029633 -293.549547)
			(xy 49.021738 -293.598124) (xy 49.006154 -293.644805) (xy 48.983283 -293.688382) (xy 48.953718 -293.727726)
			(xy 48.918225 -293.761818) (xy 48.877722 -293.789774) (xy 48.83326 -293.810872) (xy 48.785989 -293.824564)
			(xy 48.737134 -293.830496) (xy 48.687959 -293.828515) (xy 48.63974 -293.818671) (xy 48.593724 -293.801219)
			(xy 48.551103 -293.776612) (xy 48.512982 -293.745487) (xy 48.480347 -293.70865) (xy 48.454044 -293.667054)
			(xy 48.434753 -293.621778) (xy 48.422976 -293.573994) (xy 48.419016 -293.52494) (xy 48.080168 -293.52494)
			(xy 48.079673 -293.549547) (xy 48.071778 -293.598124) (xy 48.056194 -293.644805) (xy 48.033323 -293.688382)
			(xy 48.003758 -293.727726) (xy 47.968265 -293.761818) (xy 47.927762 -293.789774) (xy 47.8833 -293.810872)
			(xy 47.836029 -293.824564) (xy 47.787174 -293.830496) (xy 47.737999 -293.828515) (xy 47.68978 -293.818671)
			(xy 47.643764 -293.801219) (xy 47.601143 -293.776612) (xy 47.563022 -293.745487) (xy 47.530387 -293.70865)
			(xy 47.504084 -293.667054) (xy 47.484793 -293.621778) (xy 47.473016 -293.573994) (xy 47.469056 -293.52494)
			(xy 46.180248 -293.52494) (xy 46.179753 -293.549547) (xy 46.171858 -293.598124) (xy 46.156274 -293.644805)
			(xy 46.133403 -293.688382) (xy 46.103838 -293.727726) (xy 46.068345 -293.761818) (xy 46.027842 -293.789774)
			(xy 45.98338 -293.810872) (xy 45.936109 -293.824564) (xy 45.887254 -293.830496) (xy 45.838079 -293.828515)
			(xy 45.78986 -293.818671) (xy 45.743844 -293.801219) (xy 45.701223 -293.776612) (xy 45.663102 -293.745487)
			(xy 45.630467 -293.70865) (xy 45.604164 -293.667054) (xy 45.584873 -293.621778) (xy 45.573096 -293.573994)
			(xy 45.569136 -293.52494) (xy 44.280074 -293.52494) (xy 44.279579 -293.549547) (xy 44.271684 -293.598124)
			(xy 44.2561 -293.644805) (xy 44.233229 -293.688382) (xy 44.203664 -293.727726) (xy 44.168171 -293.761818)
			(xy 44.127668 -293.789774) (xy 44.083206 -293.810872) (xy 44.035935 -293.824564) (xy 43.98708 -293.830496)
			(xy 43.937905 -293.828515) (xy 43.889686 -293.818671) (xy 43.84367 -293.801219) (xy 43.801049 -293.776612)
			(xy 43.762928 -293.745487) (xy 43.730293 -293.70865) (xy 43.70399 -293.667054) (xy 43.684699 -293.621778)
			(xy 43.672922 -293.573994) (xy 43.668962 -293.52494) (xy 43.406849 -293.52494) (xy 43.402775 -293.580697)
			(xy 43.39058 -293.635338) (xy 43.370533 -293.687611) (xy 43.343063 -293.736395) (xy 43.308761 -293.780641)
			(xy 43.268362 -293.8194) (xy 43.222733 -293.851842) (xy 43.172855 -293.877268) (xy 43.146472 -293.886636)
			(xy 43.145964 -293.886636) (xy 43.138665 -293.889439) (xy 43.12611 -293.898741) (xy 43.121326 -293.904924)
			(xy 43.121326 -293.905178) (xy 43.116921 -293.911809) (xy 43.112008 -293.926942) (xy 43.111674 -293.934896)
			(xy 43.111674 -294.119046) (xy 43.111936 -294.126779) (xy 43.116584 -294.141527) (xy 43.120818 -294.148002)
			(xy 43.125136 -294.154352) (xy 43.137074 -294.16375) (xy 43.144186 -294.166544) (xy 43.168708 -294.1766)
			(xy 43.214445 -294.203372) (xy 43.255327 -294.237097) (xy 43.290305 -294.276911) (xy 43.318486 -294.321795)
			(xy 43.339147 -294.370599) (xy 43.351758 -294.422073) (xy 43.355999 -294.4749) (xy 43.668962 -294.4749)
			(xy 43.672922 -294.425846) (xy 43.684699 -294.378062) (xy 43.70399 -294.332786) (xy 43.730293 -294.29119)
			(xy 43.762928 -294.254353) (xy 43.801049 -294.223228) (xy 43.84367 -294.198621) (xy 43.889686 -294.181169)
			(xy 43.937905 -294.171325) (xy 43.98708 -294.169344) (xy 44.035935 -294.175276) (xy 44.083206 -294.188968)
			(xy 44.127668 -294.210066) (xy 44.168171 -294.238022) (xy 44.203664 -294.272114) (xy 44.233229 -294.311458)
			(xy 44.2561 -294.355035) (xy 44.271684 -294.401716) (xy 44.279579 -294.450293) (xy 44.280074 -294.4749)
			(xy 45.569136 -294.4749) (xy 45.573096 -294.425846) (xy 45.584873 -294.378062) (xy 45.604164 -294.332786)
			(xy 45.630467 -294.29119) (xy 45.663102 -294.254353) (xy 45.701223 -294.223228) (xy 45.743844 -294.198621)
			(xy 45.78986 -294.181169) (xy 45.838079 -294.171325) (xy 45.887254 -294.169344) (xy 45.936109 -294.175276)
			(xy 45.98338 -294.188968) (xy 46.027842 -294.210066) (xy 46.068345 -294.238022) (xy 46.103838 -294.272114)
			(xy 46.133403 -294.311458) (xy 46.156274 -294.355035) (xy 46.171858 -294.401716) (xy 46.179753 -294.450293)
			(xy 46.180248 -294.4749) (xy 46.519096 -294.4749) (xy 46.523056 -294.425846) (xy 46.534833 -294.378062)
			(xy 46.554124 -294.332786) (xy 46.580427 -294.29119) (xy 46.613062 -294.254353) (xy 46.651183 -294.223228)
			(xy 46.693804 -294.198621) (xy 46.73982 -294.181169) (xy 46.788039 -294.171325) (xy 46.837214 -294.169344)
			(xy 46.886069 -294.175276) (xy 46.93334 -294.188968) (xy 46.977802 -294.210066) (xy 47.018305 -294.238022)
			(xy 47.053798 -294.272114) (xy 47.083363 -294.311458) (xy 47.106234 -294.355035) (xy 47.121818 -294.401716)
			(xy 47.129713 -294.450293) (xy 47.130208 -294.4749) (xy 47.469056 -294.4749) (xy 47.473016 -294.425846)
			(xy 47.484793 -294.378062) (xy 47.504084 -294.332786) (xy 47.530387 -294.29119) (xy 47.563022 -294.254353)
			(xy 47.601143 -294.223228) (xy 47.643764 -294.198621) (xy 47.68978 -294.181169) (xy 47.737999 -294.171325)
			(xy 47.787174 -294.169344) (xy 47.836029 -294.175276) (xy 47.8833 -294.188968) (xy 47.927762 -294.210066)
			(xy 47.968265 -294.238022) (xy 48.003758 -294.272114) (xy 48.033323 -294.311458) (xy 48.056194 -294.355035)
			(xy 48.071778 -294.401716) (xy 48.079673 -294.450293) (xy 48.080168 -294.4749) (xy 48.419016 -294.4749)
			(xy 48.422976 -294.425846) (xy 48.434753 -294.378062) (xy 48.454044 -294.332786) (xy 48.480347 -294.29119)
			(xy 48.512982 -294.254353) (xy 48.551103 -294.223228) (xy 48.593724 -294.198621) (xy 48.63974 -294.181169)
			(xy 48.687959 -294.171325) (xy 48.737134 -294.169344) (xy 48.785989 -294.175276) (xy 48.83326 -294.188968)
			(xy 48.877722 -294.210066) (xy 48.918225 -294.238022) (xy 48.953718 -294.272114) (xy 48.983283 -294.311458)
			(xy 49.006154 -294.355035) (xy 49.021738 -294.401716) (xy 49.029633 -294.450293) (xy 49.030128 -294.4749)
			(xy 49.368976 -294.4749) (xy 49.372936 -294.425846) (xy 49.384713 -294.378062) (xy 49.404004 -294.332786)
			(xy 49.430307 -294.29119) (xy 49.462942 -294.254353) (xy 49.501063 -294.223228) (xy 49.543684 -294.198621)
			(xy 49.5897 -294.181169) (xy 49.637919 -294.171325) (xy 49.687094 -294.169344) (xy 49.735949 -294.175276)
			(xy 49.78322 -294.188968) (xy 49.827682 -294.210066) (xy 49.868185 -294.238022) (xy 49.903678 -294.272114)
			(xy 49.933243 -294.311458) (xy 49.956114 -294.355035) (xy 49.971698 -294.401716) (xy 49.979593 -294.450293)
			(xy 49.980088 -294.4749) (xy 50.31919 -294.4749) (xy 50.32315 -294.425846) (xy 50.334927 -294.378062)
			(xy 50.354218 -294.332786) (xy 50.380521 -294.29119) (xy 50.413156 -294.254353) (xy 50.451277 -294.223228)
			(xy 50.493898 -294.198621) (xy 50.539914 -294.181169) (xy 50.588133 -294.171325) (xy 50.637308 -294.169344)
			(xy 50.686163 -294.175276) (xy 50.733434 -294.188968) (xy 50.777896 -294.210066) (xy 50.818399 -294.238022)
			(xy 50.853892 -294.272114) (xy 50.883457 -294.311458) (xy 50.906328 -294.355035) (xy 50.921912 -294.401716)
			(xy 50.929807 -294.450293) (xy 50.930302 -294.4749) (xy 51.26915 -294.4749) (xy 51.27311 -294.425846)
			(xy 51.284887 -294.378062) (xy 51.304178 -294.332786) (xy 51.330481 -294.29119) (xy 51.363116 -294.254353)
			(xy 51.401237 -294.223228) (xy 51.443858 -294.198621) (xy 51.489874 -294.181169) (xy 51.538093 -294.171325)
			(xy 51.587268 -294.169344) (xy 51.636123 -294.175276) (xy 51.683394 -294.188968) (xy 51.727856 -294.210066)
			(xy 51.768359 -294.238022) (xy 51.803852 -294.272114) (xy 51.833417 -294.311458) (xy 51.856288 -294.355035)
			(xy 51.871872 -294.401716) (xy 51.879767 -294.450293) (xy 51.880262 -294.4749) (xy 52.21911 -294.4749)
			(xy 52.22307 -294.425846) (xy 52.234847 -294.378062) (xy 52.254138 -294.332786) (xy 52.280441 -294.29119)
			(xy 52.313076 -294.254353) (xy 52.351197 -294.223228) (xy 52.393818 -294.198621) (xy 52.439834 -294.181169)
			(xy 52.488053 -294.171325) (xy 52.537228 -294.169344) (xy 52.586083 -294.175276) (xy 52.633354 -294.188968)
			(xy 52.677816 -294.210066) (xy 52.718319 -294.238022) (xy 52.753812 -294.272114) (xy 52.783377 -294.311458)
			(xy 52.806248 -294.355035) (xy 52.821832 -294.401716) (xy 52.829727 -294.450293) (xy 52.830222 -294.4749)
			(xy 53.16907 -294.4749) (xy 53.17303 -294.425846) (xy 53.184807 -294.378062) (xy 53.204098 -294.332786)
			(xy 53.230401 -294.29119) (xy 53.263036 -294.254353) (xy 53.301157 -294.223228) (xy 53.343778 -294.198621)
			(xy 53.389794 -294.181169) (xy 53.438013 -294.171325) (xy 53.487188 -294.169344) (xy 53.536043 -294.175276)
			(xy 53.583314 -294.188968) (xy 53.627776 -294.210066) (xy 53.668279 -294.238022) (xy 53.703772 -294.272114)
			(xy 53.733337 -294.311458) (xy 53.756208 -294.355035) (xy 53.771792 -294.401716) (xy 53.779687 -294.450293)
			(xy 53.780182 -294.4749) (xy 54.11903 -294.4749) (xy 54.12299 -294.425846) (xy 54.134767 -294.378062)
			(xy 54.154058 -294.332786) (xy 54.180361 -294.29119) (xy 54.212996 -294.254353) (xy 54.251117 -294.223228)
			(xy 54.293738 -294.198621) (xy 54.339754 -294.181169) (xy 54.387973 -294.171325) (xy 54.437148 -294.169344)
			(xy 54.486003 -294.175276) (xy 54.533274 -294.188968) (xy 54.577736 -294.210066) (xy 54.618239 -294.238022)
			(xy 54.653732 -294.272114) (xy 54.683297 -294.311458) (xy 54.706168 -294.355035) (xy 54.721752 -294.401716)
			(xy 54.729647 -294.450293) (xy 54.730142 -294.4749) (xy 55.06899 -294.4749) (xy 55.07295 -294.425846)
			(xy 55.084727 -294.378062) (xy 55.104018 -294.332786) (xy 55.130321 -294.29119) (xy 55.162956 -294.254353)
			(xy 55.201077 -294.223228) (xy 55.243698 -294.198621) (xy 55.289714 -294.181169) (xy 55.337933 -294.171325)
			(xy 55.387108 -294.169344) (xy 55.435963 -294.175276) (xy 55.483234 -294.188968) (xy 55.527696 -294.210066)
			(xy 55.568199 -294.238022) (xy 55.603692 -294.272114) (xy 55.633257 -294.311458) (xy 55.656128 -294.355035)
			(xy 55.671712 -294.401716) (xy 55.679607 -294.450293) (xy 55.680102 -294.4749) (xy 56.01895 -294.4749)
			(xy 56.02291 -294.425846) (xy 56.034687 -294.378062) (xy 56.053978 -294.332786) (xy 56.080281 -294.29119)
			(xy 56.112916 -294.254353) (xy 56.151037 -294.223228) (xy 56.193658 -294.198621) (xy 56.239674 -294.181169)
			(xy 56.287893 -294.171325) (xy 56.337068 -294.169344) (xy 56.385923 -294.175276) (xy 56.433194 -294.188968)
			(xy 56.477656 -294.210066) (xy 56.518159 -294.238022) (xy 56.553652 -294.272114) (xy 56.583217 -294.311458)
			(xy 56.606088 -294.355035) (xy 56.621672 -294.401716) (xy 56.629567 -294.450293) (xy 56.630062 -294.4749)
			(xy 56.969164 -294.4749) (xy 56.973124 -294.425846) (xy 56.984901 -294.378062) (xy 57.004192 -294.332786)
			(xy 57.030495 -294.29119) (xy 57.06313 -294.254353) (xy 57.101251 -294.223228) (xy 57.143872 -294.198621)
			(xy 57.189888 -294.181169) (xy 57.238107 -294.171325) (xy 57.287282 -294.169344) (xy 57.336137 -294.175276)
			(xy 57.383408 -294.188968) (xy 57.42787 -294.210066) (xy 57.468373 -294.238022) (xy 57.503866 -294.272114)
			(xy 57.533431 -294.311458) (xy 57.556302 -294.355035) (xy 57.571886 -294.401716) (xy 57.579781 -294.450293)
			(xy 57.580276 -294.4749) (xy 57.919124 -294.4749) (xy 57.923084 -294.425846) (xy 57.934861 -294.378062)
			(xy 57.954152 -294.332786) (xy 57.980455 -294.29119) (xy 58.01309 -294.254353) (xy 58.051211 -294.223228)
			(xy 58.093832 -294.198621) (xy 58.139848 -294.181169) (xy 58.188067 -294.171325) (xy 58.237242 -294.169344)
			(xy 58.286097 -294.175276) (xy 58.333368 -294.188968) (xy 58.37783 -294.210066) (xy 58.418333 -294.238022)
			(xy 58.453826 -294.272114) (xy 58.483391 -294.311458) (xy 58.506262 -294.355035) (xy 58.521846 -294.401716)
			(xy 58.529741 -294.450293) (xy 58.530236 -294.4749) (xy 59.819044 -294.4749) (xy 59.823004 -294.425846)
			(xy 59.834781 -294.378062) (xy 59.854072 -294.332786) (xy 59.880375 -294.29119) (xy 59.91301 -294.254353)
			(xy 59.951131 -294.223228) (xy 59.993752 -294.198621) (xy 60.039768 -294.181169) (xy 60.087987 -294.171325)
			(xy 60.137162 -294.169344) (xy 60.186017 -294.175276) (xy 60.233288 -294.188968) (xy 60.27775 -294.210066)
			(xy 60.318253 -294.238022) (xy 60.353746 -294.272114) (xy 60.383311 -294.311458) (xy 60.406182 -294.355035)
			(xy 60.421766 -294.401716) (xy 60.429661 -294.450293) (xy 60.430156 -294.4749) (xy 60.769004 -294.4749)
			(xy 60.772964 -294.425846) (xy 60.784741 -294.378062) (xy 60.804032 -294.332786) (xy 60.830335 -294.29119)
			(xy 60.86297 -294.254353) (xy 60.901091 -294.223228) (xy 60.943712 -294.198621) (xy 60.989728 -294.181169)
			(xy 61.037947 -294.171325) (xy 61.087122 -294.169344) (xy 61.135977 -294.175276) (xy 61.183248 -294.188968)
			(xy 61.22771 -294.210066) (xy 61.268213 -294.238022) (xy 61.303706 -294.272114) (xy 61.333271 -294.311458)
			(xy 61.356142 -294.355035) (xy 61.371726 -294.401716) (xy 61.379621 -294.450293) (xy 61.380116 -294.4749)
			(xy 61.718964 -294.4749) (xy 61.722924 -294.425846) (xy 61.734701 -294.378062) (xy 61.753992 -294.332786)
			(xy 61.780295 -294.29119) (xy 61.81293 -294.254353) (xy 61.851051 -294.223228) (xy 61.893672 -294.198621)
			(xy 61.939688 -294.181169) (xy 61.987907 -294.171325) (xy 62.037082 -294.169344) (xy 62.085937 -294.175276)
			(xy 62.133208 -294.188968) (xy 62.17767 -294.210066) (xy 62.218173 -294.238022) (xy 62.253666 -294.272114)
			(xy 62.283231 -294.311458) (xy 62.306102 -294.355035) (xy 62.321686 -294.401716) (xy 62.329581 -294.450293)
			(xy 62.330076 -294.4749) (xy 62.669178 -294.4749) (xy 62.673138 -294.425846) (xy 62.684915 -294.378062)
			(xy 62.704206 -294.332786) (xy 62.730509 -294.29119) (xy 62.763144 -294.254353) (xy 62.801265 -294.223228)
			(xy 62.843886 -294.198621) (xy 62.889902 -294.181169) (xy 62.938121 -294.171325) (xy 62.987296 -294.169344)
			(xy 63.036151 -294.175276) (xy 63.083422 -294.188968) (xy 63.127884 -294.210066) (xy 63.168387 -294.238022)
			(xy 63.20388 -294.272114) (xy 63.233445 -294.311458) (xy 63.256316 -294.355035) (xy 63.2719 -294.401716)
			(xy 63.279795 -294.450293) (xy 63.28029 -294.4749) (xy 63.619138 -294.4749) (xy 63.623098 -294.425846)
			(xy 63.634875 -294.378062) (xy 63.654166 -294.332786) (xy 63.680469 -294.29119) (xy 63.713104 -294.254353)
			(xy 63.751225 -294.223228) (xy 63.793846 -294.198621) (xy 63.839862 -294.181169) (xy 63.888081 -294.171325)
			(xy 63.937256 -294.169344) (xy 63.986111 -294.175276) (xy 64.033382 -294.188968) (xy 64.077844 -294.210066)
			(xy 64.118347 -294.238022) (xy 64.15384 -294.272114) (xy 64.183405 -294.311458) (xy 64.206276 -294.355035)
			(xy 64.22186 -294.401716) (xy 64.229755 -294.450293) (xy 64.23025 -294.4749) (xy 64.569098 -294.4749)
			(xy 64.573058 -294.425846) (xy 64.584835 -294.378062) (xy 64.604126 -294.332786) (xy 64.630429 -294.29119)
			(xy 64.663064 -294.254353) (xy 64.701185 -294.223228) (xy 64.743806 -294.198621) (xy 64.789822 -294.181169)
			(xy 64.838041 -294.171325) (xy 64.887216 -294.169344) (xy 64.936071 -294.175276) (xy 64.983342 -294.188968)
			(xy 65.027804 -294.210066) (xy 65.068307 -294.238022) (xy 65.1038 -294.272114) (xy 65.133365 -294.311458)
			(xy 65.156236 -294.355035) (xy 65.17182 -294.401716) (xy 65.179715 -294.450293) (xy 65.18021 -294.4749)
			(xy 65.519058 -294.4749) (xy 65.523018 -294.425846) (xy 65.534795 -294.378062) (xy 65.554086 -294.332786)
			(xy 65.580389 -294.29119) (xy 65.613024 -294.254353) (xy 65.651145 -294.223228) (xy 65.693766 -294.198621)
			(xy 65.739782 -294.181169) (xy 65.788001 -294.171325) (xy 65.837176 -294.169344) (xy 65.886031 -294.175276)
			(xy 65.933302 -294.188968) (xy 65.977764 -294.210066) (xy 66.018267 -294.238022) (xy 66.05376 -294.272114)
			(xy 66.083325 -294.311458) (xy 66.106196 -294.355035) (xy 66.12178 -294.401716) (xy 66.129675 -294.450293)
			(xy 66.13017 -294.4749) (xy 66.469018 -294.4749) (xy 66.472978 -294.425846) (xy 66.484755 -294.378062)
			(xy 66.504046 -294.332786) (xy 66.530349 -294.29119) (xy 66.562984 -294.254353) (xy 66.601105 -294.223228)
			(xy 66.643726 -294.198621) (xy 66.689742 -294.181169) (xy 66.737961 -294.171325) (xy 66.787136 -294.169344)
			(xy 66.835991 -294.175276) (xy 66.883262 -294.188968) (xy 66.927724 -294.210066) (xy 66.968227 -294.238022)
			(xy 67.00372 -294.272114) (xy 67.033285 -294.311458) (xy 67.056156 -294.355035) (xy 67.07174 -294.401716)
			(xy 67.079635 -294.450293) (xy 67.08013 -294.4749) (xy 67.418978 -294.4749) (xy 67.422938 -294.425846)
			(xy 67.434715 -294.378062) (xy 67.454006 -294.332786) (xy 67.480309 -294.29119) (xy 67.512944 -294.254353)
			(xy 67.551065 -294.223228) (xy 67.593686 -294.198621) (xy 67.639702 -294.181169) (xy 67.687921 -294.171325)
			(xy 67.737096 -294.169344) (xy 67.785951 -294.175276) (xy 67.833222 -294.188968) (xy 67.877684 -294.210066)
			(xy 67.918187 -294.238022) (xy 67.95368 -294.272114) (xy 67.983245 -294.311458) (xy 68.006116 -294.355035)
			(xy 68.0217 -294.401716) (xy 68.029595 -294.450293) (xy 68.03009 -294.4749) (xy 68.368938 -294.4749)
			(xy 68.372898 -294.425846) (xy 68.384675 -294.378062) (xy 68.403966 -294.332786) (xy 68.430269 -294.29119)
			(xy 68.462904 -294.254353) (xy 68.501025 -294.223228) (xy 68.543646 -294.198621) (xy 68.589662 -294.181169)
			(xy 68.637881 -294.171325) (xy 68.687056 -294.169344) (xy 68.735911 -294.175276) (xy 68.783182 -294.188968)
			(xy 68.827644 -294.210066) (xy 68.868147 -294.238022) (xy 68.90364 -294.272114) (xy 68.933205 -294.311458)
			(xy 68.956076 -294.355035) (xy 68.97166 -294.401716) (xy 68.979555 -294.450293) (xy 68.98005 -294.4749)
			(xy 69.319152 -294.4749) (xy 69.323112 -294.425846) (xy 69.334889 -294.378062) (xy 69.35418 -294.332786)
			(xy 69.380483 -294.29119) (xy 69.413118 -294.254353) (xy 69.451239 -294.223228) (xy 69.49386 -294.198621)
			(xy 69.539876 -294.181169) (xy 69.588095 -294.171325) (xy 69.63727 -294.169344) (xy 69.686125 -294.175276)
			(xy 69.733396 -294.188968) (xy 69.777858 -294.210066) (xy 69.818361 -294.238022) (xy 69.853854 -294.272114)
			(xy 69.883419 -294.311458) (xy 69.90629 -294.355035) (xy 69.921874 -294.401716) (xy 69.929769 -294.450293)
			(xy 69.930264 -294.4749) (xy 69.929769 -294.499507) (xy 69.921874 -294.548084) (xy 69.90629 -294.594765)
			(xy 69.883419 -294.638342) (xy 69.853854 -294.677686) (xy 69.818361 -294.711778) (xy 69.777858 -294.739734)
			(xy 69.733396 -294.760832) (xy 69.686125 -294.774524) (xy 69.63727 -294.780456) (xy 69.588095 -294.778475)
			(xy 69.539876 -294.768631) (xy 69.49386 -294.751179) (xy 69.451239 -294.726572) (xy 69.413118 -294.695447)
			(xy 69.380483 -294.65861) (xy 69.35418 -294.617014) (xy 69.334889 -294.571738) (xy 69.323112 -294.523954)
			(xy 69.319152 -294.4749) (xy 68.98005 -294.4749) (xy 68.979555 -294.499507) (xy 68.97166 -294.548084)
			(xy 68.956076 -294.594765) (xy 68.933205 -294.638342) (xy 68.90364 -294.677686) (xy 68.868147 -294.711778)
			(xy 68.827644 -294.739734) (xy 68.783182 -294.760832) (xy 68.735911 -294.774524) (xy 68.687056 -294.780456)
			(xy 68.637881 -294.778475) (xy 68.589662 -294.768631) (xy 68.543646 -294.751179) (xy 68.501025 -294.726572)
			(xy 68.462904 -294.695447) (xy 68.430269 -294.65861) (xy 68.403966 -294.617014) (xy 68.384675 -294.571738)
			(xy 68.372898 -294.523954) (xy 68.368938 -294.4749) (xy 68.03009 -294.4749) (xy 68.029595 -294.499507)
			(xy 68.0217 -294.548084) (xy 68.006116 -294.594765) (xy 67.983245 -294.638342) (xy 67.95368 -294.677686)
			(xy 67.918187 -294.711778) (xy 67.877684 -294.739734) (xy 67.833222 -294.760832) (xy 67.785951 -294.774524)
			(xy 67.737096 -294.780456) (xy 67.687921 -294.778475) (xy 67.639702 -294.768631) (xy 67.593686 -294.751179)
			(xy 67.551065 -294.726572) (xy 67.512944 -294.695447) (xy 67.480309 -294.65861) (xy 67.454006 -294.617014)
			(xy 67.434715 -294.571738) (xy 67.422938 -294.523954) (xy 67.418978 -294.4749) (xy 67.08013 -294.4749)
			(xy 67.079635 -294.499507) (xy 67.07174 -294.548084) (xy 67.056156 -294.594765) (xy 67.033285 -294.638342)
			(xy 67.00372 -294.677686) (xy 66.968227 -294.711778) (xy 66.927724 -294.739734) (xy 66.883262 -294.760832)
			(xy 66.835991 -294.774524) (xy 66.787136 -294.780456) (xy 66.737961 -294.778475) (xy 66.689742 -294.768631)
			(xy 66.643726 -294.751179) (xy 66.601105 -294.726572) (xy 66.562984 -294.695447) (xy 66.530349 -294.65861)
			(xy 66.504046 -294.617014) (xy 66.484755 -294.571738) (xy 66.472978 -294.523954) (xy 66.469018 -294.4749)
			(xy 66.13017 -294.4749) (xy 66.129675 -294.499507) (xy 66.12178 -294.548084) (xy 66.106196 -294.594765)
			(xy 66.083325 -294.638342) (xy 66.05376 -294.677686) (xy 66.018267 -294.711778) (xy 65.977764 -294.739734)
			(xy 65.933302 -294.760832) (xy 65.886031 -294.774524) (xy 65.837176 -294.780456) (xy 65.788001 -294.778475)
			(xy 65.739782 -294.768631) (xy 65.693766 -294.751179) (xy 65.651145 -294.726572) (xy 65.613024 -294.695447)
			(xy 65.580389 -294.65861) (xy 65.554086 -294.617014) (xy 65.534795 -294.571738) (xy 65.523018 -294.523954)
			(xy 65.519058 -294.4749) (xy 65.18021 -294.4749) (xy 65.179715 -294.499507) (xy 65.17182 -294.548084)
			(xy 65.156236 -294.594765) (xy 65.133365 -294.638342) (xy 65.1038 -294.677686) (xy 65.068307 -294.711778)
			(xy 65.027804 -294.739734) (xy 64.983342 -294.760832) (xy 64.936071 -294.774524) (xy 64.887216 -294.780456)
			(xy 64.838041 -294.778475) (xy 64.789822 -294.768631) (xy 64.743806 -294.751179) (xy 64.701185 -294.726572)
			(xy 64.663064 -294.695447) (xy 64.630429 -294.65861) (xy 64.604126 -294.617014) (xy 64.584835 -294.571738)
			(xy 64.573058 -294.523954) (xy 64.569098 -294.4749) (xy 64.23025 -294.4749) (xy 64.229755 -294.499507)
			(xy 64.22186 -294.548084) (xy 64.206276 -294.594765) (xy 64.183405 -294.638342) (xy 64.15384 -294.677686)
			(xy 64.118347 -294.711778) (xy 64.077844 -294.739734) (xy 64.033382 -294.760832) (xy 63.986111 -294.774524)
			(xy 63.937256 -294.780456) (xy 63.888081 -294.778475) (xy 63.839862 -294.768631) (xy 63.793846 -294.751179)
			(xy 63.751225 -294.726572) (xy 63.713104 -294.695447) (xy 63.680469 -294.65861) (xy 63.654166 -294.617014)
			(xy 63.634875 -294.571738) (xy 63.623098 -294.523954) (xy 63.619138 -294.4749) (xy 63.28029 -294.4749)
			(xy 63.279795 -294.499507) (xy 63.2719 -294.548084) (xy 63.256316 -294.594765) (xy 63.233445 -294.638342)
			(xy 63.20388 -294.677686) (xy 63.168387 -294.711778) (xy 63.127884 -294.739734) (xy 63.083422 -294.760832)
			(xy 63.036151 -294.774524) (xy 62.987296 -294.780456) (xy 62.938121 -294.778475) (xy 62.889902 -294.768631)
			(xy 62.843886 -294.751179) (xy 62.801265 -294.726572) (xy 62.763144 -294.695447) (xy 62.730509 -294.65861)
			(xy 62.704206 -294.617014) (xy 62.684915 -294.571738) (xy 62.673138 -294.523954) (xy 62.669178 -294.4749)
			(xy 62.330076 -294.4749) (xy 62.329581 -294.499507) (xy 62.321686 -294.548084) (xy 62.306102 -294.594765)
			(xy 62.283231 -294.638342) (xy 62.253666 -294.677686) (xy 62.218173 -294.711778) (xy 62.17767 -294.739734)
			(xy 62.133208 -294.760832) (xy 62.085937 -294.774524) (xy 62.037082 -294.780456) (xy 61.987907 -294.778475)
			(xy 61.939688 -294.768631) (xy 61.893672 -294.751179) (xy 61.851051 -294.726572) (xy 61.81293 -294.695447)
			(xy 61.780295 -294.65861) (xy 61.753992 -294.617014) (xy 61.734701 -294.571738) (xy 61.722924 -294.523954)
			(xy 61.718964 -294.4749) (xy 61.380116 -294.4749) (xy 61.379621 -294.499507) (xy 61.371726 -294.548084)
			(xy 61.356142 -294.594765) (xy 61.333271 -294.638342) (xy 61.303706 -294.677686) (xy 61.268213 -294.711778)
			(xy 61.22771 -294.739734) (xy 61.183248 -294.760832) (xy 61.135977 -294.774524) (xy 61.087122 -294.780456)
			(xy 61.037947 -294.778475) (xy 60.989728 -294.768631) (xy 60.943712 -294.751179) (xy 60.901091 -294.726572)
			(xy 60.86297 -294.695447) (xy 60.830335 -294.65861) (xy 60.804032 -294.617014) (xy 60.784741 -294.571738)
			(xy 60.772964 -294.523954) (xy 60.769004 -294.4749) (xy 60.430156 -294.4749) (xy 60.429661 -294.499507)
			(xy 60.421766 -294.548084) (xy 60.406182 -294.594765) (xy 60.383311 -294.638342) (xy 60.353746 -294.677686)
			(xy 60.318253 -294.711778) (xy 60.27775 -294.739734) (xy 60.233288 -294.760832) (xy 60.186017 -294.774524)
			(xy 60.137162 -294.780456) (xy 60.087987 -294.778475) (xy 60.039768 -294.768631) (xy 59.993752 -294.751179)
			(xy 59.951131 -294.726572) (xy 59.91301 -294.695447) (xy 59.880375 -294.65861) (xy 59.854072 -294.617014)
			(xy 59.834781 -294.571738) (xy 59.823004 -294.523954) (xy 59.819044 -294.4749) (xy 58.530236 -294.4749)
			(xy 58.529741 -294.499507) (xy 58.521846 -294.548084) (xy 58.506262 -294.594765) (xy 58.483391 -294.638342)
			(xy 58.453826 -294.677686) (xy 58.418333 -294.711778) (xy 58.37783 -294.739734) (xy 58.333368 -294.760832)
			(xy 58.286097 -294.774524) (xy 58.237242 -294.780456) (xy 58.188067 -294.778475) (xy 58.139848 -294.768631)
			(xy 58.093832 -294.751179) (xy 58.051211 -294.726572) (xy 58.01309 -294.695447) (xy 57.980455 -294.65861)
			(xy 57.954152 -294.617014) (xy 57.934861 -294.571738) (xy 57.923084 -294.523954) (xy 57.919124 -294.4749)
			(xy 57.580276 -294.4749) (xy 57.579781 -294.499507) (xy 57.571886 -294.548084) (xy 57.556302 -294.594765)
			(xy 57.533431 -294.638342) (xy 57.503866 -294.677686) (xy 57.468373 -294.711778) (xy 57.42787 -294.739734)
			(xy 57.383408 -294.760832) (xy 57.336137 -294.774524) (xy 57.287282 -294.780456) (xy 57.238107 -294.778475)
			(xy 57.189888 -294.768631) (xy 57.143872 -294.751179) (xy 57.101251 -294.726572) (xy 57.06313 -294.695447)
			(xy 57.030495 -294.65861) (xy 57.004192 -294.617014) (xy 56.984901 -294.571738) (xy 56.973124 -294.523954)
			(xy 56.969164 -294.4749) (xy 56.630062 -294.4749) (xy 56.629567 -294.499507) (xy 56.621672 -294.548084)
			(xy 56.606088 -294.594765) (xy 56.583217 -294.638342) (xy 56.553652 -294.677686) (xy 56.518159 -294.711778)
			(xy 56.477656 -294.739734) (xy 56.433194 -294.760832) (xy 56.385923 -294.774524) (xy 56.337068 -294.780456)
			(xy 56.287893 -294.778475) (xy 56.239674 -294.768631) (xy 56.193658 -294.751179) (xy 56.151037 -294.726572)
			(xy 56.112916 -294.695447) (xy 56.080281 -294.65861) (xy 56.053978 -294.617014) (xy 56.034687 -294.571738)
			(xy 56.02291 -294.523954) (xy 56.01895 -294.4749) (xy 55.680102 -294.4749) (xy 55.679607 -294.499507)
			(xy 55.671712 -294.548084) (xy 55.656128 -294.594765) (xy 55.633257 -294.638342) (xy 55.603692 -294.677686)
			(xy 55.568199 -294.711778) (xy 55.527696 -294.739734) (xy 55.483234 -294.760832) (xy 55.435963 -294.774524)
			(xy 55.387108 -294.780456) (xy 55.337933 -294.778475) (xy 55.289714 -294.768631) (xy 55.243698 -294.751179)
			(xy 55.201077 -294.726572) (xy 55.162956 -294.695447) (xy 55.130321 -294.65861) (xy 55.104018 -294.617014)
			(xy 55.084727 -294.571738) (xy 55.07295 -294.523954) (xy 55.06899 -294.4749) (xy 54.730142 -294.4749)
			(xy 54.729647 -294.499507) (xy 54.721752 -294.548084) (xy 54.706168 -294.594765) (xy 54.683297 -294.638342)
			(xy 54.653732 -294.677686) (xy 54.618239 -294.711778) (xy 54.577736 -294.739734) (xy 54.533274 -294.760832)
			(xy 54.486003 -294.774524) (xy 54.437148 -294.780456) (xy 54.387973 -294.778475) (xy 54.339754 -294.768631)
			(xy 54.293738 -294.751179) (xy 54.251117 -294.726572) (xy 54.212996 -294.695447) (xy 54.180361 -294.65861)
			(xy 54.154058 -294.617014) (xy 54.134767 -294.571738) (xy 54.12299 -294.523954) (xy 54.11903 -294.4749)
			(xy 53.780182 -294.4749) (xy 53.779687 -294.499507) (xy 53.771792 -294.548084) (xy 53.756208 -294.594765)
			(xy 53.733337 -294.638342) (xy 53.703772 -294.677686) (xy 53.668279 -294.711778) (xy 53.627776 -294.739734)
			(xy 53.583314 -294.760832) (xy 53.536043 -294.774524) (xy 53.487188 -294.780456) (xy 53.438013 -294.778475)
			(xy 53.389794 -294.768631) (xy 53.343778 -294.751179) (xy 53.301157 -294.726572) (xy 53.263036 -294.695447)
			(xy 53.230401 -294.65861) (xy 53.204098 -294.617014) (xy 53.184807 -294.571738) (xy 53.17303 -294.523954)
			(xy 53.16907 -294.4749) (xy 52.830222 -294.4749) (xy 52.829727 -294.499507) (xy 52.821832 -294.548084)
			(xy 52.806248 -294.594765) (xy 52.783377 -294.638342) (xy 52.753812 -294.677686) (xy 52.718319 -294.711778)
			(xy 52.677816 -294.739734) (xy 52.633354 -294.760832) (xy 52.586083 -294.774524) (xy 52.537228 -294.780456)
			(xy 52.488053 -294.778475) (xy 52.439834 -294.768631) (xy 52.393818 -294.751179) (xy 52.351197 -294.726572)
			(xy 52.313076 -294.695447) (xy 52.280441 -294.65861) (xy 52.254138 -294.617014) (xy 52.234847 -294.571738)
			(xy 52.22307 -294.523954) (xy 52.21911 -294.4749) (xy 51.880262 -294.4749) (xy 51.879767 -294.499507)
			(xy 51.871872 -294.548084) (xy 51.856288 -294.594765) (xy 51.833417 -294.638342) (xy 51.803852 -294.677686)
			(xy 51.768359 -294.711778) (xy 51.727856 -294.739734) (xy 51.683394 -294.760832) (xy 51.636123 -294.774524)
			(xy 51.587268 -294.780456) (xy 51.538093 -294.778475) (xy 51.489874 -294.768631) (xy 51.443858 -294.751179)
			(xy 51.401237 -294.726572) (xy 51.363116 -294.695447) (xy 51.330481 -294.65861) (xy 51.304178 -294.617014)
			(xy 51.284887 -294.571738) (xy 51.27311 -294.523954) (xy 51.26915 -294.4749) (xy 50.930302 -294.4749)
			(xy 50.929807 -294.499507) (xy 50.921912 -294.548084) (xy 50.906328 -294.594765) (xy 50.883457 -294.638342)
			(xy 50.853892 -294.677686) (xy 50.818399 -294.711778) (xy 50.777896 -294.739734) (xy 50.733434 -294.760832)
			(xy 50.686163 -294.774524) (xy 50.637308 -294.780456) (xy 50.588133 -294.778475) (xy 50.539914 -294.768631)
			(xy 50.493898 -294.751179) (xy 50.451277 -294.726572) (xy 50.413156 -294.695447) (xy 50.380521 -294.65861)
			(xy 50.354218 -294.617014) (xy 50.334927 -294.571738) (xy 50.32315 -294.523954) (xy 50.31919 -294.4749)
			(xy 49.980088 -294.4749) (xy 49.979593 -294.499507) (xy 49.971698 -294.548084) (xy 49.956114 -294.594765)
			(xy 49.933243 -294.638342) (xy 49.903678 -294.677686) (xy 49.868185 -294.711778) (xy 49.827682 -294.739734)
			(xy 49.78322 -294.760832) (xy 49.735949 -294.774524) (xy 49.687094 -294.780456) (xy 49.637919 -294.778475)
			(xy 49.5897 -294.768631) (xy 49.543684 -294.751179) (xy 49.501063 -294.726572) (xy 49.462942 -294.695447)
			(xy 49.430307 -294.65861) (xy 49.404004 -294.617014) (xy 49.384713 -294.571738) (xy 49.372936 -294.523954)
			(xy 49.368976 -294.4749) (xy 49.030128 -294.4749) (xy 49.029633 -294.499507) (xy 49.021738 -294.548084)
			(xy 49.006154 -294.594765) (xy 48.983283 -294.638342) (xy 48.953718 -294.677686) (xy 48.918225 -294.711778)
			(xy 48.877722 -294.739734) (xy 48.83326 -294.760832) (xy 48.785989 -294.774524) (xy 48.737134 -294.780456)
			(xy 48.687959 -294.778475) (xy 48.63974 -294.768631) (xy 48.593724 -294.751179) (xy 48.551103 -294.726572)
			(xy 48.512982 -294.695447) (xy 48.480347 -294.65861) (xy 48.454044 -294.617014) (xy 48.434753 -294.571738)
			(xy 48.422976 -294.523954) (xy 48.419016 -294.4749) (xy 48.080168 -294.4749) (xy 48.079673 -294.499507)
			(xy 48.071778 -294.548084) (xy 48.056194 -294.594765) (xy 48.033323 -294.638342) (xy 48.003758 -294.677686)
			(xy 47.968265 -294.711778) (xy 47.927762 -294.739734) (xy 47.8833 -294.760832) (xy 47.836029 -294.774524)
			(xy 47.787174 -294.780456) (xy 47.737999 -294.778475) (xy 47.68978 -294.768631) (xy 47.643764 -294.751179)
			(xy 47.601143 -294.726572) (xy 47.563022 -294.695447) (xy 47.530387 -294.65861) (xy 47.504084 -294.617014)
			(xy 47.484793 -294.571738) (xy 47.473016 -294.523954) (xy 47.469056 -294.4749) (xy 47.130208 -294.4749)
			(xy 47.129713 -294.499507) (xy 47.121818 -294.548084) (xy 47.106234 -294.594765) (xy 47.083363 -294.638342)
			(xy 47.053798 -294.677686) (xy 47.018305 -294.711778) (xy 46.977802 -294.739734) (xy 46.93334 -294.760832)
			(xy 46.886069 -294.774524) (xy 46.837214 -294.780456) (xy 46.788039 -294.778475) (xy 46.73982 -294.768631)
			(xy 46.693804 -294.751179) (xy 46.651183 -294.726572) (xy 46.613062 -294.695447) (xy 46.580427 -294.65861)
			(xy 46.554124 -294.617014) (xy 46.534833 -294.571738) (xy 46.523056 -294.523954) (xy 46.519096 -294.4749)
			(xy 46.180248 -294.4749) (xy 46.179753 -294.499507) (xy 46.171858 -294.548084) (xy 46.156274 -294.594765)
			(xy 46.133403 -294.638342) (xy 46.103838 -294.677686) (xy 46.068345 -294.711778) (xy 46.027842 -294.739734)
			(xy 45.98338 -294.760832) (xy 45.936109 -294.774524) (xy 45.887254 -294.780456) (xy 45.838079 -294.778475)
			(xy 45.78986 -294.768631) (xy 45.743844 -294.751179) (xy 45.701223 -294.726572) (xy 45.663102 -294.695447)
			(xy 45.630467 -294.65861) (xy 45.604164 -294.617014) (xy 45.584873 -294.571738) (xy 45.573096 -294.523954)
			(xy 45.569136 -294.4749) (xy 44.280074 -294.4749) (xy 44.279579 -294.499507) (xy 44.271684 -294.548084)
			(xy 44.2561 -294.594765) (xy 44.233229 -294.638342) (xy 44.203664 -294.677686) (xy 44.168171 -294.711778)
			(xy 44.127668 -294.739734) (xy 44.083206 -294.760832) (xy 44.035935 -294.774524) (xy 43.98708 -294.780456)
			(xy 43.937905 -294.778475) (xy 43.889686 -294.768631) (xy 43.84367 -294.751179) (xy 43.801049 -294.726572)
			(xy 43.762928 -294.695447) (xy 43.730293 -294.65861) (xy 43.70399 -294.617014) (xy 43.684699 -294.571738)
			(xy 43.672922 -294.523954) (xy 43.668962 -294.4749) (xy 43.355999 -294.4749) (xy 43.351758 -294.527727)
			(xy 43.339147 -294.579201) (xy 43.318486 -294.628005) (xy 43.290305 -294.672889) (xy 43.255327 -294.712703)
			(xy 43.214445 -294.746428) (xy 43.168708 -294.7732) (xy 43.144186 -294.783256) (xy 43.137074 -294.78605)
			(xy 43.125136 -294.795448) (xy 43.120818 -294.801798) (xy 43.116664 -294.808312) (xy 43.112015 -294.823036)
			(xy 43.111674 -294.830754) (xy 43.111674 -296.37482) (xy 43.668962 -296.37482) (xy 43.672922 -296.325766)
			(xy 43.684699 -296.277982) (xy 43.70399 -296.232706) (xy 43.730293 -296.19111) (xy 43.762928 -296.154273)
			(xy 43.801049 -296.123148) (xy 43.84367 -296.098541) (xy 43.889686 -296.081089) (xy 43.937905 -296.071245)
			(xy 43.98708 -296.069264) (xy 44.035935 -296.075196) (xy 44.083206 -296.088888) (xy 44.127668 -296.109986)
			(xy 44.168171 -296.137942) (xy 44.203664 -296.172034) (xy 44.233229 -296.211378) (xy 44.2561 -296.254955)
			(xy 44.271684 -296.301636) (xy 44.279579 -296.350213) (xy 44.280074 -296.37482) (xy 45.569136 -296.37482)
			(xy 45.573096 -296.325766) (xy 45.584873 -296.277982) (xy 45.604164 -296.232706) (xy 45.630467 -296.19111)
			(xy 45.663102 -296.154273) (xy 45.701223 -296.123148) (xy 45.743844 -296.098541) (xy 45.78986 -296.081089)
			(xy 45.838079 -296.071245) (xy 45.887254 -296.069264) (xy 45.936109 -296.075196) (xy 45.98338 -296.088888)
			(xy 46.027842 -296.109986) (xy 46.068345 -296.137942) (xy 46.103838 -296.172034) (xy 46.133403 -296.211378)
			(xy 46.156274 -296.254955) (xy 46.171858 -296.301636) (xy 46.179753 -296.350213) (xy 46.180248 -296.37482)
			(xy 47.469056 -296.37482) (xy 47.473016 -296.325766) (xy 47.484793 -296.277982) (xy 47.504084 -296.232706)
			(xy 47.530387 -296.19111) (xy 47.563022 -296.154273) (xy 47.601143 -296.123148) (xy 47.643764 -296.098541)
			(xy 47.68978 -296.081089) (xy 47.737999 -296.071245) (xy 47.787174 -296.069264) (xy 47.836029 -296.075196)
			(xy 47.8833 -296.088888) (xy 47.927762 -296.109986) (xy 47.968265 -296.137942) (xy 48.003758 -296.172034)
			(xy 48.033323 -296.211378) (xy 48.056194 -296.254955) (xy 48.071778 -296.301636) (xy 48.079673 -296.350213)
			(xy 48.080168 -296.37482) (xy 48.419016 -296.37482) (xy 48.422976 -296.325766) (xy 48.434753 -296.277982)
			(xy 48.454044 -296.232706) (xy 48.480347 -296.19111) (xy 48.512982 -296.154273) (xy 48.551103 -296.123148)
			(xy 48.593724 -296.098541) (xy 48.63974 -296.081089) (xy 48.687959 -296.071245) (xy 48.737134 -296.069264)
			(xy 48.785989 -296.075196) (xy 48.83326 -296.088888) (xy 48.877722 -296.109986) (xy 48.918225 -296.137942)
			(xy 48.953718 -296.172034) (xy 48.983283 -296.211378) (xy 49.006154 -296.254955) (xy 49.021738 -296.301636)
			(xy 49.029633 -296.350213) (xy 49.030128 -296.37482) (xy 49.368976 -296.37482) (xy 49.372936 -296.325766)
			(xy 49.384713 -296.277982) (xy 49.404004 -296.232706) (xy 49.430307 -296.19111) (xy 49.462942 -296.154273)
			(xy 49.501063 -296.123148) (xy 49.543684 -296.098541) (xy 49.5897 -296.081089) (xy 49.637919 -296.071245)
			(xy 49.687094 -296.069264) (xy 49.735949 -296.075196) (xy 49.78322 -296.088888) (xy 49.827682 -296.109986)
			(xy 49.868185 -296.137942) (xy 49.903678 -296.172034) (xy 49.933243 -296.211378) (xy 49.956114 -296.254955)
			(xy 49.971698 -296.301636) (xy 49.979593 -296.350213) (xy 49.980088 -296.37482) (xy 50.31919 -296.37482)
			(xy 50.32315 -296.325766) (xy 50.334927 -296.277982) (xy 50.354218 -296.232706) (xy 50.380521 -296.19111)
			(xy 50.413156 -296.154273) (xy 50.451277 -296.123148) (xy 50.493898 -296.098541) (xy 50.539914 -296.081089)
			(xy 50.588133 -296.071245) (xy 50.637308 -296.069264) (xy 50.686163 -296.075196) (xy 50.733434 -296.088888)
			(xy 50.777896 -296.109986) (xy 50.818399 -296.137942) (xy 50.853892 -296.172034) (xy 50.883457 -296.211378)
			(xy 50.906328 -296.254955) (xy 50.921912 -296.301636) (xy 50.929807 -296.350213) (xy 50.930302 -296.37482)
			(xy 51.26915 -296.37482) (xy 51.27311 -296.325766) (xy 51.284887 -296.277982) (xy 51.304178 -296.232706)
			(xy 51.330481 -296.19111) (xy 51.363116 -296.154273) (xy 51.401237 -296.123148) (xy 51.443858 -296.098541)
			(xy 51.489874 -296.081089) (xy 51.538093 -296.071245) (xy 51.587268 -296.069264) (xy 51.636123 -296.075196)
			(xy 51.683394 -296.088888) (xy 51.727856 -296.109986) (xy 51.768359 -296.137942) (xy 51.803852 -296.172034)
			(xy 51.833417 -296.211378) (xy 51.856288 -296.254955) (xy 51.871872 -296.301636) (xy 51.879767 -296.350213)
			(xy 51.880262 -296.37482) (xy 52.21911 -296.37482) (xy 52.22307 -296.325766) (xy 52.234847 -296.277982)
			(xy 52.254138 -296.232706) (xy 52.280441 -296.19111) (xy 52.313076 -296.154273) (xy 52.351197 -296.123148)
			(xy 52.393818 -296.098541) (xy 52.439834 -296.081089) (xy 52.488053 -296.071245) (xy 52.537228 -296.069264)
			(xy 52.586083 -296.075196) (xy 52.633354 -296.088888) (xy 52.677816 -296.109986) (xy 52.718319 -296.137942)
			(xy 52.753812 -296.172034) (xy 52.783377 -296.211378) (xy 52.806248 -296.254955) (xy 52.821832 -296.301636)
			(xy 52.829727 -296.350213) (xy 52.830222 -296.37482) (xy 53.16907 -296.37482) (xy 53.17303 -296.325766)
			(xy 53.184807 -296.277982) (xy 53.204098 -296.232706) (xy 53.230401 -296.19111) (xy 53.263036 -296.154273)
			(xy 53.301157 -296.123148) (xy 53.343778 -296.098541) (xy 53.389794 -296.081089) (xy 53.438013 -296.071245)
			(xy 53.487188 -296.069264) (xy 53.536043 -296.075196) (xy 53.583314 -296.088888) (xy 53.627776 -296.109986)
			(xy 53.668279 -296.137942) (xy 53.703772 -296.172034) (xy 53.733337 -296.211378) (xy 53.756208 -296.254955)
			(xy 53.771792 -296.301636) (xy 53.779687 -296.350213) (xy 53.780182 -296.37482) (xy 54.11903 -296.37482)
			(xy 54.12299 -296.325766) (xy 54.134767 -296.277982) (xy 54.154058 -296.232706) (xy 54.180361 -296.19111)
			(xy 54.212996 -296.154273) (xy 54.251117 -296.123148) (xy 54.293738 -296.098541) (xy 54.339754 -296.081089)
			(xy 54.387973 -296.071245) (xy 54.437148 -296.069264) (xy 54.486003 -296.075196) (xy 54.533274 -296.088888)
			(xy 54.577736 -296.109986) (xy 54.618239 -296.137942) (xy 54.653732 -296.172034) (xy 54.683297 -296.211378)
			(xy 54.706168 -296.254955) (xy 54.721752 -296.301636) (xy 54.729647 -296.350213) (xy 54.730142 -296.37482)
			(xy 55.06899 -296.37482) (xy 55.07295 -296.325766) (xy 55.084727 -296.277982) (xy 55.104018 -296.232706)
			(xy 55.130321 -296.19111) (xy 55.162956 -296.154273) (xy 55.201077 -296.123148) (xy 55.243698 -296.098541)
			(xy 55.289714 -296.081089) (xy 55.337933 -296.071245) (xy 55.387108 -296.069264) (xy 55.435963 -296.075196)
			(xy 55.483234 -296.088888) (xy 55.527696 -296.109986) (xy 55.568199 -296.137942) (xy 55.603692 -296.172034)
			(xy 55.633257 -296.211378) (xy 55.656128 -296.254955) (xy 55.671712 -296.301636) (xy 55.679607 -296.350213)
			(xy 55.680102 -296.37482) (xy 56.019204 -296.37482) (xy 56.023164 -296.325766) (xy 56.034941 -296.277982)
			(xy 56.054232 -296.232706) (xy 56.080535 -296.19111) (xy 56.11317 -296.154273) (xy 56.151291 -296.123148)
			(xy 56.193912 -296.098541) (xy 56.239928 -296.081089) (xy 56.288147 -296.071245) (xy 56.337322 -296.069264)
			(xy 56.386177 -296.075196) (xy 56.433448 -296.088888) (xy 56.47791 -296.109986) (xy 56.518413 -296.137942)
			(xy 56.553906 -296.172034) (xy 56.583471 -296.211378) (xy 56.606342 -296.254955) (xy 56.621926 -296.301636)
			(xy 56.629821 -296.350213) (xy 56.630316 -296.37482) (xy 56.969164 -296.37482) (xy 56.973124 -296.325766)
			(xy 56.984901 -296.277982) (xy 57.004192 -296.232706) (xy 57.030495 -296.19111) (xy 57.06313 -296.154273)
			(xy 57.101251 -296.123148) (xy 57.143872 -296.098541) (xy 57.189888 -296.081089) (xy 57.238107 -296.071245)
			(xy 57.287282 -296.069264) (xy 57.336137 -296.075196) (xy 57.383408 -296.088888) (xy 57.42787 -296.109986)
			(xy 57.468373 -296.137942) (xy 57.503866 -296.172034) (xy 57.533431 -296.211378) (xy 57.556302 -296.254955)
			(xy 57.571886 -296.301636) (xy 57.579781 -296.350213) (xy 57.580276 -296.37482) (xy 57.919124 -296.37482)
			(xy 57.923084 -296.325766) (xy 57.934861 -296.277982) (xy 57.954152 -296.232706) (xy 57.980455 -296.19111)
			(xy 58.01309 -296.154273) (xy 58.051211 -296.123148) (xy 58.093832 -296.098541) (xy 58.139848 -296.081089)
			(xy 58.188067 -296.071245) (xy 58.237242 -296.069264) (xy 58.286097 -296.075196) (xy 58.333368 -296.088888)
			(xy 58.37783 -296.109986) (xy 58.418333 -296.137942) (xy 58.453826 -296.172034) (xy 58.483391 -296.211378)
			(xy 58.506262 -296.254955) (xy 58.521846 -296.301636) (xy 58.529741 -296.350213) (xy 58.530236 -296.37482)
			(xy 59.819044 -296.37482) (xy 59.823004 -296.325766) (xy 59.834781 -296.277982) (xy 59.854072 -296.232706)
			(xy 59.880375 -296.19111) (xy 59.91301 -296.154273) (xy 59.951131 -296.123148) (xy 59.993752 -296.098541)
			(xy 60.039768 -296.081089) (xy 60.087987 -296.071245) (xy 60.137162 -296.069264) (xy 60.186017 -296.075196)
			(xy 60.233288 -296.088888) (xy 60.27775 -296.109986) (xy 60.318253 -296.137942) (xy 60.353746 -296.172034)
			(xy 60.383311 -296.211378) (xy 60.406182 -296.254955) (xy 60.421766 -296.301636) (xy 60.429661 -296.350213)
			(xy 60.430156 -296.37482) (xy 60.769004 -296.37482) (xy 60.772964 -296.325766) (xy 60.784741 -296.277982)
			(xy 60.804032 -296.232706) (xy 60.830335 -296.19111) (xy 60.86297 -296.154273) (xy 60.901091 -296.123148)
			(xy 60.943712 -296.098541) (xy 60.989728 -296.081089) (xy 61.037947 -296.071245) (xy 61.087122 -296.069264)
			(xy 61.135977 -296.075196) (xy 61.183248 -296.088888) (xy 61.22771 -296.109986) (xy 61.268213 -296.137942)
			(xy 61.303706 -296.172034) (xy 61.333271 -296.211378) (xy 61.356142 -296.254955) (xy 61.371726 -296.301636)
			(xy 61.379621 -296.350213) (xy 61.380116 -296.37482) (xy 61.718964 -296.37482) (xy 61.722924 -296.325766)
			(xy 61.734701 -296.277982) (xy 61.753992 -296.232706) (xy 61.780295 -296.19111) (xy 61.81293 -296.154273)
			(xy 61.851051 -296.123148) (xy 61.893672 -296.098541) (xy 61.939688 -296.081089) (xy 61.987907 -296.071245)
			(xy 62.037082 -296.069264) (xy 62.085937 -296.075196) (xy 62.133208 -296.088888) (xy 62.17767 -296.109986)
			(xy 62.218173 -296.137942) (xy 62.253666 -296.172034) (xy 62.283231 -296.211378) (xy 62.306102 -296.254955)
			(xy 62.321686 -296.301636) (xy 62.329581 -296.350213) (xy 62.330076 -296.37482) (xy 62.669178 -296.37482)
			(xy 62.673138 -296.325766) (xy 62.684915 -296.277982) (xy 62.704206 -296.232706) (xy 62.730509 -296.19111)
			(xy 62.763144 -296.154273) (xy 62.801265 -296.123148) (xy 62.843886 -296.098541) (xy 62.889902 -296.081089)
			(xy 62.938121 -296.071245) (xy 62.987296 -296.069264) (xy 63.036151 -296.075196) (xy 63.083422 -296.088888)
			(xy 63.127884 -296.109986) (xy 63.168387 -296.137942) (xy 63.20388 -296.172034) (xy 63.233445 -296.211378)
			(xy 63.256316 -296.254955) (xy 63.2719 -296.301636) (xy 63.279795 -296.350213) (xy 63.28029 -296.37482)
			(xy 63.619138 -296.37482) (xy 63.623098 -296.325766) (xy 63.634875 -296.277982) (xy 63.654166 -296.232706)
			(xy 63.680469 -296.19111) (xy 63.713104 -296.154273) (xy 63.751225 -296.123148) (xy 63.793846 -296.098541)
			(xy 63.839862 -296.081089) (xy 63.888081 -296.071245) (xy 63.937256 -296.069264) (xy 63.986111 -296.075196)
			(xy 64.033382 -296.088888) (xy 64.077844 -296.109986) (xy 64.118347 -296.137942) (xy 64.15384 -296.172034)
			(xy 64.183405 -296.211378) (xy 64.206276 -296.254955) (xy 64.22186 -296.301636) (xy 64.229755 -296.350213)
			(xy 64.23025 -296.37482) (xy 64.569098 -296.37482) (xy 64.573058 -296.325766) (xy 64.584835 -296.277982)
			(xy 64.604126 -296.232706) (xy 64.630429 -296.19111) (xy 64.663064 -296.154273) (xy 64.701185 -296.123148)
			(xy 64.743806 -296.098541) (xy 64.789822 -296.081089) (xy 64.838041 -296.071245) (xy 64.887216 -296.069264)
			(xy 64.936071 -296.075196) (xy 64.983342 -296.088888) (xy 65.027804 -296.109986) (xy 65.068307 -296.137942)
			(xy 65.1038 -296.172034) (xy 65.133365 -296.211378) (xy 65.156236 -296.254955) (xy 65.17182 -296.301636)
			(xy 65.179715 -296.350213) (xy 65.18021 -296.37482) (xy 65.519058 -296.37482) (xy 65.523018 -296.325766)
			(xy 65.534795 -296.277982) (xy 65.554086 -296.232706) (xy 65.580389 -296.19111) (xy 65.613024 -296.154273)
			(xy 65.651145 -296.123148) (xy 65.693766 -296.098541) (xy 65.739782 -296.081089) (xy 65.788001 -296.071245)
			(xy 65.837176 -296.069264) (xy 65.886031 -296.075196) (xy 65.933302 -296.088888) (xy 65.977764 -296.109986)
			(xy 66.018267 -296.137942) (xy 66.05376 -296.172034) (xy 66.083325 -296.211378) (xy 66.106196 -296.254955)
			(xy 66.12178 -296.301636) (xy 66.129675 -296.350213) (xy 66.13017 -296.37482) (xy 66.469018 -296.37482)
			(xy 66.472978 -296.325766) (xy 66.484755 -296.277982) (xy 66.504046 -296.232706) (xy 66.530349 -296.19111)
			(xy 66.562984 -296.154273) (xy 66.601105 -296.123148) (xy 66.643726 -296.098541) (xy 66.689742 -296.081089)
			(xy 66.737961 -296.071245) (xy 66.787136 -296.069264) (xy 66.835991 -296.075196) (xy 66.883262 -296.088888)
			(xy 66.927724 -296.109986) (xy 66.968227 -296.137942) (xy 67.00372 -296.172034) (xy 67.033285 -296.211378)
			(xy 67.056156 -296.254955) (xy 67.07174 -296.301636) (xy 67.079635 -296.350213) (xy 67.08013 -296.37482)
			(xy 67.418978 -296.37482) (xy 67.422938 -296.325766) (xy 67.434715 -296.277982) (xy 67.454006 -296.232706)
			(xy 67.480309 -296.19111) (xy 67.512944 -296.154273) (xy 67.551065 -296.123148) (xy 67.593686 -296.098541)
			(xy 67.639702 -296.081089) (xy 67.687921 -296.071245) (xy 67.737096 -296.069264) (xy 67.785951 -296.075196)
			(xy 67.833222 -296.088888) (xy 67.877684 -296.109986) (xy 67.918187 -296.137942) (xy 67.95368 -296.172034)
			(xy 67.983245 -296.211378) (xy 68.006116 -296.254955) (xy 68.0217 -296.301636) (xy 68.029595 -296.350213)
			(xy 68.03009 -296.37482) (xy 68.368938 -296.37482) (xy 68.372898 -296.325766) (xy 68.384675 -296.277982)
			(xy 68.403966 -296.232706) (xy 68.430269 -296.19111) (xy 68.462904 -296.154273) (xy 68.501025 -296.123148)
			(xy 68.543646 -296.098541) (xy 68.589662 -296.081089) (xy 68.637881 -296.071245) (xy 68.687056 -296.069264)
			(xy 68.735911 -296.075196) (xy 68.783182 -296.088888) (xy 68.827644 -296.109986) (xy 68.868147 -296.137942)
			(xy 68.90364 -296.172034) (xy 68.933205 -296.211378) (xy 68.956076 -296.254955) (xy 68.97166 -296.301636)
			(xy 68.979555 -296.350213) (xy 68.98005 -296.37482) (xy 69.319152 -296.37482) (xy 69.323112 -296.325766)
			(xy 69.334889 -296.277982) (xy 69.35418 -296.232706) (xy 69.380483 -296.19111) (xy 69.413118 -296.154273)
			(xy 69.451239 -296.123148) (xy 69.49386 -296.098541) (xy 69.539876 -296.081089) (xy 69.588095 -296.071245)
			(xy 69.63727 -296.069264) (xy 69.686125 -296.075196) (xy 69.733396 -296.088888) (xy 69.777858 -296.109986)
			(xy 69.818361 -296.137942) (xy 69.853854 -296.172034) (xy 69.883419 -296.211378) (xy 69.90629 -296.254955)
			(xy 69.921874 -296.301636) (xy 69.929769 -296.350213) (xy 69.930264 -296.37482) (xy 69.929769 -296.399427)
			(xy 69.921874 -296.448004) (xy 69.90629 -296.494685) (xy 69.883419 -296.538262) (xy 69.853854 -296.577606)
			(xy 69.818361 -296.611698) (xy 69.777858 -296.639654) (xy 69.733396 -296.660752) (xy 69.686125 -296.674444)
			(xy 69.63727 -296.680376) (xy 69.588095 -296.678395) (xy 69.539876 -296.668551) (xy 69.49386 -296.651099)
			(xy 69.451239 -296.626492) (xy 69.413118 -296.595367) (xy 69.380483 -296.55853) (xy 69.35418 -296.516934)
			(xy 69.334889 -296.471658) (xy 69.323112 -296.423874) (xy 69.319152 -296.37482) (xy 68.98005 -296.37482)
			(xy 68.979555 -296.399427) (xy 68.97166 -296.448004) (xy 68.956076 -296.494685) (xy 68.933205 -296.538262)
			(xy 68.90364 -296.577606) (xy 68.868147 -296.611698) (xy 68.827644 -296.639654) (xy 68.783182 -296.660752)
			(xy 68.735911 -296.674444) (xy 68.687056 -296.680376) (xy 68.637881 -296.678395) (xy 68.589662 -296.668551)
			(xy 68.543646 -296.651099) (xy 68.501025 -296.626492) (xy 68.462904 -296.595367) (xy 68.430269 -296.55853)
			(xy 68.403966 -296.516934) (xy 68.384675 -296.471658) (xy 68.372898 -296.423874) (xy 68.368938 -296.37482)
			(xy 68.03009 -296.37482) (xy 68.029595 -296.399427) (xy 68.0217 -296.448004) (xy 68.006116 -296.494685)
			(xy 67.983245 -296.538262) (xy 67.95368 -296.577606) (xy 67.918187 -296.611698) (xy 67.877684 -296.639654)
			(xy 67.833222 -296.660752) (xy 67.785951 -296.674444) (xy 67.737096 -296.680376) (xy 67.687921 -296.678395)
			(xy 67.639702 -296.668551) (xy 67.593686 -296.651099) (xy 67.551065 -296.626492) (xy 67.512944 -296.595367)
			(xy 67.480309 -296.55853) (xy 67.454006 -296.516934) (xy 67.434715 -296.471658) (xy 67.422938 -296.423874)
			(xy 67.418978 -296.37482) (xy 67.08013 -296.37482) (xy 67.079635 -296.399427) (xy 67.07174 -296.448004)
			(xy 67.056156 -296.494685) (xy 67.033285 -296.538262) (xy 67.00372 -296.577606) (xy 66.968227 -296.611698)
			(xy 66.927724 -296.639654) (xy 66.883262 -296.660752) (xy 66.835991 -296.674444) (xy 66.787136 -296.680376)
			(xy 66.737961 -296.678395) (xy 66.689742 -296.668551) (xy 66.643726 -296.651099) (xy 66.601105 -296.626492)
			(xy 66.562984 -296.595367) (xy 66.530349 -296.55853) (xy 66.504046 -296.516934) (xy 66.484755 -296.471658)
			(xy 66.472978 -296.423874) (xy 66.469018 -296.37482) (xy 66.13017 -296.37482) (xy 66.129675 -296.399427)
			(xy 66.12178 -296.448004) (xy 66.106196 -296.494685) (xy 66.083325 -296.538262) (xy 66.05376 -296.577606)
			(xy 66.018267 -296.611698) (xy 65.977764 -296.639654) (xy 65.933302 -296.660752) (xy 65.886031 -296.674444)
			(xy 65.837176 -296.680376) (xy 65.788001 -296.678395) (xy 65.739782 -296.668551) (xy 65.693766 -296.651099)
			(xy 65.651145 -296.626492) (xy 65.613024 -296.595367) (xy 65.580389 -296.55853) (xy 65.554086 -296.516934)
			(xy 65.534795 -296.471658) (xy 65.523018 -296.423874) (xy 65.519058 -296.37482) (xy 65.18021 -296.37482)
			(xy 65.179715 -296.399427) (xy 65.17182 -296.448004) (xy 65.156236 -296.494685) (xy 65.133365 -296.538262)
			(xy 65.1038 -296.577606) (xy 65.068307 -296.611698) (xy 65.027804 -296.639654) (xy 64.983342 -296.660752)
			(xy 64.936071 -296.674444) (xy 64.887216 -296.680376) (xy 64.838041 -296.678395) (xy 64.789822 -296.668551)
			(xy 64.743806 -296.651099) (xy 64.701185 -296.626492) (xy 64.663064 -296.595367) (xy 64.630429 -296.55853)
			(xy 64.604126 -296.516934) (xy 64.584835 -296.471658) (xy 64.573058 -296.423874) (xy 64.569098 -296.37482)
			(xy 64.23025 -296.37482) (xy 64.229755 -296.399427) (xy 64.22186 -296.448004) (xy 64.206276 -296.494685)
			(xy 64.183405 -296.538262) (xy 64.15384 -296.577606) (xy 64.118347 -296.611698) (xy 64.077844 -296.639654)
			(xy 64.033382 -296.660752) (xy 63.986111 -296.674444) (xy 63.937256 -296.680376) (xy 63.888081 -296.678395)
			(xy 63.839862 -296.668551) (xy 63.793846 -296.651099) (xy 63.751225 -296.626492) (xy 63.713104 -296.595367)
			(xy 63.680469 -296.55853) (xy 63.654166 -296.516934) (xy 63.634875 -296.471658) (xy 63.623098 -296.423874)
			(xy 63.619138 -296.37482) (xy 63.28029 -296.37482) (xy 63.279795 -296.399427) (xy 63.2719 -296.448004)
			(xy 63.256316 -296.494685) (xy 63.233445 -296.538262) (xy 63.20388 -296.577606) (xy 63.168387 -296.611698)
			(xy 63.127884 -296.639654) (xy 63.083422 -296.660752) (xy 63.036151 -296.674444) (xy 62.987296 -296.680376)
			(xy 62.938121 -296.678395) (xy 62.889902 -296.668551) (xy 62.843886 -296.651099) (xy 62.801265 -296.626492)
			(xy 62.763144 -296.595367) (xy 62.730509 -296.55853) (xy 62.704206 -296.516934) (xy 62.684915 -296.471658)
			(xy 62.673138 -296.423874) (xy 62.669178 -296.37482) (xy 62.330076 -296.37482) (xy 62.329581 -296.399427)
			(xy 62.321686 -296.448004) (xy 62.306102 -296.494685) (xy 62.283231 -296.538262) (xy 62.253666 -296.577606)
			(xy 62.218173 -296.611698) (xy 62.17767 -296.639654) (xy 62.133208 -296.660752) (xy 62.085937 -296.674444)
			(xy 62.037082 -296.680376) (xy 61.987907 -296.678395) (xy 61.939688 -296.668551) (xy 61.893672 -296.651099)
			(xy 61.851051 -296.626492) (xy 61.81293 -296.595367) (xy 61.780295 -296.55853) (xy 61.753992 -296.516934)
			(xy 61.734701 -296.471658) (xy 61.722924 -296.423874) (xy 61.718964 -296.37482) (xy 61.380116 -296.37482)
			(xy 61.379621 -296.399427) (xy 61.371726 -296.448004) (xy 61.356142 -296.494685) (xy 61.333271 -296.538262)
			(xy 61.303706 -296.577606) (xy 61.268213 -296.611698) (xy 61.22771 -296.639654) (xy 61.183248 -296.660752)
			(xy 61.135977 -296.674444) (xy 61.087122 -296.680376) (xy 61.037947 -296.678395) (xy 60.989728 -296.668551)
			(xy 60.943712 -296.651099) (xy 60.901091 -296.626492) (xy 60.86297 -296.595367) (xy 60.830335 -296.55853)
			(xy 60.804032 -296.516934) (xy 60.784741 -296.471658) (xy 60.772964 -296.423874) (xy 60.769004 -296.37482)
			(xy 60.430156 -296.37482) (xy 60.429661 -296.399427) (xy 60.421766 -296.448004) (xy 60.406182 -296.494685)
			(xy 60.383311 -296.538262) (xy 60.353746 -296.577606) (xy 60.318253 -296.611698) (xy 60.27775 -296.639654)
			(xy 60.233288 -296.660752) (xy 60.186017 -296.674444) (xy 60.137162 -296.680376) (xy 60.087987 -296.678395)
			(xy 60.039768 -296.668551) (xy 59.993752 -296.651099) (xy 59.951131 -296.626492) (xy 59.91301 -296.595367)
			(xy 59.880375 -296.55853) (xy 59.854072 -296.516934) (xy 59.834781 -296.471658) (xy 59.823004 -296.423874)
			(xy 59.819044 -296.37482) (xy 58.530236 -296.37482) (xy 58.529741 -296.399427) (xy 58.521846 -296.448004)
			(xy 58.506262 -296.494685) (xy 58.483391 -296.538262) (xy 58.453826 -296.577606) (xy 58.418333 -296.611698)
			(xy 58.37783 -296.639654) (xy 58.333368 -296.660752) (xy 58.286097 -296.674444) (xy 58.237242 -296.680376)
			(xy 58.188067 -296.678395) (xy 58.139848 -296.668551) (xy 58.093832 -296.651099) (xy 58.051211 -296.626492)
			(xy 58.01309 -296.595367) (xy 57.980455 -296.55853) (xy 57.954152 -296.516934) (xy 57.934861 -296.471658)
			(xy 57.923084 -296.423874) (xy 57.919124 -296.37482) (xy 57.580276 -296.37482) (xy 57.579781 -296.399427)
			(xy 57.571886 -296.448004) (xy 57.556302 -296.494685) (xy 57.533431 -296.538262) (xy 57.503866 -296.577606)
			(xy 57.468373 -296.611698) (xy 57.42787 -296.639654) (xy 57.383408 -296.660752) (xy 57.336137 -296.674444)
			(xy 57.287282 -296.680376) (xy 57.238107 -296.678395) (xy 57.189888 -296.668551) (xy 57.143872 -296.651099)
			(xy 57.101251 -296.626492) (xy 57.06313 -296.595367) (xy 57.030495 -296.55853) (xy 57.004192 -296.516934)
			(xy 56.984901 -296.471658) (xy 56.973124 -296.423874) (xy 56.969164 -296.37482) (xy 56.630316 -296.37482)
			(xy 56.629821 -296.399427) (xy 56.621926 -296.448004) (xy 56.606342 -296.494685) (xy 56.583471 -296.538262)
			(xy 56.553906 -296.577606) (xy 56.518413 -296.611698) (xy 56.47791 -296.639654) (xy 56.433448 -296.660752)
			(xy 56.386177 -296.674444) (xy 56.337322 -296.680376) (xy 56.288147 -296.678395) (xy 56.239928 -296.668551)
			(xy 56.193912 -296.651099) (xy 56.151291 -296.626492) (xy 56.11317 -296.595367) (xy 56.080535 -296.55853)
			(xy 56.054232 -296.516934) (xy 56.034941 -296.471658) (xy 56.023164 -296.423874) (xy 56.019204 -296.37482)
			(xy 55.680102 -296.37482) (xy 55.679607 -296.399427) (xy 55.671712 -296.448004) (xy 55.656128 -296.494685)
			(xy 55.633257 -296.538262) (xy 55.603692 -296.577606) (xy 55.568199 -296.611698) (xy 55.527696 -296.639654)
			(xy 55.483234 -296.660752) (xy 55.435963 -296.674444) (xy 55.387108 -296.680376) (xy 55.337933 -296.678395)
			(xy 55.289714 -296.668551) (xy 55.243698 -296.651099) (xy 55.201077 -296.626492) (xy 55.162956 -296.595367)
			(xy 55.130321 -296.55853) (xy 55.104018 -296.516934) (xy 55.084727 -296.471658) (xy 55.07295 -296.423874)
			(xy 55.06899 -296.37482) (xy 54.730142 -296.37482) (xy 54.729647 -296.399427) (xy 54.721752 -296.448004)
			(xy 54.706168 -296.494685) (xy 54.683297 -296.538262) (xy 54.653732 -296.577606) (xy 54.618239 -296.611698)
			(xy 54.577736 -296.639654) (xy 54.533274 -296.660752) (xy 54.486003 -296.674444) (xy 54.437148 -296.680376)
			(xy 54.387973 -296.678395) (xy 54.339754 -296.668551) (xy 54.293738 -296.651099) (xy 54.251117 -296.626492)
			(xy 54.212996 -296.595367) (xy 54.180361 -296.55853) (xy 54.154058 -296.516934) (xy 54.134767 -296.471658)
			(xy 54.12299 -296.423874) (xy 54.11903 -296.37482) (xy 53.780182 -296.37482) (xy 53.779687 -296.399427)
			(xy 53.771792 -296.448004) (xy 53.756208 -296.494685) (xy 53.733337 -296.538262) (xy 53.703772 -296.577606)
			(xy 53.668279 -296.611698) (xy 53.627776 -296.639654) (xy 53.583314 -296.660752) (xy 53.536043 -296.674444)
			(xy 53.487188 -296.680376) (xy 53.438013 -296.678395) (xy 53.389794 -296.668551) (xy 53.343778 -296.651099)
			(xy 53.301157 -296.626492) (xy 53.263036 -296.595367) (xy 53.230401 -296.55853) (xy 53.204098 -296.516934)
			(xy 53.184807 -296.471658) (xy 53.17303 -296.423874) (xy 53.16907 -296.37482) (xy 52.830222 -296.37482)
			(xy 52.829727 -296.399427) (xy 52.821832 -296.448004) (xy 52.806248 -296.494685) (xy 52.783377 -296.538262)
			(xy 52.753812 -296.577606) (xy 52.718319 -296.611698) (xy 52.677816 -296.639654) (xy 52.633354 -296.660752)
			(xy 52.586083 -296.674444) (xy 52.537228 -296.680376) (xy 52.488053 -296.678395) (xy 52.439834 -296.668551)
			(xy 52.393818 -296.651099) (xy 52.351197 -296.626492) (xy 52.313076 -296.595367) (xy 52.280441 -296.55853)
			(xy 52.254138 -296.516934) (xy 52.234847 -296.471658) (xy 52.22307 -296.423874) (xy 52.21911 -296.37482)
			(xy 51.880262 -296.37482) (xy 51.879767 -296.399427) (xy 51.871872 -296.448004) (xy 51.856288 -296.494685)
			(xy 51.833417 -296.538262) (xy 51.803852 -296.577606) (xy 51.768359 -296.611698) (xy 51.727856 -296.639654)
			(xy 51.683394 -296.660752) (xy 51.636123 -296.674444) (xy 51.587268 -296.680376) (xy 51.538093 -296.678395)
			(xy 51.489874 -296.668551) (xy 51.443858 -296.651099) (xy 51.401237 -296.626492) (xy 51.363116 -296.595367)
			(xy 51.330481 -296.55853) (xy 51.304178 -296.516934) (xy 51.284887 -296.471658) (xy 51.27311 -296.423874)
			(xy 51.26915 -296.37482) (xy 50.930302 -296.37482) (xy 50.929807 -296.399427) (xy 50.921912 -296.448004)
			(xy 50.906328 -296.494685) (xy 50.883457 -296.538262) (xy 50.853892 -296.577606) (xy 50.818399 -296.611698)
			(xy 50.777896 -296.639654) (xy 50.733434 -296.660752) (xy 50.686163 -296.674444) (xy 50.637308 -296.680376)
			(xy 50.588133 -296.678395) (xy 50.539914 -296.668551) (xy 50.493898 -296.651099) (xy 50.451277 -296.626492)
			(xy 50.413156 -296.595367) (xy 50.380521 -296.55853) (xy 50.354218 -296.516934) (xy 50.334927 -296.471658)
			(xy 50.32315 -296.423874) (xy 50.31919 -296.37482) (xy 49.980088 -296.37482) (xy 49.979593 -296.399427)
			(xy 49.971698 -296.448004) (xy 49.956114 -296.494685) (xy 49.933243 -296.538262) (xy 49.903678 -296.577606)
			(xy 49.868185 -296.611698) (xy 49.827682 -296.639654) (xy 49.78322 -296.660752) (xy 49.735949 -296.674444)
			(xy 49.687094 -296.680376) (xy 49.637919 -296.678395) (xy 49.5897 -296.668551) (xy 49.543684 -296.651099)
			(xy 49.501063 -296.626492) (xy 49.462942 -296.595367) (xy 49.430307 -296.55853) (xy 49.404004 -296.516934)
			(xy 49.384713 -296.471658) (xy 49.372936 -296.423874) (xy 49.368976 -296.37482) (xy 49.030128 -296.37482)
			(xy 49.029633 -296.399427) (xy 49.021738 -296.448004) (xy 49.006154 -296.494685) (xy 48.983283 -296.538262)
			(xy 48.953718 -296.577606) (xy 48.918225 -296.611698) (xy 48.877722 -296.639654) (xy 48.83326 -296.660752)
			(xy 48.785989 -296.674444) (xy 48.737134 -296.680376) (xy 48.687959 -296.678395) (xy 48.63974 -296.668551)
			(xy 48.593724 -296.651099) (xy 48.551103 -296.626492) (xy 48.512982 -296.595367) (xy 48.480347 -296.55853)
			(xy 48.454044 -296.516934) (xy 48.434753 -296.471658) (xy 48.422976 -296.423874) (xy 48.419016 -296.37482)
			(xy 48.080168 -296.37482) (xy 48.079673 -296.399427) (xy 48.071778 -296.448004) (xy 48.056194 -296.494685)
			(xy 48.033323 -296.538262) (xy 48.003758 -296.577606) (xy 47.968265 -296.611698) (xy 47.927762 -296.639654)
			(xy 47.8833 -296.660752) (xy 47.836029 -296.674444) (xy 47.787174 -296.680376) (xy 47.737999 -296.678395)
			(xy 47.68978 -296.668551) (xy 47.643764 -296.651099) (xy 47.601143 -296.626492) (xy 47.563022 -296.595367)
			(xy 47.530387 -296.55853) (xy 47.504084 -296.516934) (xy 47.484793 -296.471658) (xy 47.473016 -296.423874)
			(xy 47.469056 -296.37482) (xy 46.180248 -296.37482) (xy 46.179753 -296.399427) (xy 46.171858 -296.448004)
			(xy 46.156274 -296.494685) (xy 46.133403 -296.538262) (xy 46.103838 -296.577606) (xy 46.068345 -296.611698)
			(xy 46.027842 -296.639654) (xy 45.98338 -296.660752) (xy 45.936109 -296.674444) (xy 45.887254 -296.680376)
			(xy 45.838079 -296.678395) (xy 45.78986 -296.668551) (xy 45.743844 -296.651099) (xy 45.701223 -296.626492)
			(xy 45.663102 -296.595367) (xy 45.630467 -296.55853) (xy 45.604164 -296.516934) (xy 45.584873 -296.471658)
			(xy 45.573096 -296.423874) (xy 45.569136 -296.37482) (xy 44.280074 -296.37482) (xy 44.279579 -296.399427)
			(xy 44.271684 -296.448004) (xy 44.2561 -296.494685) (xy 44.233229 -296.538262) (xy 44.203664 -296.577606)
			(xy 44.168171 -296.611698) (xy 44.127668 -296.639654) (xy 44.083206 -296.660752) (xy 44.035935 -296.674444)
			(xy 43.98708 -296.680376) (xy 43.937905 -296.678395) (xy 43.889686 -296.668551) (xy 43.84367 -296.651099)
			(xy 43.801049 -296.626492) (xy 43.762928 -296.595367) (xy 43.730293 -296.55853) (xy 43.70399 -296.516934)
			(xy 43.684699 -296.471658) (xy 43.672922 -296.423874) (xy 43.668962 -296.37482) (xy 43.111674 -296.37482)
			(xy 43.111674 -296.950384) (xy 43.11218 -296.960434) (xy 43.119903 -296.978994) (xy 43.12666 -296.986452)
			(xy 43.508422 -297.368214) (xy 43.511424 -297.371098) (xy 43.518188 -297.375951) (xy 43.521884 -297.377866)
			(xy 43.522138 -297.37812) (xy 43.531417 -297.382174) (xy 43.551615 -297.38337) (xy 43.570713 -297.376688)
			(xy 43.578526 -297.370246) (xy 43.57878 -297.369992) (xy 43.636184 -297.318176) (xy 43.644566 -297.301666)
			(xy 43.645582 -297.292014) (xy 43.648618 -297.266565) (xy 43.661535 -297.216971) (xy 43.681946 -297.169962)
			(xy 43.709361 -297.126662) (xy 43.743126 -297.088108) (xy 43.782432 -297.055221) (xy 43.826339 -297.02879)
			(xy 43.873797 -297.009445) (xy 43.92367 -296.99765) (xy 43.974766 -296.993687) (xy 44.025862 -296.99765)
			(xy 44.075735 -297.009445) (xy 44.123193 -297.02879) (xy 44.1671 -297.055221) (xy 44.206406 -297.088108)
			(xy 44.240171 -297.126662) (xy 44.267586 -297.169962) (xy 44.287997 -297.216971) (xy 44.300914 -297.266565)
			(xy 44.30395 -297.292014) (xy 44.304966 -297.301666) (xy 44.313348 -297.318176) (xy 44.370752 -297.369992)
			(xy 44.37798 -297.376075) (xy 44.3956 -297.382852) (xy 44.405042 -297.3832) (xy 44.494704 -297.3832)
			(xy 44.499457 -297.383101) (xy 44.508792 -297.381307) (xy 44.513246 -297.379644) (xy 44.521882 -297.376342)
			(xy 44.528994 -297.369992) (xy 44.586398 -297.318176) (xy 44.59478 -297.301666) (xy 44.595796 -297.292014)
			(xy 44.598832 -297.266565) (xy 44.611749 -297.216971) (xy 44.63216 -297.169962) (xy 44.659575 -297.126662)
			(xy 44.69334 -297.088108) (xy 44.732646 -297.055221) (xy 44.776553 -297.02879) (xy 44.824011 -297.009445)
			(xy 44.873884 -296.99765) (xy 44.92498 -296.993687) (xy 44.976076 -296.99765) (xy 45.025949 -297.009445)
			(xy 45.073407 -297.02879) (xy 45.117314 -297.055221) (xy 45.15662 -297.088108) (xy 45.190385 -297.126662)
			(xy 45.2178 -297.169962) (xy 45.238211 -297.216971) (xy 45.251128 -297.266565) (xy 45.254164 -297.292014)
			(xy 45.25518 -297.301666) (xy 45.263562 -297.318176) (xy 45.320966 -297.369992) (xy 45.328195 -297.376073)
			(xy 45.345815 -297.382846) (xy 45.355256 -297.3832) (xy 45.444664 -297.3832) (xy 45.449418 -297.383105)
			(xy 45.458755 -297.381317) (xy 45.463206 -297.379644) (xy 45.471842 -297.376342) (xy 45.478954 -297.369992)
			(xy 45.536358 -297.318176) (xy 45.54474 -297.301666) (xy 45.545756 -297.292014) (xy 45.54897 -297.265142)
			(xy 45.56302 -297.212883) (xy 45.585395 -297.163609) (xy 45.615497 -297.118639) (xy 45.652522 -297.079172)
			(xy 45.69548 -297.046262) (xy 45.743226 -297.020789) (xy 45.794483 -297.003433) (xy 45.847882 -296.994657)
			(xy 45.87494 -296.994072) (xy 45.900926 -296.994585) (xy 45.952257 -297.00272) (xy 46.001683 -297.018784)
			(xy 46.047988 -297.042382) (xy 46.090033 -297.072932) (xy 46.126781 -297.109682) (xy 46.157329 -297.151729)
			(xy 46.180923 -297.198036) (xy 46.196985 -297.247463) (xy 46.205117 -297.298794) (xy 46.205648 -297.32478)
			(xy 46.519096 -297.32478) (xy 46.523056 -297.275726) (xy 46.534833 -297.227942) (xy 46.554124 -297.182666)
			(xy 46.580427 -297.14107) (xy 46.613062 -297.104233) (xy 46.651183 -297.073108) (xy 46.693804 -297.048501)
			(xy 46.73982 -297.031049) (xy 46.788039 -297.021205) (xy 46.837214 -297.019224) (xy 46.886069 -297.025156)
			(xy 46.93334 -297.038848) (xy 46.977802 -297.059946) (xy 47.018305 -297.087902) (xy 47.053798 -297.121994)
			(xy 47.083363 -297.161338) (xy 47.106234 -297.204915) (xy 47.121818 -297.251596) (xy 47.129713 -297.300173)
			(xy 47.130208 -297.32478) (xy 47.469056 -297.32478) (xy 47.473016 -297.275726) (xy 47.484793 -297.227942)
			(xy 47.504084 -297.182666) (xy 47.530387 -297.14107) (xy 47.563022 -297.104233) (xy 47.601143 -297.073108)
			(xy 47.643764 -297.048501) (xy 47.68978 -297.031049) (xy 47.737999 -297.021205) (xy 47.787174 -297.019224)
			(xy 47.836029 -297.025156) (xy 47.8833 -297.038848) (xy 47.927762 -297.059946) (xy 47.968265 -297.087902)
			(xy 48.003758 -297.121994) (xy 48.033323 -297.161338) (xy 48.056194 -297.204915) (xy 48.071778 -297.251596)
			(xy 48.079673 -297.300173) (xy 48.080168 -297.32478) (xy 48.419016 -297.32478) (xy 48.422976 -297.275726)
			(xy 48.434753 -297.227942) (xy 48.454044 -297.182666) (xy 48.480347 -297.14107) (xy 48.512982 -297.104233)
			(xy 48.551103 -297.073108) (xy 48.593724 -297.048501) (xy 48.63974 -297.031049) (xy 48.687959 -297.021205)
			(xy 48.737134 -297.019224) (xy 48.785989 -297.025156) (xy 48.83326 -297.038848) (xy 48.877722 -297.059946)
			(xy 48.918225 -297.087902) (xy 48.953718 -297.121994) (xy 48.983283 -297.161338) (xy 49.006154 -297.204915)
			(xy 49.021738 -297.251596) (xy 49.029633 -297.300173) (xy 49.030128 -297.32478) (xy 49.368976 -297.32478)
			(xy 49.372936 -297.275726) (xy 49.384713 -297.227942) (xy 49.404004 -297.182666) (xy 49.430307 -297.14107)
			(xy 49.462942 -297.104233) (xy 49.501063 -297.073108) (xy 49.543684 -297.048501) (xy 49.5897 -297.031049)
			(xy 49.637919 -297.021205) (xy 49.687094 -297.019224) (xy 49.735949 -297.025156) (xy 49.78322 -297.038848)
			(xy 49.827682 -297.059946) (xy 49.868185 -297.087902) (xy 49.903678 -297.121994) (xy 49.933243 -297.161338)
			(xy 49.956114 -297.204915) (xy 49.971698 -297.251596) (xy 49.979593 -297.300173) (xy 49.980088 -297.32478)
			(xy 50.31919 -297.32478) (xy 50.32315 -297.275726) (xy 50.334927 -297.227942) (xy 50.354218 -297.182666)
			(xy 50.380521 -297.14107) (xy 50.413156 -297.104233) (xy 50.451277 -297.073108) (xy 50.493898 -297.048501)
			(xy 50.539914 -297.031049) (xy 50.588133 -297.021205) (xy 50.637308 -297.019224) (xy 50.686163 -297.025156)
			(xy 50.733434 -297.038848) (xy 50.777896 -297.059946) (xy 50.818399 -297.087902) (xy 50.853892 -297.121994)
			(xy 50.883457 -297.161338) (xy 50.906328 -297.204915) (xy 50.921912 -297.251596) (xy 50.929807 -297.300173)
			(xy 50.930302 -297.32478) (xy 51.26915 -297.32478) (xy 51.27311 -297.275726) (xy 51.284887 -297.227942)
			(xy 51.304178 -297.182666) (xy 51.330481 -297.14107) (xy 51.363116 -297.104233) (xy 51.401237 -297.073108)
			(xy 51.443858 -297.048501) (xy 51.489874 -297.031049) (xy 51.538093 -297.021205) (xy 51.587268 -297.019224)
			(xy 51.636123 -297.025156) (xy 51.683394 -297.038848) (xy 51.727856 -297.059946) (xy 51.768359 -297.087902)
			(xy 51.803852 -297.121994) (xy 51.833417 -297.161338) (xy 51.856288 -297.204915) (xy 51.871872 -297.251596)
			(xy 51.879767 -297.300173) (xy 51.880262 -297.32478) (xy 52.21911 -297.32478) (xy 52.22307 -297.275726)
			(xy 52.234847 -297.227942) (xy 52.254138 -297.182666) (xy 52.280441 -297.14107) (xy 52.313076 -297.104233)
			(xy 52.351197 -297.073108) (xy 52.393818 -297.048501) (xy 52.439834 -297.031049) (xy 52.488053 -297.021205)
			(xy 52.537228 -297.019224) (xy 52.586083 -297.025156) (xy 52.633354 -297.038848) (xy 52.677816 -297.059946)
			(xy 52.718319 -297.087902) (xy 52.753812 -297.121994) (xy 52.783377 -297.161338) (xy 52.806248 -297.204915)
			(xy 52.821832 -297.251596) (xy 52.829727 -297.300173) (xy 52.830222 -297.32478) (xy 53.16907 -297.32478)
			(xy 53.17303 -297.275726) (xy 53.184807 -297.227942) (xy 53.204098 -297.182666) (xy 53.230401 -297.14107)
			(xy 53.263036 -297.104233) (xy 53.301157 -297.073108) (xy 53.343778 -297.048501) (xy 53.389794 -297.031049)
			(xy 53.438013 -297.021205) (xy 53.487188 -297.019224) (xy 53.536043 -297.025156) (xy 53.583314 -297.038848)
			(xy 53.627776 -297.059946) (xy 53.668279 -297.087902) (xy 53.703772 -297.121994) (xy 53.733337 -297.161338)
			(xy 53.756208 -297.204915) (xy 53.771792 -297.251596) (xy 53.779687 -297.300173) (xy 53.780182 -297.32478)
			(xy 54.11903 -297.32478) (xy 54.12299 -297.275726) (xy 54.134767 -297.227942) (xy 54.154058 -297.182666)
			(xy 54.180361 -297.14107) (xy 54.212996 -297.104233) (xy 54.251117 -297.073108) (xy 54.293738 -297.048501)
			(xy 54.339754 -297.031049) (xy 54.387973 -297.021205) (xy 54.437148 -297.019224) (xy 54.486003 -297.025156)
			(xy 54.533274 -297.038848) (xy 54.577736 -297.059946) (xy 54.618239 -297.087902) (xy 54.653732 -297.121994)
			(xy 54.683297 -297.161338) (xy 54.706168 -297.204915) (xy 54.721752 -297.251596) (xy 54.729647 -297.300173)
			(xy 54.730142 -297.32478) (xy 55.06899 -297.32478) (xy 55.07295 -297.275726) (xy 55.084727 -297.227942)
			(xy 55.104018 -297.182666) (xy 55.130321 -297.14107) (xy 55.162956 -297.104233) (xy 55.201077 -297.073108)
			(xy 55.243698 -297.048501) (xy 55.289714 -297.031049) (xy 55.337933 -297.021205) (xy 55.387108 -297.019224)
			(xy 55.435963 -297.025156) (xy 55.483234 -297.038848) (xy 55.527696 -297.059946) (xy 55.568199 -297.087902)
			(xy 55.603692 -297.121994) (xy 55.633257 -297.161338) (xy 55.656128 -297.204915) (xy 55.671712 -297.251596)
			(xy 55.679607 -297.300173) (xy 55.680102 -297.32478) (xy 56.01895 -297.32478) (xy 56.02291 -297.275726)
			(xy 56.034687 -297.227942) (xy 56.053978 -297.182666) (xy 56.080281 -297.14107) (xy 56.112916 -297.104233)
			(xy 56.151037 -297.073108) (xy 56.193658 -297.048501) (xy 56.239674 -297.031049) (xy 56.287893 -297.021205)
			(xy 56.337068 -297.019224) (xy 56.385923 -297.025156) (xy 56.433194 -297.038848) (xy 56.477656 -297.059946)
			(xy 56.518159 -297.087902) (xy 56.553652 -297.121994) (xy 56.583217 -297.161338) (xy 56.606088 -297.204915)
			(xy 56.621672 -297.251596) (xy 56.629567 -297.300173) (xy 56.630062 -297.32478) (xy 56.969164 -297.32478)
			(xy 56.973124 -297.275726) (xy 56.984901 -297.227942) (xy 57.004192 -297.182666) (xy 57.030495 -297.14107)
			(xy 57.06313 -297.104233) (xy 57.101251 -297.073108) (xy 57.143872 -297.048501) (xy 57.189888 -297.031049)
			(xy 57.238107 -297.021205) (xy 57.287282 -297.019224) (xy 57.336137 -297.025156) (xy 57.383408 -297.038848)
			(xy 57.42787 -297.059946) (xy 57.468373 -297.087902) (xy 57.503866 -297.121994) (xy 57.533431 -297.161338)
			(xy 57.556302 -297.204915) (xy 57.571886 -297.251596) (xy 57.579781 -297.300173) (xy 57.580276 -297.32478)
			(xy 57.919124 -297.32478) (xy 57.923084 -297.275726) (xy 57.934861 -297.227942) (xy 57.954152 -297.182666)
			(xy 57.980455 -297.14107) (xy 58.01309 -297.104233) (xy 58.051211 -297.073108) (xy 58.093832 -297.048501)
			(xy 58.139848 -297.031049) (xy 58.188067 -297.021205) (xy 58.237242 -297.019224) (xy 58.286097 -297.025156)
			(xy 58.333368 -297.038848) (xy 58.37783 -297.059946) (xy 58.418333 -297.087902) (xy 58.453826 -297.121994)
			(xy 58.483391 -297.161338) (xy 58.506262 -297.204915) (xy 58.521846 -297.251596) (xy 58.529741 -297.300173)
			(xy 58.530236 -297.32478) (xy 59.819044 -297.32478) (xy 59.823004 -297.275726) (xy 59.834781 -297.227942)
			(xy 59.854072 -297.182666) (xy 59.880375 -297.14107) (xy 59.91301 -297.104233) (xy 59.951131 -297.073108)
			(xy 59.993752 -297.048501) (xy 60.039768 -297.031049) (xy 60.087987 -297.021205) (xy 60.137162 -297.019224)
			(xy 60.186017 -297.025156) (xy 60.233288 -297.038848) (xy 60.27775 -297.059946) (xy 60.318253 -297.087902)
			(xy 60.353746 -297.121994) (xy 60.383311 -297.161338) (xy 60.406182 -297.204915) (xy 60.421766 -297.251596)
			(xy 60.429661 -297.300173) (xy 60.430156 -297.32478) (xy 60.769004 -297.32478) (xy 60.772964 -297.275726)
			(xy 60.784741 -297.227942) (xy 60.804032 -297.182666) (xy 60.830335 -297.14107) (xy 60.86297 -297.104233)
			(xy 60.901091 -297.073108) (xy 60.943712 -297.048501) (xy 60.989728 -297.031049) (xy 61.037947 -297.021205)
			(xy 61.087122 -297.019224) (xy 61.135977 -297.025156) (xy 61.183248 -297.038848) (xy 61.22771 -297.059946)
			(xy 61.268213 -297.087902) (xy 61.303706 -297.121994) (xy 61.333271 -297.161338) (xy 61.356142 -297.204915)
			(xy 61.371726 -297.251596) (xy 61.379621 -297.300173) (xy 61.380116 -297.32478) (xy 61.718964 -297.32478)
			(xy 61.722924 -297.275726) (xy 61.734701 -297.227942) (xy 61.753992 -297.182666) (xy 61.780295 -297.14107)
			(xy 61.81293 -297.104233) (xy 61.851051 -297.073108) (xy 61.893672 -297.048501) (xy 61.939688 -297.031049)
			(xy 61.987907 -297.021205) (xy 62.037082 -297.019224) (xy 62.085937 -297.025156) (xy 62.133208 -297.038848)
			(xy 62.17767 -297.059946) (xy 62.218173 -297.087902) (xy 62.253666 -297.121994) (xy 62.283231 -297.161338)
			(xy 62.306102 -297.204915) (xy 62.321686 -297.251596) (xy 62.329581 -297.300173) (xy 62.330076 -297.32478)
			(xy 62.669178 -297.32478) (xy 62.673138 -297.275726) (xy 62.684915 -297.227942) (xy 62.704206 -297.182666)
			(xy 62.730509 -297.14107) (xy 62.763144 -297.104233) (xy 62.801265 -297.073108) (xy 62.843886 -297.048501)
			(xy 62.889902 -297.031049) (xy 62.938121 -297.021205) (xy 62.987296 -297.019224) (xy 63.036151 -297.025156)
			(xy 63.083422 -297.038848) (xy 63.127884 -297.059946) (xy 63.168387 -297.087902) (xy 63.20388 -297.121994)
			(xy 63.233445 -297.161338) (xy 63.256316 -297.204915) (xy 63.2719 -297.251596) (xy 63.279795 -297.300173)
			(xy 63.28029 -297.32478) (xy 63.619138 -297.32478) (xy 63.623098 -297.275726) (xy 63.634875 -297.227942)
			(xy 63.654166 -297.182666) (xy 63.680469 -297.14107) (xy 63.713104 -297.104233) (xy 63.751225 -297.073108)
			(xy 63.793846 -297.048501) (xy 63.839862 -297.031049) (xy 63.888081 -297.021205) (xy 63.937256 -297.019224)
			(xy 63.986111 -297.025156) (xy 64.033382 -297.038848) (xy 64.077844 -297.059946) (xy 64.118347 -297.087902)
			(xy 64.15384 -297.121994) (xy 64.183405 -297.161338) (xy 64.206276 -297.204915) (xy 64.22186 -297.251596)
			(xy 64.229755 -297.300173) (xy 64.23025 -297.32478) (xy 64.569098 -297.32478) (xy 64.573058 -297.275726)
			(xy 64.584835 -297.227942) (xy 64.604126 -297.182666) (xy 64.630429 -297.14107) (xy 64.663064 -297.104233)
			(xy 64.701185 -297.073108) (xy 64.743806 -297.048501) (xy 64.789822 -297.031049) (xy 64.838041 -297.021205)
			(xy 64.887216 -297.019224) (xy 64.936071 -297.025156) (xy 64.983342 -297.038848) (xy 65.027804 -297.059946)
			(xy 65.068307 -297.087902) (xy 65.1038 -297.121994) (xy 65.133365 -297.161338) (xy 65.156236 -297.204915)
			(xy 65.17182 -297.251596) (xy 65.179715 -297.300173) (xy 65.18021 -297.32478) (xy 65.519058 -297.32478)
			(xy 65.523018 -297.275726) (xy 65.534795 -297.227942) (xy 65.554086 -297.182666) (xy 65.580389 -297.14107)
			(xy 65.613024 -297.104233) (xy 65.651145 -297.073108) (xy 65.693766 -297.048501) (xy 65.739782 -297.031049)
			(xy 65.788001 -297.021205) (xy 65.837176 -297.019224) (xy 65.886031 -297.025156) (xy 65.933302 -297.038848)
			(xy 65.977764 -297.059946) (xy 66.018267 -297.087902) (xy 66.05376 -297.121994) (xy 66.083325 -297.161338)
			(xy 66.106196 -297.204915) (xy 66.12178 -297.251596) (xy 66.129675 -297.300173) (xy 66.13017 -297.32478)
			(xy 66.469018 -297.32478) (xy 66.472978 -297.275726) (xy 66.484755 -297.227942) (xy 66.504046 -297.182666)
			(xy 66.530349 -297.14107) (xy 66.562984 -297.104233) (xy 66.601105 -297.073108) (xy 66.643726 -297.048501)
			(xy 66.689742 -297.031049) (xy 66.737961 -297.021205) (xy 66.787136 -297.019224) (xy 66.835991 -297.025156)
			(xy 66.883262 -297.038848) (xy 66.927724 -297.059946) (xy 66.968227 -297.087902) (xy 67.00372 -297.121994)
			(xy 67.033285 -297.161338) (xy 67.056156 -297.204915) (xy 67.07174 -297.251596) (xy 67.079635 -297.300173)
			(xy 67.08013 -297.32478) (xy 67.418978 -297.32478) (xy 67.422938 -297.275726) (xy 67.434715 -297.227942)
			(xy 67.454006 -297.182666) (xy 67.480309 -297.14107) (xy 67.512944 -297.104233) (xy 67.551065 -297.073108)
			(xy 67.593686 -297.048501) (xy 67.639702 -297.031049) (xy 67.687921 -297.021205) (xy 67.737096 -297.019224)
			(xy 67.785951 -297.025156) (xy 67.833222 -297.038848) (xy 67.877684 -297.059946) (xy 67.918187 -297.087902)
			(xy 67.95368 -297.121994) (xy 67.983245 -297.161338) (xy 68.006116 -297.204915) (xy 68.0217 -297.251596)
			(xy 68.029595 -297.300173) (xy 68.03009 -297.32478) (xy 68.029595 -297.349387) (xy 68.0217 -297.397964)
			(xy 68.006116 -297.444645) (xy 67.983245 -297.488222) (xy 67.95368 -297.527566) (xy 67.918187 -297.561658)
			(xy 67.877684 -297.589614) (xy 67.833222 -297.610712) (xy 67.785951 -297.624404) (xy 67.737096 -297.630336)
			(xy 67.687921 -297.628355) (xy 67.639702 -297.618511) (xy 67.593686 -297.601059) (xy 67.551065 -297.576452)
			(xy 67.512944 -297.545327) (xy 67.480309 -297.50849) (xy 67.454006 -297.466894) (xy 67.434715 -297.421618)
			(xy 67.422938 -297.373834) (xy 67.418978 -297.32478) (xy 67.08013 -297.32478) (xy 67.079635 -297.349387)
			(xy 67.07174 -297.397964) (xy 67.056156 -297.444645) (xy 67.033285 -297.488222) (xy 67.00372 -297.527566)
			(xy 66.968227 -297.561658) (xy 66.927724 -297.589614) (xy 66.883262 -297.610712) (xy 66.835991 -297.624404)
			(xy 66.787136 -297.630336) (xy 66.737961 -297.628355) (xy 66.689742 -297.618511) (xy 66.643726 -297.601059)
			(xy 66.601105 -297.576452) (xy 66.562984 -297.545327) (xy 66.530349 -297.50849) (xy 66.504046 -297.466894)
			(xy 66.484755 -297.421618) (xy 66.472978 -297.373834) (xy 66.469018 -297.32478) (xy 66.13017 -297.32478)
			(xy 66.129675 -297.349387) (xy 66.12178 -297.397964) (xy 66.106196 -297.444645) (xy 66.083325 -297.488222)
			(xy 66.05376 -297.527566) (xy 66.018267 -297.561658) (xy 65.977764 -297.589614) (xy 65.933302 -297.610712)
			(xy 65.886031 -297.624404) (xy 65.837176 -297.630336) (xy 65.788001 -297.628355) (xy 65.739782 -297.618511)
			(xy 65.693766 -297.601059) (xy 65.651145 -297.576452) (xy 65.613024 -297.545327) (xy 65.580389 -297.50849)
			(xy 65.554086 -297.466894) (xy 65.534795 -297.421618) (xy 65.523018 -297.373834) (xy 65.519058 -297.32478)
			(xy 65.18021 -297.32478) (xy 65.179715 -297.349387) (xy 65.17182 -297.397964) (xy 65.156236 -297.444645)
			(xy 65.133365 -297.488222) (xy 65.1038 -297.527566) (xy 65.068307 -297.561658) (xy 65.027804 -297.589614)
			(xy 64.983342 -297.610712) (xy 64.936071 -297.624404) (xy 64.887216 -297.630336) (xy 64.838041 -297.628355)
			(xy 64.789822 -297.618511) (xy 64.743806 -297.601059) (xy 64.701185 -297.576452) (xy 64.663064 -297.545327)
			(xy 64.630429 -297.50849) (xy 64.604126 -297.466894) (xy 64.584835 -297.421618) (xy 64.573058 -297.373834)
			(xy 64.569098 -297.32478) (xy 64.23025 -297.32478) (xy 64.229755 -297.349387) (xy 64.22186 -297.397964)
			(xy 64.206276 -297.444645) (xy 64.183405 -297.488222) (xy 64.15384 -297.527566) (xy 64.118347 -297.561658)
			(xy 64.077844 -297.589614) (xy 64.033382 -297.610712) (xy 63.986111 -297.624404) (xy 63.937256 -297.630336)
			(xy 63.888081 -297.628355) (xy 63.839862 -297.618511) (xy 63.793846 -297.601059) (xy 63.751225 -297.576452)
			(xy 63.713104 -297.545327) (xy 63.680469 -297.50849) (xy 63.654166 -297.466894) (xy 63.634875 -297.421618)
			(xy 63.623098 -297.373834) (xy 63.619138 -297.32478) (xy 63.28029 -297.32478) (xy 63.279795 -297.349387)
			(xy 63.2719 -297.397964) (xy 63.256316 -297.444645) (xy 63.233445 -297.488222) (xy 63.20388 -297.527566)
			(xy 63.168387 -297.561658) (xy 63.127884 -297.589614) (xy 63.083422 -297.610712) (xy 63.036151 -297.624404)
			(xy 62.987296 -297.630336) (xy 62.938121 -297.628355) (xy 62.889902 -297.618511) (xy 62.843886 -297.601059)
			(xy 62.801265 -297.576452) (xy 62.763144 -297.545327) (xy 62.730509 -297.50849) (xy 62.704206 -297.466894)
			(xy 62.684915 -297.421618) (xy 62.673138 -297.373834) (xy 62.669178 -297.32478) (xy 62.330076 -297.32478)
			(xy 62.329581 -297.349387) (xy 62.321686 -297.397964) (xy 62.306102 -297.444645) (xy 62.283231 -297.488222)
			(xy 62.253666 -297.527566) (xy 62.218173 -297.561658) (xy 62.17767 -297.589614) (xy 62.133208 -297.610712)
			(xy 62.085937 -297.624404) (xy 62.037082 -297.630336) (xy 61.987907 -297.628355) (xy 61.939688 -297.618511)
			(xy 61.893672 -297.601059) (xy 61.851051 -297.576452) (xy 61.81293 -297.545327) (xy 61.780295 -297.50849)
			(xy 61.753992 -297.466894) (xy 61.734701 -297.421618) (xy 61.722924 -297.373834) (xy 61.718964 -297.32478)
			(xy 61.380116 -297.32478) (xy 61.379621 -297.349387) (xy 61.371726 -297.397964) (xy 61.356142 -297.444645)
			(xy 61.333271 -297.488222) (xy 61.303706 -297.527566) (xy 61.268213 -297.561658) (xy 61.22771 -297.589614)
			(xy 61.183248 -297.610712) (xy 61.135977 -297.624404) (xy 61.087122 -297.630336) (xy 61.037947 -297.628355)
			(xy 60.989728 -297.618511) (xy 60.943712 -297.601059) (xy 60.901091 -297.576452) (xy 60.86297 -297.545327)
			(xy 60.830335 -297.50849) (xy 60.804032 -297.466894) (xy 60.784741 -297.421618) (xy 60.772964 -297.373834)
			(xy 60.769004 -297.32478) (xy 60.430156 -297.32478) (xy 60.429661 -297.349387) (xy 60.421766 -297.397964)
			(xy 60.406182 -297.444645) (xy 60.383311 -297.488222) (xy 60.353746 -297.527566) (xy 60.318253 -297.561658)
			(xy 60.27775 -297.589614) (xy 60.233288 -297.610712) (xy 60.186017 -297.624404) (xy 60.137162 -297.630336)
			(xy 60.087987 -297.628355) (xy 60.039768 -297.618511) (xy 59.993752 -297.601059) (xy 59.951131 -297.576452)
			(xy 59.91301 -297.545327) (xy 59.880375 -297.50849) (xy 59.854072 -297.466894) (xy 59.834781 -297.421618)
			(xy 59.823004 -297.373834) (xy 59.819044 -297.32478) (xy 58.530236 -297.32478) (xy 58.529741 -297.349387)
			(xy 58.521846 -297.397964) (xy 58.506262 -297.444645) (xy 58.483391 -297.488222) (xy 58.453826 -297.527566)
			(xy 58.418333 -297.561658) (xy 58.37783 -297.589614) (xy 58.333368 -297.610712) (xy 58.286097 -297.624404)
			(xy 58.237242 -297.630336) (xy 58.188067 -297.628355) (xy 58.139848 -297.618511) (xy 58.093832 -297.601059)
			(xy 58.051211 -297.576452) (xy 58.01309 -297.545327) (xy 57.980455 -297.50849) (xy 57.954152 -297.466894)
			(xy 57.934861 -297.421618) (xy 57.923084 -297.373834) (xy 57.919124 -297.32478) (xy 57.580276 -297.32478)
			(xy 57.579781 -297.349387) (xy 57.571886 -297.397964) (xy 57.556302 -297.444645) (xy 57.533431 -297.488222)
			(xy 57.503866 -297.527566) (xy 57.468373 -297.561658) (xy 57.42787 -297.589614) (xy 57.383408 -297.610712)
			(xy 57.336137 -297.624404) (xy 57.287282 -297.630336) (xy 57.238107 -297.628355) (xy 57.189888 -297.618511)
			(xy 57.143872 -297.601059) (xy 57.101251 -297.576452) (xy 57.06313 -297.545327) (xy 57.030495 -297.50849)
			(xy 57.004192 -297.466894) (xy 56.984901 -297.421618) (xy 56.973124 -297.373834) (xy 56.969164 -297.32478)
			(xy 56.630062 -297.32478) (xy 56.629567 -297.349387) (xy 56.621672 -297.397964) (xy 56.606088 -297.444645)
			(xy 56.583217 -297.488222) (xy 56.553652 -297.527566) (xy 56.518159 -297.561658) (xy 56.477656 -297.589614)
			(xy 56.433194 -297.610712) (xy 56.385923 -297.624404) (xy 56.337068 -297.630336) (xy 56.287893 -297.628355)
			(xy 56.239674 -297.618511) (xy 56.193658 -297.601059) (xy 56.151037 -297.576452) (xy 56.112916 -297.545327)
			(xy 56.080281 -297.50849) (xy 56.053978 -297.466894) (xy 56.034687 -297.421618) (xy 56.02291 -297.373834)
			(xy 56.01895 -297.32478) (xy 55.680102 -297.32478) (xy 55.679607 -297.349387) (xy 55.671712 -297.397964)
			(xy 55.656128 -297.444645) (xy 55.633257 -297.488222) (xy 55.603692 -297.527566) (xy 55.568199 -297.561658)
			(xy 55.527696 -297.589614) (xy 55.483234 -297.610712) (xy 55.435963 -297.624404) (xy 55.387108 -297.630336)
			(xy 55.337933 -297.628355) (xy 55.289714 -297.618511) (xy 55.243698 -297.601059) (xy 55.201077 -297.576452)
			(xy 55.162956 -297.545327) (xy 55.130321 -297.50849) (xy 55.104018 -297.466894) (xy 55.084727 -297.421618)
			(xy 55.07295 -297.373834) (xy 55.06899 -297.32478) (xy 54.730142 -297.32478) (xy 54.729647 -297.349387)
			(xy 54.721752 -297.397964) (xy 54.706168 -297.444645) (xy 54.683297 -297.488222) (xy 54.653732 -297.527566)
			(xy 54.618239 -297.561658) (xy 54.577736 -297.589614) (xy 54.533274 -297.610712) (xy 54.486003 -297.624404)
			(xy 54.437148 -297.630336) (xy 54.387973 -297.628355) (xy 54.339754 -297.618511) (xy 54.293738 -297.601059)
			(xy 54.251117 -297.576452) (xy 54.212996 -297.545327) (xy 54.180361 -297.50849) (xy 54.154058 -297.466894)
			(xy 54.134767 -297.421618) (xy 54.12299 -297.373834) (xy 54.11903 -297.32478) (xy 53.780182 -297.32478)
			(xy 53.779687 -297.349387) (xy 53.771792 -297.397964) (xy 53.756208 -297.444645) (xy 53.733337 -297.488222)
			(xy 53.703772 -297.527566) (xy 53.668279 -297.561658) (xy 53.627776 -297.589614) (xy 53.583314 -297.610712)
			(xy 53.536043 -297.624404) (xy 53.487188 -297.630336) (xy 53.438013 -297.628355) (xy 53.389794 -297.618511)
			(xy 53.343778 -297.601059) (xy 53.301157 -297.576452) (xy 53.263036 -297.545327) (xy 53.230401 -297.50849)
			(xy 53.204098 -297.466894) (xy 53.184807 -297.421618) (xy 53.17303 -297.373834) (xy 53.16907 -297.32478)
			(xy 52.830222 -297.32478) (xy 52.829727 -297.349387) (xy 52.821832 -297.397964) (xy 52.806248 -297.444645)
			(xy 52.783377 -297.488222) (xy 52.753812 -297.527566) (xy 52.718319 -297.561658) (xy 52.677816 -297.589614)
			(xy 52.633354 -297.610712) (xy 52.586083 -297.624404) (xy 52.537228 -297.630336) (xy 52.488053 -297.628355)
			(xy 52.439834 -297.618511) (xy 52.393818 -297.601059) (xy 52.351197 -297.576452) (xy 52.313076 -297.545327)
			(xy 52.280441 -297.50849) (xy 52.254138 -297.466894) (xy 52.234847 -297.421618) (xy 52.22307 -297.373834)
			(xy 52.21911 -297.32478) (xy 51.880262 -297.32478) (xy 51.879767 -297.349387) (xy 51.871872 -297.397964)
			(xy 51.856288 -297.444645) (xy 51.833417 -297.488222) (xy 51.803852 -297.527566) (xy 51.768359 -297.561658)
			(xy 51.727856 -297.589614) (xy 51.683394 -297.610712) (xy 51.636123 -297.624404) (xy 51.587268 -297.630336)
			(xy 51.538093 -297.628355) (xy 51.489874 -297.618511) (xy 51.443858 -297.601059) (xy 51.401237 -297.576452)
			(xy 51.363116 -297.545327) (xy 51.330481 -297.50849) (xy 51.304178 -297.466894) (xy 51.284887 -297.421618)
			(xy 51.27311 -297.373834) (xy 51.26915 -297.32478) (xy 50.930302 -297.32478) (xy 50.929807 -297.349387)
			(xy 50.921912 -297.397964) (xy 50.906328 -297.444645) (xy 50.883457 -297.488222) (xy 50.853892 -297.527566)
			(xy 50.818399 -297.561658) (xy 50.777896 -297.589614) (xy 50.733434 -297.610712) (xy 50.686163 -297.624404)
			(xy 50.637308 -297.630336) (xy 50.588133 -297.628355) (xy 50.539914 -297.618511) (xy 50.493898 -297.601059)
			(xy 50.451277 -297.576452) (xy 50.413156 -297.545327) (xy 50.380521 -297.50849) (xy 50.354218 -297.466894)
			(xy 50.334927 -297.421618) (xy 50.32315 -297.373834) (xy 50.31919 -297.32478) (xy 49.980088 -297.32478)
			(xy 49.979593 -297.349387) (xy 49.971698 -297.397964) (xy 49.956114 -297.444645) (xy 49.933243 -297.488222)
			(xy 49.903678 -297.527566) (xy 49.868185 -297.561658) (xy 49.827682 -297.589614) (xy 49.78322 -297.610712)
			(xy 49.735949 -297.624404) (xy 49.687094 -297.630336) (xy 49.637919 -297.628355) (xy 49.5897 -297.618511)
			(xy 49.543684 -297.601059) (xy 49.501063 -297.576452) (xy 49.462942 -297.545327) (xy 49.430307 -297.50849)
			(xy 49.404004 -297.466894) (xy 49.384713 -297.421618) (xy 49.372936 -297.373834) (xy 49.368976 -297.32478)
			(xy 49.030128 -297.32478) (xy 49.029633 -297.349387) (xy 49.021738 -297.397964) (xy 49.006154 -297.444645)
			(xy 48.983283 -297.488222) (xy 48.953718 -297.527566) (xy 48.918225 -297.561658) (xy 48.877722 -297.589614)
			(xy 48.83326 -297.610712) (xy 48.785989 -297.624404) (xy 48.737134 -297.630336) (xy 48.687959 -297.628355)
			(xy 48.63974 -297.618511) (xy 48.593724 -297.601059) (xy 48.551103 -297.576452) (xy 48.512982 -297.545327)
			(xy 48.480347 -297.50849) (xy 48.454044 -297.466894) (xy 48.434753 -297.421618) (xy 48.422976 -297.373834)
			(xy 48.419016 -297.32478) (xy 48.080168 -297.32478) (xy 48.079673 -297.349387) (xy 48.071778 -297.397964)
			(xy 48.056194 -297.444645) (xy 48.033323 -297.488222) (xy 48.003758 -297.527566) (xy 47.968265 -297.561658)
			(xy 47.927762 -297.589614) (xy 47.8833 -297.610712) (xy 47.836029 -297.624404) (xy 47.787174 -297.630336)
			(xy 47.737999 -297.628355) (xy 47.68978 -297.618511) (xy 47.643764 -297.601059) (xy 47.601143 -297.576452)
			(xy 47.563022 -297.545327) (xy 47.530387 -297.50849) (xy 47.504084 -297.466894) (xy 47.484793 -297.421618)
			(xy 47.473016 -297.373834) (xy 47.469056 -297.32478) (xy 47.130208 -297.32478) (xy 47.129713 -297.349387)
			(xy 47.121818 -297.397964) (xy 47.106234 -297.444645) (xy 47.083363 -297.488222) (xy 47.053798 -297.527566)
			(xy 47.018305 -297.561658) (xy 46.977802 -297.589614) (xy 46.93334 -297.610712) (xy 46.886069 -297.624404)
			(xy 46.837214 -297.630336) (xy 46.788039 -297.628355) (xy 46.73982 -297.618511) (xy 46.693804 -297.601059)
			(xy 46.651183 -297.576452) (xy 46.613062 -297.545327) (xy 46.580427 -297.50849) (xy 46.554124 -297.466894)
			(xy 46.534833 -297.421618) (xy 46.523056 -297.373834) (xy 46.519096 -297.32478) (xy 46.205648 -297.32478)
			(xy 46.205201 -297.349641) (xy 46.197759 -297.398803) (xy 46.18304 -297.446297) (xy 46.161375 -297.491051)
			(xy 46.133253 -297.532056) (xy 46.099309 -297.568389) (xy 46.060307 -297.599229) (xy 46.017127 -297.623882)
			(xy 45.970742 -297.641791) (xy 45.946568 -297.647614) (xy 45.929042 -297.651424) (xy 45.90669 -297.679364)
			(xy 45.90669 -297.920156) (xy 45.929042 -297.948096) (xy 45.946568 -297.951906) (xy 45.97215 -297.958108)
			(xy 46.021079 -297.977513) (xy 46.066316 -298.004426) (xy 46.106718 -298.038165) (xy 46.141264 -298.077879)
			(xy 46.169082 -298.122565) (xy 46.189469 -298.171093) (xy 46.201911 -298.222238) (xy 46.206092 -298.274709)
			(xy 46.20609 -298.27474) (xy 47.469056 -298.27474) (xy 47.473016 -298.225686) (xy 47.484793 -298.177902)
			(xy 47.504084 -298.132626) (xy 47.530387 -298.09103) (xy 47.563022 -298.054193) (xy 47.601143 -298.023068)
			(xy 47.643764 -297.998461) (xy 47.68978 -297.981009) (xy 47.737999 -297.971165) (xy 47.787174 -297.969184)
			(xy 47.836029 -297.975116) (xy 47.8833 -297.988808) (xy 47.927762 -298.009906) (xy 47.968265 -298.037862)
			(xy 48.003758 -298.071954) (xy 48.033323 -298.111298) (xy 48.056194 -298.154875) (xy 48.071778 -298.201556)
			(xy 48.079673 -298.250133) (xy 48.080168 -298.27474) (xy 48.419016 -298.27474) (xy 48.422976 -298.225686)
			(xy 48.434753 -298.177902) (xy 48.454044 -298.132626) (xy 48.480347 -298.09103) (xy 48.512982 -298.054193)
			(xy 48.551103 -298.023068) (xy 48.593724 -297.998461) (xy 48.63974 -297.981009) (xy 48.687959 -297.971165)
			(xy 48.737134 -297.969184) (xy 48.785989 -297.975116) (xy 48.83326 -297.988808) (xy 48.877722 -298.009906)
			(xy 48.918225 -298.037862) (xy 48.953718 -298.071954) (xy 48.983283 -298.111298) (xy 49.006154 -298.154875)
			(xy 49.021738 -298.201556) (xy 49.029633 -298.250133) (xy 49.030128 -298.27474) (xy 49.368976 -298.27474)
			(xy 49.372936 -298.225686) (xy 49.384713 -298.177902) (xy 49.404004 -298.132626) (xy 49.430307 -298.09103)
			(xy 49.462942 -298.054193) (xy 49.501063 -298.023068) (xy 49.543684 -297.998461) (xy 49.5897 -297.981009)
			(xy 49.637919 -297.971165) (xy 49.687094 -297.969184) (xy 49.735949 -297.975116) (xy 49.78322 -297.988808)
			(xy 49.827682 -298.009906) (xy 49.868185 -298.037862) (xy 49.903678 -298.071954) (xy 49.933243 -298.111298)
			(xy 49.956114 -298.154875) (xy 49.971698 -298.201556) (xy 49.979593 -298.250133) (xy 49.980088 -298.27474)
			(xy 50.31919 -298.27474) (xy 50.32315 -298.225686) (xy 50.334927 -298.177902) (xy 50.354218 -298.132626)
			(xy 50.380521 -298.09103) (xy 50.413156 -298.054193) (xy 50.451277 -298.023068) (xy 50.493898 -297.998461)
			(xy 50.539914 -297.981009) (xy 50.588133 -297.971165) (xy 50.637308 -297.969184) (xy 50.686163 -297.975116)
			(xy 50.733434 -297.988808) (xy 50.777896 -298.009906) (xy 50.818399 -298.037862) (xy 50.853892 -298.071954)
			(xy 50.883457 -298.111298) (xy 50.906328 -298.154875) (xy 50.921912 -298.201556) (xy 50.929807 -298.250133)
			(xy 50.930302 -298.27474) (xy 51.26915 -298.27474) (xy 51.27311 -298.225686) (xy 51.284887 -298.177902)
			(xy 51.304178 -298.132626) (xy 51.330481 -298.09103) (xy 51.363116 -298.054193) (xy 51.401237 -298.023068)
			(xy 51.443858 -297.998461) (xy 51.489874 -297.981009) (xy 51.538093 -297.971165) (xy 51.587268 -297.969184)
			(xy 51.636123 -297.975116) (xy 51.683394 -297.988808) (xy 51.727856 -298.009906) (xy 51.768359 -298.037862)
			(xy 51.803852 -298.071954) (xy 51.833417 -298.111298) (xy 51.856288 -298.154875) (xy 51.871872 -298.201556)
			(xy 51.879767 -298.250133) (xy 51.880262 -298.27474) (xy 52.21911 -298.27474) (xy 52.22307 -298.225686)
			(xy 52.234847 -298.177902) (xy 52.254138 -298.132626) (xy 52.280441 -298.09103) (xy 52.313076 -298.054193)
			(xy 52.351197 -298.023068) (xy 52.393818 -297.998461) (xy 52.439834 -297.981009) (xy 52.488053 -297.971165)
			(xy 52.537228 -297.969184) (xy 52.586083 -297.975116) (xy 52.633354 -297.988808) (xy 52.677816 -298.009906)
			(xy 52.718319 -298.037862) (xy 52.753812 -298.071954) (xy 52.783377 -298.111298) (xy 52.806248 -298.154875)
			(xy 52.821832 -298.201556) (xy 52.829727 -298.250133) (xy 52.830222 -298.27474) (xy 53.16907 -298.27474)
			(xy 53.17303 -298.225686) (xy 53.184807 -298.177902) (xy 53.204098 -298.132626) (xy 53.230401 -298.09103)
			(xy 53.263036 -298.054193) (xy 53.301157 -298.023068) (xy 53.343778 -297.998461) (xy 53.389794 -297.981009)
			(xy 53.438013 -297.971165) (xy 53.487188 -297.969184) (xy 53.536043 -297.975116) (xy 53.583314 -297.988808)
			(xy 53.627776 -298.009906) (xy 53.668279 -298.037862) (xy 53.703772 -298.071954) (xy 53.733337 -298.111298)
			(xy 53.756208 -298.154875) (xy 53.771792 -298.201556) (xy 53.779687 -298.250133) (xy 53.780182 -298.27474)
			(xy 54.11903 -298.27474) (xy 54.12299 -298.225686) (xy 54.134767 -298.177902) (xy 54.154058 -298.132626)
			(xy 54.180361 -298.09103) (xy 54.212996 -298.054193) (xy 54.251117 -298.023068) (xy 54.293738 -297.998461)
			(xy 54.339754 -297.981009) (xy 54.387973 -297.971165) (xy 54.437148 -297.969184) (xy 54.486003 -297.975116)
			(xy 54.533274 -297.988808) (xy 54.577736 -298.009906) (xy 54.618239 -298.037862) (xy 54.653732 -298.071954)
			(xy 54.683297 -298.111298) (xy 54.706168 -298.154875) (xy 54.721752 -298.201556) (xy 54.729647 -298.250133)
			(xy 54.730142 -298.27474) (xy 55.06899 -298.27474) (xy 55.07295 -298.225686) (xy 55.084727 -298.177902)
			(xy 55.104018 -298.132626) (xy 55.130321 -298.09103) (xy 55.162956 -298.054193) (xy 55.201077 -298.023068)
			(xy 55.243698 -297.998461) (xy 55.289714 -297.981009) (xy 55.337933 -297.971165) (xy 55.387108 -297.969184)
			(xy 55.435963 -297.975116) (xy 55.483234 -297.988808) (xy 55.527696 -298.009906) (xy 55.568199 -298.037862)
			(xy 55.603692 -298.071954) (xy 55.633257 -298.111298) (xy 55.656128 -298.154875) (xy 55.671712 -298.201556)
			(xy 55.679607 -298.250133) (xy 55.680102 -298.27474) (xy 56.01895 -298.27474) (xy 56.02291 -298.225686)
			(xy 56.034687 -298.177902) (xy 56.053978 -298.132626) (xy 56.080281 -298.09103) (xy 56.112916 -298.054193)
			(xy 56.151037 -298.023068) (xy 56.193658 -297.998461) (xy 56.239674 -297.981009) (xy 56.287893 -297.971165)
			(xy 56.337068 -297.969184) (xy 56.385923 -297.975116) (xy 56.433194 -297.988808) (xy 56.477656 -298.009906)
			(xy 56.518159 -298.037862) (xy 56.553652 -298.071954) (xy 56.583217 -298.111298) (xy 56.606088 -298.154875)
			(xy 56.621672 -298.201556) (xy 56.629567 -298.250133) (xy 56.630062 -298.27474) (xy 56.969164 -298.27474)
			(xy 56.973124 -298.225686) (xy 56.984901 -298.177902) (xy 57.004192 -298.132626) (xy 57.030495 -298.09103)
			(xy 57.06313 -298.054193) (xy 57.101251 -298.023068) (xy 57.143872 -297.998461) (xy 57.189888 -297.981009)
			(xy 57.238107 -297.971165) (xy 57.287282 -297.969184) (xy 57.336137 -297.975116) (xy 57.383408 -297.988808)
			(xy 57.42787 -298.009906) (xy 57.468373 -298.037862) (xy 57.503866 -298.071954) (xy 57.533431 -298.111298)
			(xy 57.556302 -298.154875) (xy 57.571886 -298.201556) (xy 57.579781 -298.250133) (xy 57.580276 -298.27474)
			(xy 57.919124 -298.27474) (xy 57.923084 -298.225686) (xy 57.934861 -298.177902) (xy 57.954152 -298.132626)
			(xy 57.980455 -298.09103) (xy 58.01309 -298.054193) (xy 58.051211 -298.023068) (xy 58.093832 -297.998461)
			(xy 58.139848 -297.981009) (xy 58.188067 -297.971165) (xy 58.237242 -297.969184) (xy 58.286097 -297.975116)
			(xy 58.333368 -297.988808) (xy 58.37783 -298.009906) (xy 58.418333 -298.037862) (xy 58.453826 -298.071954)
			(xy 58.483391 -298.111298) (xy 58.506262 -298.154875) (xy 58.521846 -298.201556) (xy 58.529741 -298.250133)
			(xy 58.530236 -298.27474) (xy 59.819044 -298.27474) (xy 59.823004 -298.225686) (xy 59.834781 -298.177902)
			(xy 59.854072 -298.132626) (xy 59.880375 -298.09103) (xy 59.91301 -298.054193) (xy 59.951131 -298.023068)
			(xy 59.993752 -297.998461) (xy 60.039768 -297.981009) (xy 60.087987 -297.971165) (xy 60.137162 -297.969184)
			(xy 60.186017 -297.975116) (xy 60.233288 -297.988808) (xy 60.27775 -298.009906) (xy 60.318253 -298.037862)
			(xy 60.353746 -298.071954) (xy 60.383311 -298.111298) (xy 60.406182 -298.154875) (xy 60.421766 -298.201556)
			(xy 60.429661 -298.250133) (xy 60.430156 -298.27474) (xy 60.769004 -298.27474) (xy 60.772964 -298.225686)
			(xy 60.784741 -298.177902) (xy 60.804032 -298.132626) (xy 60.830335 -298.09103) (xy 60.86297 -298.054193)
			(xy 60.901091 -298.023068) (xy 60.943712 -297.998461) (xy 60.989728 -297.981009) (xy 61.037947 -297.971165)
			(xy 61.087122 -297.969184) (xy 61.135977 -297.975116) (xy 61.183248 -297.988808) (xy 61.22771 -298.009906)
			(xy 61.268213 -298.037862) (xy 61.303706 -298.071954) (xy 61.333271 -298.111298) (xy 61.356142 -298.154875)
			(xy 61.371726 -298.201556) (xy 61.379621 -298.250133) (xy 61.380116 -298.27474) (xy 61.718964 -298.27474)
			(xy 61.722924 -298.225686) (xy 61.734701 -298.177902) (xy 61.753992 -298.132626) (xy 61.780295 -298.09103)
			(xy 61.81293 -298.054193) (xy 61.851051 -298.023068) (xy 61.893672 -297.998461) (xy 61.939688 -297.981009)
			(xy 61.987907 -297.971165) (xy 62.037082 -297.969184) (xy 62.085937 -297.975116) (xy 62.133208 -297.988808)
			(xy 62.17767 -298.009906) (xy 62.218173 -298.037862) (xy 62.253666 -298.071954) (xy 62.283231 -298.111298)
			(xy 62.306102 -298.154875) (xy 62.321686 -298.201556) (xy 62.329581 -298.250133) (xy 62.330076 -298.27474)
			(xy 62.669178 -298.27474) (xy 62.673138 -298.225686) (xy 62.684915 -298.177902) (xy 62.704206 -298.132626)
			(xy 62.730509 -298.09103) (xy 62.763144 -298.054193) (xy 62.801265 -298.023068) (xy 62.843886 -297.998461)
			(xy 62.889902 -297.981009) (xy 62.938121 -297.971165) (xy 62.987296 -297.969184) (xy 63.036151 -297.975116)
			(xy 63.083422 -297.988808) (xy 63.127884 -298.009906) (xy 63.168387 -298.037862) (xy 63.20388 -298.071954)
			(xy 63.233445 -298.111298) (xy 63.256316 -298.154875) (xy 63.2719 -298.201556) (xy 63.279795 -298.250133)
			(xy 63.28029 -298.27474) (xy 63.619138 -298.27474) (xy 63.623098 -298.225686) (xy 63.634875 -298.177902)
			(xy 63.654166 -298.132626) (xy 63.680469 -298.09103) (xy 63.713104 -298.054193) (xy 63.751225 -298.023068)
			(xy 63.793846 -297.998461) (xy 63.839862 -297.981009) (xy 63.888081 -297.971165) (xy 63.937256 -297.969184)
			(xy 63.986111 -297.975116) (xy 64.033382 -297.988808) (xy 64.077844 -298.009906) (xy 64.118347 -298.037862)
			(xy 64.15384 -298.071954) (xy 64.183405 -298.111298) (xy 64.206276 -298.154875) (xy 64.22186 -298.201556)
			(xy 64.229755 -298.250133) (xy 64.23025 -298.27474) (xy 64.569098 -298.27474) (xy 64.573058 -298.225686)
			(xy 64.584835 -298.177902) (xy 64.604126 -298.132626) (xy 64.630429 -298.09103) (xy 64.663064 -298.054193)
			(xy 64.701185 -298.023068) (xy 64.743806 -297.998461) (xy 64.789822 -297.981009) (xy 64.838041 -297.971165)
			(xy 64.887216 -297.969184) (xy 64.936071 -297.975116) (xy 64.983342 -297.988808) (xy 65.027804 -298.009906)
			(xy 65.068307 -298.037862) (xy 65.1038 -298.071954) (xy 65.133365 -298.111298) (xy 65.156236 -298.154875)
			(xy 65.17182 -298.201556) (xy 65.179715 -298.250133) (xy 65.18021 -298.27474) (xy 65.519058 -298.27474)
			(xy 65.523018 -298.225686) (xy 65.534795 -298.177902) (xy 65.554086 -298.132626) (xy 65.580389 -298.09103)
			(xy 65.613024 -298.054193) (xy 65.651145 -298.023068) (xy 65.693766 -297.998461) (xy 65.739782 -297.981009)
			(xy 65.788001 -297.971165) (xy 65.837176 -297.969184) (xy 65.886031 -297.975116) (xy 65.933302 -297.988808)
			(xy 65.977764 -298.009906) (xy 66.018267 -298.037862) (xy 66.05376 -298.071954) (xy 66.083325 -298.111298)
			(xy 66.106196 -298.154875) (xy 66.12178 -298.201556) (xy 66.129675 -298.250133) (xy 66.13017 -298.27474)
			(xy 66.469018 -298.27474) (xy 66.472978 -298.225686) (xy 66.484755 -298.177902) (xy 66.504046 -298.132626)
			(xy 66.530349 -298.09103) (xy 66.562984 -298.054193) (xy 66.601105 -298.023068) (xy 66.643726 -297.998461)
			(xy 66.689742 -297.981009) (xy 66.737961 -297.971165) (xy 66.787136 -297.969184) (xy 66.835991 -297.975116)
			(xy 66.883262 -297.988808) (xy 66.927724 -298.009906) (xy 66.968227 -298.037862) (xy 67.00372 -298.071954)
			(xy 67.033285 -298.111298) (xy 67.056156 -298.154875) (xy 67.07174 -298.201556) (xy 67.079635 -298.250133)
			(xy 67.08013 -298.27474) (xy 67.418978 -298.27474) (xy 67.422938 -298.225686) (xy 67.434715 -298.177902)
			(xy 67.454006 -298.132626) (xy 67.480309 -298.09103) (xy 67.512944 -298.054193) (xy 67.551065 -298.023068)
			(xy 67.593686 -297.998461) (xy 67.639702 -297.981009) (xy 67.687921 -297.971165) (xy 67.737096 -297.969184)
			(xy 67.785951 -297.975116) (xy 67.833222 -297.988808) (xy 67.877684 -298.009906) (xy 67.918187 -298.037862)
			(xy 67.95368 -298.071954) (xy 67.983245 -298.111298) (xy 68.006116 -298.154875) (xy 68.0217 -298.201556)
			(xy 68.029595 -298.250133) (xy 68.03009 -298.27474) (xy 68.029595 -298.299347) (xy 68.0217 -298.347924)
			(xy 68.006116 -298.394605) (xy 67.983245 -298.438182) (xy 67.95368 -298.477526) (xy 67.918187 -298.511618)
			(xy 67.877684 -298.539574) (xy 67.833222 -298.560672) (xy 67.785951 -298.574364) (xy 67.737096 -298.580296)
			(xy 67.687921 -298.578315) (xy 67.639702 -298.568471) (xy 67.593686 -298.551019) (xy 67.551065 -298.526412)
			(xy 67.512944 -298.495287) (xy 67.480309 -298.45845) (xy 67.454006 -298.416854) (xy 67.434715 -298.371578)
			(xy 67.422938 -298.323794) (xy 67.418978 -298.27474) (xy 67.08013 -298.27474) (xy 67.079635 -298.299347)
			(xy 67.07174 -298.347924) (xy 67.056156 -298.394605) (xy 67.033285 -298.438182) (xy 67.00372 -298.477526)
			(xy 66.968227 -298.511618) (xy 66.927724 -298.539574) (xy 66.883262 -298.560672) (xy 66.835991 -298.574364)
			(xy 66.787136 -298.580296) (xy 66.737961 -298.578315) (xy 66.689742 -298.568471) (xy 66.643726 -298.551019)
			(xy 66.601105 -298.526412) (xy 66.562984 -298.495287) (xy 66.530349 -298.45845) (xy 66.504046 -298.416854)
			(xy 66.484755 -298.371578) (xy 66.472978 -298.323794) (xy 66.469018 -298.27474) (xy 66.13017 -298.27474)
			(xy 66.129675 -298.299347) (xy 66.12178 -298.347924) (xy 66.106196 -298.394605) (xy 66.083325 -298.438182)
			(xy 66.05376 -298.477526) (xy 66.018267 -298.511618) (xy 65.977764 -298.539574) (xy 65.933302 -298.560672)
			(xy 65.886031 -298.574364) (xy 65.837176 -298.580296) (xy 65.788001 -298.578315) (xy 65.739782 -298.568471)
			(xy 65.693766 -298.551019) (xy 65.651145 -298.526412) (xy 65.613024 -298.495287) (xy 65.580389 -298.45845)
			(xy 65.554086 -298.416854) (xy 65.534795 -298.371578) (xy 65.523018 -298.323794) (xy 65.519058 -298.27474)
			(xy 65.18021 -298.27474) (xy 65.179715 -298.299347) (xy 65.17182 -298.347924) (xy 65.156236 -298.394605)
			(xy 65.133365 -298.438182) (xy 65.1038 -298.477526) (xy 65.068307 -298.511618) (xy 65.027804 -298.539574)
			(xy 64.983342 -298.560672) (xy 64.936071 -298.574364) (xy 64.887216 -298.580296) (xy 64.838041 -298.578315)
			(xy 64.789822 -298.568471) (xy 64.743806 -298.551019) (xy 64.701185 -298.526412) (xy 64.663064 -298.495287)
			(xy 64.630429 -298.45845) (xy 64.604126 -298.416854) (xy 64.584835 -298.371578) (xy 64.573058 -298.323794)
			(xy 64.569098 -298.27474) (xy 64.23025 -298.27474) (xy 64.229755 -298.299347) (xy 64.22186 -298.347924)
			(xy 64.206276 -298.394605) (xy 64.183405 -298.438182) (xy 64.15384 -298.477526) (xy 64.118347 -298.511618)
			(xy 64.077844 -298.539574) (xy 64.033382 -298.560672) (xy 63.986111 -298.574364) (xy 63.937256 -298.580296)
			(xy 63.888081 -298.578315) (xy 63.839862 -298.568471) (xy 63.793846 -298.551019) (xy 63.751225 -298.526412)
			(xy 63.713104 -298.495287) (xy 63.680469 -298.45845) (xy 63.654166 -298.416854) (xy 63.634875 -298.371578)
			(xy 63.623098 -298.323794) (xy 63.619138 -298.27474) (xy 63.28029 -298.27474) (xy 63.279795 -298.299347)
			(xy 63.2719 -298.347924) (xy 63.256316 -298.394605) (xy 63.233445 -298.438182) (xy 63.20388 -298.477526)
			(xy 63.168387 -298.511618) (xy 63.127884 -298.539574) (xy 63.083422 -298.560672) (xy 63.036151 -298.574364)
			(xy 62.987296 -298.580296) (xy 62.938121 -298.578315) (xy 62.889902 -298.568471) (xy 62.843886 -298.551019)
			(xy 62.801265 -298.526412) (xy 62.763144 -298.495287) (xy 62.730509 -298.45845) (xy 62.704206 -298.416854)
			(xy 62.684915 -298.371578) (xy 62.673138 -298.323794) (xy 62.669178 -298.27474) (xy 62.330076 -298.27474)
			(xy 62.329581 -298.299347) (xy 62.321686 -298.347924) (xy 62.306102 -298.394605) (xy 62.283231 -298.438182)
			(xy 62.253666 -298.477526) (xy 62.218173 -298.511618) (xy 62.17767 -298.539574) (xy 62.133208 -298.560672)
			(xy 62.085937 -298.574364) (xy 62.037082 -298.580296) (xy 61.987907 -298.578315) (xy 61.939688 -298.568471)
			(xy 61.893672 -298.551019) (xy 61.851051 -298.526412) (xy 61.81293 -298.495287) (xy 61.780295 -298.45845)
			(xy 61.753992 -298.416854) (xy 61.734701 -298.371578) (xy 61.722924 -298.323794) (xy 61.718964 -298.27474)
			(xy 61.380116 -298.27474) (xy 61.379621 -298.299347) (xy 61.371726 -298.347924) (xy 61.356142 -298.394605)
			(xy 61.333271 -298.438182) (xy 61.303706 -298.477526) (xy 61.268213 -298.511618) (xy 61.22771 -298.539574)
			(xy 61.183248 -298.560672) (xy 61.135977 -298.574364) (xy 61.087122 -298.580296) (xy 61.037947 -298.578315)
			(xy 60.989728 -298.568471) (xy 60.943712 -298.551019) (xy 60.901091 -298.526412) (xy 60.86297 -298.495287)
			(xy 60.830335 -298.45845) (xy 60.804032 -298.416854) (xy 60.784741 -298.371578) (xy 60.772964 -298.323794)
			(xy 60.769004 -298.27474) (xy 60.430156 -298.27474) (xy 60.429661 -298.299347) (xy 60.421766 -298.347924)
			(xy 60.406182 -298.394605) (xy 60.383311 -298.438182) (xy 60.353746 -298.477526) (xy 60.318253 -298.511618)
			(xy 60.27775 -298.539574) (xy 60.233288 -298.560672) (xy 60.186017 -298.574364) (xy 60.137162 -298.580296)
			(xy 60.087987 -298.578315) (xy 60.039768 -298.568471) (xy 59.993752 -298.551019) (xy 59.951131 -298.526412)
			(xy 59.91301 -298.495287) (xy 59.880375 -298.45845) (xy 59.854072 -298.416854) (xy 59.834781 -298.371578)
			(xy 59.823004 -298.323794) (xy 59.819044 -298.27474) (xy 58.530236 -298.27474) (xy 58.529741 -298.299347)
			(xy 58.521846 -298.347924) (xy 58.506262 -298.394605) (xy 58.483391 -298.438182) (xy 58.453826 -298.477526)
			(xy 58.418333 -298.511618) (xy 58.37783 -298.539574) (xy 58.333368 -298.560672) (xy 58.286097 -298.574364)
			(xy 58.237242 -298.580296) (xy 58.188067 -298.578315) (xy 58.139848 -298.568471) (xy 58.093832 -298.551019)
			(xy 58.051211 -298.526412) (xy 58.01309 -298.495287) (xy 57.980455 -298.45845) (xy 57.954152 -298.416854)
			(xy 57.934861 -298.371578) (xy 57.923084 -298.323794) (xy 57.919124 -298.27474) (xy 57.580276 -298.27474)
			(xy 57.579781 -298.299347) (xy 57.571886 -298.347924) (xy 57.556302 -298.394605) (xy 57.533431 -298.438182)
			(xy 57.503866 -298.477526) (xy 57.468373 -298.511618) (xy 57.42787 -298.539574) (xy 57.383408 -298.560672)
			(xy 57.336137 -298.574364) (xy 57.287282 -298.580296) (xy 57.238107 -298.578315) (xy 57.189888 -298.568471)
			(xy 57.143872 -298.551019) (xy 57.101251 -298.526412) (xy 57.06313 -298.495287) (xy 57.030495 -298.45845)
			(xy 57.004192 -298.416854) (xy 56.984901 -298.371578) (xy 56.973124 -298.323794) (xy 56.969164 -298.27474)
			(xy 56.630062 -298.27474) (xy 56.629567 -298.299347) (xy 56.621672 -298.347924) (xy 56.606088 -298.394605)
			(xy 56.583217 -298.438182) (xy 56.553652 -298.477526) (xy 56.518159 -298.511618) (xy 56.477656 -298.539574)
			(xy 56.433194 -298.560672) (xy 56.385923 -298.574364) (xy 56.337068 -298.580296) (xy 56.287893 -298.578315)
			(xy 56.239674 -298.568471) (xy 56.193658 -298.551019) (xy 56.151037 -298.526412) (xy 56.112916 -298.495287)
			(xy 56.080281 -298.45845) (xy 56.053978 -298.416854) (xy 56.034687 -298.371578) (xy 56.02291 -298.323794)
			(xy 56.01895 -298.27474) (xy 55.680102 -298.27474) (xy 55.679607 -298.299347) (xy 55.671712 -298.347924)
			(xy 55.656128 -298.394605) (xy 55.633257 -298.438182) (xy 55.603692 -298.477526) (xy 55.568199 -298.511618)
			(xy 55.527696 -298.539574) (xy 55.483234 -298.560672) (xy 55.435963 -298.574364) (xy 55.387108 -298.580296)
			(xy 55.337933 -298.578315) (xy 55.289714 -298.568471) (xy 55.243698 -298.551019) (xy 55.201077 -298.526412)
			(xy 55.162956 -298.495287) (xy 55.130321 -298.45845) (xy 55.104018 -298.416854) (xy 55.084727 -298.371578)
			(xy 55.07295 -298.323794) (xy 55.06899 -298.27474) (xy 54.730142 -298.27474) (xy 54.729647 -298.299347)
			(xy 54.721752 -298.347924) (xy 54.706168 -298.394605) (xy 54.683297 -298.438182) (xy 54.653732 -298.477526)
			(xy 54.618239 -298.511618) (xy 54.577736 -298.539574) (xy 54.533274 -298.560672) (xy 54.486003 -298.574364)
			(xy 54.437148 -298.580296) (xy 54.387973 -298.578315) (xy 54.339754 -298.568471) (xy 54.293738 -298.551019)
			(xy 54.251117 -298.526412) (xy 54.212996 -298.495287) (xy 54.180361 -298.45845) (xy 54.154058 -298.416854)
			(xy 54.134767 -298.371578) (xy 54.12299 -298.323794) (xy 54.11903 -298.27474) (xy 53.780182 -298.27474)
			(xy 53.779687 -298.299347) (xy 53.771792 -298.347924) (xy 53.756208 -298.394605) (xy 53.733337 -298.438182)
			(xy 53.703772 -298.477526) (xy 53.668279 -298.511618) (xy 53.627776 -298.539574) (xy 53.583314 -298.560672)
			(xy 53.536043 -298.574364) (xy 53.487188 -298.580296) (xy 53.438013 -298.578315) (xy 53.389794 -298.568471)
			(xy 53.343778 -298.551019) (xy 53.301157 -298.526412) (xy 53.263036 -298.495287) (xy 53.230401 -298.45845)
			(xy 53.204098 -298.416854) (xy 53.184807 -298.371578) (xy 53.17303 -298.323794) (xy 53.16907 -298.27474)
			(xy 52.830222 -298.27474) (xy 52.829727 -298.299347) (xy 52.821832 -298.347924) (xy 52.806248 -298.394605)
			(xy 52.783377 -298.438182) (xy 52.753812 -298.477526) (xy 52.718319 -298.511618) (xy 52.677816 -298.539574)
			(xy 52.633354 -298.560672) (xy 52.586083 -298.574364) (xy 52.537228 -298.580296) (xy 52.488053 -298.578315)
			(xy 52.439834 -298.568471) (xy 52.393818 -298.551019) (xy 52.351197 -298.526412) (xy 52.313076 -298.495287)
			(xy 52.280441 -298.45845) (xy 52.254138 -298.416854) (xy 52.234847 -298.371578) (xy 52.22307 -298.323794)
			(xy 52.21911 -298.27474) (xy 51.880262 -298.27474) (xy 51.879767 -298.299347) (xy 51.871872 -298.347924)
			(xy 51.856288 -298.394605) (xy 51.833417 -298.438182) (xy 51.803852 -298.477526) (xy 51.768359 -298.511618)
			(xy 51.727856 -298.539574) (xy 51.683394 -298.560672) (xy 51.636123 -298.574364) (xy 51.587268 -298.580296)
			(xy 51.538093 -298.578315) (xy 51.489874 -298.568471) (xy 51.443858 -298.551019) (xy 51.401237 -298.526412)
			(xy 51.363116 -298.495287) (xy 51.330481 -298.45845) (xy 51.304178 -298.416854) (xy 51.284887 -298.371578)
			(xy 51.27311 -298.323794) (xy 51.26915 -298.27474) (xy 50.930302 -298.27474) (xy 50.929807 -298.299347)
			(xy 50.921912 -298.347924) (xy 50.906328 -298.394605) (xy 50.883457 -298.438182) (xy 50.853892 -298.477526)
			(xy 50.818399 -298.511618) (xy 50.777896 -298.539574) (xy 50.733434 -298.560672) (xy 50.686163 -298.574364)
			(xy 50.637308 -298.580296) (xy 50.588133 -298.578315) (xy 50.539914 -298.568471) (xy 50.493898 -298.551019)
			(xy 50.451277 -298.526412) (xy 50.413156 -298.495287) (xy 50.380521 -298.45845) (xy 50.354218 -298.416854)
			(xy 50.334927 -298.371578) (xy 50.32315 -298.323794) (xy 50.31919 -298.27474) (xy 49.980088 -298.27474)
			(xy 49.979593 -298.299347) (xy 49.971698 -298.347924) (xy 49.956114 -298.394605) (xy 49.933243 -298.438182)
			(xy 49.903678 -298.477526) (xy 49.868185 -298.511618) (xy 49.827682 -298.539574) (xy 49.78322 -298.560672)
			(xy 49.735949 -298.574364) (xy 49.687094 -298.580296) (xy 49.637919 -298.578315) (xy 49.5897 -298.568471)
			(xy 49.543684 -298.551019) (xy 49.501063 -298.526412) (xy 49.462942 -298.495287) (xy 49.430307 -298.45845)
			(xy 49.404004 -298.416854) (xy 49.384713 -298.371578) (xy 49.372936 -298.323794) (xy 49.368976 -298.27474)
			(xy 49.030128 -298.27474) (xy 49.029633 -298.299347) (xy 49.021738 -298.347924) (xy 49.006154 -298.394605)
			(xy 48.983283 -298.438182) (xy 48.953718 -298.477526) (xy 48.918225 -298.511618) (xy 48.877722 -298.539574)
			(xy 48.83326 -298.560672) (xy 48.785989 -298.574364) (xy 48.737134 -298.580296) (xy 48.687959 -298.578315)
			(xy 48.63974 -298.568471) (xy 48.593724 -298.551019) (xy 48.551103 -298.526412) (xy 48.512982 -298.495287)
			(xy 48.480347 -298.45845) (xy 48.454044 -298.416854) (xy 48.434753 -298.371578) (xy 48.422976 -298.323794)
			(xy 48.419016 -298.27474) (xy 48.080168 -298.27474) (xy 48.079673 -298.299347) (xy 48.071778 -298.347924)
			(xy 48.056194 -298.394605) (xy 48.033323 -298.438182) (xy 48.003758 -298.477526) (xy 47.968265 -298.511618)
			(xy 47.927762 -298.539574) (xy 47.8833 -298.560672) (xy 47.836029 -298.574364) (xy 47.787174 -298.580296)
			(xy 47.737999 -298.578315) (xy 47.68978 -298.568471) (xy 47.643764 -298.551019) (xy 47.601143 -298.526412)
			(xy 47.563022 -298.495287) (xy 47.530387 -298.45845) (xy 47.504084 -298.416854) (xy 47.484793 -298.371578)
			(xy 47.473016 -298.323794) (xy 47.469056 -298.27474) (xy 46.20609 -298.27474) (xy 46.201908 -298.327179)
			(xy 46.189464 -298.378324) (xy 46.169074 -298.426851) (xy 46.141254 -298.471535) (xy 46.106706 -298.511247)
			(xy 46.066302 -298.544984) (xy 46.021064 -298.571894) (xy 45.972134 -298.591297) (xy 45.946568 -298.597574)
			(xy 45.929042 -298.601384) (xy 45.90669 -298.629324) (xy 45.90669 -298.87037) (xy 45.929042 -298.89831)
			(xy 45.946568 -298.90212) (xy 45.972157 -298.908322) (xy 46.0211 -298.92773) (xy 46.066349 -298.954646)
			(xy 46.106763 -298.988392) (xy 46.141321 -299.028114) (xy 46.169148 -299.072809) (xy 46.189543 -299.121349)
			(xy 46.201991 -299.172506) (xy 46.206173 -299.224954) (xy 46.519096 -299.224954) (xy 46.523056 -299.1759)
			(xy 46.534833 -299.128116) (xy 46.554124 -299.08284) (xy 46.580427 -299.041244) (xy 46.613062 -299.004407)
			(xy 46.651183 -298.973282) (xy 46.693804 -298.948675) (xy 46.73982 -298.931223) (xy 46.788039 -298.921379)
			(xy 46.837214 -298.919398) (xy 46.886069 -298.92533) (xy 46.93334 -298.939022) (xy 46.977802 -298.96012)
			(xy 47.018305 -298.988076) (xy 47.053798 -299.022168) (xy 47.083363 -299.061512) (xy 47.106234 -299.105089)
			(xy 47.121818 -299.15177) (xy 47.129713 -299.200347) (xy 47.130208 -299.224954) (xy 47.469056 -299.224954)
			(xy 47.473016 -299.1759) (xy 47.484793 -299.128116) (xy 47.504084 -299.08284) (xy 47.530387 -299.041244)
			(xy 47.563022 -299.004407) (xy 47.601143 -298.973282) (xy 47.643764 -298.948675) (xy 47.68978 -298.931223)
			(xy 47.737999 -298.921379) (xy 47.787174 -298.919398) (xy 47.836029 -298.92533) (xy 47.8833 -298.939022)
			(xy 47.927762 -298.96012) (xy 47.968265 -298.988076) (xy 48.003758 -299.022168) (xy 48.033323 -299.061512)
			(xy 48.056194 -299.105089) (xy 48.071778 -299.15177) (xy 48.079673 -299.200347) (xy 48.080168 -299.224954)
			(xy 48.419016 -299.224954) (xy 48.422976 -299.1759) (xy 48.434753 -299.128116) (xy 48.454044 -299.08284)
			(xy 48.480347 -299.041244) (xy 48.512982 -299.004407) (xy 48.551103 -298.973282) (xy 48.593724 -298.948675)
			(xy 48.63974 -298.931223) (xy 48.687959 -298.921379) (xy 48.737134 -298.919398) (xy 48.785989 -298.92533)
			(xy 48.83326 -298.939022) (xy 48.877722 -298.96012) (xy 48.918225 -298.988076) (xy 48.953718 -299.022168)
			(xy 48.983283 -299.061512) (xy 49.006154 -299.105089) (xy 49.021738 -299.15177) (xy 49.029633 -299.200347)
			(xy 49.030128 -299.224954) (xy 49.368976 -299.224954) (xy 49.372936 -299.1759) (xy 49.384713 -299.128116)
			(xy 49.404004 -299.08284) (xy 49.430307 -299.041244) (xy 49.462942 -299.004407) (xy 49.501063 -298.973282)
			(xy 49.543684 -298.948675) (xy 49.5897 -298.931223) (xy 49.637919 -298.921379) (xy 49.687094 -298.919398)
			(xy 49.735949 -298.92533) (xy 49.78322 -298.939022) (xy 49.827682 -298.96012) (xy 49.868185 -298.988076)
			(xy 49.903678 -299.022168) (xy 49.933243 -299.061512) (xy 49.956114 -299.105089) (xy 49.971698 -299.15177)
			(xy 49.979593 -299.200347) (xy 49.980088 -299.224954) (xy 50.31919 -299.224954) (xy 50.32315 -299.1759)
			(xy 50.334927 -299.128116) (xy 50.354218 -299.08284) (xy 50.380521 -299.041244) (xy 50.413156 -299.004407)
			(xy 50.451277 -298.973282) (xy 50.493898 -298.948675) (xy 50.539914 -298.931223) (xy 50.588133 -298.921379)
			(xy 50.637308 -298.919398) (xy 50.686163 -298.92533) (xy 50.733434 -298.939022) (xy 50.777896 -298.96012)
			(xy 50.818399 -298.988076) (xy 50.853892 -299.022168) (xy 50.883457 -299.061512) (xy 50.906328 -299.105089)
			(xy 50.921912 -299.15177) (xy 50.929807 -299.200347) (xy 50.930302 -299.224954) (xy 51.26915 -299.224954)
			(xy 51.27311 -299.1759) (xy 51.284887 -299.128116) (xy 51.304178 -299.08284) (xy 51.330481 -299.041244)
			(xy 51.363116 -299.004407) (xy 51.401237 -298.973282) (xy 51.443858 -298.948675) (xy 51.489874 -298.931223)
			(xy 51.538093 -298.921379) (xy 51.587268 -298.919398) (xy 51.636123 -298.92533) (xy 51.683394 -298.939022)
			(xy 51.727856 -298.96012) (xy 51.768359 -298.988076) (xy 51.803852 -299.022168) (xy 51.833417 -299.061512)
			(xy 51.856288 -299.105089) (xy 51.871872 -299.15177) (xy 51.879767 -299.200347) (xy 51.880262 -299.224954)
			(xy 52.21911 -299.224954) (xy 52.22307 -299.1759) (xy 52.234847 -299.128116) (xy 52.254138 -299.08284)
			(xy 52.280441 -299.041244) (xy 52.313076 -299.004407) (xy 52.351197 -298.973282) (xy 52.393818 -298.948675)
			(xy 52.439834 -298.931223) (xy 52.488053 -298.921379) (xy 52.537228 -298.919398) (xy 52.586083 -298.92533)
			(xy 52.633354 -298.939022) (xy 52.677816 -298.96012) (xy 52.718319 -298.988076) (xy 52.753812 -299.022168)
			(xy 52.783377 -299.061512) (xy 52.806248 -299.105089) (xy 52.821832 -299.15177) (xy 52.829727 -299.200347)
			(xy 52.830222 -299.224954) (xy 53.16907 -299.224954) (xy 53.17303 -299.1759) (xy 53.184807 -299.128116)
			(xy 53.204098 -299.08284) (xy 53.230401 -299.041244) (xy 53.263036 -299.004407) (xy 53.301157 -298.973282)
			(xy 53.343778 -298.948675) (xy 53.389794 -298.931223) (xy 53.438013 -298.921379) (xy 53.487188 -298.919398)
			(xy 53.536043 -298.92533) (xy 53.583314 -298.939022) (xy 53.627776 -298.96012) (xy 53.668279 -298.988076)
			(xy 53.703772 -299.022168) (xy 53.733337 -299.061512) (xy 53.756208 -299.105089) (xy 53.771792 -299.15177)
			(xy 53.779687 -299.200347) (xy 53.780182 -299.224954) (xy 54.11903 -299.224954) (xy 54.12299 -299.1759)
			(xy 54.134767 -299.128116) (xy 54.154058 -299.08284) (xy 54.180361 -299.041244) (xy 54.212996 -299.004407)
			(xy 54.251117 -298.973282) (xy 54.293738 -298.948675) (xy 54.339754 -298.931223) (xy 54.387973 -298.921379)
			(xy 54.437148 -298.919398) (xy 54.486003 -298.92533) (xy 54.533274 -298.939022) (xy 54.577736 -298.96012)
			(xy 54.618239 -298.988076) (xy 54.653732 -299.022168) (xy 54.683297 -299.061512) (xy 54.706168 -299.105089)
			(xy 54.721752 -299.15177) (xy 54.729647 -299.200347) (xy 54.730142 -299.224954) (xy 55.06899 -299.224954)
			(xy 55.07295 -299.1759) (xy 55.084727 -299.128116) (xy 55.104018 -299.08284) (xy 55.130321 -299.041244)
			(xy 55.162956 -299.004407) (xy 55.201077 -298.973282) (xy 55.243698 -298.948675) (xy 55.289714 -298.931223)
			(xy 55.337933 -298.921379) (xy 55.387108 -298.919398) (xy 55.435963 -298.92533) (xy 55.483234 -298.939022)
			(xy 55.527696 -298.96012) (xy 55.568199 -298.988076) (xy 55.603692 -299.022168) (xy 55.633257 -299.061512)
			(xy 55.656128 -299.105089) (xy 55.671712 -299.15177) (xy 55.679607 -299.200347) (xy 55.680102 -299.224954)
			(xy 56.01895 -299.224954) (xy 56.02291 -299.1759) (xy 56.034687 -299.128116) (xy 56.053978 -299.08284)
			(xy 56.080281 -299.041244) (xy 56.112916 -299.004407) (xy 56.151037 -298.973282) (xy 56.193658 -298.948675)
			(xy 56.239674 -298.931223) (xy 56.287893 -298.921379) (xy 56.337068 -298.919398) (xy 56.385923 -298.92533)
			(xy 56.433194 -298.939022) (xy 56.477656 -298.96012) (xy 56.518159 -298.988076) (xy 56.553652 -299.022168)
			(xy 56.583217 -299.061512) (xy 56.606088 -299.105089) (xy 56.621672 -299.15177) (xy 56.629567 -299.200347)
			(xy 56.630062 -299.224954) (xy 56.969164 -299.224954) (xy 56.973124 -299.1759) (xy 56.984901 -299.128116)
			(xy 57.004192 -299.08284) (xy 57.030495 -299.041244) (xy 57.06313 -299.004407) (xy 57.101251 -298.973282)
			(xy 57.143872 -298.948675) (xy 57.189888 -298.931223) (xy 57.238107 -298.921379) (xy 57.287282 -298.919398)
			(xy 57.336137 -298.92533) (xy 57.383408 -298.939022) (xy 57.42787 -298.96012) (xy 57.468373 -298.988076)
			(xy 57.503866 -299.022168) (xy 57.533431 -299.061512) (xy 57.556302 -299.105089) (xy 57.571886 -299.15177)
			(xy 57.579781 -299.200347) (xy 57.580276 -299.224954) (xy 57.919124 -299.224954) (xy 57.923084 -299.1759)
			(xy 57.934861 -299.128116) (xy 57.954152 -299.08284) (xy 57.980455 -299.041244) (xy 58.01309 -299.004407)
			(xy 58.051211 -298.973282) (xy 58.093832 -298.948675) (xy 58.139848 -298.931223) (xy 58.188067 -298.921379)
			(xy 58.237242 -298.919398) (xy 58.286097 -298.92533) (xy 58.333368 -298.939022) (xy 58.37783 -298.96012)
			(xy 58.418333 -298.988076) (xy 58.453826 -299.022168) (xy 58.483391 -299.061512) (xy 58.506262 -299.105089)
			(xy 58.521846 -299.15177) (xy 58.529741 -299.200347) (xy 58.530236 -299.224954) (xy 59.819044 -299.224954)
			(xy 59.823004 -299.1759) (xy 59.834781 -299.128116) (xy 59.854072 -299.08284) (xy 59.880375 -299.041244)
			(xy 59.91301 -299.004407) (xy 59.951131 -298.973282) (xy 59.993752 -298.948675) (xy 60.039768 -298.931223)
			(xy 60.087987 -298.921379) (xy 60.137162 -298.919398) (xy 60.186017 -298.92533) (xy 60.233288 -298.939022)
			(xy 60.27775 -298.96012) (xy 60.318253 -298.988076) (xy 60.353746 -299.022168) (xy 60.383311 -299.061512)
			(xy 60.406182 -299.105089) (xy 60.421766 -299.15177) (xy 60.429661 -299.200347) (xy 60.430156 -299.224954)
			(xy 60.769004 -299.224954) (xy 60.772964 -299.1759) (xy 60.784741 -299.128116) (xy 60.804032 -299.08284)
			(xy 60.830335 -299.041244) (xy 60.86297 -299.004407) (xy 60.901091 -298.973282) (xy 60.943712 -298.948675)
			(xy 60.989728 -298.931223) (xy 61.037947 -298.921379) (xy 61.087122 -298.919398) (xy 61.135977 -298.92533)
			(xy 61.183248 -298.939022) (xy 61.22771 -298.96012) (xy 61.268213 -298.988076) (xy 61.303706 -299.022168)
			(xy 61.333271 -299.061512) (xy 61.356142 -299.105089) (xy 61.371726 -299.15177) (xy 61.379621 -299.200347)
			(xy 61.380116 -299.224954) (xy 61.718964 -299.224954) (xy 61.722924 -299.1759) (xy 61.734701 -299.128116)
			(xy 61.753992 -299.08284) (xy 61.780295 -299.041244) (xy 61.81293 -299.004407) (xy 61.851051 -298.973282)
			(xy 61.893672 -298.948675) (xy 61.939688 -298.931223) (xy 61.987907 -298.921379) (xy 62.037082 -298.919398)
			(xy 62.085937 -298.92533) (xy 62.133208 -298.939022) (xy 62.17767 -298.96012) (xy 62.218173 -298.988076)
			(xy 62.253666 -299.022168) (xy 62.283231 -299.061512) (xy 62.306102 -299.105089) (xy 62.321686 -299.15177)
			(xy 62.329581 -299.200347) (xy 62.330076 -299.224954) (xy 62.669178 -299.224954) (xy 62.673138 -299.1759)
			(xy 62.684915 -299.128116) (xy 62.704206 -299.08284) (xy 62.730509 -299.041244) (xy 62.763144 -299.004407)
			(xy 62.801265 -298.973282) (xy 62.843886 -298.948675) (xy 62.889902 -298.931223) (xy 62.938121 -298.921379)
			(xy 62.987296 -298.919398) (xy 63.036151 -298.92533) (xy 63.083422 -298.939022) (xy 63.127884 -298.96012)
			(xy 63.168387 -298.988076) (xy 63.20388 -299.022168) (xy 63.233445 -299.061512) (xy 63.256316 -299.105089)
			(xy 63.2719 -299.15177) (xy 63.279795 -299.200347) (xy 63.28029 -299.224954) (xy 63.619138 -299.224954)
			(xy 63.623098 -299.1759) (xy 63.634875 -299.128116) (xy 63.654166 -299.08284) (xy 63.680469 -299.041244)
			(xy 63.713104 -299.004407) (xy 63.751225 -298.973282) (xy 63.793846 -298.948675) (xy 63.839862 -298.931223)
			(xy 63.888081 -298.921379) (xy 63.937256 -298.919398) (xy 63.986111 -298.92533) (xy 64.033382 -298.939022)
			(xy 64.077844 -298.96012) (xy 64.118347 -298.988076) (xy 64.15384 -299.022168) (xy 64.183405 -299.061512)
			(xy 64.206276 -299.105089) (xy 64.22186 -299.15177) (xy 64.229755 -299.200347) (xy 64.23025 -299.224954)
			(xy 64.569098 -299.224954) (xy 64.573058 -299.1759) (xy 64.584835 -299.128116) (xy 64.604126 -299.08284)
			(xy 64.630429 -299.041244) (xy 64.663064 -299.004407) (xy 64.701185 -298.973282) (xy 64.743806 -298.948675)
			(xy 64.789822 -298.931223) (xy 64.838041 -298.921379) (xy 64.887216 -298.919398) (xy 64.936071 -298.92533)
			(xy 64.983342 -298.939022) (xy 65.027804 -298.96012) (xy 65.068307 -298.988076) (xy 65.1038 -299.022168)
			(xy 65.133365 -299.061512) (xy 65.156236 -299.105089) (xy 65.17182 -299.15177) (xy 65.179715 -299.200347)
			(xy 65.18021 -299.224954) (xy 65.519058 -299.224954) (xy 65.523018 -299.1759) (xy 65.534795 -299.128116)
			(xy 65.554086 -299.08284) (xy 65.580389 -299.041244) (xy 65.613024 -299.004407) (xy 65.651145 -298.973282)
			(xy 65.693766 -298.948675) (xy 65.739782 -298.931223) (xy 65.788001 -298.921379) (xy 65.837176 -298.919398)
			(xy 65.886031 -298.92533) (xy 65.933302 -298.939022) (xy 65.977764 -298.96012) (xy 66.018267 -298.988076)
			(xy 66.05376 -299.022168) (xy 66.083325 -299.061512) (xy 66.106196 -299.105089) (xy 66.12178 -299.15177)
			(xy 66.129675 -299.200347) (xy 66.13017 -299.224954) (xy 66.469018 -299.224954) (xy 66.472978 -299.1759)
			(xy 66.484755 -299.128116) (xy 66.504046 -299.08284) (xy 66.530349 -299.041244) (xy 66.562984 -299.004407)
			(xy 66.601105 -298.973282) (xy 66.643726 -298.948675) (xy 66.689742 -298.931223) (xy 66.737961 -298.921379)
			(xy 66.787136 -298.919398) (xy 66.835991 -298.92533) (xy 66.883262 -298.939022) (xy 66.927724 -298.96012)
			(xy 66.968227 -298.988076) (xy 67.00372 -299.022168) (xy 67.033285 -299.061512) (xy 67.056156 -299.105089)
			(xy 67.07174 -299.15177) (xy 67.079635 -299.200347) (xy 67.08013 -299.224954) (xy 67.418978 -299.224954)
			(xy 67.422938 -299.1759) (xy 67.434715 -299.128116) (xy 67.454006 -299.08284) (xy 67.480309 -299.041244)
			(xy 67.512944 -299.004407) (xy 67.551065 -298.973282) (xy 67.593686 -298.948675) (xy 67.639702 -298.931223)
			(xy 67.687921 -298.921379) (xy 67.737096 -298.919398) (xy 67.785951 -298.92533) (xy 67.833222 -298.939022)
			(xy 67.877684 -298.96012) (xy 67.918187 -298.988076) (xy 67.95368 -299.022168) (xy 67.983245 -299.061512)
			(xy 68.006116 -299.105089) (xy 68.0217 -299.15177) (xy 68.029595 -299.200347) (xy 68.03009 -299.224954)
			(xy 68.029595 -299.249561) (xy 68.0217 -299.298138) (xy 68.006116 -299.344819) (xy 67.983245 -299.388396)
			(xy 67.95368 -299.42774) (xy 67.918187 -299.461832) (xy 67.877684 -299.489788) (xy 67.833222 -299.510886)
			(xy 67.785951 -299.524578) (xy 67.737096 -299.53051) (xy 67.687921 -299.528529) (xy 67.639702 -299.518685)
			(xy 67.593686 -299.501233) (xy 67.551065 -299.476626) (xy 67.512944 -299.445501) (xy 67.480309 -299.408664)
			(xy 67.454006 -299.367068) (xy 67.434715 -299.321792) (xy 67.422938 -299.274008) (xy 67.418978 -299.224954)
			(xy 67.08013 -299.224954) (xy 67.079635 -299.249561) (xy 67.07174 -299.298138) (xy 67.056156 -299.344819)
			(xy 67.033285 -299.388396) (xy 67.00372 -299.42774) (xy 66.968227 -299.461832) (xy 66.927724 -299.489788)
			(xy 66.883262 -299.510886) (xy 66.835991 -299.524578) (xy 66.787136 -299.53051) (xy 66.737961 -299.528529)
			(xy 66.689742 -299.518685) (xy 66.643726 -299.501233) (xy 66.601105 -299.476626) (xy 66.562984 -299.445501)
			(xy 66.530349 -299.408664) (xy 66.504046 -299.367068) (xy 66.484755 -299.321792) (xy 66.472978 -299.274008)
			(xy 66.469018 -299.224954) (xy 66.13017 -299.224954) (xy 66.129675 -299.249561) (xy 66.12178 -299.298138)
			(xy 66.106196 -299.344819) (xy 66.083325 -299.388396) (xy 66.05376 -299.42774) (xy 66.018267 -299.461832)
			(xy 65.977764 -299.489788) (xy 65.933302 -299.510886) (xy 65.886031 -299.524578) (xy 65.837176 -299.53051)
			(xy 65.788001 -299.528529) (xy 65.739782 -299.518685) (xy 65.693766 -299.501233) (xy 65.651145 -299.476626)
			(xy 65.613024 -299.445501) (xy 65.580389 -299.408664) (xy 65.554086 -299.367068) (xy 65.534795 -299.321792)
			(xy 65.523018 -299.274008) (xy 65.519058 -299.224954) (xy 65.18021 -299.224954) (xy 65.179715 -299.249561)
			(xy 65.17182 -299.298138) (xy 65.156236 -299.344819) (xy 65.133365 -299.388396) (xy 65.1038 -299.42774)
			(xy 65.068307 -299.461832) (xy 65.027804 -299.489788) (xy 64.983342 -299.510886) (xy 64.936071 -299.524578)
			(xy 64.887216 -299.53051) (xy 64.838041 -299.528529) (xy 64.789822 -299.518685) (xy 64.743806 -299.501233)
			(xy 64.701185 -299.476626) (xy 64.663064 -299.445501) (xy 64.630429 -299.408664) (xy 64.604126 -299.367068)
			(xy 64.584835 -299.321792) (xy 64.573058 -299.274008) (xy 64.569098 -299.224954) (xy 64.23025 -299.224954)
			(xy 64.229755 -299.249561) (xy 64.22186 -299.298138) (xy 64.206276 -299.344819) (xy 64.183405 -299.388396)
			(xy 64.15384 -299.42774) (xy 64.118347 -299.461832) (xy 64.077844 -299.489788) (xy 64.033382 -299.510886)
			(xy 63.986111 -299.524578) (xy 63.937256 -299.53051) (xy 63.888081 -299.528529) (xy 63.839862 -299.518685)
			(xy 63.793846 -299.501233) (xy 63.751225 -299.476626) (xy 63.713104 -299.445501) (xy 63.680469 -299.408664)
			(xy 63.654166 -299.367068) (xy 63.634875 -299.321792) (xy 63.623098 -299.274008) (xy 63.619138 -299.224954)
			(xy 63.28029 -299.224954) (xy 63.279795 -299.249561) (xy 63.2719 -299.298138) (xy 63.256316 -299.344819)
			(xy 63.233445 -299.388396) (xy 63.20388 -299.42774) (xy 63.168387 -299.461832) (xy 63.127884 -299.489788)
			(xy 63.083422 -299.510886) (xy 63.036151 -299.524578) (xy 62.987296 -299.53051) (xy 62.938121 -299.528529)
			(xy 62.889902 -299.518685) (xy 62.843886 -299.501233) (xy 62.801265 -299.476626) (xy 62.763144 -299.445501)
			(xy 62.730509 -299.408664) (xy 62.704206 -299.367068) (xy 62.684915 -299.321792) (xy 62.673138 -299.274008)
			(xy 62.669178 -299.224954) (xy 62.330076 -299.224954) (xy 62.329581 -299.249561) (xy 62.321686 -299.298138)
			(xy 62.306102 -299.344819) (xy 62.283231 -299.388396) (xy 62.253666 -299.42774) (xy 62.218173 -299.461832)
			(xy 62.17767 -299.489788) (xy 62.133208 -299.510886) (xy 62.085937 -299.524578) (xy 62.037082 -299.53051)
			(xy 61.987907 -299.528529) (xy 61.939688 -299.518685) (xy 61.893672 -299.501233) (xy 61.851051 -299.476626)
			(xy 61.81293 -299.445501) (xy 61.780295 -299.408664) (xy 61.753992 -299.367068) (xy 61.734701 -299.321792)
			(xy 61.722924 -299.274008) (xy 61.718964 -299.224954) (xy 61.380116 -299.224954) (xy 61.379621 -299.249561)
			(xy 61.371726 -299.298138) (xy 61.356142 -299.344819) (xy 61.333271 -299.388396) (xy 61.303706 -299.42774)
			(xy 61.268213 -299.461832) (xy 61.22771 -299.489788) (xy 61.183248 -299.510886) (xy 61.135977 -299.524578)
			(xy 61.087122 -299.53051) (xy 61.037947 -299.528529) (xy 60.989728 -299.518685) (xy 60.943712 -299.501233)
			(xy 60.901091 -299.476626) (xy 60.86297 -299.445501) (xy 60.830335 -299.408664) (xy 60.804032 -299.367068)
			(xy 60.784741 -299.321792) (xy 60.772964 -299.274008) (xy 60.769004 -299.224954) (xy 60.430156 -299.224954)
			(xy 60.429661 -299.249561) (xy 60.421766 -299.298138) (xy 60.406182 -299.344819) (xy 60.383311 -299.388396)
			(xy 60.353746 -299.42774) (xy 60.318253 -299.461832) (xy 60.27775 -299.489788) (xy 60.233288 -299.510886)
			(xy 60.186017 -299.524578) (xy 60.137162 -299.53051) (xy 60.087987 -299.528529) (xy 60.039768 -299.518685)
			(xy 59.993752 -299.501233) (xy 59.951131 -299.476626) (xy 59.91301 -299.445501) (xy 59.880375 -299.408664)
			(xy 59.854072 -299.367068) (xy 59.834781 -299.321792) (xy 59.823004 -299.274008) (xy 59.819044 -299.224954)
			(xy 58.530236 -299.224954) (xy 58.529741 -299.249561) (xy 58.521846 -299.298138) (xy 58.506262 -299.344819)
			(xy 58.483391 -299.388396) (xy 58.453826 -299.42774) (xy 58.418333 -299.461832) (xy 58.37783 -299.489788)
			(xy 58.333368 -299.510886) (xy 58.286097 -299.524578) (xy 58.237242 -299.53051) (xy 58.188067 -299.528529)
			(xy 58.139848 -299.518685) (xy 58.093832 -299.501233) (xy 58.051211 -299.476626) (xy 58.01309 -299.445501)
			(xy 57.980455 -299.408664) (xy 57.954152 -299.367068) (xy 57.934861 -299.321792) (xy 57.923084 -299.274008)
			(xy 57.919124 -299.224954) (xy 57.580276 -299.224954) (xy 57.579781 -299.249561) (xy 57.571886 -299.298138)
			(xy 57.556302 -299.344819) (xy 57.533431 -299.388396) (xy 57.503866 -299.42774) (xy 57.468373 -299.461832)
			(xy 57.42787 -299.489788) (xy 57.383408 -299.510886) (xy 57.336137 -299.524578) (xy 57.287282 -299.53051)
			(xy 57.238107 -299.528529) (xy 57.189888 -299.518685) (xy 57.143872 -299.501233) (xy 57.101251 -299.476626)
			(xy 57.06313 -299.445501) (xy 57.030495 -299.408664) (xy 57.004192 -299.367068) (xy 56.984901 -299.321792)
			(xy 56.973124 -299.274008) (xy 56.969164 -299.224954) (xy 56.630062 -299.224954) (xy 56.629567 -299.249561)
			(xy 56.621672 -299.298138) (xy 56.606088 -299.344819) (xy 56.583217 -299.388396) (xy 56.553652 -299.42774)
			(xy 56.518159 -299.461832) (xy 56.477656 -299.489788) (xy 56.433194 -299.510886) (xy 56.385923 -299.524578)
			(xy 56.337068 -299.53051) (xy 56.287893 -299.528529) (xy 56.239674 -299.518685) (xy 56.193658 -299.501233)
			(xy 56.151037 -299.476626) (xy 56.112916 -299.445501) (xy 56.080281 -299.408664) (xy 56.053978 -299.367068)
			(xy 56.034687 -299.321792) (xy 56.02291 -299.274008) (xy 56.01895 -299.224954) (xy 55.680102 -299.224954)
			(xy 55.679607 -299.249561) (xy 55.671712 -299.298138) (xy 55.656128 -299.344819) (xy 55.633257 -299.388396)
			(xy 55.603692 -299.42774) (xy 55.568199 -299.461832) (xy 55.527696 -299.489788) (xy 55.483234 -299.510886)
			(xy 55.435963 -299.524578) (xy 55.387108 -299.53051) (xy 55.337933 -299.528529) (xy 55.289714 -299.518685)
			(xy 55.243698 -299.501233) (xy 55.201077 -299.476626) (xy 55.162956 -299.445501) (xy 55.130321 -299.408664)
			(xy 55.104018 -299.367068) (xy 55.084727 -299.321792) (xy 55.07295 -299.274008) (xy 55.06899 -299.224954)
			(xy 54.730142 -299.224954) (xy 54.729647 -299.249561) (xy 54.721752 -299.298138) (xy 54.706168 -299.344819)
			(xy 54.683297 -299.388396) (xy 54.653732 -299.42774) (xy 54.618239 -299.461832) (xy 54.577736 -299.489788)
			(xy 54.533274 -299.510886) (xy 54.486003 -299.524578) (xy 54.437148 -299.53051) (xy 54.387973 -299.528529)
			(xy 54.339754 -299.518685) (xy 54.293738 -299.501233) (xy 54.251117 -299.476626) (xy 54.212996 -299.445501)
			(xy 54.180361 -299.408664) (xy 54.154058 -299.367068) (xy 54.134767 -299.321792) (xy 54.12299 -299.274008)
			(xy 54.11903 -299.224954) (xy 53.780182 -299.224954) (xy 53.779687 -299.249561) (xy 53.771792 -299.298138)
			(xy 53.756208 -299.344819) (xy 53.733337 -299.388396) (xy 53.703772 -299.42774) (xy 53.668279 -299.461832)
			(xy 53.627776 -299.489788) (xy 53.583314 -299.510886) (xy 53.536043 -299.524578) (xy 53.487188 -299.53051)
			(xy 53.438013 -299.528529) (xy 53.389794 -299.518685) (xy 53.343778 -299.501233) (xy 53.301157 -299.476626)
			(xy 53.263036 -299.445501) (xy 53.230401 -299.408664) (xy 53.204098 -299.367068) (xy 53.184807 -299.321792)
			(xy 53.17303 -299.274008) (xy 53.16907 -299.224954) (xy 52.830222 -299.224954) (xy 52.829727 -299.249561)
			(xy 52.821832 -299.298138) (xy 52.806248 -299.344819) (xy 52.783377 -299.388396) (xy 52.753812 -299.42774)
			(xy 52.718319 -299.461832) (xy 52.677816 -299.489788) (xy 52.633354 -299.510886) (xy 52.586083 -299.524578)
			(xy 52.537228 -299.53051) (xy 52.488053 -299.528529) (xy 52.439834 -299.518685) (xy 52.393818 -299.501233)
			(xy 52.351197 -299.476626) (xy 52.313076 -299.445501) (xy 52.280441 -299.408664) (xy 52.254138 -299.367068)
			(xy 52.234847 -299.321792) (xy 52.22307 -299.274008) (xy 52.21911 -299.224954) (xy 51.880262 -299.224954)
			(xy 51.879767 -299.249561) (xy 51.871872 -299.298138) (xy 51.856288 -299.344819) (xy 51.833417 -299.388396)
			(xy 51.803852 -299.42774) (xy 51.768359 -299.461832) (xy 51.727856 -299.489788) (xy 51.683394 -299.510886)
			(xy 51.636123 -299.524578) (xy 51.587268 -299.53051) (xy 51.538093 -299.528529) (xy 51.489874 -299.518685)
			(xy 51.443858 -299.501233) (xy 51.401237 -299.476626) (xy 51.363116 -299.445501) (xy 51.330481 -299.408664)
			(xy 51.304178 -299.367068) (xy 51.284887 -299.321792) (xy 51.27311 -299.274008) (xy 51.26915 -299.224954)
			(xy 50.930302 -299.224954) (xy 50.929807 -299.249561) (xy 50.921912 -299.298138) (xy 50.906328 -299.344819)
			(xy 50.883457 -299.388396) (xy 50.853892 -299.42774) (xy 50.818399 -299.461832) (xy 50.777896 -299.489788)
			(xy 50.733434 -299.510886) (xy 50.686163 -299.524578) (xy 50.637308 -299.53051) (xy 50.588133 -299.528529)
			(xy 50.539914 -299.518685) (xy 50.493898 -299.501233) (xy 50.451277 -299.476626) (xy 50.413156 -299.445501)
			(xy 50.380521 -299.408664) (xy 50.354218 -299.367068) (xy 50.334927 -299.321792) (xy 50.32315 -299.274008)
			(xy 50.31919 -299.224954) (xy 49.980088 -299.224954) (xy 49.979593 -299.249561) (xy 49.971698 -299.298138)
			(xy 49.956114 -299.344819) (xy 49.933243 -299.388396) (xy 49.903678 -299.42774) (xy 49.868185 -299.461832)
			(xy 49.827682 -299.489788) (xy 49.78322 -299.510886) (xy 49.735949 -299.524578) (xy 49.687094 -299.53051)
			(xy 49.637919 -299.528529) (xy 49.5897 -299.518685) (xy 49.543684 -299.501233) (xy 49.501063 -299.476626)
			(xy 49.462942 -299.445501) (xy 49.430307 -299.408664) (xy 49.404004 -299.367068) (xy 49.384713 -299.321792)
			(xy 49.372936 -299.274008) (xy 49.368976 -299.224954) (xy 49.030128 -299.224954) (xy 49.029633 -299.249561)
			(xy 49.021738 -299.298138) (xy 49.006154 -299.344819) (xy 48.983283 -299.388396) (xy 48.953718 -299.42774)
			(xy 48.918225 -299.461832) (xy 48.877722 -299.489788) (xy 48.83326 -299.510886) (xy 48.785989 -299.524578)
			(xy 48.737134 -299.53051) (xy 48.687959 -299.528529) (xy 48.63974 -299.518685) (xy 48.593724 -299.501233)
			(xy 48.551103 -299.476626) (xy 48.512982 -299.445501) (xy 48.480347 -299.408664) (xy 48.454044 -299.367068)
			(xy 48.434753 -299.321792) (xy 48.422976 -299.274008) (xy 48.419016 -299.224954) (xy 48.080168 -299.224954)
			(xy 48.079673 -299.249561) (xy 48.071778 -299.298138) (xy 48.056194 -299.344819) (xy 48.033323 -299.388396)
			(xy 48.003758 -299.42774) (xy 47.968265 -299.461832) (xy 47.927762 -299.489788) (xy 47.8833 -299.510886)
			(xy 47.836029 -299.524578) (xy 47.787174 -299.53051) (xy 47.737999 -299.528529) (xy 47.68978 -299.518685)
			(xy 47.643764 -299.501233) (xy 47.601143 -299.476626) (xy 47.563022 -299.445501) (xy 47.530387 -299.408664)
			(xy 47.504084 -299.367068) (xy 47.484793 -299.321792) (xy 47.473016 -299.274008) (xy 47.469056 -299.224954)
			(xy 47.130208 -299.224954) (xy 47.129713 -299.249561) (xy 47.121818 -299.298138) (xy 47.106234 -299.344819)
			(xy 47.083363 -299.388396) (xy 47.053798 -299.42774) (xy 47.018305 -299.461832) (xy 46.977802 -299.489788)
			(xy 46.93334 -299.510886) (xy 46.886069 -299.524578) (xy 46.837214 -299.53051) (xy 46.788039 -299.528529)
			(xy 46.73982 -299.518685) (xy 46.693804 -299.501233) (xy 46.651183 -299.476626) (xy 46.613062 -299.445501)
			(xy 46.580427 -299.408664) (xy 46.554124 -299.367068) (xy 46.534833 -299.321792) (xy 46.523056 -299.274008)
			(xy 46.519096 -299.224954) (xy 46.206173 -299.224954) (xy 46.206176 -299.22499) (xy 46.201994 -299.277474)
			(xy 46.18955 -299.328632) (xy 46.169157 -299.377173) (xy 46.141332 -299.42187) (xy 46.106778 -299.461594)
			(xy 46.066366 -299.495342) (xy 46.021118 -299.522261) (xy 45.972176 -299.541672) (xy 45.946568 -299.547788)
			(xy 45.929042 -299.551598) (xy 45.90669 -299.579538) (xy 45.90669 -299.82033) (xy 45.929042 -299.84827)
			(xy 45.946568 -299.85208) (xy 45.972152 -299.858282) (xy 46.021086 -299.877688) (xy 46.066326 -299.904602)
			(xy 46.106732 -299.938343) (xy 46.141281 -299.978059) (xy 46.169102 -300.022748) (xy 46.189492 -300.07128)
			(xy 46.201935 -300.122429) (xy 46.206118 -300.174903) (xy 46.206117 -300.174914) (xy 47.469056 -300.174914)
			(xy 47.473016 -300.12586) (xy 47.484793 -300.078076) (xy 47.504084 -300.0328) (xy 47.530387 -299.991204)
			(xy 47.563022 -299.954367) (xy 47.601143 -299.923242) (xy 47.643764 -299.898635) (xy 47.68978 -299.881183)
			(xy 47.737999 -299.871339) (xy 47.787174 -299.869358) (xy 47.836029 -299.87529) (xy 47.8833 -299.888982)
			(xy 47.927762 -299.91008) (xy 47.968265 -299.938036) (xy 48.003758 -299.972128) (xy 48.033323 -300.011472)
			(xy 48.056194 -300.055049) (xy 48.071778 -300.10173) (xy 48.079673 -300.150307) (xy 48.080168 -300.174914)
			(xy 48.419016 -300.174914) (xy 48.422976 -300.12586) (xy 48.434753 -300.078076) (xy 48.454044 -300.0328)
			(xy 48.480347 -299.991204) (xy 48.512982 -299.954367) (xy 48.551103 -299.923242) (xy 48.593724 -299.898635)
			(xy 48.63974 -299.881183) (xy 48.687959 -299.871339) (xy 48.737134 -299.869358) (xy 48.785989 -299.87529)
			(xy 48.83326 -299.888982) (xy 48.877722 -299.91008) (xy 48.918225 -299.938036) (xy 48.953718 -299.972128)
			(xy 48.983283 -300.011472) (xy 49.006154 -300.055049) (xy 49.021738 -300.10173) (xy 49.029633 -300.150307)
			(xy 49.030128 -300.174914) (xy 49.368976 -300.174914) (xy 49.372936 -300.12586) (xy 49.384713 -300.078076)
			(xy 49.404004 -300.0328) (xy 49.430307 -299.991204) (xy 49.462942 -299.954367) (xy 49.501063 -299.923242)
			(xy 49.543684 -299.898635) (xy 49.5897 -299.881183) (xy 49.637919 -299.871339) (xy 49.687094 -299.869358)
			(xy 49.735949 -299.87529) (xy 49.78322 -299.888982) (xy 49.827682 -299.91008) (xy 49.868185 -299.938036)
			(xy 49.903678 -299.972128) (xy 49.933243 -300.011472) (xy 49.956114 -300.055049) (xy 49.971698 -300.10173)
			(xy 49.979593 -300.150307) (xy 49.980088 -300.174914) (xy 50.31919 -300.174914) (xy 50.32315 -300.12586)
			(xy 50.334927 -300.078076) (xy 50.354218 -300.0328) (xy 50.380521 -299.991204) (xy 50.413156 -299.954367)
			(xy 50.451277 -299.923242) (xy 50.493898 -299.898635) (xy 50.539914 -299.881183) (xy 50.588133 -299.871339)
			(xy 50.637308 -299.869358) (xy 50.686163 -299.87529) (xy 50.733434 -299.888982) (xy 50.777896 -299.91008)
			(xy 50.818399 -299.938036) (xy 50.853892 -299.972128) (xy 50.883457 -300.011472) (xy 50.906328 -300.055049)
			(xy 50.921912 -300.10173) (xy 50.929807 -300.150307) (xy 50.930302 -300.174914) (xy 51.26915 -300.174914)
			(xy 51.27311 -300.12586) (xy 51.284887 -300.078076) (xy 51.304178 -300.0328) (xy 51.330481 -299.991204)
			(xy 51.363116 -299.954367) (xy 51.401237 -299.923242) (xy 51.443858 -299.898635) (xy 51.489874 -299.881183)
			(xy 51.538093 -299.871339) (xy 51.587268 -299.869358) (xy 51.636123 -299.87529) (xy 51.683394 -299.888982)
			(xy 51.727856 -299.91008) (xy 51.768359 -299.938036) (xy 51.803852 -299.972128) (xy 51.833417 -300.011472)
			(xy 51.856288 -300.055049) (xy 51.871872 -300.10173) (xy 51.879767 -300.150307) (xy 51.880262 -300.174914)
			(xy 52.21911 -300.174914) (xy 52.22307 -300.12586) (xy 52.234847 -300.078076) (xy 52.254138 -300.0328)
			(xy 52.280441 -299.991204) (xy 52.313076 -299.954367) (xy 52.351197 -299.923242) (xy 52.393818 -299.898635)
			(xy 52.439834 -299.881183) (xy 52.488053 -299.871339) (xy 52.537228 -299.869358) (xy 52.586083 -299.87529)
			(xy 52.633354 -299.888982) (xy 52.677816 -299.91008) (xy 52.718319 -299.938036) (xy 52.753812 -299.972128)
			(xy 52.783377 -300.011472) (xy 52.806248 -300.055049) (xy 52.821832 -300.10173) (xy 52.829727 -300.150307)
			(xy 52.830222 -300.174914) (xy 53.16907 -300.174914) (xy 53.17303 -300.12586) (xy 53.184807 -300.078076)
			(xy 53.204098 -300.0328) (xy 53.230401 -299.991204) (xy 53.263036 -299.954367) (xy 53.301157 -299.923242)
			(xy 53.343778 -299.898635) (xy 53.389794 -299.881183) (xy 53.438013 -299.871339) (xy 53.487188 -299.869358)
			(xy 53.536043 -299.87529) (xy 53.583314 -299.888982) (xy 53.627776 -299.91008) (xy 53.668279 -299.938036)
			(xy 53.703772 -299.972128) (xy 53.733337 -300.011472) (xy 53.756208 -300.055049) (xy 53.771792 -300.10173)
			(xy 53.779687 -300.150307) (xy 53.780182 -300.174914) (xy 54.11903 -300.174914) (xy 54.12299 -300.12586)
			(xy 54.134767 -300.078076) (xy 54.154058 -300.0328) (xy 54.180361 -299.991204) (xy 54.212996 -299.954367)
			(xy 54.251117 -299.923242) (xy 54.293738 -299.898635) (xy 54.339754 -299.881183) (xy 54.387973 -299.871339)
			(xy 54.437148 -299.869358) (xy 54.486003 -299.87529) (xy 54.533274 -299.888982) (xy 54.577736 -299.91008)
			(xy 54.618239 -299.938036) (xy 54.653732 -299.972128) (xy 54.683297 -300.011472) (xy 54.706168 -300.055049)
			(xy 54.721752 -300.10173) (xy 54.729647 -300.150307) (xy 54.730142 -300.174914) (xy 55.06899 -300.174914)
			(xy 55.07295 -300.12586) (xy 55.084727 -300.078076) (xy 55.104018 -300.0328) (xy 55.130321 -299.991204)
			(xy 55.162956 -299.954367) (xy 55.201077 -299.923242) (xy 55.243698 -299.898635) (xy 55.289714 -299.881183)
			(xy 55.337933 -299.871339) (xy 55.387108 -299.869358) (xy 55.435963 -299.87529) (xy 55.483234 -299.888982)
			(xy 55.527696 -299.91008) (xy 55.568199 -299.938036) (xy 55.603692 -299.972128) (xy 55.633257 -300.011472)
			(xy 55.656128 -300.055049) (xy 55.671712 -300.10173) (xy 55.679607 -300.150307) (xy 55.680102 -300.174914)
			(xy 56.01895 -300.174914) (xy 56.02291 -300.12586) (xy 56.034687 -300.078076) (xy 56.053978 -300.0328)
			(xy 56.080281 -299.991204) (xy 56.112916 -299.954367) (xy 56.151037 -299.923242) (xy 56.193658 -299.898635)
			(xy 56.239674 -299.881183) (xy 56.287893 -299.871339) (xy 56.337068 -299.869358) (xy 56.385923 -299.87529)
			(xy 56.433194 -299.888982) (xy 56.477656 -299.91008) (xy 56.518159 -299.938036) (xy 56.553652 -299.972128)
			(xy 56.583217 -300.011472) (xy 56.606088 -300.055049) (xy 56.621672 -300.10173) (xy 56.629567 -300.150307)
			(xy 56.630062 -300.174914) (xy 56.969164 -300.174914) (xy 56.973124 -300.12586) (xy 56.984901 -300.078076)
			(xy 57.004192 -300.0328) (xy 57.030495 -299.991204) (xy 57.06313 -299.954367) (xy 57.101251 -299.923242)
			(xy 57.143872 -299.898635) (xy 57.189888 -299.881183) (xy 57.238107 -299.871339) (xy 57.287282 -299.869358)
			(xy 57.336137 -299.87529) (xy 57.383408 -299.888982) (xy 57.42787 -299.91008) (xy 57.468373 -299.938036)
			(xy 57.503866 -299.972128) (xy 57.533431 -300.011472) (xy 57.556302 -300.055049) (xy 57.571886 -300.10173)
			(xy 57.579781 -300.150307) (xy 57.580276 -300.174914) (xy 57.919124 -300.174914) (xy 57.923084 -300.12586)
			(xy 57.934861 -300.078076) (xy 57.954152 -300.0328) (xy 57.980455 -299.991204) (xy 58.01309 -299.954367)
			(xy 58.051211 -299.923242) (xy 58.093832 -299.898635) (xy 58.139848 -299.881183) (xy 58.188067 -299.871339)
			(xy 58.237242 -299.869358) (xy 58.286097 -299.87529) (xy 58.333368 -299.888982) (xy 58.37783 -299.91008)
			(xy 58.418333 -299.938036) (xy 58.453826 -299.972128) (xy 58.483391 -300.011472) (xy 58.506262 -300.055049)
			(xy 58.521846 -300.10173) (xy 58.529741 -300.150307) (xy 58.530236 -300.174914) (xy 59.819044 -300.174914)
			(xy 59.823004 -300.12586) (xy 59.834781 -300.078076) (xy 59.854072 -300.0328) (xy 59.880375 -299.991204)
			(xy 59.91301 -299.954367) (xy 59.951131 -299.923242) (xy 59.993752 -299.898635) (xy 60.039768 -299.881183)
			(xy 60.087987 -299.871339) (xy 60.137162 -299.869358) (xy 60.186017 -299.87529) (xy 60.233288 -299.888982)
			(xy 60.27775 -299.91008) (xy 60.318253 -299.938036) (xy 60.353746 -299.972128) (xy 60.383311 -300.011472)
			(xy 60.406182 -300.055049) (xy 60.421766 -300.10173) (xy 60.429661 -300.150307) (xy 60.430156 -300.174914)
			(xy 60.769004 -300.174914) (xy 60.772964 -300.12586) (xy 60.784741 -300.078076) (xy 60.804032 -300.0328)
			(xy 60.830335 -299.991204) (xy 60.86297 -299.954367) (xy 60.901091 -299.923242) (xy 60.943712 -299.898635)
			(xy 60.989728 -299.881183) (xy 61.037947 -299.871339) (xy 61.087122 -299.869358) (xy 61.135977 -299.87529)
			(xy 61.183248 -299.888982) (xy 61.22771 -299.91008) (xy 61.268213 -299.938036) (xy 61.303706 -299.972128)
			(xy 61.333271 -300.011472) (xy 61.356142 -300.055049) (xy 61.371726 -300.10173) (xy 61.379621 -300.150307)
			(xy 61.380116 -300.174914) (xy 61.718964 -300.174914) (xy 61.722924 -300.12586) (xy 61.734701 -300.078076)
			(xy 61.753992 -300.0328) (xy 61.780295 -299.991204) (xy 61.81293 -299.954367) (xy 61.851051 -299.923242)
			(xy 61.893672 -299.898635) (xy 61.939688 -299.881183) (xy 61.987907 -299.871339) (xy 62.037082 -299.869358)
			(xy 62.085937 -299.87529) (xy 62.133208 -299.888982) (xy 62.17767 -299.91008) (xy 62.218173 -299.938036)
			(xy 62.253666 -299.972128) (xy 62.283231 -300.011472) (xy 62.306102 -300.055049) (xy 62.321686 -300.10173)
			(xy 62.329581 -300.150307) (xy 62.330076 -300.174914) (xy 62.669178 -300.174914) (xy 62.673138 -300.12586)
			(xy 62.684915 -300.078076) (xy 62.704206 -300.0328) (xy 62.730509 -299.991204) (xy 62.763144 -299.954367)
			(xy 62.801265 -299.923242) (xy 62.843886 -299.898635) (xy 62.889902 -299.881183) (xy 62.938121 -299.871339)
			(xy 62.987296 -299.869358) (xy 63.036151 -299.87529) (xy 63.083422 -299.888982) (xy 63.127884 -299.91008)
			(xy 63.168387 -299.938036) (xy 63.20388 -299.972128) (xy 63.233445 -300.011472) (xy 63.256316 -300.055049)
			(xy 63.2719 -300.10173) (xy 63.279795 -300.150307) (xy 63.28029 -300.174914) (xy 63.619138 -300.174914)
			(xy 63.623098 -300.12586) (xy 63.634875 -300.078076) (xy 63.654166 -300.0328) (xy 63.680469 -299.991204)
			(xy 63.713104 -299.954367) (xy 63.751225 -299.923242) (xy 63.793846 -299.898635) (xy 63.839862 -299.881183)
			(xy 63.888081 -299.871339) (xy 63.937256 -299.869358) (xy 63.986111 -299.87529) (xy 64.033382 -299.888982)
			(xy 64.077844 -299.91008) (xy 64.118347 -299.938036) (xy 64.15384 -299.972128) (xy 64.183405 -300.011472)
			(xy 64.206276 -300.055049) (xy 64.22186 -300.10173) (xy 64.229755 -300.150307) (xy 64.23025 -300.174914)
			(xy 64.569098 -300.174914) (xy 64.573058 -300.12586) (xy 64.584835 -300.078076) (xy 64.604126 -300.0328)
			(xy 64.630429 -299.991204) (xy 64.663064 -299.954367) (xy 64.701185 -299.923242) (xy 64.743806 -299.898635)
			(xy 64.789822 -299.881183) (xy 64.838041 -299.871339) (xy 64.887216 -299.869358) (xy 64.936071 -299.87529)
			(xy 64.983342 -299.888982) (xy 65.027804 -299.91008) (xy 65.068307 -299.938036) (xy 65.1038 -299.972128)
			(xy 65.133365 -300.011472) (xy 65.156236 -300.055049) (xy 65.17182 -300.10173) (xy 65.179715 -300.150307)
			(xy 65.18021 -300.174914) (xy 65.519058 -300.174914) (xy 65.523018 -300.12586) (xy 65.534795 -300.078076)
			(xy 65.554086 -300.0328) (xy 65.580389 -299.991204) (xy 65.613024 -299.954367) (xy 65.651145 -299.923242)
			(xy 65.693766 -299.898635) (xy 65.739782 -299.881183) (xy 65.788001 -299.871339) (xy 65.837176 -299.869358)
			(xy 65.886031 -299.87529) (xy 65.933302 -299.888982) (xy 65.977764 -299.91008) (xy 66.018267 -299.938036)
			(xy 66.05376 -299.972128) (xy 66.083325 -300.011472) (xy 66.106196 -300.055049) (xy 66.12178 -300.10173)
			(xy 66.129675 -300.150307) (xy 66.13017 -300.174914) (xy 66.469018 -300.174914) (xy 66.472978 -300.12586)
			(xy 66.484755 -300.078076) (xy 66.504046 -300.0328) (xy 66.530349 -299.991204) (xy 66.562984 -299.954367)
			(xy 66.601105 -299.923242) (xy 66.643726 -299.898635) (xy 66.689742 -299.881183) (xy 66.737961 -299.871339)
			(xy 66.787136 -299.869358) (xy 66.835991 -299.87529) (xy 66.883262 -299.888982) (xy 66.927724 -299.91008)
			(xy 66.968227 -299.938036) (xy 67.00372 -299.972128) (xy 67.033285 -300.011472) (xy 67.056156 -300.055049)
			(xy 67.07174 -300.10173) (xy 67.079635 -300.150307) (xy 67.08013 -300.174914) (xy 67.418978 -300.174914)
			(xy 67.422938 -300.12586) (xy 67.434715 -300.078076) (xy 67.454006 -300.0328) (xy 67.480309 -299.991204)
			(xy 67.512944 -299.954367) (xy 67.551065 -299.923242) (xy 67.593686 -299.898635) (xy 67.639702 -299.881183)
			(xy 67.687921 -299.871339) (xy 67.737096 -299.869358) (xy 67.785951 -299.87529) (xy 67.833222 -299.888982)
			(xy 67.877684 -299.91008) (xy 67.918187 -299.938036) (xy 67.95368 -299.972128) (xy 67.983245 -300.011472)
			(xy 68.006116 -300.055049) (xy 68.0217 -300.10173) (xy 68.029595 -300.150307) (xy 68.03009 -300.174914)
			(xy 68.029595 -300.199521) (xy 68.0217 -300.248098) (xy 68.006116 -300.294779) (xy 67.983245 -300.338356)
			(xy 67.95368 -300.3777) (xy 67.918187 -300.411792) (xy 67.877684 -300.439748) (xy 67.833222 -300.460846)
			(xy 67.785951 -300.474538) (xy 67.737096 -300.48047) (xy 67.687921 -300.478489) (xy 67.639702 -300.468645)
			(xy 67.593686 -300.451193) (xy 67.551065 -300.426586) (xy 67.512944 -300.395461) (xy 67.480309 -300.358624)
			(xy 67.454006 -300.317028) (xy 67.434715 -300.271752) (xy 67.422938 -300.223968) (xy 67.418978 -300.174914)
			(xy 67.08013 -300.174914) (xy 67.079635 -300.199521) (xy 67.07174 -300.248098) (xy 67.056156 -300.294779)
			(xy 67.033285 -300.338356) (xy 67.00372 -300.3777) (xy 66.968227 -300.411792) (xy 66.927724 -300.439748)
			(xy 66.883262 -300.460846) (xy 66.835991 -300.474538) (xy 66.787136 -300.48047) (xy 66.737961 -300.478489)
			(xy 66.689742 -300.468645) (xy 66.643726 -300.451193) (xy 66.601105 -300.426586) (xy 66.562984 -300.395461)
			(xy 66.530349 -300.358624) (xy 66.504046 -300.317028) (xy 66.484755 -300.271752) (xy 66.472978 -300.223968)
			(xy 66.469018 -300.174914) (xy 66.13017 -300.174914) (xy 66.129675 -300.199521) (xy 66.12178 -300.248098)
			(xy 66.106196 -300.294779) (xy 66.083325 -300.338356) (xy 66.05376 -300.3777) (xy 66.018267 -300.411792)
			(xy 65.977764 -300.439748) (xy 65.933302 -300.460846) (xy 65.886031 -300.474538) (xy 65.837176 -300.48047)
			(xy 65.788001 -300.478489) (xy 65.739782 -300.468645) (xy 65.693766 -300.451193) (xy 65.651145 -300.426586)
			(xy 65.613024 -300.395461) (xy 65.580389 -300.358624) (xy 65.554086 -300.317028) (xy 65.534795 -300.271752)
			(xy 65.523018 -300.223968) (xy 65.519058 -300.174914) (xy 65.18021 -300.174914) (xy 65.179715 -300.199521)
			(xy 65.17182 -300.248098) (xy 65.156236 -300.294779) (xy 65.133365 -300.338356) (xy 65.1038 -300.3777)
			(xy 65.068307 -300.411792) (xy 65.027804 -300.439748) (xy 64.983342 -300.460846) (xy 64.936071 -300.474538)
			(xy 64.887216 -300.48047) (xy 64.838041 -300.478489) (xy 64.789822 -300.468645) (xy 64.743806 -300.451193)
			(xy 64.701185 -300.426586) (xy 64.663064 -300.395461) (xy 64.630429 -300.358624) (xy 64.604126 -300.317028)
			(xy 64.584835 -300.271752) (xy 64.573058 -300.223968) (xy 64.569098 -300.174914) (xy 64.23025 -300.174914)
			(xy 64.229755 -300.199521) (xy 64.22186 -300.248098) (xy 64.206276 -300.294779) (xy 64.183405 -300.338356)
			(xy 64.15384 -300.3777) (xy 64.118347 -300.411792) (xy 64.077844 -300.439748) (xy 64.033382 -300.460846)
			(xy 63.986111 -300.474538) (xy 63.937256 -300.48047) (xy 63.888081 -300.478489) (xy 63.839862 -300.468645)
			(xy 63.793846 -300.451193) (xy 63.751225 -300.426586) (xy 63.713104 -300.395461) (xy 63.680469 -300.358624)
			(xy 63.654166 -300.317028) (xy 63.634875 -300.271752) (xy 63.623098 -300.223968) (xy 63.619138 -300.174914)
			(xy 63.28029 -300.174914) (xy 63.279795 -300.199521) (xy 63.2719 -300.248098) (xy 63.256316 -300.294779)
			(xy 63.233445 -300.338356) (xy 63.20388 -300.3777) (xy 63.168387 -300.411792) (xy 63.127884 -300.439748)
			(xy 63.083422 -300.460846) (xy 63.036151 -300.474538) (xy 62.987296 -300.48047) (xy 62.938121 -300.478489)
			(xy 62.889902 -300.468645) (xy 62.843886 -300.451193) (xy 62.801265 -300.426586) (xy 62.763144 -300.395461)
			(xy 62.730509 -300.358624) (xy 62.704206 -300.317028) (xy 62.684915 -300.271752) (xy 62.673138 -300.223968)
			(xy 62.669178 -300.174914) (xy 62.330076 -300.174914) (xy 62.329581 -300.199521) (xy 62.321686 -300.248098)
			(xy 62.306102 -300.294779) (xy 62.283231 -300.338356) (xy 62.253666 -300.3777) (xy 62.218173 -300.411792)
			(xy 62.17767 -300.439748) (xy 62.133208 -300.460846) (xy 62.085937 -300.474538) (xy 62.037082 -300.48047)
			(xy 61.987907 -300.478489) (xy 61.939688 -300.468645) (xy 61.893672 -300.451193) (xy 61.851051 -300.426586)
			(xy 61.81293 -300.395461) (xy 61.780295 -300.358624) (xy 61.753992 -300.317028) (xy 61.734701 -300.271752)
			(xy 61.722924 -300.223968) (xy 61.718964 -300.174914) (xy 61.380116 -300.174914) (xy 61.379621 -300.199521)
			(xy 61.371726 -300.248098) (xy 61.356142 -300.294779) (xy 61.333271 -300.338356) (xy 61.303706 -300.3777)
			(xy 61.268213 -300.411792) (xy 61.22771 -300.439748) (xy 61.183248 -300.460846) (xy 61.135977 -300.474538)
			(xy 61.087122 -300.48047) (xy 61.037947 -300.478489) (xy 60.989728 -300.468645) (xy 60.943712 -300.451193)
			(xy 60.901091 -300.426586) (xy 60.86297 -300.395461) (xy 60.830335 -300.358624) (xy 60.804032 -300.317028)
			(xy 60.784741 -300.271752) (xy 60.772964 -300.223968) (xy 60.769004 -300.174914) (xy 60.430156 -300.174914)
			(xy 60.429661 -300.199521) (xy 60.421766 -300.248098) (xy 60.406182 -300.294779) (xy 60.383311 -300.338356)
			(xy 60.353746 -300.3777) (xy 60.318253 -300.411792) (xy 60.27775 -300.439748) (xy 60.233288 -300.460846)
			(xy 60.186017 -300.474538) (xy 60.137162 -300.48047) (xy 60.087987 -300.478489) (xy 60.039768 -300.468645)
			(xy 59.993752 -300.451193) (xy 59.951131 -300.426586) (xy 59.91301 -300.395461) (xy 59.880375 -300.358624)
			(xy 59.854072 -300.317028) (xy 59.834781 -300.271752) (xy 59.823004 -300.223968) (xy 59.819044 -300.174914)
			(xy 58.530236 -300.174914) (xy 58.529741 -300.199521) (xy 58.521846 -300.248098) (xy 58.506262 -300.294779)
			(xy 58.483391 -300.338356) (xy 58.453826 -300.3777) (xy 58.418333 -300.411792) (xy 58.37783 -300.439748)
			(xy 58.333368 -300.460846) (xy 58.286097 -300.474538) (xy 58.237242 -300.48047) (xy 58.188067 -300.478489)
			(xy 58.139848 -300.468645) (xy 58.093832 -300.451193) (xy 58.051211 -300.426586) (xy 58.01309 -300.395461)
			(xy 57.980455 -300.358624) (xy 57.954152 -300.317028) (xy 57.934861 -300.271752) (xy 57.923084 -300.223968)
			(xy 57.919124 -300.174914) (xy 57.580276 -300.174914) (xy 57.579781 -300.199521) (xy 57.571886 -300.248098)
			(xy 57.556302 -300.294779) (xy 57.533431 -300.338356) (xy 57.503866 -300.3777) (xy 57.468373 -300.411792)
			(xy 57.42787 -300.439748) (xy 57.383408 -300.460846) (xy 57.336137 -300.474538) (xy 57.287282 -300.48047)
			(xy 57.238107 -300.478489) (xy 57.189888 -300.468645) (xy 57.143872 -300.451193) (xy 57.101251 -300.426586)
			(xy 57.06313 -300.395461) (xy 57.030495 -300.358624) (xy 57.004192 -300.317028) (xy 56.984901 -300.271752)
			(xy 56.973124 -300.223968) (xy 56.969164 -300.174914) (xy 56.630062 -300.174914) (xy 56.629567 -300.199521)
			(xy 56.621672 -300.248098) (xy 56.606088 -300.294779) (xy 56.583217 -300.338356) (xy 56.553652 -300.3777)
			(xy 56.518159 -300.411792) (xy 56.477656 -300.439748) (xy 56.433194 -300.460846) (xy 56.385923 -300.474538)
			(xy 56.337068 -300.48047) (xy 56.287893 -300.478489) (xy 56.239674 -300.468645) (xy 56.193658 -300.451193)
			(xy 56.151037 -300.426586) (xy 56.112916 -300.395461) (xy 56.080281 -300.358624) (xy 56.053978 -300.317028)
			(xy 56.034687 -300.271752) (xy 56.02291 -300.223968) (xy 56.01895 -300.174914) (xy 55.680102 -300.174914)
			(xy 55.679607 -300.199521) (xy 55.671712 -300.248098) (xy 55.656128 -300.294779) (xy 55.633257 -300.338356)
			(xy 55.603692 -300.3777) (xy 55.568199 -300.411792) (xy 55.527696 -300.439748) (xy 55.483234 -300.460846)
			(xy 55.435963 -300.474538) (xy 55.387108 -300.48047) (xy 55.337933 -300.478489) (xy 55.289714 -300.468645)
			(xy 55.243698 -300.451193) (xy 55.201077 -300.426586) (xy 55.162956 -300.395461) (xy 55.130321 -300.358624)
			(xy 55.104018 -300.317028) (xy 55.084727 -300.271752) (xy 55.07295 -300.223968) (xy 55.06899 -300.174914)
			(xy 54.730142 -300.174914) (xy 54.729647 -300.199521) (xy 54.721752 -300.248098) (xy 54.706168 -300.294779)
			(xy 54.683297 -300.338356) (xy 54.653732 -300.3777) (xy 54.618239 -300.411792) (xy 54.577736 -300.439748)
			(xy 54.533274 -300.460846) (xy 54.486003 -300.474538) (xy 54.437148 -300.48047) (xy 54.387973 -300.478489)
			(xy 54.339754 -300.468645) (xy 54.293738 -300.451193) (xy 54.251117 -300.426586) (xy 54.212996 -300.395461)
			(xy 54.180361 -300.358624) (xy 54.154058 -300.317028) (xy 54.134767 -300.271752) (xy 54.12299 -300.223968)
			(xy 54.11903 -300.174914) (xy 53.780182 -300.174914) (xy 53.779687 -300.199521) (xy 53.771792 -300.248098)
			(xy 53.756208 -300.294779) (xy 53.733337 -300.338356) (xy 53.703772 -300.3777) (xy 53.668279 -300.411792)
			(xy 53.627776 -300.439748) (xy 53.583314 -300.460846) (xy 53.536043 -300.474538) (xy 53.487188 -300.48047)
			(xy 53.438013 -300.478489) (xy 53.389794 -300.468645) (xy 53.343778 -300.451193) (xy 53.301157 -300.426586)
			(xy 53.263036 -300.395461) (xy 53.230401 -300.358624) (xy 53.204098 -300.317028) (xy 53.184807 -300.271752)
			(xy 53.17303 -300.223968) (xy 53.16907 -300.174914) (xy 52.830222 -300.174914) (xy 52.829727 -300.199521)
			(xy 52.821832 -300.248098) (xy 52.806248 -300.294779) (xy 52.783377 -300.338356) (xy 52.753812 -300.3777)
			(xy 52.718319 -300.411792) (xy 52.677816 -300.439748) (xy 52.633354 -300.460846) (xy 52.586083 -300.474538)
			(xy 52.537228 -300.48047) (xy 52.488053 -300.478489) (xy 52.439834 -300.468645) (xy 52.393818 -300.451193)
			(xy 52.351197 -300.426586) (xy 52.313076 -300.395461) (xy 52.280441 -300.358624) (xy 52.254138 -300.317028)
			(xy 52.234847 -300.271752) (xy 52.22307 -300.223968) (xy 52.21911 -300.174914) (xy 51.880262 -300.174914)
			(xy 51.879767 -300.199521) (xy 51.871872 -300.248098) (xy 51.856288 -300.294779) (xy 51.833417 -300.338356)
			(xy 51.803852 -300.3777) (xy 51.768359 -300.411792) (xy 51.727856 -300.439748) (xy 51.683394 -300.460846)
			(xy 51.636123 -300.474538) (xy 51.587268 -300.48047) (xy 51.538093 -300.478489) (xy 51.489874 -300.468645)
			(xy 51.443858 -300.451193) (xy 51.401237 -300.426586) (xy 51.363116 -300.395461) (xy 51.330481 -300.358624)
			(xy 51.304178 -300.317028) (xy 51.284887 -300.271752) (xy 51.27311 -300.223968) (xy 51.26915 -300.174914)
			(xy 50.930302 -300.174914) (xy 50.929807 -300.199521) (xy 50.921912 -300.248098) (xy 50.906328 -300.294779)
			(xy 50.883457 -300.338356) (xy 50.853892 -300.3777) (xy 50.818399 -300.411792) (xy 50.777896 -300.439748)
			(xy 50.733434 -300.460846) (xy 50.686163 -300.474538) (xy 50.637308 -300.48047) (xy 50.588133 -300.478489)
			(xy 50.539914 -300.468645) (xy 50.493898 -300.451193) (xy 50.451277 -300.426586) (xy 50.413156 -300.395461)
			(xy 50.380521 -300.358624) (xy 50.354218 -300.317028) (xy 50.334927 -300.271752) (xy 50.32315 -300.223968)
			(xy 50.31919 -300.174914) (xy 49.980088 -300.174914) (xy 49.979593 -300.199521) (xy 49.971698 -300.248098)
			(xy 49.956114 -300.294779) (xy 49.933243 -300.338356) (xy 49.903678 -300.3777) (xy 49.868185 -300.411792)
			(xy 49.827682 -300.439748) (xy 49.78322 -300.460846) (xy 49.735949 -300.474538) (xy 49.687094 -300.48047)
			(xy 49.637919 -300.478489) (xy 49.5897 -300.468645) (xy 49.543684 -300.451193) (xy 49.501063 -300.426586)
			(xy 49.462942 -300.395461) (xy 49.430307 -300.358624) (xy 49.404004 -300.317028) (xy 49.384713 -300.271752)
			(xy 49.372936 -300.223968) (xy 49.368976 -300.174914) (xy 49.030128 -300.174914) (xy 49.029633 -300.199521)
			(xy 49.021738 -300.248098) (xy 49.006154 -300.294779) (xy 48.983283 -300.338356) (xy 48.953718 -300.3777)
			(xy 48.918225 -300.411792) (xy 48.877722 -300.439748) (xy 48.83326 -300.460846) (xy 48.785989 -300.474538)
			(xy 48.737134 -300.48047) (xy 48.687959 -300.478489) (xy 48.63974 -300.468645) (xy 48.593724 -300.451193)
			(xy 48.551103 -300.426586) (xy 48.512982 -300.395461) (xy 48.480347 -300.358624) (xy 48.454044 -300.317028)
			(xy 48.434753 -300.271752) (xy 48.422976 -300.223968) (xy 48.419016 -300.174914) (xy 48.080168 -300.174914)
			(xy 48.079673 -300.199521) (xy 48.071778 -300.248098) (xy 48.056194 -300.294779) (xy 48.033323 -300.338356)
			(xy 48.003758 -300.3777) (xy 47.968265 -300.411792) (xy 47.927762 -300.439748) (xy 47.8833 -300.460846)
			(xy 47.836029 -300.474538) (xy 47.787174 -300.48047) (xy 47.737999 -300.478489) (xy 47.68978 -300.468645)
			(xy 47.643764 -300.451193) (xy 47.601143 -300.426586) (xy 47.563022 -300.395461) (xy 47.530387 -300.358624)
			(xy 47.504084 -300.317028) (xy 47.484793 -300.271752) (xy 47.473016 -300.223968) (xy 47.469056 -300.174914)
			(xy 46.206117 -300.174914) (xy 46.201934 -300.227377) (xy 46.18949 -300.278526) (xy 46.169099 -300.327058)
			(xy 46.141278 -300.371746) (xy 46.106727 -300.411461) (xy 46.066321 -300.445202) (xy 46.02108 -300.472115)
			(xy 45.972147 -300.49152) (xy 45.946568 -300.497748) (xy 45.929042 -300.501558) (xy 45.90669 -300.529498)
			(xy 45.90669 -300.77029) (xy 45.929042 -300.79823) (xy 45.946568 -300.80204) (xy 45.970977 -300.80793)
			(xy 46.017789 -300.826087) (xy 46.061317 -300.851114) (xy 46.100561 -300.882436) (xy 46.134616 -300.919331)
			(xy 46.162701 -300.960953) (xy 46.184169 -301.006342) (xy 46.198527 -301.054456) (xy 46.205444 -301.104187)
			(xy 46.205163 -301.124874) (xy 47.469056 -301.124874) (xy 47.473016 -301.07582) (xy 47.484793 -301.028036)
			(xy 47.504084 -300.98276) (xy 47.530387 -300.941164) (xy 47.563022 -300.904327) (xy 47.601143 -300.873202)
			(xy 47.643764 -300.848595) (xy 47.68978 -300.831143) (xy 47.737999 -300.821299) (xy 47.787174 -300.819318)
			(xy 47.836029 -300.82525) (xy 47.8833 -300.838942) (xy 47.927762 -300.86004) (xy 47.968265 -300.887996)
			(xy 48.003758 -300.922088) (xy 48.033323 -300.961432) (xy 48.056194 -301.005009) (xy 48.071778 -301.05169)
			(xy 48.079673 -301.100267) (xy 48.080168 -301.124874) (xy 48.419016 -301.124874) (xy 48.422976 -301.07582)
			(xy 48.434753 -301.028036) (xy 48.454044 -300.98276) (xy 48.480347 -300.941164) (xy 48.512982 -300.904327)
			(xy 48.551103 -300.873202) (xy 48.593724 -300.848595) (xy 48.63974 -300.831143) (xy 48.687959 -300.821299)
			(xy 48.737134 -300.819318) (xy 48.785989 -300.82525) (xy 48.83326 -300.838942) (xy 48.877722 -300.86004)
			(xy 48.918225 -300.887996) (xy 48.953718 -300.922088) (xy 48.983283 -300.961432) (xy 49.006154 -301.005009)
			(xy 49.021738 -301.05169) (xy 49.029633 -301.100267) (xy 49.030128 -301.124874) (xy 49.368976 -301.124874)
			(xy 49.372936 -301.07582) (xy 49.384713 -301.028036) (xy 49.404004 -300.98276) (xy 49.430307 -300.941164)
			(xy 49.462942 -300.904327) (xy 49.501063 -300.873202) (xy 49.543684 -300.848595) (xy 49.5897 -300.831143)
			(xy 49.637919 -300.821299) (xy 49.687094 -300.819318) (xy 49.735949 -300.82525) (xy 49.78322 -300.838942)
			(xy 49.827682 -300.86004) (xy 49.868185 -300.887996) (xy 49.903678 -300.922088) (xy 49.933243 -300.961432)
			(xy 49.956114 -301.005009) (xy 49.971698 -301.05169) (xy 49.979593 -301.100267) (xy 49.980088 -301.124874)
			(xy 50.31919 -301.124874) (xy 50.32315 -301.07582) (xy 50.334927 -301.028036) (xy 50.354218 -300.98276)
			(xy 50.380521 -300.941164) (xy 50.413156 -300.904327) (xy 50.451277 -300.873202) (xy 50.493898 -300.848595)
			(xy 50.539914 -300.831143) (xy 50.588133 -300.821299) (xy 50.637308 -300.819318) (xy 50.686163 -300.82525)
			(xy 50.733434 -300.838942) (xy 50.777896 -300.86004) (xy 50.818399 -300.887996) (xy 50.853892 -300.922088)
			(xy 50.883457 -300.961432) (xy 50.906328 -301.005009) (xy 50.921912 -301.05169) (xy 50.929807 -301.100267)
			(xy 50.930302 -301.124874) (xy 51.26915 -301.124874) (xy 51.27311 -301.07582) (xy 51.284887 -301.028036)
			(xy 51.304178 -300.98276) (xy 51.330481 -300.941164) (xy 51.363116 -300.904327) (xy 51.401237 -300.873202)
			(xy 51.443858 -300.848595) (xy 51.489874 -300.831143) (xy 51.538093 -300.821299) (xy 51.587268 -300.819318)
			(xy 51.636123 -300.82525) (xy 51.683394 -300.838942) (xy 51.727856 -300.86004) (xy 51.768359 -300.887996)
			(xy 51.803852 -300.922088) (xy 51.833417 -300.961432) (xy 51.856288 -301.005009) (xy 51.871872 -301.05169)
			(xy 51.879767 -301.100267) (xy 51.880262 -301.124874) (xy 52.21911 -301.124874) (xy 52.22307 -301.07582)
			(xy 52.234847 -301.028036) (xy 52.254138 -300.98276) (xy 52.280441 -300.941164) (xy 52.313076 -300.904327)
			(xy 52.351197 -300.873202) (xy 52.393818 -300.848595) (xy 52.439834 -300.831143) (xy 52.488053 -300.821299)
			(xy 52.537228 -300.819318) (xy 52.586083 -300.82525) (xy 52.633354 -300.838942) (xy 52.677816 -300.86004)
			(xy 52.718319 -300.887996) (xy 52.753812 -300.922088) (xy 52.783377 -300.961432) (xy 52.806248 -301.005009)
			(xy 52.821832 -301.05169) (xy 52.829727 -301.100267) (xy 52.830222 -301.124874) (xy 53.16907 -301.124874)
			(xy 53.17303 -301.07582) (xy 53.184807 -301.028036) (xy 53.204098 -300.98276) (xy 53.230401 -300.941164)
			(xy 53.263036 -300.904327) (xy 53.301157 -300.873202) (xy 53.343778 -300.848595) (xy 53.389794 -300.831143)
			(xy 53.438013 -300.821299) (xy 53.487188 -300.819318) (xy 53.536043 -300.82525) (xy 53.583314 -300.838942)
			(xy 53.627776 -300.86004) (xy 53.668279 -300.887996) (xy 53.703772 -300.922088) (xy 53.733337 -300.961432)
			(xy 53.756208 -301.005009) (xy 53.771792 -301.05169) (xy 53.779687 -301.100267) (xy 53.780182 -301.124874)
			(xy 54.11903 -301.124874) (xy 54.12299 -301.07582) (xy 54.134767 -301.028036) (xy 54.154058 -300.98276)
			(xy 54.180361 -300.941164) (xy 54.212996 -300.904327) (xy 54.251117 -300.873202) (xy 54.293738 -300.848595)
			(xy 54.339754 -300.831143) (xy 54.387973 -300.821299) (xy 54.437148 -300.819318) (xy 54.486003 -300.82525)
			(xy 54.533274 -300.838942) (xy 54.577736 -300.86004) (xy 54.618239 -300.887996) (xy 54.653732 -300.922088)
			(xy 54.683297 -300.961432) (xy 54.706168 -301.005009) (xy 54.721752 -301.05169) (xy 54.729647 -301.100267)
			(xy 54.730142 -301.124874) (xy 55.06899 -301.124874) (xy 55.07295 -301.07582) (xy 55.084727 -301.028036)
			(xy 55.104018 -300.98276) (xy 55.130321 -300.941164) (xy 55.162956 -300.904327) (xy 55.201077 -300.873202)
			(xy 55.243698 -300.848595) (xy 55.289714 -300.831143) (xy 55.337933 -300.821299) (xy 55.387108 -300.819318)
			(xy 55.435963 -300.82525) (xy 55.483234 -300.838942) (xy 55.527696 -300.86004) (xy 55.568199 -300.887996)
			(xy 55.603692 -300.922088) (xy 55.633257 -300.961432) (xy 55.656128 -301.005009) (xy 55.671712 -301.05169)
			(xy 55.679607 -301.100267) (xy 55.680102 -301.124874) (xy 56.01895 -301.124874) (xy 56.02291 -301.07582)
			(xy 56.034687 -301.028036) (xy 56.053978 -300.98276) (xy 56.080281 -300.941164) (xy 56.112916 -300.904327)
			(xy 56.151037 -300.873202) (xy 56.193658 -300.848595) (xy 56.239674 -300.831143) (xy 56.287893 -300.821299)
			(xy 56.337068 -300.819318) (xy 56.385923 -300.82525) (xy 56.433194 -300.838942) (xy 56.477656 -300.86004)
			(xy 56.518159 -300.887996) (xy 56.553652 -300.922088) (xy 56.583217 -300.961432) (xy 56.606088 -301.005009)
			(xy 56.621672 -301.05169) (xy 56.629567 -301.100267) (xy 56.630062 -301.124874) (xy 56.969164 -301.124874)
			(xy 56.973124 -301.07582) (xy 56.984901 -301.028036) (xy 57.004192 -300.98276) (xy 57.030495 -300.941164)
			(xy 57.06313 -300.904327) (xy 57.101251 -300.873202) (xy 57.143872 -300.848595) (xy 57.189888 -300.831143)
			(xy 57.238107 -300.821299) (xy 57.287282 -300.819318) (xy 57.336137 -300.82525) (xy 57.383408 -300.838942)
			(xy 57.42787 -300.86004) (xy 57.468373 -300.887996) (xy 57.503866 -300.922088) (xy 57.533431 -300.961432)
			(xy 57.556302 -301.005009) (xy 57.571886 -301.05169) (xy 57.579781 -301.100267) (xy 57.580276 -301.124874)
			(xy 57.919124 -301.124874) (xy 57.923084 -301.07582) (xy 57.934861 -301.028036) (xy 57.954152 -300.98276)
			(xy 57.980455 -300.941164) (xy 58.01309 -300.904327) (xy 58.051211 -300.873202) (xy 58.093832 -300.848595)
			(xy 58.139848 -300.831143) (xy 58.188067 -300.821299) (xy 58.237242 -300.819318) (xy 58.286097 -300.82525)
			(xy 58.333368 -300.838942) (xy 58.37783 -300.86004) (xy 58.418333 -300.887996) (xy 58.453826 -300.922088)
			(xy 58.483391 -300.961432) (xy 58.506262 -301.005009) (xy 58.521846 -301.05169) (xy 58.529741 -301.100267)
			(xy 58.530236 -301.124874) (xy 59.819044 -301.124874) (xy 59.823004 -301.07582) (xy 59.834781 -301.028036)
			(xy 59.854072 -300.98276) (xy 59.880375 -300.941164) (xy 59.91301 -300.904327) (xy 59.951131 -300.873202)
			(xy 59.993752 -300.848595) (xy 60.039768 -300.831143) (xy 60.087987 -300.821299) (xy 60.137162 -300.819318)
			(xy 60.186017 -300.82525) (xy 60.233288 -300.838942) (xy 60.27775 -300.86004) (xy 60.318253 -300.887996)
			(xy 60.353746 -300.922088) (xy 60.383311 -300.961432) (xy 60.406182 -301.005009) (xy 60.421766 -301.05169)
			(xy 60.429661 -301.100267) (xy 60.430156 -301.124874) (xy 60.769004 -301.124874) (xy 60.772964 -301.07582)
			(xy 60.784741 -301.028036) (xy 60.804032 -300.98276) (xy 60.830335 -300.941164) (xy 60.86297 -300.904327)
			(xy 60.901091 -300.873202) (xy 60.943712 -300.848595) (xy 60.989728 -300.831143) (xy 61.037947 -300.821299)
			(xy 61.087122 -300.819318) (xy 61.135977 -300.82525) (xy 61.183248 -300.838942) (xy 61.22771 -300.86004)
			(xy 61.268213 -300.887996) (xy 61.303706 -300.922088) (xy 61.333271 -300.961432) (xy 61.356142 -301.005009)
			(xy 61.371726 -301.05169) (xy 61.379621 -301.100267) (xy 61.380116 -301.124874) (xy 61.718964 -301.124874)
			(xy 61.722924 -301.07582) (xy 61.734701 -301.028036) (xy 61.753992 -300.98276) (xy 61.780295 -300.941164)
			(xy 61.81293 -300.904327) (xy 61.851051 -300.873202) (xy 61.893672 -300.848595) (xy 61.939688 -300.831143)
			(xy 61.987907 -300.821299) (xy 62.037082 -300.819318) (xy 62.085937 -300.82525) (xy 62.133208 -300.838942)
			(xy 62.17767 -300.86004) (xy 62.218173 -300.887996) (xy 62.253666 -300.922088) (xy 62.283231 -300.961432)
			(xy 62.306102 -301.005009) (xy 62.321686 -301.05169) (xy 62.329581 -301.100267) (xy 62.330076 -301.124874)
			(xy 62.669178 -301.124874) (xy 62.673138 -301.07582) (xy 62.684915 -301.028036) (xy 62.704206 -300.98276)
			(xy 62.730509 -300.941164) (xy 62.763144 -300.904327) (xy 62.801265 -300.873202) (xy 62.843886 -300.848595)
			(xy 62.889902 -300.831143) (xy 62.938121 -300.821299) (xy 62.987296 -300.819318) (xy 63.036151 -300.82525)
			(xy 63.083422 -300.838942) (xy 63.127884 -300.86004) (xy 63.168387 -300.887996) (xy 63.20388 -300.922088)
			(xy 63.233445 -300.961432) (xy 63.256316 -301.005009) (xy 63.2719 -301.05169) (xy 63.279795 -301.100267)
			(xy 63.28029 -301.124874) (xy 63.619138 -301.124874) (xy 63.623098 -301.07582) (xy 63.634875 -301.028036)
			(xy 63.654166 -300.98276) (xy 63.680469 -300.941164) (xy 63.713104 -300.904327) (xy 63.751225 -300.873202)
			(xy 63.793846 -300.848595) (xy 63.839862 -300.831143) (xy 63.888081 -300.821299) (xy 63.937256 -300.819318)
			(xy 63.986111 -300.82525) (xy 64.033382 -300.838942) (xy 64.077844 -300.86004) (xy 64.118347 -300.887996)
			(xy 64.15384 -300.922088) (xy 64.183405 -300.961432) (xy 64.206276 -301.005009) (xy 64.22186 -301.05169)
			(xy 64.229755 -301.100267) (xy 64.23025 -301.124874) (xy 64.569098 -301.124874) (xy 64.573058 -301.07582)
			(xy 64.584835 -301.028036) (xy 64.604126 -300.98276) (xy 64.630429 -300.941164) (xy 64.663064 -300.904327)
			(xy 64.701185 -300.873202) (xy 64.743806 -300.848595) (xy 64.789822 -300.831143) (xy 64.838041 -300.821299)
			(xy 64.887216 -300.819318) (xy 64.936071 -300.82525) (xy 64.983342 -300.838942) (xy 65.027804 -300.86004)
			(xy 65.068307 -300.887996) (xy 65.1038 -300.922088) (xy 65.133365 -300.961432) (xy 65.156236 -301.005009)
			(xy 65.17182 -301.05169) (xy 65.179715 -301.100267) (xy 65.18021 -301.124874) (xy 65.519058 -301.124874)
			(xy 65.523018 -301.07582) (xy 65.534795 -301.028036) (xy 65.554086 -300.98276) (xy 65.580389 -300.941164)
			(xy 65.613024 -300.904327) (xy 65.651145 -300.873202) (xy 65.693766 -300.848595) (xy 65.739782 -300.831143)
			(xy 65.788001 -300.821299) (xy 65.837176 -300.819318) (xy 65.886031 -300.82525) (xy 65.933302 -300.838942)
			(xy 65.977764 -300.86004) (xy 66.018267 -300.887996) (xy 66.05376 -300.922088) (xy 66.083325 -300.961432)
			(xy 66.106196 -301.005009) (xy 66.12178 -301.05169) (xy 66.129675 -301.100267) (xy 66.13017 -301.124874)
			(xy 66.469018 -301.124874) (xy 66.472978 -301.07582) (xy 66.484755 -301.028036) (xy 66.504046 -300.98276)
			(xy 66.530349 -300.941164) (xy 66.562984 -300.904327) (xy 66.601105 -300.873202) (xy 66.643726 -300.848595)
			(xy 66.689742 -300.831143) (xy 66.737961 -300.821299) (xy 66.787136 -300.819318) (xy 66.835991 -300.82525)
			(xy 66.883262 -300.838942) (xy 66.927724 -300.86004) (xy 66.968227 -300.887996) (xy 67.00372 -300.922088)
			(xy 67.033285 -300.961432) (xy 67.056156 -301.005009) (xy 67.07174 -301.05169) (xy 67.079635 -301.100267)
			(xy 67.08013 -301.124874) (xy 67.418978 -301.124874) (xy 67.422938 -301.07582) (xy 67.434715 -301.028036)
			(xy 67.454006 -300.98276) (xy 67.480309 -300.941164) (xy 67.512944 -300.904327) (xy 67.551065 -300.873202)
			(xy 67.593686 -300.848595) (xy 67.639702 -300.831143) (xy 67.687921 -300.821299) (xy 67.737096 -300.819318)
			(xy 67.785951 -300.82525) (xy 67.833222 -300.838942) (xy 67.877684 -300.86004) (xy 67.918187 -300.887996)
			(xy 67.95368 -300.922088) (xy 67.983245 -300.961432) (xy 68.006116 -301.005009) (xy 68.0217 -301.05169)
			(xy 68.029595 -301.100267) (xy 68.03009 -301.124874) (xy 68.368938 -301.124874) (xy 68.372898 -301.07582)
			(xy 68.384675 -301.028036) (xy 68.403966 -300.98276) (xy 68.430269 -300.941164) (xy 68.462904 -300.904327)
			(xy 68.501025 -300.873202) (xy 68.543646 -300.848595) (xy 68.589662 -300.831143) (xy 68.637881 -300.821299)
			(xy 68.687056 -300.819318) (xy 68.735911 -300.82525) (xy 68.783182 -300.838942) (xy 68.827644 -300.86004)
			(xy 68.868147 -300.887996) (xy 68.90364 -300.922088) (xy 68.933205 -300.961432) (xy 68.956076 -301.005009)
			(xy 68.97166 -301.05169) (xy 68.979555 -301.100267) (xy 68.98005 -301.124874) (xy 68.979555 -301.149481)
			(xy 68.97166 -301.198058) (xy 68.956076 -301.244739) (xy 68.933205 -301.288316) (xy 68.90364 -301.32766)
			(xy 68.868147 -301.361752) (xy 68.827644 -301.389708) (xy 68.783182 -301.410806) (xy 68.735911 -301.424498)
			(xy 68.687056 -301.43043) (xy 68.637881 -301.428449) (xy 68.589662 -301.418605) (xy 68.543646 -301.401153)
			(xy 68.501025 -301.376546) (xy 68.462904 -301.345421) (xy 68.430269 -301.308584) (xy 68.403966 -301.266988)
			(xy 68.384675 -301.221712) (xy 68.372898 -301.173928) (xy 68.368938 -301.124874) (xy 68.03009 -301.124874)
			(xy 68.029595 -301.149481) (xy 68.0217 -301.198058) (xy 68.006116 -301.244739) (xy 67.983245 -301.288316)
			(xy 67.95368 -301.32766) (xy 67.918187 -301.361752) (xy 67.877684 -301.389708) (xy 67.833222 -301.410806)
			(xy 67.785951 -301.424498) (xy 67.737096 -301.43043) (xy 67.687921 -301.428449) (xy 67.639702 -301.418605)
			(xy 67.593686 -301.401153) (xy 67.551065 -301.376546) (xy 67.512944 -301.345421) (xy 67.480309 -301.308584)
			(xy 67.454006 -301.266988) (xy 67.434715 -301.221712) (xy 67.422938 -301.173928) (xy 67.418978 -301.124874)
			(xy 67.08013 -301.124874) (xy 67.079635 -301.149481) (xy 67.07174 -301.198058) (xy 67.056156 -301.244739)
			(xy 67.033285 -301.288316) (xy 67.00372 -301.32766) (xy 66.968227 -301.361752) (xy 66.927724 -301.389708)
			(xy 66.883262 -301.410806) (xy 66.835991 -301.424498) (xy 66.787136 -301.43043) (xy 66.737961 -301.428449)
			(xy 66.689742 -301.418605) (xy 66.643726 -301.401153) (xy 66.601105 -301.376546) (xy 66.562984 -301.345421)
			(xy 66.530349 -301.308584) (xy 66.504046 -301.266988) (xy 66.484755 -301.221712) (xy 66.472978 -301.173928)
			(xy 66.469018 -301.124874) (xy 66.13017 -301.124874) (xy 66.129675 -301.149481) (xy 66.12178 -301.198058)
			(xy 66.106196 -301.244739) (xy 66.083325 -301.288316) (xy 66.05376 -301.32766) (xy 66.018267 -301.361752)
			(xy 65.977764 -301.389708) (xy 65.933302 -301.410806) (xy 65.886031 -301.424498) (xy 65.837176 -301.43043)
			(xy 65.788001 -301.428449) (xy 65.739782 -301.418605) (xy 65.693766 -301.401153) (xy 65.651145 -301.376546)
			(xy 65.613024 -301.345421) (xy 65.580389 -301.308584) (xy 65.554086 -301.266988) (xy 65.534795 -301.221712)
			(xy 65.523018 -301.173928) (xy 65.519058 -301.124874) (xy 65.18021 -301.124874) (xy 65.179715 -301.149481)
			(xy 65.17182 -301.198058) (xy 65.156236 -301.244739) (xy 65.133365 -301.288316) (xy 65.1038 -301.32766)
			(xy 65.068307 -301.361752) (xy 65.027804 -301.389708) (xy 64.983342 -301.410806) (xy 64.936071 -301.424498)
			(xy 64.887216 -301.43043) (xy 64.838041 -301.428449) (xy 64.789822 -301.418605) (xy 64.743806 -301.401153)
			(xy 64.701185 -301.376546) (xy 64.663064 -301.345421) (xy 64.630429 -301.308584) (xy 64.604126 -301.266988)
			(xy 64.584835 -301.221712) (xy 64.573058 -301.173928) (xy 64.569098 -301.124874) (xy 64.23025 -301.124874)
			(xy 64.229755 -301.149481) (xy 64.22186 -301.198058) (xy 64.206276 -301.244739) (xy 64.183405 -301.288316)
			(xy 64.15384 -301.32766) (xy 64.118347 -301.361752) (xy 64.077844 -301.389708) (xy 64.033382 -301.410806)
			(xy 63.986111 -301.424498) (xy 63.937256 -301.43043) (xy 63.888081 -301.428449) (xy 63.839862 -301.418605)
			(xy 63.793846 -301.401153) (xy 63.751225 -301.376546) (xy 63.713104 -301.345421) (xy 63.680469 -301.308584)
			(xy 63.654166 -301.266988) (xy 63.634875 -301.221712) (xy 63.623098 -301.173928) (xy 63.619138 -301.124874)
			(xy 63.28029 -301.124874) (xy 63.279795 -301.149481) (xy 63.2719 -301.198058) (xy 63.256316 -301.244739)
			(xy 63.233445 -301.288316) (xy 63.20388 -301.32766) (xy 63.168387 -301.361752) (xy 63.127884 -301.389708)
			(xy 63.083422 -301.410806) (xy 63.036151 -301.424498) (xy 62.987296 -301.43043) (xy 62.938121 -301.428449)
			(xy 62.889902 -301.418605) (xy 62.843886 -301.401153) (xy 62.801265 -301.376546) (xy 62.763144 -301.345421)
			(xy 62.730509 -301.308584) (xy 62.704206 -301.266988) (xy 62.684915 -301.221712) (xy 62.673138 -301.173928)
			(xy 62.669178 -301.124874) (xy 62.330076 -301.124874) (xy 62.329581 -301.149481) (xy 62.321686 -301.198058)
			(xy 62.306102 -301.244739) (xy 62.283231 -301.288316) (xy 62.253666 -301.32766) (xy 62.218173 -301.361752)
			(xy 62.17767 -301.389708) (xy 62.133208 -301.410806) (xy 62.085937 -301.424498) (xy 62.037082 -301.43043)
			(xy 61.987907 -301.428449) (xy 61.939688 -301.418605) (xy 61.893672 -301.401153) (xy 61.851051 -301.376546)
			(xy 61.81293 -301.345421) (xy 61.780295 -301.308584) (xy 61.753992 -301.266988) (xy 61.734701 -301.221712)
			(xy 61.722924 -301.173928) (xy 61.718964 -301.124874) (xy 61.380116 -301.124874) (xy 61.379621 -301.149481)
			(xy 61.371726 -301.198058) (xy 61.356142 -301.244739) (xy 61.333271 -301.288316) (xy 61.303706 -301.32766)
			(xy 61.268213 -301.361752) (xy 61.22771 -301.389708) (xy 61.183248 -301.410806) (xy 61.135977 -301.424498)
			(xy 61.087122 -301.43043) (xy 61.037947 -301.428449) (xy 60.989728 -301.418605) (xy 60.943712 -301.401153)
			(xy 60.901091 -301.376546) (xy 60.86297 -301.345421) (xy 60.830335 -301.308584) (xy 60.804032 -301.266988)
			(xy 60.784741 -301.221712) (xy 60.772964 -301.173928) (xy 60.769004 -301.124874) (xy 60.430156 -301.124874)
			(xy 60.429661 -301.149481) (xy 60.421766 -301.198058) (xy 60.406182 -301.244739) (xy 60.383311 -301.288316)
			(xy 60.353746 -301.32766) (xy 60.318253 -301.361752) (xy 60.27775 -301.389708) (xy 60.233288 -301.410806)
			(xy 60.186017 -301.424498) (xy 60.137162 -301.43043) (xy 60.087987 -301.428449) (xy 60.039768 -301.418605)
			(xy 59.993752 -301.401153) (xy 59.951131 -301.376546) (xy 59.91301 -301.345421) (xy 59.880375 -301.308584)
			(xy 59.854072 -301.266988) (xy 59.834781 -301.221712) (xy 59.823004 -301.173928) (xy 59.819044 -301.124874)
			(xy 58.530236 -301.124874) (xy 58.529741 -301.149481) (xy 58.521846 -301.198058) (xy 58.506262 -301.244739)
			(xy 58.483391 -301.288316) (xy 58.453826 -301.32766) (xy 58.418333 -301.361752) (xy 58.37783 -301.389708)
			(xy 58.333368 -301.410806) (xy 58.286097 -301.424498) (xy 58.237242 -301.43043) (xy 58.188067 -301.428449)
			(xy 58.139848 -301.418605) (xy 58.093832 -301.401153) (xy 58.051211 -301.376546) (xy 58.01309 -301.345421)
			(xy 57.980455 -301.308584) (xy 57.954152 -301.266988) (xy 57.934861 -301.221712) (xy 57.923084 -301.173928)
			(xy 57.919124 -301.124874) (xy 57.580276 -301.124874) (xy 57.579781 -301.149481) (xy 57.571886 -301.198058)
			(xy 57.556302 -301.244739) (xy 57.533431 -301.288316) (xy 57.503866 -301.32766) (xy 57.468373 -301.361752)
			(xy 57.42787 -301.389708) (xy 57.383408 -301.410806) (xy 57.336137 -301.424498) (xy 57.287282 -301.43043)
			(xy 57.238107 -301.428449) (xy 57.189888 -301.418605) (xy 57.143872 -301.401153) (xy 57.101251 -301.376546)
			(xy 57.06313 -301.345421) (xy 57.030495 -301.308584) (xy 57.004192 -301.266988) (xy 56.984901 -301.221712)
			(xy 56.973124 -301.173928) (xy 56.969164 -301.124874) (xy 56.630062 -301.124874) (xy 56.629567 -301.149481)
			(xy 56.621672 -301.198058) (xy 56.606088 -301.244739) (xy 56.583217 -301.288316) (xy 56.553652 -301.32766)
			(xy 56.518159 -301.361752) (xy 56.477656 -301.389708) (xy 56.433194 -301.410806) (xy 56.385923 -301.424498)
			(xy 56.337068 -301.43043) (xy 56.287893 -301.428449) (xy 56.239674 -301.418605) (xy 56.193658 -301.401153)
			(xy 56.151037 -301.376546) (xy 56.112916 -301.345421) (xy 56.080281 -301.308584) (xy 56.053978 -301.266988)
			(xy 56.034687 -301.221712) (xy 56.02291 -301.173928) (xy 56.01895 -301.124874) (xy 55.680102 -301.124874)
			(xy 55.679607 -301.149481) (xy 55.671712 -301.198058) (xy 55.656128 -301.244739) (xy 55.633257 -301.288316)
			(xy 55.603692 -301.32766) (xy 55.568199 -301.361752) (xy 55.527696 -301.389708) (xy 55.483234 -301.410806)
			(xy 55.435963 -301.424498) (xy 55.387108 -301.43043) (xy 55.337933 -301.428449) (xy 55.289714 -301.418605)
			(xy 55.243698 -301.401153) (xy 55.201077 -301.376546) (xy 55.162956 -301.345421) (xy 55.130321 -301.308584)
			(xy 55.104018 -301.266988) (xy 55.084727 -301.221712) (xy 55.07295 -301.173928) (xy 55.06899 -301.124874)
			(xy 54.730142 -301.124874) (xy 54.729647 -301.149481) (xy 54.721752 -301.198058) (xy 54.706168 -301.244739)
			(xy 54.683297 -301.288316) (xy 54.653732 -301.32766) (xy 54.618239 -301.361752) (xy 54.577736 -301.389708)
			(xy 54.533274 -301.410806) (xy 54.486003 -301.424498) (xy 54.437148 -301.43043) (xy 54.387973 -301.428449)
			(xy 54.339754 -301.418605) (xy 54.293738 -301.401153) (xy 54.251117 -301.376546) (xy 54.212996 -301.345421)
			(xy 54.180361 -301.308584) (xy 54.154058 -301.266988) (xy 54.134767 -301.221712) (xy 54.12299 -301.173928)
			(xy 54.11903 -301.124874) (xy 53.780182 -301.124874) (xy 53.779687 -301.149481) (xy 53.771792 -301.198058)
			(xy 53.756208 -301.244739) (xy 53.733337 -301.288316) (xy 53.703772 -301.32766) (xy 53.668279 -301.361752)
			(xy 53.627776 -301.389708) (xy 53.583314 -301.410806) (xy 53.536043 -301.424498) (xy 53.487188 -301.43043)
			(xy 53.438013 -301.428449) (xy 53.389794 -301.418605) (xy 53.343778 -301.401153) (xy 53.301157 -301.376546)
			(xy 53.263036 -301.345421) (xy 53.230401 -301.308584) (xy 53.204098 -301.266988) (xy 53.184807 -301.221712)
			(xy 53.17303 -301.173928) (xy 53.16907 -301.124874) (xy 52.830222 -301.124874) (xy 52.829727 -301.149481)
			(xy 52.821832 -301.198058) (xy 52.806248 -301.244739) (xy 52.783377 -301.288316) (xy 52.753812 -301.32766)
			(xy 52.718319 -301.361752) (xy 52.677816 -301.389708) (xy 52.633354 -301.410806) (xy 52.586083 -301.424498)
			(xy 52.537228 -301.43043) (xy 52.488053 -301.428449) (xy 52.439834 -301.418605) (xy 52.393818 -301.401153)
			(xy 52.351197 -301.376546) (xy 52.313076 -301.345421) (xy 52.280441 -301.308584) (xy 52.254138 -301.266988)
			(xy 52.234847 -301.221712) (xy 52.22307 -301.173928) (xy 52.21911 -301.124874) (xy 51.880262 -301.124874)
			(xy 51.879767 -301.149481) (xy 51.871872 -301.198058) (xy 51.856288 -301.244739) (xy 51.833417 -301.288316)
			(xy 51.803852 -301.32766) (xy 51.768359 -301.361752) (xy 51.727856 -301.389708) (xy 51.683394 -301.410806)
			(xy 51.636123 -301.424498) (xy 51.587268 -301.43043) (xy 51.538093 -301.428449) (xy 51.489874 -301.418605)
			(xy 51.443858 -301.401153) (xy 51.401237 -301.376546) (xy 51.363116 -301.345421) (xy 51.330481 -301.308584)
			(xy 51.304178 -301.266988) (xy 51.284887 -301.221712) (xy 51.27311 -301.173928) (xy 51.26915 -301.124874)
			(xy 50.930302 -301.124874) (xy 50.929807 -301.149481) (xy 50.921912 -301.198058) (xy 50.906328 -301.244739)
			(xy 50.883457 -301.288316) (xy 50.853892 -301.32766) (xy 50.818399 -301.361752) (xy 50.777896 -301.389708)
			(xy 50.733434 -301.410806) (xy 50.686163 -301.424498) (xy 50.637308 -301.43043) (xy 50.588133 -301.428449)
			(xy 50.539914 -301.418605) (xy 50.493898 -301.401153) (xy 50.451277 -301.376546) (xy 50.413156 -301.345421)
			(xy 50.380521 -301.308584) (xy 50.354218 -301.266988) (xy 50.334927 -301.221712) (xy 50.32315 -301.173928)
			(xy 50.31919 -301.124874) (xy 49.980088 -301.124874) (xy 49.979593 -301.149481) (xy 49.971698 -301.198058)
			(xy 49.956114 -301.244739) (xy 49.933243 -301.288316) (xy 49.903678 -301.32766) (xy 49.868185 -301.361752)
			(xy 49.827682 -301.389708) (xy 49.78322 -301.410806) (xy 49.735949 -301.424498) (xy 49.687094 -301.43043)
			(xy 49.637919 -301.428449) (xy 49.5897 -301.418605) (xy 49.543684 -301.401153) (xy 49.501063 -301.376546)
			(xy 49.462942 -301.345421) (xy 49.430307 -301.308584) (xy 49.404004 -301.266988) (xy 49.384713 -301.221712)
			(xy 49.372936 -301.173928) (xy 49.368976 -301.124874) (xy 49.030128 -301.124874) (xy 49.029633 -301.149481)
			(xy 49.021738 -301.198058) (xy 49.006154 -301.244739) (xy 48.983283 -301.288316) (xy 48.953718 -301.32766)
			(xy 48.918225 -301.361752) (xy 48.877722 -301.389708) (xy 48.83326 -301.410806) (xy 48.785989 -301.424498)
			(xy 48.737134 -301.43043) (xy 48.687959 -301.428449) (xy 48.63974 -301.418605) (xy 48.593724 -301.401153)
			(xy 48.551103 -301.376546) (xy 48.512982 -301.345421) (xy 48.480347 -301.308584) (xy 48.454044 -301.266988)
			(xy 48.434753 -301.221712) (xy 48.422976 -301.173928) (xy 48.419016 -301.124874) (xy 48.080168 -301.124874)
			(xy 48.079673 -301.149481) (xy 48.071778 -301.198058) (xy 48.056194 -301.244739) (xy 48.033323 -301.288316)
			(xy 48.003758 -301.32766) (xy 47.968265 -301.361752) (xy 47.927762 -301.389708) (xy 47.8833 -301.410806)
			(xy 47.836029 -301.424498) (xy 47.787174 -301.43043) (xy 47.737999 -301.428449) (xy 47.68978 -301.418605)
			(xy 47.643764 -301.401153) (xy 47.601143 -301.376546) (xy 47.563022 -301.345421) (xy 47.530387 -301.308584)
			(xy 47.504084 -301.266988) (xy 47.484793 -301.221712) (xy 47.473016 -301.173928) (xy 47.469056 -301.124874)
			(xy 46.205163 -301.124874) (xy 46.204761 -301.154393) (xy 46.201076 -301.17923) (xy 46.199044 -301.191168)
			(xy 46.206156 -301.213774) (xy 46.279054 -301.290228) (xy 46.301406 -301.298102) (xy 46.313598 -301.296832)
			(xy 46.322642 -301.295784) (xy 46.340816 -301.294642) (xy 46.34992 -301.294546) (xy 46.375178 -301.295069)
			(xy 46.425005 -301.303386) (xy 46.472783 -301.319791) (xy 46.51721 -301.343837) (xy 46.557073 -301.374866)
			(xy 46.591286 -301.412033) (xy 46.618914 -301.454324) (xy 46.639206 -301.500586) (xy 46.651606 -301.549556)
			(xy 46.655778 -301.5999) (xy 46.651606 -301.650244) (xy 46.639206 -301.699214) (xy 46.618914 -301.745476)
			(xy 46.591286 -301.787767) (xy 46.557073 -301.824934) (xy 46.51721 -301.855963) (xy 46.472783 -301.880009)
			(xy 46.425005 -301.896414) (xy 46.375178 -301.904731) (xy 46.34992 -301.905162) (xy 46.340816 -301.905063)
			(xy 46.322643 -301.903917) (xy 46.313598 -301.902876) (xy 46.301406 -301.901606) (xy 46.279054 -301.90948)
			(xy 46.206156 -301.985934) (xy 46.199298 -302.00854) (xy 46.20133 -302.020478) (xy 46.2032 -302.032523)
			(xy 46.205364 -302.056806) (xy 46.205648 -302.068992) (xy 46.205798 -302.074834) (xy 49.368976 -302.074834)
			(xy 49.372936 -302.02578) (xy 49.384713 -301.977996) (xy 49.404004 -301.93272) (xy 49.430307 -301.891124)
			(xy 49.462942 -301.854287) (xy 49.501063 -301.823162) (xy 49.543684 -301.798555) (xy 49.5897 -301.781103)
			(xy 49.637919 -301.771259) (xy 49.687094 -301.769278) (xy 49.735949 -301.77521) (xy 49.78322 -301.788902)
			(xy 49.827682 -301.81) (xy 49.868185 -301.837956) (xy 49.903678 -301.872048) (xy 49.933243 -301.911392)
			(xy 49.956114 -301.954969) (xy 49.971698 -302.00165) (xy 49.979593 -302.050227) (xy 49.980088 -302.074834)
			(xy 50.31919 -302.074834) (xy 50.32315 -302.02578) (xy 50.334927 -301.977996) (xy 50.354218 -301.93272)
			(xy 50.380521 -301.891124) (xy 50.413156 -301.854287) (xy 50.451277 -301.823162) (xy 50.493898 -301.798555)
			(xy 50.539914 -301.781103) (xy 50.588133 -301.771259) (xy 50.637308 -301.769278) (xy 50.686163 -301.77521)
			(xy 50.733434 -301.788902) (xy 50.777896 -301.81) (xy 50.818399 -301.837956) (xy 50.853892 -301.872048)
			(xy 50.883457 -301.911392) (xy 50.906328 -301.954969) (xy 50.921912 -302.00165) (xy 50.929807 -302.050227)
			(xy 50.930302 -302.074834) (xy 51.26915 -302.074834) (xy 51.27311 -302.02578) (xy 51.284887 -301.977996)
			(xy 51.304178 -301.93272) (xy 51.330481 -301.891124) (xy 51.363116 -301.854287) (xy 51.401237 -301.823162)
			(xy 51.443858 -301.798555) (xy 51.489874 -301.781103) (xy 51.538093 -301.771259) (xy 51.587268 -301.769278)
			(xy 51.636123 -301.77521) (xy 51.683394 -301.788902) (xy 51.727856 -301.81) (xy 51.768359 -301.837956)
			(xy 51.803852 -301.872048) (xy 51.833417 -301.911392) (xy 51.856288 -301.954969) (xy 51.871872 -302.00165)
			(xy 51.879767 -302.050227) (xy 51.880262 -302.074834) (xy 52.21911 -302.074834) (xy 52.22307 -302.02578)
			(xy 52.234847 -301.977996) (xy 52.254138 -301.93272) (xy 52.280441 -301.891124) (xy 52.313076 -301.854287)
			(xy 52.351197 -301.823162) (xy 52.393818 -301.798555) (xy 52.439834 -301.781103) (xy 52.488053 -301.771259)
			(xy 52.537228 -301.769278) (xy 52.586083 -301.77521) (xy 52.633354 -301.788902) (xy 52.677816 -301.81)
			(xy 52.718319 -301.837956) (xy 52.753812 -301.872048) (xy 52.783377 -301.911392) (xy 52.806248 -301.954969)
			(xy 52.821832 -302.00165) (xy 52.829727 -302.050227) (xy 52.830222 -302.074834) (xy 53.16907 -302.074834)
			(xy 53.17303 -302.02578) (xy 53.184807 -301.977996) (xy 53.204098 -301.93272) (xy 53.230401 -301.891124)
			(xy 53.263036 -301.854287) (xy 53.301157 -301.823162) (xy 53.343778 -301.798555) (xy 53.389794 -301.781103)
			(xy 53.438013 -301.771259) (xy 53.487188 -301.769278) (xy 53.536043 -301.77521) (xy 53.583314 -301.788902)
			(xy 53.627776 -301.81) (xy 53.668279 -301.837956) (xy 53.703772 -301.872048) (xy 53.733337 -301.911392)
			(xy 53.756208 -301.954969) (xy 53.771792 -302.00165) (xy 53.779687 -302.050227) (xy 53.780182 -302.074834)
			(xy 54.11903 -302.074834) (xy 54.12299 -302.02578) (xy 54.134767 -301.977996) (xy 54.154058 -301.93272)
			(xy 54.180361 -301.891124) (xy 54.212996 -301.854287) (xy 54.251117 -301.823162) (xy 54.293738 -301.798555)
			(xy 54.339754 -301.781103) (xy 54.387973 -301.771259) (xy 54.437148 -301.769278) (xy 54.486003 -301.77521)
			(xy 54.533274 -301.788902) (xy 54.577736 -301.81) (xy 54.618239 -301.837956) (xy 54.653732 -301.872048)
			(xy 54.683297 -301.911392) (xy 54.706168 -301.954969) (xy 54.721752 -302.00165) (xy 54.729647 -302.050227)
			(xy 54.730142 -302.074834) (xy 55.06899 -302.074834) (xy 55.07295 -302.02578) (xy 55.084727 -301.977996)
			(xy 55.104018 -301.93272) (xy 55.130321 -301.891124) (xy 55.162956 -301.854287) (xy 55.201077 -301.823162)
			(xy 55.243698 -301.798555) (xy 55.289714 -301.781103) (xy 55.337933 -301.771259) (xy 55.387108 -301.769278)
			(xy 55.435963 -301.77521) (xy 55.483234 -301.788902) (xy 55.527696 -301.81) (xy 55.568199 -301.837956)
			(xy 55.603692 -301.872048) (xy 55.633257 -301.911392) (xy 55.656128 -301.954969) (xy 55.671712 -302.00165)
			(xy 55.679607 -302.050227) (xy 55.680102 -302.074834) (xy 56.01895 -302.074834) (xy 56.02291 -302.02578)
			(xy 56.034687 -301.977996) (xy 56.053978 -301.93272) (xy 56.080281 -301.891124) (xy 56.112916 -301.854287)
			(xy 56.151037 -301.823162) (xy 56.193658 -301.798555) (xy 56.239674 -301.781103) (xy 56.287893 -301.771259)
			(xy 56.337068 -301.769278) (xy 56.385923 -301.77521) (xy 56.433194 -301.788902) (xy 56.477656 -301.81)
			(xy 56.518159 -301.837956) (xy 56.553652 -301.872048) (xy 56.583217 -301.911392) (xy 56.606088 -301.954969)
			(xy 56.621672 -302.00165) (xy 56.629567 -302.050227) (xy 56.630062 -302.074834) (xy 56.969164 -302.074834)
			(xy 56.973124 -302.02578) (xy 56.984901 -301.977996) (xy 57.004192 -301.93272) (xy 57.030495 -301.891124)
			(xy 57.06313 -301.854287) (xy 57.101251 -301.823162) (xy 57.143872 -301.798555) (xy 57.189888 -301.781103)
			(xy 57.238107 -301.771259) (xy 57.287282 -301.769278) (xy 57.336137 -301.77521) (xy 57.383408 -301.788902)
			(xy 57.42787 -301.81) (xy 57.468373 -301.837956) (xy 57.503866 -301.872048) (xy 57.533431 -301.911392)
			(xy 57.556302 -301.954969) (xy 57.571886 -302.00165) (xy 57.579781 -302.050227) (xy 57.580276 -302.074834)
			(xy 57.919124 -302.074834) (xy 57.923084 -302.02578) (xy 57.934861 -301.977996) (xy 57.954152 -301.93272)
			(xy 57.980455 -301.891124) (xy 58.01309 -301.854287) (xy 58.051211 -301.823162) (xy 58.093832 -301.798555)
			(xy 58.139848 -301.781103) (xy 58.188067 -301.771259) (xy 58.237242 -301.769278) (xy 58.286097 -301.77521)
			(xy 58.333368 -301.788902) (xy 58.37783 -301.81) (xy 58.418333 -301.837956) (xy 58.453826 -301.872048)
			(xy 58.483391 -301.911392) (xy 58.506262 -301.954969) (xy 58.521846 -302.00165) (xy 58.529741 -302.050227)
			(xy 58.530236 -302.074834) (xy 59.819044 -302.074834) (xy 59.823004 -302.02578) (xy 59.834781 -301.977996)
			(xy 59.854072 -301.93272) (xy 59.880375 -301.891124) (xy 59.91301 -301.854287) (xy 59.951131 -301.823162)
			(xy 59.993752 -301.798555) (xy 60.039768 -301.781103) (xy 60.087987 -301.771259) (xy 60.137162 -301.769278)
			(xy 60.186017 -301.77521) (xy 60.233288 -301.788902) (xy 60.27775 -301.81) (xy 60.318253 -301.837956)
			(xy 60.353746 -301.872048) (xy 60.383311 -301.911392) (xy 60.406182 -301.954969) (xy 60.421766 -302.00165)
			(xy 60.429661 -302.050227) (xy 60.430156 -302.074834) (xy 60.769004 -302.074834) (xy 60.772964 -302.02578)
			(xy 60.784741 -301.977996) (xy 60.804032 -301.93272) (xy 60.830335 -301.891124) (xy 60.86297 -301.854287)
			(xy 60.901091 -301.823162) (xy 60.943712 -301.798555) (xy 60.989728 -301.781103) (xy 61.037947 -301.771259)
			(xy 61.087122 -301.769278) (xy 61.135977 -301.77521) (xy 61.183248 -301.788902) (xy 61.22771 -301.81)
			(xy 61.268213 -301.837956) (xy 61.303706 -301.872048) (xy 61.333271 -301.911392) (xy 61.356142 -301.954969)
			(xy 61.371726 -302.00165) (xy 61.379621 -302.050227) (xy 61.380116 -302.074834) (xy 61.718964 -302.074834)
			(xy 61.722924 -302.02578) (xy 61.734701 -301.977996) (xy 61.753992 -301.93272) (xy 61.780295 -301.891124)
			(xy 61.81293 -301.854287) (xy 61.851051 -301.823162) (xy 61.893672 -301.798555) (xy 61.939688 -301.781103)
			(xy 61.987907 -301.771259) (xy 62.037082 -301.769278) (xy 62.085937 -301.77521) (xy 62.133208 -301.788902)
			(xy 62.17767 -301.81) (xy 62.218173 -301.837956) (xy 62.253666 -301.872048) (xy 62.283231 -301.911392)
			(xy 62.306102 -301.954969) (xy 62.321686 -302.00165) (xy 62.329581 -302.050227) (xy 62.330076 -302.074834)
			(xy 62.669178 -302.074834) (xy 62.673138 -302.02578) (xy 62.684915 -301.977996) (xy 62.704206 -301.93272)
			(xy 62.730509 -301.891124) (xy 62.763144 -301.854287) (xy 62.801265 -301.823162) (xy 62.843886 -301.798555)
			(xy 62.889902 -301.781103) (xy 62.938121 -301.771259) (xy 62.987296 -301.769278) (xy 63.036151 -301.77521)
			(xy 63.083422 -301.788902) (xy 63.127884 -301.81) (xy 63.168387 -301.837956) (xy 63.20388 -301.872048)
			(xy 63.233445 -301.911392) (xy 63.256316 -301.954969) (xy 63.2719 -302.00165) (xy 63.279795 -302.050227)
			(xy 63.28029 -302.074834) (xy 63.619138 -302.074834) (xy 63.623098 -302.02578) (xy 63.634875 -301.977996)
			(xy 63.654166 -301.93272) (xy 63.680469 -301.891124) (xy 63.713104 -301.854287) (xy 63.751225 -301.823162)
			(xy 63.793846 -301.798555) (xy 63.839862 -301.781103) (xy 63.888081 -301.771259) (xy 63.937256 -301.769278)
			(xy 63.986111 -301.77521) (xy 64.033382 -301.788902) (xy 64.077844 -301.81) (xy 64.118347 -301.837956)
			(xy 64.15384 -301.872048) (xy 64.183405 -301.911392) (xy 64.206276 -301.954969) (xy 64.22186 -302.00165)
			(xy 64.229755 -302.050227) (xy 64.23025 -302.074834) (xy 64.569098 -302.074834) (xy 64.573058 -302.02578)
			(xy 64.584835 -301.977996) (xy 64.604126 -301.93272) (xy 64.630429 -301.891124) (xy 64.663064 -301.854287)
			(xy 64.701185 -301.823162) (xy 64.743806 -301.798555) (xy 64.789822 -301.781103) (xy 64.838041 -301.771259)
			(xy 64.887216 -301.769278) (xy 64.936071 -301.77521) (xy 64.983342 -301.788902) (xy 65.027804 -301.81)
			(xy 65.068307 -301.837956) (xy 65.1038 -301.872048) (xy 65.133365 -301.911392) (xy 65.156236 -301.954969)
			(xy 65.17182 -302.00165) (xy 65.179715 -302.050227) (xy 65.18021 -302.074834) (xy 65.519058 -302.074834)
			(xy 65.523018 -302.02578) (xy 65.534795 -301.977996) (xy 65.554086 -301.93272) (xy 65.580389 -301.891124)
			(xy 65.613024 -301.854287) (xy 65.651145 -301.823162) (xy 65.693766 -301.798555) (xy 65.739782 -301.781103)
			(xy 65.788001 -301.771259) (xy 65.837176 -301.769278) (xy 65.886031 -301.77521) (xy 65.933302 -301.788902)
			(xy 65.977764 -301.81) (xy 66.018267 -301.837956) (xy 66.05376 -301.872048) (xy 66.083325 -301.911392)
			(xy 66.106196 -301.954969) (xy 66.12178 -302.00165) (xy 66.129675 -302.050227) (xy 66.13017 -302.074834)
			(xy 66.469018 -302.074834) (xy 66.472978 -302.02578) (xy 66.484755 -301.977996) (xy 66.504046 -301.93272)
			(xy 66.530349 -301.891124) (xy 66.562984 -301.854287) (xy 66.601105 -301.823162) (xy 66.643726 -301.798555)
			(xy 66.689742 -301.781103) (xy 66.737961 -301.771259) (xy 66.787136 -301.769278) (xy 66.835991 -301.77521)
			(xy 66.883262 -301.788902) (xy 66.927724 -301.81) (xy 66.968227 -301.837956) (xy 67.00372 -301.872048)
			(xy 67.033285 -301.911392) (xy 67.056156 -301.954969) (xy 67.07174 -302.00165) (xy 67.079635 -302.050227)
			(xy 67.08013 -302.074834) (xy 67.418978 -302.074834) (xy 67.422938 -302.02578) (xy 67.434715 -301.977996)
			(xy 67.454006 -301.93272) (xy 67.480309 -301.891124) (xy 67.512944 -301.854287) (xy 67.551065 -301.823162)
			(xy 67.593686 -301.798555) (xy 67.639702 -301.781103) (xy 67.687921 -301.771259) (xy 67.737096 -301.769278)
			(xy 67.785951 -301.77521) (xy 67.833222 -301.788902) (xy 67.877684 -301.81) (xy 67.918187 -301.837956)
			(xy 67.95368 -301.872048) (xy 67.983245 -301.911392) (xy 68.006116 -301.954969) (xy 68.0217 -302.00165)
			(xy 68.029595 -302.050227) (xy 68.03009 -302.074834) (xy 68.368938 -302.074834) (xy 68.372898 -302.02578)
			(xy 68.384675 -301.977996) (xy 68.403966 -301.93272) (xy 68.430269 -301.891124) (xy 68.462904 -301.854287)
			(xy 68.501025 -301.823162) (xy 68.543646 -301.798555) (xy 68.589662 -301.781103) (xy 68.637881 -301.771259)
			(xy 68.687056 -301.769278) (xy 68.735911 -301.77521) (xy 68.783182 -301.788902) (xy 68.827644 -301.81)
			(xy 68.868147 -301.837956) (xy 68.90364 -301.872048) (xy 68.933205 -301.911392) (xy 68.956076 -301.954969)
			(xy 68.97166 -302.00165) (xy 68.979555 -302.050227) (xy 68.98005 -302.074834) (xy 68.979555 -302.099441)
			(xy 68.97166 -302.148018) (xy 68.956076 -302.194699) (xy 68.933205 -302.238276) (xy 68.90364 -302.27762)
			(xy 68.868147 -302.311712) (xy 68.827644 -302.339668) (xy 68.783182 -302.360766) (xy 68.735911 -302.374458)
			(xy 68.687056 -302.38039) (xy 68.637881 -302.378409) (xy 68.589662 -302.368565) (xy 68.543646 -302.351113)
			(xy 68.501025 -302.326506) (xy 68.462904 -302.295381) (xy 68.430269 -302.258544) (xy 68.403966 -302.216948)
			(xy 68.384675 -302.171672) (xy 68.372898 -302.123888) (xy 68.368938 -302.074834) (xy 68.03009 -302.074834)
			(xy 68.029595 -302.099441) (xy 68.0217 -302.148018) (xy 68.006116 -302.194699) (xy 67.983245 -302.238276)
			(xy 67.95368 -302.27762) (xy 67.918187 -302.311712) (xy 67.877684 -302.339668) (xy 67.833222 -302.360766)
			(xy 67.785951 -302.374458) (xy 67.737096 -302.38039) (xy 67.687921 -302.378409) (xy 67.639702 -302.368565)
			(xy 67.593686 -302.351113) (xy 67.551065 -302.326506) (xy 67.512944 -302.295381) (xy 67.480309 -302.258544)
			(xy 67.454006 -302.216948) (xy 67.434715 -302.171672) (xy 67.422938 -302.123888) (xy 67.418978 -302.074834)
			(xy 67.08013 -302.074834) (xy 67.079635 -302.099441) (xy 67.07174 -302.148018) (xy 67.056156 -302.194699)
			(xy 67.033285 -302.238276) (xy 67.00372 -302.27762) (xy 66.968227 -302.311712) (xy 66.927724 -302.339668)
			(xy 66.883262 -302.360766) (xy 66.835991 -302.374458) (xy 66.787136 -302.38039) (xy 66.737961 -302.378409)
			(xy 66.689742 -302.368565) (xy 66.643726 -302.351113) (xy 66.601105 -302.326506) (xy 66.562984 -302.295381)
			(xy 66.530349 -302.258544) (xy 66.504046 -302.216948) (xy 66.484755 -302.171672) (xy 66.472978 -302.123888)
			(xy 66.469018 -302.074834) (xy 66.13017 -302.074834) (xy 66.129675 -302.099441) (xy 66.12178 -302.148018)
			(xy 66.106196 -302.194699) (xy 66.083325 -302.238276) (xy 66.05376 -302.27762) (xy 66.018267 -302.311712)
			(xy 65.977764 -302.339668) (xy 65.933302 -302.360766) (xy 65.886031 -302.374458) (xy 65.837176 -302.38039)
			(xy 65.788001 -302.378409) (xy 65.739782 -302.368565) (xy 65.693766 -302.351113) (xy 65.651145 -302.326506)
			(xy 65.613024 -302.295381) (xy 65.580389 -302.258544) (xy 65.554086 -302.216948) (xy 65.534795 -302.171672)
			(xy 65.523018 -302.123888) (xy 65.519058 -302.074834) (xy 65.18021 -302.074834) (xy 65.179715 -302.099441)
			(xy 65.17182 -302.148018) (xy 65.156236 -302.194699) (xy 65.133365 -302.238276) (xy 65.1038 -302.27762)
			(xy 65.068307 -302.311712) (xy 65.027804 -302.339668) (xy 64.983342 -302.360766) (xy 64.936071 -302.374458)
			(xy 64.887216 -302.38039) (xy 64.838041 -302.378409) (xy 64.789822 -302.368565) (xy 64.743806 -302.351113)
			(xy 64.701185 -302.326506) (xy 64.663064 -302.295381) (xy 64.630429 -302.258544) (xy 64.604126 -302.216948)
			(xy 64.584835 -302.171672) (xy 64.573058 -302.123888) (xy 64.569098 -302.074834) (xy 64.23025 -302.074834)
			(xy 64.229755 -302.099441) (xy 64.22186 -302.148018) (xy 64.206276 -302.194699) (xy 64.183405 -302.238276)
			(xy 64.15384 -302.27762) (xy 64.118347 -302.311712) (xy 64.077844 -302.339668) (xy 64.033382 -302.360766)
			(xy 63.986111 -302.374458) (xy 63.937256 -302.38039) (xy 63.888081 -302.378409) (xy 63.839862 -302.368565)
			(xy 63.793846 -302.351113) (xy 63.751225 -302.326506) (xy 63.713104 -302.295381) (xy 63.680469 -302.258544)
			(xy 63.654166 -302.216948) (xy 63.634875 -302.171672) (xy 63.623098 -302.123888) (xy 63.619138 -302.074834)
			(xy 63.28029 -302.074834) (xy 63.279795 -302.099441) (xy 63.2719 -302.148018) (xy 63.256316 -302.194699)
			(xy 63.233445 -302.238276) (xy 63.20388 -302.27762) (xy 63.168387 -302.311712) (xy 63.127884 -302.339668)
			(xy 63.083422 -302.360766) (xy 63.036151 -302.374458) (xy 62.987296 -302.38039) (xy 62.938121 -302.378409)
			(xy 62.889902 -302.368565) (xy 62.843886 -302.351113) (xy 62.801265 -302.326506) (xy 62.763144 -302.295381)
			(xy 62.730509 -302.258544) (xy 62.704206 -302.216948) (xy 62.684915 -302.171672) (xy 62.673138 -302.123888)
			(xy 62.669178 -302.074834) (xy 62.330076 -302.074834) (xy 62.329581 -302.099441) (xy 62.321686 -302.148018)
			(xy 62.306102 -302.194699) (xy 62.283231 -302.238276) (xy 62.253666 -302.27762) (xy 62.218173 -302.311712)
			(xy 62.17767 -302.339668) (xy 62.133208 -302.360766) (xy 62.085937 -302.374458) (xy 62.037082 -302.38039)
			(xy 61.987907 -302.378409) (xy 61.939688 -302.368565) (xy 61.893672 -302.351113) (xy 61.851051 -302.326506)
			(xy 61.81293 -302.295381) (xy 61.780295 -302.258544) (xy 61.753992 -302.216948) (xy 61.734701 -302.171672)
			(xy 61.722924 -302.123888) (xy 61.718964 -302.074834) (xy 61.380116 -302.074834) (xy 61.379621 -302.099441)
			(xy 61.371726 -302.148018) (xy 61.356142 -302.194699) (xy 61.333271 -302.238276) (xy 61.303706 -302.27762)
			(xy 61.268213 -302.311712) (xy 61.22771 -302.339668) (xy 61.183248 -302.360766) (xy 61.135977 -302.374458)
			(xy 61.087122 -302.38039) (xy 61.037947 -302.378409) (xy 60.989728 -302.368565) (xy 60.943712 -302.351113)
			(xy 60.901091 -302.326506) (xy 60.86297 -302.295381) (xy 60.830335 -302.258544) (xy 60.804032 -302.216948)
			(xy 60.784741 -302.171672) (xy 60.772964 -302.123888) (xy 60.769004 -302.074834) (xy 60.430156 -302.074834)
			(xy 60.429661 -302.099441) (xy 60.421766 -302.148018) (xy 60.406182 -302.194699) (xy 60.383311 -302.238276)
			(xy 60.353746 -302.27762) (xy 60.318253 -302.311712) (xy 60.27775 -302.339668) (xy 60.233288 -302.360766)
			(xy 60.186017 -302.374458) (xy 60.137162 -302.38039) (xy 60.087987 -302.378409) (xy 60.039768 -302.368565)
			(xy 59.993752 -302.351113) (xy 59.951131 -302.326506) (xy 59.91301 -302.295381) (xy 59.880375 -302.258544)
			(xy 59.854072 -302.216948) (xy 59.834781 -302.171672) (xy 59.823004 -302.123888) (xy 59.819044 -302.074834)
			(xy 58.530236 -302.074834) (xy 58.529741 -302.099441) (xy 58.521846 -302.148018) (xy 58.506262 -302.194699)
			(xy 58.483391 -302.238276) (xy 58.453826 -302.27762) (xy 58.418333 -302.311712) (xy 58.37783 -302.339668)
			(xy 58.333368 -302.360766) (xy 58.286097 -302.374458) (xy 58.237242 -302.38039) (xy 58.188067 -302.378409)
			(xy 58.139848 -302.368565) (xy 58.093832 -302.351113) (xy 58.051211 -302.326506) (xy 58.01309 -302.295381)
			(xy 57.980455 -302.258544) (xy 57.954152 -302.216948) (xy 57.934861 -302.171672) (xy 57.923084 -302.123888)
			(xy 57.919124 -302.074834) (xy 57.580276 -302.074834) (xy 57.579781 -302.099441) (xy 57.571886 -302.148018)
			(xy 57.556302 -302.194699) (xy 57.533431 -302.238276) (xy 57.503866 -302.27762) (xy 57.468373 -302.311712)
			(xy 57.42787 -302.339668) (xy 57.383408 -302.360766) (xy 57.336137 -302.374458) (xy 57.287282 -302.38039)
			(xy 57.238107 -302.378409) (xy 57.189888 -302.368565) (xy 57.143872 -302.351113) (xy 57.101251 -302.326506)
			(xy 57.06313 -302.295381) (xy 57.030495 -302.258544) (xy 57.004192 -302.216948) (xy 56.984901 -302.171672)
			(xy 56.973124 -302.123888) (xy 56.969164 -302.074834) (xy 56.630062 -302.074834) (xy 56.629567 -302.099441)
			(xy 56.621672 -302.148018) (xy 56.606088 -302.194699) (xy 56.583217 -302.238276) (xy 56.553652 -302.27762)
			(xy 56.518159 -302.311712) (xy 56.477656 -302.339668) (xy 56.433194 -302.360766) (xy 56.385923 -302.374458)
			(xy 56.337068 -302.38039) (xy 56.287893 -302.378409) (xy 56.239674 -302.368565) (xy 56.193658 -302.351113)
			(xy 56.151037 -302.326506) (xy 56.112916 -302.295381) (xy 56.080281 -302.258544) (xy 56.053978 -302.216948)
			(xy 56.034687 -302.171672) (xy 56.02291 -302.123888) (xy 56.01895 -302.074834) (xy 55.680102 -302.074834)
			(xy 55.679607 -302.099441) (xy 55.671712 -302.148018) (xy 55.656128 -302.194699) (xy 55.633257 -302.238276)
			(xy 55.603692 -302.27762) (xy 55.568199 -302.311712) (xy 55.527696 -302.339668) (xy 55.483234 -302.360766)
			(xy 55.435963 -302.374458) (xy 55.387108 -302.38039) (xy 55.337933 -302.378409) (xy 55.289714 -302.368565)
			(xy 55.243698 -302.351113) (xy 55.201077 -302.326506) (xy 55.162956 -302.295381) (xy 55.130321 -302.258544)
			(xy 55.104018 -302.216948) (xy 55.084727 -302.171672) (xy 55.07295 -302.123888) (xy 55.06899 -302.074834)
			(xy 54.730142 -302.074834) (xy 54.729647 -302.099441) (xy 54.721752 -302.148018) (xy 54.706168 -302.194699)
			(xy 54.683297 -302.238276) (xy 54.653732 -302.27762) (xy 54.618239 -302.311712) (xy 54.577736 -302.339668)
			(xy 54.533274 -302.360766) (xy 54.486003 -302.374458) (xy 54.437148 -302.38039) (xy 54.387973 -302.378409)
			(xy 54.339754 -302.368565) (xy 54.293738 -302.351113) (xy 54.251117 -302.326506) (xy 54.212996 -302.295381)
			(xy 54.180361 -302.258544) (xy 54.154058 -302.216948) (xy 54.134767 -302.171672) (xy 54.12299 -302.123888)
			(xy 54.11903 -302.074834) (xy 53.780182 -302.074834) (xy 53.779687 -302.099441) (xy 53.771792 -302.148018)
			(xy 53.756208 -302.194699) (xy 53.733337 -302.238276) (xy 53.703772 -302.27762) (xy 53.668279 -302.311712)
			(xy 53.627776 -302.339668) (xy 53.583314 -302.360766) (xy 53.536043 -302.374458) (xy 53.487188 -302.38039)
			(xy 53.438013 -302.378409) (xy 53.389794 -302.368565) (xy 53.343778 -302.351113) (xy 53.301157 -302.326506)
			(xy 53.263036 -302.295381) (xy 53.230401 -302.258544) (xy 53.204098 -302.216948) (xy 53.184807 -302.171672)
			(xy 53.17303 -302.123888) (xy 53.16907 -302.074834) (xy 52.830222 -302.074834) (xy 52.829727 -302.099441)
			(xy 52.821832 -302.148018) (xy 52.806248 -302.194699) (xy 52.783377 -302.238276) (xy 52.753812 -302.27762)
			(xy 52.718319 -302.311712) (xy 52.677816 -302.339668) (xy 52.633354 -302.360766) (xy 52.586083 -302.374458)
			(xy 52.537228 -302.38039) (xy 52.488053 -302.378409) (xy 52.439834 -302.368565) (xy 52.393818 -302.351113)
			(xy 52.351197 -302.326506) (xy 52.313076 -302.295381) (xy 52.280441 -302.258544) (xy 52.254138 -302.216948)
			(xy 52.234847 -302.171672) (xy 52.22307 -302.123888) (xy 52.21911 -302.074834) (xy 51.880262 -302.074834)
			(xy 51.879767 -302.099441) (xy 51.871872 -302.148018) (xy 51.856288 -302.194699) (xy 51.833417 -302.238276)
			(xy 51.803852 -302.27762) (xy 51.768359 -302.311712) (xy 51.727856 -302.339668) (xy 51.683394 -302.360766)
			(xy 51.636123 -302.374458) (xy 51.587268 -302.38039) (xy 51.538093 -302.378409) (xy 51.489874 -302.368565)
			(xy 51.443858 -302.351113) (xy 51.401237 -302.326506) (xy 51.363116 -302.295381) (xy 51.330481 -302.258544)
			(xy 51.304178 -302.216948) (xy 51.284887 -302.171672) (xy 51.27311 -302.123888) (xy 51.26915 -302.074834)
			(xy 50.930302 -302.074834) (xy 50.929807 -302.099441) (xy 50.921912 -302.148018) (xy 50.906328 -302.194699)
			(xy 50.883457 -302.238276) (xy 50.853892 -302.27762) (xy 50.818399 -302.311712) (xy 50.777896 -302.339668)
			(xy 50.733434 -302.360766) (xy 50.686163 -302.374458) (xy 50.637308 -302.38039) (xy 50.588133 -302.378409)
			(xy 50.539914 -302.368565) (xy 50.493898 -302.351113) (xy 50.451277 -302.326506) (xy 50.413156 -302.295381)
			(xy 50.380521 -302.258544) (xy 50.354218 -302.216948) (xy 50.334927 -302.171672) (xy 50.32315 -302.123888)
			(xy 50.31919 -302.074834) (xy 49.980088 -302.074834) (xy 49.979593 -302.099441) (xy 49.971698 -302.148018)
			(xy 49.956114 -302.194699) (xy 49.933243 -302.238276) (xy 49.903678 -302.27762) (xy 49.868185 -302.311712)
			(xy 49.827682 -302.339668) (xy 49.78322 -302.360766) (xy 49.735949 -302.374458) (xy 49.687094 -302.38039)
			(xy 49.637919 -302.378409) (xy 49.5897 -302.368565) (xy 49.543684 -302.351113) (xy 49.501063 -302.326506)
			(xy 49.462942 -302.295381) (xy 49.430307 -302.258544) (xy 49.404004 -302.216948) (xy 49.384713 -302.171672)
			(xy 49.372936 -302.123888) (xy 49.368976 -302.074834) (xy 46.205798 -302.074834) (xy 46.205902 -302.078898)
			(xy 46.213268 -302.096678) (xy 46.353984 -302.237394) (xy 46.369986 -302.245014) (xy 46.378876 -302.245776)
			(xy 46.406074 -302.248999) (xy 46.458782 -302.263862) (xy 46.507998 -302.287882) (xy 46.552144 -302.320288)
			(xy 46.571408 -302.339756) (xy 46.578884 -302.346915) (xy 46.597897 -302.355047) (xy 46.608238 -302.355504)
			(xy 49.072546 -302.355504) (xy 49.082612 -302.355936) (xy 49.101204 -302.363662) (xy 49.108614 -302.37049)
			(xy 49.391316 -302.653192) (xy 49.397402 -302.659781) (xy 49.40495 -302.67604) (xy 49.406048 -302.684942)
			(xy 49.407318 -302.69815) (xy 49.421542 -302.719486) (xy 49.458118 -302.738536) (xy 49.466715 -302.742445)
			(xy 49.485481 -302.744414) (xy 49.494694 -302.742346) (xy 49.508918 -302.738536) (xy 49.514506 -302.735488)
			(xy 49.539198 -302.722481) (xy 49.591864 -302.704028) (xy 49.646878 -302.694667) (xy 49.67478 -302.694086)
			(xy 49.700771 -302.694568) (xy 49.752113 -302.702697) (xy 49.801551 -302.718757) (xy 49.847868 -302.742354)
			(xy 49.889923 -302.772907) (xy 49.92668 -302.809662) (xy 49.957235 -302.851715) (xy 49.980835 -302.898031)
			(xy 49.996899 -302.947468) (xy 50.005031 -302.998809) (xy 50.005031 -303.024794) (xy 50.31919 -303.024794)
			(xy 50.32315 -302.97574) (xy 50.334927 -302.927956) (xy 50.354218 -302.88268) (xy 50.380521 -302.841084)
			(xy 50.413156 -302.804247) (xy 50.451277 -302.773122) (xy 50.493898 -302.748515) (xy 50.539914 -302.731063)
			(xy 50.588133 -302.721219) (xy 50.637308 -302.719238) (xy 50.686163 -302.72517) (xy 50.733434 -302.738862)
			(xy 50.777896 -302.75996) (xy 50.818399 -302.787916) (xy 50.853892 -302.822008) (xy 50.883457 -302.861352)
			(xy 50.906328 -302.904929) (xy 50.921912 -302.95161) (xy 50.929807 -303.000187) (xy 50.930302 -303.024794)
			(xy 51.26915 -303.024794) (xy 51.27311 -302.97574) (xy 51.284887 -302.927956) (xy 51.304178 -302.88268)
			(xy 51.330481 -302.841084) (xy 51.363116 -302.804247) (xy 51.401237 -302.773122) (xy 51.443858 -302.748515)
			(xy 51.489874 -302.731063) (xy 51.538093 -302.721219) (xy 51.587268 -302.719238) (xy 51.636123 -302.72517)
			(xy 51.683394 -302.738862) (xy 51.727856 -302.75996) (xy 51.768359 -302.787916) (xy 51.803852 -302.822008)
			(xy 51.833417 -302.861352) (xy 51.856288 -302.904929) (xy 51.871872 -302.95161) (xy 51.879767 -303.000187)
			(xy 51.880262 -303.024794) (xy 52.21911 -303.024794) (xy 52.22307 -302.97574) (xy 52.234847 -302.927956)
			(xy 52.254138 -302.88268) (xy 52.280441 -302.841084) (xy 52.313076 -302.804247) (xy 52.351197 -302.773122)
			(xy 52.393818 -302.748515) (xy 52.439834 -302.731063) (xy 52.488053 -302.721219) (xy 52.537228 -302.719238)
			(xy 52.586083 -302.72517) (xy 52.633354 -302.738862) (xy 52.677816 -302.75996) (xy 52.718319 -302.787916)
			(xy 52.753812 -302.822008) (xy 52.783377 -302.861352) (xy 52.806248 -302.904929) (xy 52.821832 -302.95161)
			(xy 52.829727 -303.000187) (xy 52.830222 -303.024794) (xy 53.16907 -303.024794) (xy 53.17303 -302.97574)
			(xy 53.184807 -302.927956) (xy 53.204098 -302.88268) (xy 53.230401 -302.841084) (xy 53.263036 -302.804247)
			(xy 53.301157 -302.773122) (xy 53.343778 -302.748515) (xy 53.389794 -302.731063) (xy 53.438013 -302.721219)
			(xy 53.487188 -302.719238) (xy 53.536043 -302.72517) (xy 53.583314 -302.738862) (xy 53.627776 -302.75996)
			(xy 53.668279 -302.787916) (xy 53.703772 -302.822008) (xy 53.733337 -302.861352) (xy 53.756208 -302.904929)
			(xy 53.771792 -302.95161) (xy 53.779687 -303.000187) (xy 53.780182 -303.024794) (xy 54.11903 -303.024794)
			(xy 54.12299 -302.97574) (xy 54.134767 -302.927956) (xy 54.154058 -302.88268) (xy 54.180361 -302.841084)
			(xy 54.212996 -302.804247) (xy 54.251117 -302.773122) (xy 54.293738 -302.748515) (xy 54.339754 -302.731063)
			(xy 54.387973 -302.721219) (xy 54.437148 -302.719238) (xy 54.486003 -302.72517) (xy 54.533274 -302.738862)
			(xy 54.577736 -302.75996) (xy 54.618239 -302.787916) (xy 54.653732 -302.822008) (xy 54.683297 -302.861352)
			(xy 54.706168 -302.904929) (xy 54.721752 -302.95161) (xy 54.729647 -303.000187) (xy 54.730142 -303.024794)
			(xy 55.06899 -303.024794) (xy 55.07295 -302.97574) (xy 55.084727 -302.927956) (xy 55.104018 -302.88268)
			(xy 55.130321 -302.841084) (xy 55.162956 -302.804247) (xy 55.201077 -302.773122) (xy 55.243698 -302.748515)
			(xy 55.289714 -302.731063) (xy 55.337933 -302.721219) (xy 55.387108 -302.719238) (xy 55.435963 -302.72517)
			(xy 55.483234 -302.738862) (xy 55.527696 -302.75996) (xy 55.568199 -302.787916) (xy 55.603692 -302.822008)
			(xy 55.633257 -302.861352) (xy 55.656128 -302.904929) (xy 55.671712 -302.95161) (xy 55.679607 -303.000187)
			(xy 55.680102 -303.024794) (xy 56.01895 -303.024794) (xy 56.02291 -302.97574) (xy 56.034687 -302.927956)
			(xy 56.053978 -302.88268) (xy 56.080281 -302.841084) (xy 56.112916 -302.804247) (xy 56.151037 -302.773122)
			(xy 56.193658 -302.748515) (xy 56.239674 -302.731063) (xy 56.287893 -302.721219) (xy 56.337068 -302.719238)
			(xy 56.385923 -302.72517) (xy 56.433194 -302.738862) (xy 56.477656 -302.75996) (xy 56.518159 -302.787916)
			(xy 56.553652 -302.822008) (xy 56.583217 -302.861352) (xy 56.606088 -302.904929) (xy 56.621672 -302.95161)
			(xy 56.629567 -303.000187) (xy 56.630062 -303.024794) (xy 56.969164 -303.024794) (xy 56.973124 -302.97574)
			(xy 56.984901 -302.927956) (xy 57.004192 -302.88268) (xy 57.030495 -302.841084) (xy 57.06313 -302.804247)
			(xy 57.101251 -302.773122) (xy 57.143872 -302.748515) (xy 57.189888 -302.731063) (xy 57.238107 -302.721219)
			(xy 57.287282 -302.719238) (xy 57.336137 -302.72517) (xy 57.383408 -302.738862) (xy 57.42787 -302.75996)
			(xy 57.468373 -302.787916) (xy 57.503866 -302.822008) (xy 57.533431 -302.861352) (xy 57.556302 -302.904929)
			(xy 57.571886 -302.95161) (xy 57.579781 -303.000187) (xy 57.580276 -303.024794) (xy 57.919124 -303.024794)
			(xy 57.923084 -302.97574) (xy 57.934861 -302.927956) (xy 57.954152 -302.88268) (xy 57.980455 -302.841084)
			(xy 58.01309 -302.804247) (xy 58.051211 -302.773122) (xy 58.093832 -302.748515) (xy 58.139848 -302.731063)
			(xy 58.188067 -302.721219) (xy 58.237242 -302.719238) (xy 58.286097 -302.72517) (xy 58.333368 -302.738862)
			(xy 58.37783 -302.75996) (xy 58.418333 -302.787916) (xy 58.453826 -302.822008) (xy 58.483391 -302.861352)
			(xy 58.506262 -302.904929) (xy 58.521846 -302.95161) (xy 58.529741 -303.000187) (xy 58.530236 -303.024794)
			(xy 59.819044 -303.024794) (xy 59.823004 -302.97574) (xy 59.834781 -302.927956) (xy 59.854072 -302.88268)
			(xy 59.880375 -302.841084) (xy 59.91301 -302.804247) (xy 59.951131 -302.773122) (xy 59.993752 -302.748515)
			(xy 60.039768 -302.731063) (xy 60.087987 -302.721219) (xy 60.137162 -302.719238) (xy 60.186017 -302.72517)
			(xy 60.233288 -302.738862) (xy 60.27775 -302.75996) (xy 60.318253 -302.787916) (xy 60.353746 -302.822008)
			(xy 60.383311 -302.861352) (xy 60.406182 -302.904929) (xy 60.421766 -302.95161) (xy 60.429661 -303.000187)
			(xy 60.430156 -303.024794) (xy 60.769004 -303.024794) (xy 60.772964 -302.97574) (xy 60.784741 -302.927956)
			(xy 60.804032 -302.88268) (xy 60.830335 -302.841084) (xy 60.86297 -302.804247) (xy 60.901091 -302.773122)
			(xy 60.943712 -302.748515) (xy 60.989728 -302.731063) (xy 61.037947 -302.721219) (xy 61.087122 -302.719238)
			(xy 61.135977 -302.72517) (xy 61.183248 -302.738862) (xy 61.22771 -302.75996) (xy 61.268213 -302.787916)
			(xy 61.303706 -302.822008) (xy 61.333271 -302.861352) (xy 61.356142 -302.904929) (xy 61.371726 -302.95161)
			(xy 61.379621 -303.000187) (xy 61.380116 -303.024794) (xy 61.718964 -303.024794) (xy 61.722924 -302.97574)
			(xy 61.734701 -302.927956) (xy 61.753992 -302.88268) (xy 61.780295 -302.841084) (xy 61.81293 -302.804247)
			(xy 61.851051 -302.773122) (xy 61.893672 -302.748515) (xy 61.939688 -302.731063) (xy 61.987907 -302.721219)
			(xy 62.037082 -302.719238) (xy 62.085937 -302.72517) (xy 62.133208 -302.738862) (xy 62.17767 -302.75996)
			(xy 62.218173 -302.787916) (xy 62.253666 -302.822008) (xy 62.283231 -302.861352) (xy 62.306102 -302.904929)
			(xy 62.321686 -302.95161) (xy 62.329581 -303.000187) (xy 62.330076 -303.024794) (xy 62.669178 -303.024794)
			(xy 62.673138 -302.97574) (xy 62.684915 -302.927956) (xy 62.704206 -302.88268) (xy 62.730509 -302.841084)
			(xy 62.763144 -302.804247) (xy 62.801265 -302.773122) (xy 62.843886 -302.748515) (xy 62.889902 -302.731063)
			(xy 62.938121 -302.721219) (xy 62.987296 -302.719238) (xy 63.036151 -302.72517) (xy 63.083422 -302.738862)
			(xy 63.127884 -302.75996) (xy 63.168387 -302.787916) (xy 63.20388 -302.822008) (xy 63.233445 -302.861352)
			(xy 63.256316 -302.904929) (xy 63.2719 -302.95161) (xy 63.279795 -303.000187) (xy 63.28029 -303.024794)
			(xy 63.619138 -303.024794) (xy 63.623098 -302.97574) (xy 63.634875 -302.927956) (xy 63.654166 -302.88268)
			(xy 63.680469 -302.841084) (xy 63.713104 -302.804247) (xy 63.751225 -302.773122) (xy 63.793846 -302.748515)
			(xy 63.839862 -302.731063) (xy 63.888081 -302.721219) (xy 63.937256 -302.719238) (xy 63.986111 -302.72517)
			(xy 64.033382 -302.738862) (xy 64.077844 -302.75996) (xy 64.118347 -302.787916) (xy 64.15384 -302.822008)
			(xy 64.183405 -302.861352) (xy 64.206276 -302.904929) (xy 64.22186 -302.95161) (xy 64.229755 -303.000187)
			(xy 64.23025 -303.024794) (xy 64.569098 -303.024794) (xy 64.573058 -302.97574) (xy 64.584835 -302.927956)
			(xy 64.604126 -302.88268) (xy 64.630429 -302.841084) (xy 64.663064 -302.804247) (xy 64.701185 -302.773122)
			(xy 64.743806 -302.748515) (xy 64.789822 -302.731063) (xy 64.838041 -302.721219) (xy 64.887216 -302.719238)
			(xy 64.936071 -302.72517) (xy 64.983342 -302.738862) (xy 65.027804 -302.75996) (xy 65.068307 -302.787916)
			(xy 65.1038 -302.822008) (xy 65.133365 -302.861352) (xy 65.156236 -302.904929) (xy 65.17182 -302.95161)
			(xy 65.179715 -303.000187) (xy 65.18021 -303.024794) (xy 65.519058 -303.024794) (xy 65.523018 -302.97574)
			(xy 65.534795 -302.927956) (xy 65.554086 -302.88268) (xy 65.580389 -302.841084) (xy 65.613024 -302.804247)
			(xy 65.651145 -302.773122) (xy 65.693766 -302.748515) (xy 65.739782 -302.731063) (xy 65.788001 -302.721219)
			(xy 65.837176 -302.719238) (xy 65.886031 -302.72517) (xy 65.933302 -302.738862) (xy 65.977764 -302.75996)
			(xy 66.018267 -302.787916) (xy 66.05376 -302.822008) (xy 66.083325 -302.861352) (xy 66.106196 -302.904929)
			(xy 66.12178 -302.95161) (xy 66.129675 -303.000187) (xy 66.13017 -303.024794) (xy 66.469018 -303.024794)
			(xy 66.472978 -302.97574) (xy 66.484755 -302.927956) (xy 66.504046 -302.88268) (xy 66.530349 -302.841084)
			(xy 66.562984 -302.804247) (xy 66.601105 -302.773122) (xy 66.643726 -302.748515) (xy 66.689742 -302.731063)
			(xy 66.737961 -302.721219) (xy 66.787136 -302.719238) (xy 66.835991 -302.72517) (xy 66.883262 -302.738862)
			(xy 66.927724 -302.75996) (xy 66.968227 -302.787916) (xy 67.00372 -302.822008) (xy 67.033285 -302.861352)
			(xy 67.056156 -302.904929) (xy 67.07174 -302.95161) (xy 67.079635 -303.000187) (xy 67.08013 -303.024794)
			(xy 67.418978 -303.024794) (xy 67.422938 -302.97574) (xy 67.434715 -302.927956) (xy 67.454006 -302.88268)
			(xy 67.480309 -302.841084) (xy 67.512944 -302.804247) (xy 67.551065 -302.773122) (xy 67.593686 -302.748515)
			(xy 67.639702 -302.731063) (xy 67.687921 -302.721219) (xy 67.737096 -302.719238) (xy 67.785951 -302.72517)
			(xy 67.833222 -302.738862) (xy 67.877684 -302.75996) (xy 67.918187 -302.787916) (xy 67.95368 -302.822008)
			(xy 67.983245 -302.861352) (xy 68.006116 -302.904929) (xy 68.0217 -302.95161) (xy 68.029595 -303.000187)
			(xy 68.03009 -303.024794) (xy 68.368938 -303.024794) (xy 68.372898 -302.97574) (xy 68.384675 -302.927956)
			(xy 68.403966 -302.88268) (xy 68.430269 -302.841084) (xy 68.462904 -302.804247) (xy 68.501025 -302.773122)
			(xy 68.543646 -302.748515) (xy 68.589662 -302.731063) (xy 68.637881 -302.721219) (xy 68.687056 -302.719238)
			(xy 68.735911 -302.72517) (xy 68.783182 -302.738862) (xy 68.827644 -302.75996) (xy 68.868147 -302.787916)
			(xy 68.90364 -302.822008) (xy 68.933205 -302.861352) (xy 68.956076 -302.904929) (xy 68.97166 -302.95161)
			(xy 68.979555 -303.000187) (xy 68.98005 -303.024794) (xy 68.979555 -303.049401) (xy 68.97166 -303.097978)
			(xy 68.956076 -303.144659) (xy 68.933205 -303.188236) (xy 68.90364 -303.22758) (xy 68.868147 -303.261672)
			(xy 68.827644 -303.289628) (xy 68.783182 -303.310726) (xy 68.735911 -303.324418) (xy 68.687056 -303.33035)
			(xy 68.637881 -303.328369) (xy 68.589662 -303.318525) (xy 68.543646 -303.301073) (xy 68.501025 -303.276466)
			(xy 68.462904 -303.245341) (xy 68.430269 -303.208504) (xy 68.403966 -303.166908) (xy 68.384675 -303.121632)
			(xy 68.372898 -303.073848) (xy 68.368938 -303.024794) (xy 68.03009 -303.024794) (xy 68.029595 -303.049401)
			(xy 68.0217 -303.097978) (xy 68.006116 -303.144659) (xy 67.983245 -303.188236) (xy 67.95368 -303.22758)
			(xy 67.918187 -303.261672) (xy 67.877684 -303.289628) (xy 67.833222 -303.310726) (xy 67.785951 -303.324418)
			(xy 67.737096 -303.33035) (xy 67.687921 -303.328369) (xy 67.639702 -303.318525) (xy 67.593686 -303.301073)
			(xy 67.551065 -303.276466) (xy 67.512944 -303.245341) (xy 67.480309 -303.208504) (xy 67.454006 -303.166908)
			(xy 67.434715 -303.121632) (xy 67.422938 -303.073848) (xy 67.418978 -303.024794) (xy 67.08013 -303.024794)
			(xy 67.079635 -303.049401) (xy 67.07174 -303.097978) (xy 67.056156 -303.144659) (xy 67.033285 -303.188236)
			(xy 67.00372 -303.22758) (xy 66.968227 -303.261672) (xy 66.927724 -303.289628) (xy 66.883262 -303.310726)
			(xy 66.835991 -303.324418) (xy 66.787136 -303.33035) (xy 66.737961 -303.328369) (xy 66.689742 -303.318525)
			(xy 66.643726 -303.301073) (xy 66.601105 -303.276466) (xy 66.562984 -303.245341) (xy 66.530349 -303.208504)
			(xy 66.504046 -303.166908) (xy 66.484755 -303.121632) (xy 66.472978 -303.073848) (xy 66.469018 -303.024794)
			(xy 66.13017 -303.024794) (xy 66.129675 -303.049401) (xy 66.12178 -303.097978) (xy 66.106196 -303.144659)
			(xy 66.083325 -303.188236) (xy 66.05376 -303.22758) (xy 66.018267 -303.261672) (xy 65.977764 -303.289628)
			(xy 65.933302 -303.310726) (xy 65.886031 -303.324418) (xy 65.837176 -303.33035) (xy 65.788001 -303.328369)
			(xy 65.739782 -303.318525) (xy 65.693766 -303.301073) (xy 65.651145 -303.276466) (xy 65.613024 -303.245341)
			(xy 65.580389 -303.208504) (xy 65.554086 -303.166908) (xy 65.534795 -303.121632) (xy 65.523018 -303.073848)
			(xy 65.519058 -303.024794) (xy 65.18021 -303.024794) (xy 65.179715 -303.049401) (xy 65.17182 -303.097978)
			(xy 65.156236 -303.144659) (xy 65.133365 -303.188236) (xy 65.1038 -303.22758) (xy 65.068307 -303.261672)
			(xy 65.027804 -303.289628) (xy 64.983342 -303.310726) (xy 64.936071 -303.324418) (xy 64.887216 -303.33035)
			(xy 64.838041 -303.328369) (xy 64.789822 -303.318525) (xy 64.743806 -303.301073) (xy 64.701185 -303.276466)
			(xy 64.663064 -303.245341) (xy 64.630429 -303.208504) (xy 64.604126 -303.166908) (xy 64.584835 -303.121632)
			(xy 64.573058 -303.073848) (xy 64.569098 -303.024794) (xy 64.23025 -303.024794) (xy 64.229755 -303.049401)
			(xy 64.22186 -303.097978) (xy 64.206276 -303.144659) (xy 64.183405 -303.188236) (xy 64.15384 -303.22758)
			(xy 64.118347 -303.261672) (xy 64.077844 -303.289628) (xy 64.033382 -303.310726) (xy 63.986111 -303.324418)
			(xy 63.937256 -303.33035) (xy 63.888081 -303.328369) (xy 63.839862 -303.318525) (xy 63.793846 -303.301073)
			(xy 63.751225 -303.276466) (xy 63.713104 -303.245341) (xy 63.680469 -303.208504) (xy 63.654166 -303.166908)
			(xy 63.634875 -303.121632) (xy 63.623098 -303.073848) (xy 63.619138 -303.024794) (xy 63.28029 -303.024794)
			(xy 63.279795 -303.049401) (xy 63.2719 -303.097978) (xy 63.256316 -303.144659) (xy 63.233445 -303.188236)
			(xy 63.20388 -303.22758) (xy 63.168387 -303.261672) (xy 63.127884 -303.289628) (xy 63.083422 -303.310726)
			(xy 63.036151 -303.324418) (xy 62.987296 -303.33035) (xy 62.938121 -303.328369) (xy 62.889902 -303.318525)
			(xy 62.843886 -303.301073) (xy 62.801265 -303.276466) (xy 62.763144 -303.245341) (xy 62.730509 -303.208504)
			(xy 62.704206 -303.166908) (xy 62.684915 -303.121632) (xy 62.673138 -303.073848) (xy 62.669178 -303.024794)
			(xy 62.330076 -303.024794) (xy 62.329581 -303.049401) (xy 62.321686 -303.097978) (xy 62.306102 -303.144659)
			(xy 62.283231 -303.188236) (xy 62.253666 -303.22758) (xy 62.218173 -303.261672) (xy 62.17767 -303.289628)
			(xy 62.133208 -303.310726) (xy 62.085937 -303.324418) (xy 62.037082 -303.33035) (xy 61.987907 -303.328369)
			(xy 61.939688 -303.318525) (xy 61.893672 -303.301073) (xy 61.851051 -303.276466) (xy 61.81293 -303.245341)
			(xy 61.780295 -303.208504) (xy 61.753992 -303.166908) (xy 61.734701 -303.121632) (xy 61.722924 -303.073848)
			(xy 61.718964 -303.024794) (xy 61.380116 -303.024794) (xy 61.379621 -303.049401) (xy 61.371726 -303.097978)
			(xy 61.356142 -303.144659) (xy 61.333271 -303.188236) (xy 61.303706 -303.22758) (xy 61.268213 -303.261672)
			(xy 61.22771 -303.289628) (xy 61.183248 -303.310726) (xy 61.135977 -303.324418) (xy 61.087122 -303.33035)
			(xy 61.037947 -303.328369) (xy 60.989728 -303.318525) (xy 60.943712 -303.301073) (xy 60.901091 -303.276466)
			(xy 60.86297 -303.245341) (xy 60.830335 -303.208504) (xy 60.804032 -303.166908) (xy 60.784741 -303.121632)
			(xy 60.772964 -303.073848) (xy 60.769004 -303.024794) (xy 60.430156 -303.024794) (xy 60.429661 -303.049401)
			(xy 60.421766 -303.097978) (xy 60.406182 -303.144659) (xy 60.383311 -303.188236) (xy 60.353746 -303.22758)
			(xy 60.318253 -303.261672) (xy 60.27775 -303.289628) (xy 60.233288 -303.310726) (xy 60.186017 -303.324418)
			(xy 60.137162 -303.33035) (xy 60.087987 -303.328369) (xy 60.039768 -303.318525) (xy 59.993752 -303.301073)
			(xy 59.951131 -303.276466) (xy 59.91301 -303.245341) (xy 59.880375 -303.208504) (xy 59.854072 -303.166908)
			(xy 59.834781 -303.121632) (xy 59.823004 -303.073848) (xy 59.819044 -303.024794) (xy 58.530236 -303.024794)
			(xy 58.529741 -303.049401) (xy 58.521846 -303.097978) (xy 58.506262 -303.144659) (xy 58.483391 -303.188236)
			(xy 58.453826 -303.22758) (xy 58.418333 -303.261672) (xy 58.37783 -303.289628) (xy 58.333368 -303.310726)
			(xy 58.286097 -303.324418) (xy 58.237242 -303.33035) (xy 58.188067 -303.328369) (xy 58.139848 -303.318525)
			(xy 58.093832 -303.301073) (xy 58.051211 -303.276466) (xy 58.01309 -303.245341) (xy 57.980455 -303.208504)
			(xy 57.954152 -303.166908) (xy 57.934861 -303.121632) (xy 57.923084 -303.073848) (xy 57.919124 -303.024794)
			(xy 57.580276 -303.024794) (xy 57.579781 -303.049401) (xy 57.571886 -303.097978) (xy 57.556302 -303.144659)
			(xy 57.533431 -303.188236) (xy 57.503866 -303.22758) (xy 57.468373 -303.261672) (xy 57.42787 -303.289628)
			(xy 57.383408 -303.310726) (xy 57.336137 -303.324418) (xy 57.287282 -303.33035) (xy 57.238107 -303.328369)
			(xy 57.189888 -303.318525) (xy 57.143872 -303.301073) (xy 57.101251 -303.276466) (xy 57.06313 -303.245341)
			(xy 57.030495 -303.208504) (xy 57.004192 -303.166908) (xy 56.984901 -303.121632) (xy 56.973124 -303.073848)
			(xy 56.969164 -303.024794) (xy 56.630062 -303.024794) (xy 56.629567 -303.049401) (xy 56.621672 -303.097978)
			(xy 56.606088 -303.144659) (xy 56.583217 -303.188236) (xy 56.553652 -303.22758) (xy 56.518159 -303.261672)
			(xy 56.477656 -303.289628) (xy 56.433194 -303.310726) (xy 56.385923 -303.324418) (xy 56.337068 -303.33035)
			(xy 56.287893 -303.328369) (xy 56.239674 -303.318525) (xy 56.193658 -303.301073) (xy 56.151037 -303.276466)
			(xy 56.112916 -303.245341) (xy 56.080281 -303.208504) (xy 56.053978 -303.166908) (xy 56.034687 -303.121632)
			(xy 56.02291 -303.073848) (xy 56.01895 -303.024794) (xy 55.680102 -303.024794) (xy 55.679607 -303.049401)
			(xy 55.671712 -303.097978) (xy 55.656128 -303.144659) (xy 55.633257 -303.188236) (xy 55.603692 -303.22758)
			(xy 55.568199 -303.261672) (xy 55.527696 -303.289628) (xy 55.483234 -303.310726) (xy 55.435963 -303.324418)
			(xy 55.387108 -303.33035) (xy 55.337933 -303.328369) (xy 55.289714 -303.318525) (xy 55.243698 -303.301073)
			(xy 55.201077 -303.276466) (xy 55.162956 -303.245341) (xy 55.130321 -303.208504) (xy 55.104018 -303.166908)
			(xy 55.084727 -303.121632) (xy 55.07295 -303.073848) (xy 55.06899 -303.024794) (xy 54.730142 -303.024794)
			(xy 54.729647 -303.049401) (xy 54.721752 -303.097978) (xy 54.706168 -303.144659) (xy 54.683297 -303.188236)
			(xy 54.653732 -303.22758) (xy 54.618239 -303.261672) (xy 54.577736 -303.289628) (xy 54.533274 -303.310726)
			(xy 54.486003 -303.324418) (xy 54.437148 -303.33035) (xy 54.387973 -303.328369) (xy 54.339754 -303.318525)
			(xy 54.293738 -303.301073) (xy 54.251117 -303.276466) (xy 54.212996 -303.245341) (xy 54.180361 -303.208504)
			(xy 54.154058 -303.166908) (xy 54.134767 -303.121632) (xy 54.12299 -303.073848) (xy 54.11903 -303.024794)
			(xy 53.780182 -303.024794) (xy 53.779687 -303.049401) (xy 53.771792 -303.097978) (xy 53.756208 -303.144659)
			(xy 53.733337 -303.188236) (xy 53.703772 -303.22758) (xy 53.668279 -303.261672) (xy 53.627776 -303.289628)
			(xy 53.583314 -303.310726) (xy 53.536043 -303.324418) (xy 53.487188 -303.33035) (xy 53.438013 -303.328369)
			(xy 53.389794 -303.318525) (xy 53.343778 -303.301073) (xy 53.301157 -303.276466) (xy 53.263036 -303.245341)
			(xy 53.230401 -303.208504) (xy 53.204098 -303.166908) (xy 53.184807 -303.121632) (xy 53.17303 -303.073848)
			(xy 53.16907 -303.024794) (xy 52.830222 -303.024794) (xy 52.829727 -303.049401) (xy 52.821832 -303.097978)
			(xy 52.806248 -303.144659) (xy 52.783377 -303.188236) (xy 52.753812 -303.22758) (xy 52.718319 -303.261672)
			(xy 52.677816 -303.289628) (xy 52.633354 -303.310726) (xy 52.586083 -303.324418) (xy 52.537228 -303.33035)
			(xy 52.488053 -303.328369) (xy 52.439834 -303.318525) (xy 52.393818 -303.301073) (xy 52.351197 -303.276466)
			(xy 52.313076 -303.245341) (xy 52.280441 -303.208504) (xy 52.254138 -303.166908) (xy 52.234847 -303.121632)
			(xy 52.22307 -303.073848) (xy 52.21911 -303.024794) (xy 51.880262 -303.024794) (xy 51.879767 -303.049401)
			(xy 51.871872 -303.097978) (xy 51.856288 -303.144659) (xy 51.833417 -303.188236) (xy 51.803852 -303.22758)
			(xy 51.768359 -303.261672) (xy 51.727856 -303.289628) (xy 51.683394 -303.310726) (xy 51.636123 -303.324418)
			(xy 51.587268 -303.33035) (xy 51.538093 -303.328369) (xy 51.489874 -303.318525) (xy 51.443858 -303.301073)
			(xy 51.401237 -303.276466) (xy 51.363116 -303.245341) (xy 51.330481 -303.208504) (xy 51.304178 -303.166908)
			(xy 51.284887 -303.121632) (xy 51.27311 -303.073848) (xy 51.26915 -303.024794) (xy 50.930302 -303.024794)
			(xy 50.929807 -303.049401) (xy 50.921912 -303.097978) (xy 50.906328 -303.144659) (xy 50.883457 -303.188236)
			(xy 50.853892 -303.22758) (xy 50.818399 -303.261672) (xy 50.777896 -303.289628) (xy 50.733434 -303.310726)
			(xy 50.686163 -303.324418) (xy 50.637308 -303.33035) (xy 50.588133 -303.328369) (xy 50.539914 -303.318525)
			(xy 50.493898 -303.301073) (xy 50.451277 -303.276466) (xy 50.413156 -303.245341) (xy 50.380521 -303.208504)
			(xy 50.354218 -303.166908) (xy 50.334927 -303.121632) (xy 50.32315 -303.073848) (xy 50.31919 -303.024794)
			(xy 50.005031 -303.024794) (xy 50.005031 -303.050791) (xy 49.996899 -303.102132) (xy 49.980835 -303.151569)
			(xy 49.957235 -303.197885) (xy 49.92668 -303.239938) (xy 49.889923 -303.276693) (xy 49.847868 -303.307246)
			(xy 49.801551 -303.330843) (xy 49.752113 -303.346903) (xy 49.700771 -303.355032) (xy 49.67478 -303.355502)
			(xy 49.65291 -303.355149) (xy 49.609552 -303.349385) (xy 49.56733 -303.337961) (xy 49.547018 -303.329848)
			(xy 49.53508 -303.325022) (xy 49.510188 -303.327308) (xy 49.428908 -303.38141) (xy 49.418855 -303.388931)
			(xy 49.407015 -303.411038) (xy 49.406302 -303.423574) (xy 49.406302 -303.575974) (xy 49.406938 -303.588534)
			(xy 49.418786 -303.610679) (xy 49.428908 -303.618138) (xy 49.510188 -303.67224) (xy 49.53508 -303.674526)
			(xy 49.547018 -303.6697) (xy 49.567328 -303.661581) (xy 49.60955 -303.650155) (xy 49.65291 -303.644391)
			(xy 49.67478 -303.644046) (xy 49.70077 -303.644554) (xy 49.752109 -303.652682) (xy 49.801545 -303.66874)
			(xy 49.847861 -303.692335) (xy 49.889916 -303.722883) (xy 49.926674 -303.759634) (xy 49.957231 -303.801683)
			(xy 49.980834 -303.847994) (xy 49.996903 -303.897427) (xy 50.005041 -303.948765) (xy 50.005488 -303.974754)
			(xy 50.004934 -304.002372) (xy 49.995753 -304.05684) (xy 49.97764 -304.109021) (xy 49.964848 -304.133504)
			(xy 49.958244 -304.145442) (xy 49.958752 -304.172366) (xy 50.010314 -304.25898) (xy 50.015113 -304.266355)
			(xy 50.028666 -304.277556) (xy 50.045211 -304.283507) (xy 50.054002 -304.283872)
		)
		(stroke
			(width 0)
			(type solid)
		)
		(fill yes)
		(layer "In5.Cu")
		(net "P1V8_PEX")
	)
	(gr_poly
		(pts
			(xy 282.445714 -304.283872) (xy 282.454503 -304.2835) (xy 282.471042 -304.277546) (xy 282.48459 -304.266345)
			(xy 282.489402 -304.25898) (xy 282.540964 -304.172112) (xy 282.541472 -304.145442) (xy 282.534868 -304.133504)
			(xy 282.522089 -304.109015) (xy 282.503975 -304.056835) (xy 282.494786 -304.002371) (xy 282.494228 -303.974754)
			(xy 282.494738 -303.948767) (xy 282.502868 -303.897432) (xy 282.518929 -303.848002) (xy 282.542525 -303.801692)
			(xy 282.573075 -303.759644) (xy 282.609826 -303.722893) (xy 282.651874 -303.692343) (xy 282.698184 -303.668747)
			(xy 282.747614 -303.652686) (xy 282.798949 -303.644556) (xy 282.850923 -303.644556) (xy 282.902258 -303.652686)
			(xy 282.951688 -303.668747) (xy 282.997998 -303.692343) (xy 283.040046 -303.722893) (xy 283.076797 -303.759644)
			(xy 283.107347 -303.801692) (xy 283.130943 -303.848002) (xy 283.147004 -303.897432) (xy 283.155134 -303.948767)
			(xy 283.155644 -303.974754) (xy 283.15509 -304.002372) (xy 283.145911 -304.05684) (xy 283.1278 -304.109023)
			(xy 283.115004 -304.133504) (xy 283.1084 -304.145442) (xy 283.108908 -304.172112) (xy 283.16047 -304.25898)
			(xy 283.165266 -304.26636) (xy 283.178818 -304.277573) (xy 283.195364 -304.283538) (xy 283.204158 -304.283872)
			(xy 283.395674 -304.283872) (xy 283.404467 -304.283507) (xy 283.421016 -304.277561) (xy 283.434575 -304.266363)
			(xy 283.439362 -304.25898) (xy 283.490924 -304.172112) (xy 283.491432 -304.145442) (xy 283.484828 -304.133504)
			(xy 283.47205 -304.109015) (xy 283.453939 -304.056835) (xy 283.444751 -304.002371) (xy 283.444188 -303.974754)
			(xy 283.444698 -303.948767) (xy 283.452828 -303.897432) (xy 283.468889 -303.848002) (xy 283.492485 -303.801692)
			(xy 283.523035 -303.759644) (xy 283.559786 -303.722893) (xy 283.601834 -303.692343) (xy 283.648144 -303.668747)
			(xy 283.697574 -303.652686) (xy 283.748909 -303.644556) (xy 283.800883 -303.644556) (xy 283.852218 -303.652686)
			(xy 283.901648 -303.668747) (xy 283.947958 -303.692343) (xy 283.990006 -303.722893) (xy 284.026757 -303.759644)
			(xy 284.057307 -303.801692) (xy 284.080903 -303.848002) (xy 284.096964 -303.897432) (xy 284.105094 -303.948767)
			(xy 284.105604 -303.974754) (xy 284.10505 -304.002372) (xy 284.09587 -304.05684) (xy 284.077757 -304.109021)
			(xy 284.064964 -304.133504) (xy 284.05836 -304.145442) (xy 284.058868 -304.172112) (xy 284.11043 -304.25898)
			(xy 284.115229 -304.266354) (xy 284.128783 -304.27755) (xy 284.145328 -304.283496) (xy 284.154118 -304.283872)
			(xy 284.345634 -304.283872) (xy 284.354421 -304.283497) (xy 284.370956 -304.277539) (xy 284.384498 -304.266336)
			(xy 284.389322 -304.25898) (xy 284.440884 -304.172112) (xy 284.441392 -304.145442) (xy 284.434788 -304.133504)
			(xy 284.422008 -304.109015) (xy 284.403894 -304.056836) (xy 284.394704 -304.002371) (xy 284.394148 -303.974754)
			(xy 284.394658 -303.948767) (xy 284.402788 -303.897432) (xy 284.418849 -303.848002) (xy 284.442445 -303.801692)
			(xy 284.472995 -303.759644) (xy 284.509746 -303.722893) (xy 284.551794 -303.692343) (xy 284.598104 -303.668747)
			(xy 284.647534 -303.652686) (xy 284.698869 -303.644556) (xy 284.750843 -303.644556) (xy 284.802178 -303.652686)
			(xy 284.851608 -303.668747) (xy 284.897918 -303.692343) (xy 284.939966 -303.722893) (xy 284.976717 -303.759644)
			(xy 285.007267 -303.801692) (xy 285.030863 -303.848002) (xy 285.046924 -303.897432) (xy 285.055054 -303.948767)
			(xy 285.055564 -303.974754) (xy 285.05501 -304.002372) (xy 285.045829 -304.056839) (xy 285.027714 -304.10902)
			(xy 285.014924 -304.133504) (xy 285.00832 -304.145442) (xy 285.008828 -304.172112) (xy 285.06039 -304.25898)
			(xy 285.065187 -304.266358) (xy 285.07874 -304.277565) (xy 285.095285 -304.283524) (xy 285.104078 -304.283872)
			(xy 285.295594 -304.283872) (xy 285.304385 -304.283504) (xy 285.320929 -304.277554) (xy 285.334483 -304.266354)
			(xy 285.339282 -304.25898) (xy 285.390844 -304.172112) (xy 285.391352 -304.145442) (xy 285.384748 -304.133504)
			(xy 285.371969 -304.109015) (xy 285.353857 -304.056835) (xy 285.344669 -304.002371) (xy 285.344108 -303.974754)
			(xy 285.344618 -303.948767) (xy 285.352748 -303.897432) (xy 285.368809 -303.848002) (xy 285.392405 -303.801692)
			(xy 285.422955 -303.759644) (xy 285.459706 -303.722893) (xy 285.501754 -303.692343) (xy 285.548064 -303.668747)
			(xy 285.597494 -303.652686) (xy 285.648829 -303.644556) (xy 285.700803 -303.644556) (xy 285.752138 -303.652686)
			(xy 285.801568 -303.668747) (xy 285.847878 -303.692343) (xy 285.889926 -303.722893) (xy 285.926677 -303.759644)
			(xy 285.957227 -303.801692) (xy 285.980823 -303.848002) (xy 285.996884 -303.897432) (xy 286.005014 -303.948767)
			(xy 286.005524 -303.974754) (xy 286.00497 -304.002372) (xy 285.99579 -304.05684) (xy 285.977678 -304.109022)
			(xy 285.964884 -304.133504) (xy 285.95828 -304.145442) (xy 285.958788 -304.172112) (xy 286.01035 -304.25898)
			(xy 286.015146 -304.266363) (xy 286.028696 -304.27758) (xy 286.045243 -304.283552) (xy 286.054038 -304.283872)
			(xy 286.245554 -304.283872) (xy 286.254348 -304.28351) (xy 286.270903 -304.277569) (xy 286.284467 -304.266373)
			(xy 286.289242 -304.25898) (xy 286.340804 -304.172112) (xy 286.341312 -304.145442) (xy 286.334708 -304.133504)
			(xy 286.321931 -304.109015) (xy 286.303821 -304.056835) (xy 286.294634 -304.002371) (xy 286.294068 -303.974754)
			(xy 286.294578 -303.948767) (xy 286.302708 -303.897432) (xy 286.318769 -303.848002) (xy 286.342365 -303.801692)
			(xy 286.372915 -303.759644) (xy 286.409666 -303.722893) (xy 286.451714 -303.692343) (xy 286.498024 -303.668747)
			(xy 286.547454 -303.652686) (xy 286.598789 -303.644556) (xy 286.650763 -303.644556) (xy 286.702098 -303.652686)
			(xy 286.751528 -303.668747) (xy 286.797838 -303.692343) (xy 286.839886 -303.722893) (xy 286.876637 -303.759644)
			(xy 286.907187 -303.801692) (xy 286.930783 -303.848002) (xy 286.946844 -303.897432) (xy 286.954974 -303.948767)
			(xy 286.955484 -303.974754) (xy 286.95493 -304.002372) (xy 286.945749 -304.056839) (xy 286.927635 -304.109021)
			(xy 286.914844 -304.133504) (xy 286.90824 -304.145442) (xy 286.908748 -304.172112) (xy 286.96031 -304.25898)
			(xy 286.965108 -304.266356) (xy 286.978662 -304.277558) (xy 286.995206 -304.28351) (xy 287.003998 -304.283872)
			(xy 287.195514 -304.283872) (xy 287.204303 -304.2835) (xy 287.220842 -304.277546) (xy 287.23439 -304.266345)
			(xy 287.239202 -304.25898) (xy 287.290764 -304.172112) (xy 287.291272 -304.145442) (xy 287.284668 -304.133504)
			(xy 287.271889 -304.109015) (xy 287.253775 -304.056835) (xy 287.244586 -304.002371) (xy 287.244028 -303.974754)
			(xy 287.244538 -303.948767) (xy 287.252668 -303.897432) (xy 287.268729 -303.848002) (xy 287.292325 -303.801692)
			(xy 287.322875 -303.759644) (xy 287.359626 -303.722893) (xy 287.401674 -303.692343) (xy 287.447984 -303.668747)
			(xy 287.497414 -303.652686) (xy 287.548749 -303.644556) (xy 287.600723 -303.644556) (xy 287.652058 -303.652686)
			(xy 287.701488 -303.668747) (xy 287.747798 -303.692343) (xy 287.789846 -303.722893) (xy 287.826597 -303.759644)
			(xy 287.857147 -303.801692) (xy 287.880743 -303.848002) (xy 287.896804 -303.897432) (xy 287.904934 -303.948767)
			(xy 287.905444 -303.974754) (xy 287.90489 -304.002372) (xy 287.895711 -304.05684) (xy 287.8776 -304.109023)
			(xy 287.864804 -304.133504) (xy 287.8582 -304.145442) (xy 287.858708 -304.172112) (xy 287.91027 -304.25898)
			(xy 287.915066 -304.26636) (xy 287.928618 -304.277573) (xy 287.945164 -304.283538) (xy 287.953958 -304.283872)
			(xy 288.145474 -304.283872) (xy 288.154267 -304.283507) (xy 288.170816 -304.277561) (xy 288.184375 -304.266363)
			(xy 288.189162 -304.25898) (xy 288.240724 -304.172112) (xy 288.241232 -304.145442) (xy 288.234628 -304.133504)
			(xy 288.22185 -304.109015) (xy 288.203739 -304.056835) (xy 288.194551 -304.002371) (xy 288.193988 -303.974754)
			(xy 288.194498 -303.948767) (xy 288.202628 -303.897432) (xy 288.218689 -303.848002) (xy 288.242285 -303.801692)
			(xy 288.272835 -303.759644) (xy 288.309586 -303.722893) (xy 288.351634 -303.692343) (xy 288.397944 -303.668747)
			(xy 288.447374 -303.652686) (xy 288.498709 -303.644556) (xy 288.550683 -303.644556) (xy 288.602018 -303.652686)
			(xy 288.651448 -303.668747) (xy 288.697758 -303.692343) (xy 288.739806 -303.722893) (xy 288.776557 -303.759644)
			(xy 288.807107 -303.801692) (xy 288.830703 -303.848002) (xy 288.846764 -303.897432) (xy 288.854894 -303.948767)
			(xy 288.855404 -303.974754) (xy 288.85485 -304.002372) (xy 288.84567 -304.05684) (xy 288.827557 -304.109021)
			(xy 288.814764 -304.133504) (xy 288.80816 -304.145442) (xy 288.808668 -304.172112) (xy 288.86023 -304.25898)
			(xy 288.865029 -304.266354) (xy 288.878583 -304.27755) (xy 288.895128 -304.283496) (xy 288.903918 -304.283872)
			(xy 289.095688 -304.283872) (xy 289.104479 -304.283505) (xy 289.121025 -304.277556) (xy 289.13458 -304.266357)
			(xy 289.139376 -304.25898) (xy 289.190938 -304.172112) (xy 289.191446 -304.145442) (xy 289.184842 -304.133504)
			(xy 289.172064 -304.109015) (xy 289.153952 -304.056835) (xy 289.144763 -304.002371) (xy 289.144202 -303.974754)
			(xy 289.144712 -303.948767) (xy 289.152842 -303.897432) (xy 289.168903 -303.848002) (xy 289.192499 -303.801692)
			(xy 289.223049 -303.759644) (xy 289.2598 -303.722893) (xy 289.301848 -303.692343) (xy 289.348158 -303.668747)
			(xy 289.397588 -303.652686) (xy 289.448923 -303.644556) (xy 289.500897 -303.644556) (xy 289.552232 -303.652686)
			(xy 289.601662 -303.668747) (xy 289.647972 -303.692343) (xy 289.69002 -303.722893) (xy 289.726771 -303.759644)
			(xy 289.757321 -303.801692) (xy 289.780917 -303.848002) (xy 289.796978 -303.897432) (xy 289.805108 -303.948767)
			(xy 289.805618 -303.974754) (xy 289.805064 -304.002372) (xy 289.795884 -304.05684) (xy 289.777772 -304.109022)
			(xy 289.764978 -304.133504) (xy 289.758374 -304.145442) (xy 289.758882 -304.172112) (xy 289.810444 -304.25898)
			(xy 289.815239 -304.266363) (xy 289.82879 -304.277582) (xy 289.845336 -304.283556) (xy 289.854132 -304.283872)
			(xy 290.045648 -304.283872) (xy 290.054443 -304.283511) (xy 290.070999 -304.277571) (xy 290.084565 -304.266375)
			(xy 290.089336 -304.25898) (xy 290.140898 -304.172112) (xy 290.141406 -304.145442) (xy 290.134802 -304.133504)
			(xy 290.122022 -304.109016) (xy 290.103906 -304.056836) (xy 290.094716 -304.002371) (xy 290.094162 -303.974754)
			(xy 290.094672 -303.948767) (xy 290.102802 -303.897432) (xy 290.118863 -303.848002) (xy 290.142459 -303.801692)
			(xy 290.173009 -303.759644) (xy 290.20976 -303.722893) (xy 290.251808 -303.692343) (xy 290.298118 -303.668747)
			(xy 290.347548 -303.652686) (xy 290.398883 -303.644556) (xy 290.450857 -303.644556) (xy 290.502192 -303.652686)
			(xy 290.551622 -303.668747) (xy 290.597932 -303.692343) (xy 290.63998 -303.722893) (xy 290.676731 -303.759644)
			(xy 290.707281 -303.801692) (xy 290.730877 -303.848002) (xy 290.746938 -303.897432) (xy 290.755068 -303.948767)
			(xy 290.755578 -303.974754) (xy 290.755024 -304.002372) (xy 290.745843 -304.056839) (xy 290.727729 -304.10902)
			(xy 290.714938 -304.133504) (xy 290.708334 -304.145442) (xy 290.708842 -304.172112) (xy 290.760404 -304.25898)
			(xy 290.765202 -304.266356) (xy 290.778755 -304.27756) (xy 290.7953 -304.283514) (xy 290.804092 -304.283872)
			(xy 291.945568 -304.283872) (xy 291.954361 -304.283508) (xy 291.970912 -304.277564) (xy 291.984472 -304.266366)
			(xy 291.989256 -304.25898) (xy 292.040818 -304.172112) (xy 292.041326 -304.145442) (xy 292.034722 -304.133504)
			(xy 292.021944 -304.109015) (xy 292.003834 -304.056835) (xy 291.994646 -304.002371) (xy 291.994082 -303.974754)
			(xy 291.994592 -303.948767) (xy 292.002722 -303.897432) (xy 292.018783 -303.848002) (xy 292.042379 -303.801692)
			(xy 292.072929 -303.759644) (xy 292.10968 -303.722893) (xy 292.151728 -303.692343) (xy 292.198038 -303.668747)
			(xy 292.247468 -303.652686) (xy 292.298803 -303.644556) (xy 292.350777 -303.644556) (xy 292.402112 -303.652686)
			(xy 292.451542 -303.668747) (xy 292.497852 -303.692343) (xy 292.5399 -303.722893) (xy 292.576651 -303.759644)
			(xy 292.607201 -303.801692) (xy 292.630797 -303.848002) (xy 292.646858 -303.897432) (xy 292.654988 -303.948767)
			(xy 292.655498 -303.974754) (xy 292.654944 -304.002372) (xy 292.645764 -304.05684) (xy 292.62765 -304.109021)
			(xy 292.614858 -304.133504) (xy 292.608254 -304.145442) (xy 292.608762 -304.172112) (xy 292.660324 -304.25898)
			(xy 292.665123 -304.266354) (xy 292.678677 -304.277552) (xy 292.695221 -304.2835) (xy 292.704012 -304.283872)
			(xy 292.895528 -304.283872) (xy 292.904316 -304.283498) (xy 292.920852 -304.277541) (xy 292.934396 -304.266339)
			(xy 292.939216 -304.25898) (xy 292.990778 -304.172112) (xy 292.991286 -304.145442) (xy 292.984682 -304.133504)
			(xy 292.971902 -304.109015) (xy 292.953788 -304.056836) (xy 292.944599 -304.002371) (xy 292.944042 -303.974754)
			(xy 292.944552 -303.948767) (xy 292.952682 -303.897432) (xy 292.968743 -303.848002) (xy 292.992339 -303.801692)
			(xy 293.022889 -303.759644) (xy 293.05964 -303.722893) (xy 293.101688 -303.692343) (xy 293.147998 -303.668747)
			(xy 293.197428 -303.652686) (xy 293.248763 -303.644556) (xy 293.300737 -303.644556) (xy 293.352072 -303.652686)
			(xy 293.401502 -303.668747) (xy 293.447812 -303.692343) (xy 293.48986 -303.722893) (xy 293.526611 -303.759644)
			(xy 293.557161 -303.801692) (xy 293.580757 -303.848002) (xy 293.596818 -303.897432) (xy 293.604948 -303.948767)
			(xy 293.605458 -303.974754) (xy 293.604904 -304.002372) (xy 293.595722 -304.056839) (xy 293.577607 -304.10902)
			(xy 293.564818 -304.133504) (xy 293.558214 -304.145442) (xy 293.558722 -304.172112) (xy 293.610284 -304.25898)
			(xy 293.615081 -304.266359) (xy 293.628633 -304.277568) (xy 293.645179 -304.283528) (xy 293.653972 -304.283872)
			(xy 293.845488 -304.283872) (xy 293.854279 -304.283505) (xy 293.870825 -304.277556) (xy 293.88438 -304.266357)
			(xy 293.889176 -304.25898) (xy 293.940738 -304.172112) (xy 293.941246 -304.145442) (xy 293.934642 -304.133504)
			(xy 293.921864 -304.109015) (xy 293.903752 -304.056835) (xy 293.894563 -304.002371) (xy 293.894002 -303.974754)
			(xy 293.894512 -303.948767) (xy 293.902642 -303.897432) (xy 293.918703 -303.848002) (xy 293.942299 -303.801692)
			(xy 293.972849 -303.759644) (xy 294.0096 -303.722893) (xy 294.051648 -303.692343) (xy 294.097958 -303.668747)
			(xy 294.147388 -303.652686) (xy 294.198723 -303.644556) (xy 294.250697 -303.644556) (xy 294.302032 -303.652686)
			(xy 294.351462 -303.668747) (xy 294.397772 -303.692343) (xy 294.43982 -303.722893) (xy 294.476571 -303.759644)
			(xy 294.507121 -303.801692) (xy 294.530717 -303.848002) (xy 294.546778 -303.897432) (xy 294.554908 -303.948767)
			(xy 294.555418 -303.974754) (xy 294.554864 -304.002372) (xy 294.545684 -304.05684) (xy 294.527572 -304.109022)
			(xy 294.514778 -304.133504) (xy 294.508174 -304.145442) (xy 294.508682 -304.172112) (xy 294.560244 -304.25898)
			(xy 294.565039 -304.266363) (xy 294.57859 -304.277582) (xy 294.595136 -304.283556) (xy 294.603932 -304.283872)
			(xy 294.795702 -304.283872) (xy 294.804492 -304.283502) (xy 294.821035 -304.277551) (xy 294.834586 -304.266351)
			(xy 294.83939 -304.25898) (xy 294.890952 -304.172112) (xy 294.89146 -304.145442) (xy 294.884856 -304.133504)
			(xy 294.872077 -304.109015) (xy 294.853964 -304.056835) (xy 294.844776 -304.002371) (xy 294.844216 -303.974754)
			(xy 294.844726 -303.948767) (xy 294.852856 -303.897432) (xy 294.868917 -303.848002) (xy 294.892513 -303.801692)
			(xy 294.923063 -303.759644) (xy 294.959814 -303.722893) (xy 295.001862 -303.692343) (xy 295.048172 -303.668747)
			(xy 295.097602 -303.652686) (xy 295.148937 -303.644556) (xy 295.200911 -303.644556) (xy 295.252246 -303.652686)
			(xy 295.301676 -303.668747) (xy 295.347986 -303.692343) (xy 295.390034 -303.722893) (xy 295.426785 -303.759644)
			(xy 295.457335 -303.801692) (xy 295.480931 -303.848002) (xy 295.496992 -303.897432) (xy 295.505122 -303.948767)
			(xy 295.505632 -303.974754) (xy 295.505078 -304.002372) (xy 295.495899 -304.05684) (xy 295.477787 -304.109023)
			(xy 295.464992 -304.133504) (xy 295.458388 -304.145442) (xy 295.458896 -304.172112) (xy 295.510458 -304.25898)
			(xy 295.515254 -304.266362) (xy 295.528805 -304.277577) (xy 295.545351 -304.283546) (xy 295.554146 -304.283872)
			(xy 295.745662 -304.283872) (xy 295.754456 -304.283509) (xy 295.771008 -304.277566) (xy 295.78457 -304.266369)
			(xy 295.78935 -304.25898) (xy 295.840912 -304.172112) (xy 295.84142 -304.145442) (xy 295.834816 -304.133504)
			(xy 295.822039 -304.109015) (xy 295.803928 -304.056835) (xy 295.794741 -304.002371) (xy 295.794176 -303.974754)
			(xy 295.794686 -303.948767) (xy 295.802816 -303.897432) (xy 295.818877 -303.848002) (xy 295.842473 -303.801692)
			(xy 295.873023 -303.759644) (xy 295.909774 -303.722893) (xy 295.951822 -303.692343) (xy 295.998132 -303.668747)
			(xy 296.047562 -303.652686) (xy 296.098897 -303.644556) (xy 296.150871 -303.644556) (xy 296.202206 -303.652686)
			(xy 296.251636 -303.668747) (xy 296.297946 -303.692343) (xy 296.339994 -303.722893) (xy 296.376745 -303.759644)
			(xy 296.407295 -303.801692) (xy 296.430891 -303.848002) (xy 296.446952 -303.897432) (xy 296.455082 -303.948767)
			(xy 296.455592 -303.974754) (xy 296.455038 -304.002372) (xy 296.445857 -304.05684) (xy 296.427744 -304.109021)
			(xy 296.414952 -304.133504) (xy 296.408348 -304.145442) (xy 296.408856 -304.172112) (xy 296.460418 -304.25898)
			(xy 296.465217 -304.266355) (xy 296.47877 -304.277555) (xy 296.495315 -304.283505) (xy 296.504106 -304.283872)
			(xy 296.695622 -304.283872) (xy 296.70441 -304.283499) (xy 296.720948 -304.277543) (xy 296.734493 -304.266342)
			(xy 296.73931 -304.25898) (xy 296.790872 -304.172112) (xy 296.79138 -304.145442) (xy 296.784776 -304.133504)
			(xy 296.771996 -304.109015) (xy 296.753883 -304.056836) (xy 296.744693 -304.002371) (xy 296.744136 -303.974754)
			(xy 296.744646 -303.948767) (xy 296.752776 -303.897432) (xy 296.768837 -303.848002) (xy 296.792433 -303.801692)
			(xy 296.822983 -303.759644) (xy 296.859734 -303.722893) (xy 296.901782 -303.692343) (xy 296.948092 -303.668747)
			(xy 296.997522 -303.652686) (xy 297.048857 -303.644556) (xy 297.100831 -303.644556) (xy 297.152166 -303.652686)
			(xy 297.201596 -303.668747) (xy 297.247906 -303.692343) (xy 297.289954 -303.722893) (xy 297.326705 -303.759644)
			(xy 297.357255 -303.801692) (xy 297.380851 -303.848002) (xy 297.396912 -303.897432) (xy 297.405042 -303.948767)
			(xy 297.405552 -303.974754) (xy 297.404998 -304.002372) (xy 297.395816 -304.056839) (xy 297.377701 -304.109019)
			(xy 297.364912 -304.133504) (xy 297.358308 -304.145442) (xy 297.358816 -304.172112) (xy 297.410378 -304.25898)
			(xy 297.415175 -304.26636) (xy 297.428727 -304.27757) (xy 297.445272 -304.283533) (xy 297.454066 -304.283872)
			(xy 297.645582 -304.283872) (xy 297.654374 -304.283506) (xy 297.670921 -304.277558) (xy 297.684478 -304.26636)
			(xy 297.68927 -304.25898) (xy 297.740832 -304.172112) (xy 297.74134 -304.145442) (xy 297.734736 -304.133504)
			(xy 297.721958 -304.109015) (xy 297.703846 -304.056835) (xy 297.694658 -304.002371) (xy 297.694096 -303.974754)
			(xy 297.694606 -303.948767) (xy 297.702736 -303.897432) (xy 297.718797 -303.848002) (xy 297.742393 -303.801692)
			(xy 297.772943 -303.759644) (xy 297.809694 -303.722893) (xy 297.851742 -303.692343) (xy 297.898052 -303.668747)
			(xy 297.947482 -303.652686) (xy 297.998817 -303.644556) (xy 298.050791 -303.644556) (xy 298.102126 -303.652686)
			(xy 298.151556 -303.668747) (xy 298.197866 -303.692343) (xy 298.239914 -303.722893) (xy 298.276665 -303.759644)
			(xy 298.307215 -303.801692) (xy 298.330811 -303.848002) (xy 298.346872 -303.897432) (xy 298.355002 -303.948767)
			(xy 298.355512 -303.974754) (xy 298.354958 -304.002372) (xy 298.345778 -304.05684) (xy 298.327665 -304.109022)
			(xy 298.314872 -304.133504) (xy 298.308268 -304.145442) (xy 298.308776 -304.172112) (xy 298.360338 -304.25898)
			(xy 298.365138 -304.266353) (xy 298.378692 -304.277547) (xy 298.395236 -304.283491) (xy 298.404026 -304.283872)
			(xy 298.595542 -304.283872) (xy 298.604337 -304.283512) (xy 298.620895 -304.277573) (xy 298.634462 -304.266378)
			(xy 298.63923 -304.25898) (xy 298.690792 -304.172112) (xy 298.6913 -304.145442) (xy 298.684696 -304.133504)
			(xy 298.671916 -304.109015) (xy 298.653801 -304.056836) (xy 298.644611 -304.002371) (xy 298.644056 -303.974754)
			(xy 298.644566 -303.948767) (xy 298.652696 -303.897432) (xy 298.668757 -303.848002) (xy 298.692353 -303.801692)
			(xy 298.722903 -303.759644) (xy 298.759654 -303.722893) (xy 298.801702 -303.692343) (xy 298.848012 -303.668747)
			(xy 298.897442 -303.652686) (xy 298.948777 -303.644556) (xy 299.000751 -303.644556) (xy 299.052086 -303.652686)
			(xy 299.101516 -303.668747) (xy 299.147826 -303.692343) (xy 299.189874 -303.722893) (xy 299.226625 -303.759644)
			(xy 299.257175 -303.801692) (xy 299.280771 -303.848002) (xy 299.296832 -303.897432) (xy 299.304962 -303.948767)
			(xy 299.305472 -303.974754) (xy 299.304918 -304.002372) (xy 299.295737 -304.056839) (xy 299.277622 -304.10902)
			(xy 299.264832 -304.133504) (xy 299.258228 -304.145442) (xy 299.258736 -304.172112) (xy 299.310298 -304.25898)
			(xy 299.315096 -304.266357) (xy 299.328648 -304.277562) (xy 299.345194 -304.283519) (xy 299.353986 -304.283872)
			(xy 299.545502 -304.283872) (xy 299.554292 -304.283502) (xy 299.570835 -304.277551) (xy 299.584386 -304.266351)
			(xy 299.58919 -304.25898) (xy 299.640752 -304.172112) (xy 299.64126 -304.145442) (xy 299.634656 -304.133504)
			(xy 299.621877 -304.109015) (xy 299.603764 -304.056835) (xy 299.594576 -304.002371) (xy 299.594016 -303.974754)
			(xy 299.594526 -303.948767) (xy 299.602656 -303.897432) (xy 299.618717 -303.848002) (xy 299.642313 -303.801692)
			(xy 299.672863 -303.759644) (xy 299.709614 -303.722893) (xy 299.751662 -303.692343) (xy 299.797972 -303.668747)
			(xy 299.847402 -303.652686) (xy 299.898737 -303.644556) (xy 299.950711 -303.644556) (xy 300.002046 -303.652686)
			(xy 300.051476 -303.668747) (xy 300.097786 -303.692343) (xy 300.139834 -303.722893) (xy 300.176585 -303.759644)
			(xy 300.207135 -303.801692) (xy 300.230731 -303.848002) (xy 300.246792 -303.897432) (xy 300.254922 -303.948767)
			(xy 300.255432 -303.974754) (xy 300.254878 -304.002372) (xy 300.245699 -304.05684) (xy 300.227587 -304.109023)
			(xy 300.214792 -304.133504) (xy 300.208188 -304.145442) (xy 300.208696 -304.172112) (xy 300.260258 -304.25898)
			(xy 300.265054 -304.266362) (xy 300.278605 -304.277577) (xy 300.295151 -304.283546) (xy 300.303946 -304.283872)
			(xy 300.503336 -304.283872) (xy 300.512142 -304.283449) (xy 300.528688 -304.277398) (xy 300.542224 -304.266122)
			(xy 300.547024 -304.258726) (xy 300.598332 -304.171096) (xy 300.598332 -304.144172) (xy 300.591728 -304.132488)
			(xy 300.578311 -304.107517) (xy 300.559281 -304.054124) (xy 300.549622 -303.998269) (xy 300.549056 -303.969928)
			(xy 300.549566 -303.943941) (xy 300.557696 -303.892606) (xy 300.573757 -303.843176) (xy 300.597353 -303.796866)
			(xy 300.627903 -303.754818) (xy 300.664654 -303.718067) (xy 300.706702 -303.687517) (xy 300.753012 -303.663921)
			(xy 300.802442 -303.64786) (xy 300.853777 -303.63973) (xy 300.905751 -303.63973) (xy 300.957086 -303.64786)
			(xy 301.006516 -303.663921) (xy 301.052826 -303.687517) (xy 301.094874 -303.718067) (xy 301.131625 -303.754818)
			(xy 301.162175 -303.796866) (xy 301.185771 -303.843176) (xy 301.201832 -303.892606) (xy 301.209962 -303.943941)
			(xy 301.210472 -303.969928) (xy 301.209888 -303.998268) (xy 301.200231 -304.05412) (xy 301.181203 -304.10751)
			(xy 301.1678 -304.132488) (xy 301.161196 -304.144172) (xy 301.161196 -304.171096) (xy 301.212504 -304.258726)
			(xy 301.217266 -304.266156) (xy 301.230799 -304.277461) (xy 301.247375 -304.283475) (xy 301.256192 -304.283872)
			(xy 301.445676 -304.283872) (xy 301.454468 -304.283507) (xy 301.471017 -304.277561) (xy 301.484576 -304.266363)
			(xy 301.489364 -304.25898) (xy 301.540926 -304.172112) (xy 301.541434 -304.145442) (xy 301.53483 -304.133504)
			(xy 301.522052 -304.109015) (xy 301.503941 -304.056835) (xy 301.494753 -304.002371) (xy 301.49419 -303.974754)
			(xy 301.494703 -303.948769) (xy 301.502839 -303.89744) (xy 301.518904 -303.848016) (xy 301.542503 -303.801712)
			(xy 301.573053 -303.75967) (xy 301.609804 -303.722924) (xy 301.65185 -303.692379) (xy 301.698156 -303.668787)
			(xy 301.747583 -303.652729) (xy 301.798913 -303.6446) (xy 301.824898 -303.644046) (xy 301.848166 -303.644443)
			(xy 301.894243 -303.650969) (xy 301.938948 -303.663894) (xy 301.981399 -303.682961) (xy 302.020756 -303.707794)
			(xy 302.038766 -303.722532) (xy 302.050196 -303.732184) (xy 302.079406 -303.736248) (xy 302.176688 -303.69129)
			(xy 302.185321 -303.686855) (xy 302.198665 -303.672787) (xy 302.205807 -303.654759) (xy 302.206152 -303.645062)
			(xy 302.206152 -300.978062) (xy 302.205721 -300.967996) (xy 302.197991 -300.949406) (xy 302.191166 -300.941994)
			(xy 301.86757 -300.618398) (xy 301.86017 -300.611557) (xy 301.841572 -300.603833) (xy 301.831502 -300.603412)
			(xy 300.512988 -300.603412) (xy 300.502918 -300.602987) (xy 300.484316 -300.595271) (xy 300.47692 -300.588426)
			(xy 300.454822 -300.566328) (xy 300.447985 -300.558927) (xy 300.440273 -300.540328) (xy 300.439836 -300.53026)
			(xy 300.439836 -297.41114) (xy 300.440271 -297.401075) (xy 300.448005 -297.38249) (xy 300.454822 -297.375072)
			(xy 300.54042 -297.289474) (xy 300.547532 -297.275758) (xy 300.548802 -297.267884) (xy 300.5537 -297.242647)
			(xy 300.570266 -297.193982) (xy 300.594165 -297.148468) (xy 300.624821 -297.107201) (xy 300.661494 -297.071177)
			(xy 300.703302 -297.041263) (xy 300.749235 -297.018181) (xy 300.798188 -297.002486) (xy 300.84898 -296.994557)
			(xy 300.874684 -296.994072) (xy 300.901722 -296.99461) (xy 300.955077 -297.003407) (xy 301.006289 -297.020769)
			(xy 301.053993 -297.046233) (xy 301.096918 -297.079121) (xy 301.133919 -297.118556) (xy 301.164009 -297.163485)
			(xy 301.186387 -297.212713) (xy 301.193962 -297.238674) (xy 301.198534 -297.255438) (xy 301.225712 -297.276266)
			(xy 301.47387 -297.276266) (xy 301.501048 -297.255438) (xy 301.50562 -297.238674) (xy 301.512697 -297.214228)
			(xy 301.533319 -297.167703) (xy 301.560826 -297.124887) (xy 301.594568 -297.08679) (xy 301.633748 -297.054312)
			(xy 301.677441 -297.02822) (xy 301.724615 -297.00913) (xy 301.774158 -296.997493) (xy 301.824898 -296.993583)
			(xy 301.875638 -296.997493) (xy 301.925181 -297.00913) (xy 301.972355 -297.02822) (xy 302.016048 -297.054312)
			(xy 302.055228 -297.08679) (xy 302.08897 -297.124887) (xy 302.116477 -297.167703) (xy 302.137099 -297.214228)
			(xy 302.144176 -297.238674) (xy 302.148748 -297.255438) (xy 302.175926 -297.276266) (xy 302.42383 -297.276266)
			(xy 302.451008 -297.255438) (xy 302.45558 -297.238674) (xy 302.462391 -297.215119) (xy 302.482008 -297.170182)
			(xy 302.508048 -297.128636) (xy 302.53994 -297.091393) (xy 302.576984 -297.05927) (xy 302.618368 -297.032973)
			(xy 302.663182 -297.013078) (xy 302.710444 -297.000022) (xy 302.734726 -296.996612) (xy 302.75403 -296.994072)
			(xy 302.77943 -296.96537) (xy 302.77943 -296.73423) (xy 302.75403 -296.705528) (xy 302.734726 -296.702988)
			(xy 302.709743 -296.69945) (xy 302.661174 -296.685782) (xy 302.615246 -296.664893) (xy 302.573024 -296.637268)
			(xy 302.53549 -296.603549) (xy 302.503515 -296.564519) (xy 302.477841 -296.521084) (xy 302.459064 -296.474252)
			(xy 302.44762 -296.425111) (xy 302.443776 -296.374802) (xy 302.44762 -296.324493) (xy 302.459062 -296.275352)
			(xy 302.477838 -296.228521) (xy 302.503512 -296.185085) (xy 302.535487 -296.146054) (xy 302.57302 -296.112335)
			(xy 302.615241 -296.08471) (xy 302.661169 -296.06382) (xy 302.709738 -296.050151) (xy 302.734726 -296.046652)
			(xy 302.75403 -296.044112) (xy 302.77943 -296.01541) (xy 302.77943 -294.83431) (xy 302.75403 -294.805608)
			(xy 302.734726 -294.803068) (xy 302.709744 -294.79953) (xy 302.661179 -294.785862) (xy 302.615253 -294.764974)
			(xy 302.573034 -294.737351) (xy 302.535503 -294.703634) (xy 302.50353 -294.664606) (xy 302.477857 -294.621173)
			(xy 302.459082 -294.574344) (xy 302.44764 -294.525206) (xy 302.443796 -294.4749) (xy 302.44764 -294.424594)
			(xy 302.459082 -294.375456) (xy 302.477857 -294.328627) (xy 302.50353 -294.285194) (xy 302.535503 -294.246166)
			(xy 302.573034 -294.212449) (xy 302.615253 -294.184826) (xy 302.661179 -294.163938) (xy 302.709744 -294.15027)
			(xy 302.734726 -294.146732) (xy 302.75403 -294.144192) (xy 302.77943 -294.11549) (xy 302.77943 -293.88435)
			(xy 302.75403 -293.855648) (xy 302.734726 -293.853108) (xy 302.709741 -293.84957) (xy 302.661169 -293.835901)
			(xy 302.615238 -293.815011) (xy 302.573014 -293.787385) (xy 302.535477 -293.753665) (xy 302.5035 -293.714632)
			(xy 302.477824 -293.671195) (xy 302.459046 -293.62436) (xy 302.447601 -293.575217) (xy 302.443756 -293.524905)
			(xy 302.4476 -293.474593) (xy 302.459043 -293.425449) (xy 302.47782 -293.378614) (xy 302.503494 -293.335176)
			(xy 302.535471 -293.296142) (xy 302.573006 -293.262421) (xy 302.61523 -293.234794) (xy 302.66116 -293.213902)
			(xy 302.709732 -293.200232) (xy 302.734726 -293.196772) (xy 302.75403 -293.194232) (xy 302.77943 -293.16553)
			(xy 302.77943 -292.93439) (xy 302.75403 -292.905688) (xy 302.734726 -292.903148) (xy 302.709746 -292.89961)
			(xy 302.661183 -292.885943) (xy 302.61526 -292.865055) (xy 302.573045 -292.837433) (xy 302.535515 -292.803718)
			(xy 302.503544 -292.764692) (xy 302.477874 -292.721262) (xy 302.4591 -292.674436) (xy 302.447659 -292.625301)
			(xy 302.443815 -292.574998) (xy 302.44766 -292.524695) (xy 302.459102 -292.47556) (xy 302.477876 -292.428734)
			(xy 302.503547 -292.385304) (xy 302.535519 -292.346278) (xy 302.573048 -292.312564) (xy 302.615265 -292.284942)
			(xy 302.661188 -292.264056) (xy 302.709751 -292.250389) (xy 302.734726 -292.246812) (xy 302.75403 -292.244272)
			(xy 302.77943 -292.21557) (xy 302.77943 -291.984176) (xy 302.75403 -291.955474) (xy 302.734726 -291.952934)
			(xy 302.709747 -291.949396) (xy 302.661186 -291.935729) (xy 302.615266 -291.914843) (xy 302.573052 -291.887221)
			(xy 302.535524 -291.853507) (xy 302.503555 -291.814483) (xy 302.477886 -291.771054) (xy 302.459113 -291.72423)
			(xy 302.447672 -291.675097) (xy 302.443829 -291.624796) (xy 302.447674 -291.574495) (xy 302.459115 -291.525362)
			(xy 302.477889 -291.478538) (xy 302.50356 -291.43511) (xy 302.53553 -291.396087) (xy 302.573058 -291.362374)
			(xy 302.615273 -291.334754) (xy 302.661194 -291.313868) (xy 302.709755 -291.300202) (xy 302.734726 -291.296598)
			(xy 302.75403 -291.294058) (xy 302.77943 -291.265356) (xy 302.77943 -291.034216) (xy 302.75403 -291.005514)
			(xy 302.734726 -291.002974) (xy 302.709744 -290.999436) (xy 302.661177 -290.985768) (xy 302.615251 -290.96488)
			(xy 302.573031 -290.937256) (xy 302.535499 -290.903538) (xy 302.503525 -290.86451) (xy 302.477852 -290.821076)
			(xy 302.459077 -290.774246) (xy 302.447634 -290.725108) (xy 302.44379 -290.674801) (xy 302.447634 -290.624494)
			(xy 302.459076 -290.575355) (xy 302.477852 -290.528525) (xy 302.503524 -290.485092) (xy 302.535498 -290.446063)
			(xy 302.57303 -290.412345) (xy 302.61525 -290.384721) (xy 302.661176 -290.363832) (xy 302.709743 -290.350164)
			(xy 302.734726 -290.346638) (xy 302.75403 -290.344098) (xy 302.77943 -290.315396) (xy 302.77943 -290.084256)
			(xy 302.75403 -290.055554) (xy 302.734726 -290.053014) (xy 302.709741 -290.049476) (xy 302.661168 -290.035807)
			(xy 302.615236 -290.014917) (xy 302.573011 -289.98729) (xy 302.535474 -289.953569) (xy 302.503495 -289.914536)
			(xy 302.477819 -289.871098) (xy 302.45904 -289.824263) (xy 302.447595 -289.775118) (xy 302.44375 -289.724806)
			(xy 302.447594 -289.674493) (xy 302.459037 -289.625348) (xy 302.477814 -289.578512) (xy 302.503489 -289.535073)
			(xy 302.535466 -289.496039) (xy 302.573002 -289.462317) (xy 302.615226 -289.434689) (xy 302.661158 -289.413797)
			(xy 302.70973 -289.400126) (xy 302.734726 -289.396678) (xy 302.75403 -289.394138) (xy 302.77943 -289.365436)
			(xy 302.77943 -289.134296) (xy 302.75403 -289.105594) (xy 302.734726 -289.103054) (xy 302.708539 -289.099319)
			(xy 302.657732 -289.084608) (xy 302.609913 -289.061999) (xy 302.566301 -289.03207) (xy 302.528006 -288.995582)
			(xy 302.496006 -288.953466) (xy 302.471115 -288.906794) (xy 302.453968 -288.856756) (xy 302.445002 -288.804628)
			(xy 302.44415 -288.778188) (xy 302.44415 -288.774632) (xy 302.44457 -288.750731) (xy 302.451453 -288.703427)
			(xy 302.457866 -288.680398) (xy 302.460108 -288.671564) (xy 302.458869 -288.653393) (xy 302.45134 -288.63681)
			(xy 302.445166 -288.630106) (xy 302.228504 -288.413444) (xy 302.221392 -288.406078) (xy 302.202596 -288.398458)
			(xy 301.20844 -288.398458) (xy 301.198852 -288.398866) (xy 301.181005 -288.405885) (xy 301.16695 -288.418931)
			(xy 301.162466 -288.427414) (xy 301.12335 -288.510472) (xy 301.119587 -288.519337) (xy 301.118303 -288.538538)
			(xy 301.124186 -288.55686) (xy 301.129954 -288.564574) (xy 301.147612 -288.586963) (xy 301.175773 -288.63654)
			(xy 301.195029 -288.690207) (xy 301.204812 -288.746378) (xy 301.205392 -288.774886) (xy 301.204882 -288.800873)
			(xy 301.196752 -288.852208) (xy 301.180691 -288.901638) (xy 301.157095 -288.947948) (xy 301.126545 -288.989996)
			(xy 301.089794 -289.026747) (xy 301.047746 -289.057297) (xy 301.001436 -289.080893) (xy 300.952006 -289.096954)
			(xy 300.900671 -289.105084) (xy 300.848697 -289.105084) (xy 300.797362 -289.096954) (xy 300.747932 -289.080893)
			(xy 300.701622 -289.057297) (xy 300.659574 -289.026747) (xy 300.622823 -288.989996) (xy 300.592273 -288.947948)
			(xy 300.568677 -288.901638) (xy 300.552616 -288.852208) (xy 300.544486 -288.800873) (xy 300.543976 -288.774886)
			(xy 300.544067 -288.762136) (xy 300.545974 -288.736707) (xy 300.547786 -288.724086) (xy 300.552944 -288.694978)
			(xy 300.572214 -288.639099) (xy 300.601117 -288.587539) (xy 300.619414 -288.56432) (xy 300.625185 -288.556661)
			(xy 300.63105 -288.538417) (xy 300.629772 -288.519297) (xy 300.626018 -288.510472) (xy 300.586902 -288.427414)
			(xy 300.582428 -288.418914) (xy 300.568401 -288.405814) (xy 300.550527 -288.398821) (xy 300.540928 -288.398458)
			(xy 300.25848 -288.398458) (xy 300.248866 -288.398875) (xy 300.230993 -288.40597) (xy 300.216995 -288.419154)
			(xy 300.212506 -288.427668) (xy 300.166786 -288.524188) (xy 300.170596 -288.553144) (xy 300.179994 -288.564574)
			(xy 300.19765 -288.586964) (xy 300.225808 -288.636541) (xy 300.245062 -288.690208) (xy 300.254843 -288.746378)
			(xy 300.255432 -288.774886) (xy 300.254922 -288.800873) (xy 300.246792 -288.852208) (xy 300.230731 -288.901638)
			(xy 300.207135 -288.947948) (xy 300.176585 -288.989996) (xy 300.139834 -289.026747) (xy 300.097786 -289.057297)
			(xy 300.051476 -289.080893) (xy 300.002046 -289.096954) (xy 299.950711 -289.105084) (xy 299.898737 -289.105084)
			(xy 299.847402 -289.096954) (xy 299.797972 -289.080893) (xy 299.751662 -289.057297) (xy 299.709614 -289.026747)
			(xy 299.672863 -288.989996) (xy 299.642313 -288.947948) (xy 299.618717 -288.901638) (xy 299.602656 -288.852208)
			(xy 299.594526 -288.800873) (xy 299.594016 -288.774886) (xy 299.594614 -288.746379) (xy 299.604388 -288.690209)
			(xy 299.623645 -288.636546) (xy 299.651814 -288.586977) (xy 299.669454 -288.564574) (xy 299.678852 -288.553144)
			(xy 299.682662 -288.524188) (xy 299.636942 -288.427668) (xy 299.63248 -288.419136) (xy 299.618467 -288.405954)
			(xy 299.600587 -288.398853) (xy 299.590968 -288.398458) (xy 299.30852 -288.398458) (xy 299.298901 -288.398868)
			(xy 299.281018 -288.405955) (xy 299.267007 -288.419137) (xy 299.262546 -288.427668) (xy 299.216826 -288.524188)
			(xy 299.220636 -288.553144) (xy 299.230034 -288.564574) (xy 299.247693 -288.586963) (xy 299.275856 -288.636539)
			(xy 299.295113 -288.690206) (xy 299.304896 -288.746378) (xy 299.305472 -288.774886) (xy 299.304962 -288.800873)
			(xy 299.296832 -288.852208) (xy 299.280771 -288.901638) (xy 299.257175 -288.947948) (xy 299.226625 -288.989996)
			(xy 299.189874 -289.026747) (xy 299.147826 -289.057297) (xy 299.101516 -289.080893) (xy 299.052086 -289.096954)
			(xy 299.000751 -289.105084) (xy 298.948777 -289.105084) (xy 298.897442 -289.096954) (xy 298.848012 -289.080893)
			(xy 298.801702 -289.057297) (xy 298.759654 -289.026747) (xy 298.722903 -288.989996) (xy 298.692353 -288.947948)
			(xy 298.668757 -288.901638) (xy 298.652696 -288.852208) (xy 298.644566 -288.800873) (xy 298.644056 -288.774886)
			(xy 298.644653 -288.746379) (xy 298.654426 -288.690208) (xy 298.67368 -288.636542) (xy 298.701846 -288.58697)
			(xy 298.719494 -288.564574) (xy 298.728892 -288.553144) (xy 298.732702 -288.524188) (xy 298.686982 -288.427668)
			(xy 298.682517 -288.419143) (xy 298.668501 -288.405977) (xy 298.650623 -288.398896) (xy 298.641008 -288.398458)
			(xy 298.35856 -288.398458) (xy 298.348948 -288.398878) (xy 298.331081 -288.405978) (xy 298.317089 -288.419162)
			(xy 298.312586 -288.427668) (xy 298.266866 -288.524188) (xy 298.270676 -288.553144) (xy 298.280074 -288.564574)
			(xy 298.297731 -288.586964) (xy 298.325891 -288.636541) (xy 298.345146 -288.690207) (xy 298.354927 -288.746378)
			(xy 298.355512 -288.774886) (xy 298.355002 -288.800873) (xy 298.346872 -288.852208) (xy 298.330811 -288.901638)
			(xy 298.307215 -288.947948) (xy 298.276665 -288.989996) (xy 298.239914 -289.026747) (xy 298.197866 -289.057297)
			(xy 298.151556 -289.080893) (xy 298.102126 -289.096954) (xy 298.050791 -289.105084) (xy 297.998817 -289.105084)
			(xy 297.947482 -289.096954) (xy 297.898052 -289.080893) (xy 297.851742 -289.057297) (xy 297.809694 -289.026747)
			(xy 297.772943 -288.989996) (xy 297.742393 -288.947948) (xy 297.718797 -288.901638) (xy 297.702736 -288.852208)
			(xy 297.694606 -288.800873) (xy 297.694096 -288.774886) (xy 297.694693 -288.746379) (xy 297.704467 -288.690209)
			(xy 297.723723 -288.636544) (xy 297.751891 -288.586974) (xy 297.769534 -288.564574) (xy 297.778932 -288.553144)
			(xy 297.782742 -288.524188) (xy 297.737022 -288.427668) (xy 297.732559 -288.419138) (xy 297.718545 -288.405962)
			(xy 297.700665 -288.398867) (xy 297.691048 -288.398458) (xy 297.4086 -288.398458) (xy 297.398984 -288.398871)
			(xy 297.381106 -288.405962) (xy 297.367101 -288.419145) (xy 297.362626 -288.427668) (xy 297.316906 -288.524188)
			(xy 297.320716 -288.553144) (xy 297.330114 -288.564574) (xy 297.347774 -288.586962) (xy 297.375939 -288.636538)
			(xy 297.395197 -288.690205) (xy 297.404981 -288.746377) (xy 297.405552 -288.774886) (xy 297.405042 -288.800873)
			(xy 297.396912 -288.852208) (xy 297.380851 -288.901638) (xy 297.357255 -288.947948) (xy 297.326705 -288.989996)
			(xy 297.289954 -289.026747) (xy 297.247906 -289.057297) (xy 297.201596 -289.080893) (xy 297.152166 -289.096954)
			(xy 297.100831 -289.105084) (xy 297.048857 -289.105084) (xy 296.997522 -289.096954) (xy 296.948092 -289.080893)
			(xy 296.901782 -289.057297) (xy 296.859734 -289.026747) (xy 296.822983 -288.989996) (xy 296.792433 -288.947948)
			(xy 296.768837 -288.901638) (xy 296.752776 -288.852208) (xy 296.744646 -288.800873) (xy 296.744136 -288.774886)
			(xy 296.744734 -288.746379) (xy 296.754509 -288.69021) (xy 296.773767 -288.636547) (xy 296.801937 -288.586979)
			(xy 296.819574 -288.564574) (xy 296.828972 -288.553144) (xy 296.832782 -288.524188) (xy 296.787062 -288.427668)
			(xy 296.782596 -288.419145) (xy 296.768579 -288.405985) (xy 296.750701 -288.398911) (xy 296.741088 -288.398458)
			(xy 296.45864 -288.398458) (xy 296.449019 -288.398865) (xy 296.43113 -288.405947) (xy 296.417114 -288.419128)
			(xy 296.412666 -288.427668) (xy 296.366946 -288.524188) (xy 296.370756 -288.553144) (xy 296.380154 -288.564574)
			(xy 296.397812 -288.586963) (xy 296.425973 -288.63654) (xy 296.445229 -288.690207) (xy 296.455012 -288.746378)
			(xy 296.455592 -288.774886) (xy 296.455082 -288.800873) (xy 296.446952 -288.852208) (xy 296.430891 -288.901638)
			(xy 296.407295 -288.947948) (xy 296.376745 -288.989996) (xy 296.339994 -289.026747) (xy 296.297946 -289.057297)
			(xy 296.251636 -289.080893) (xy 296.202206 -289.096954) (xy 296.150871 -289.105084) (xy 296.098897 -289.105084)
			(xy 296.047562 -289.096954) (xy 295.998132 -289.080893) (xy 295.951822 -289.057297) (xy 295.909774 -289.026747)
			(xy 295.873023 -288.989996) (xy 295.842473 -288.947948) (xy 295.818877 -288.901638) (xy 295.802816 -288.852208)
			(xy 295.794686 -288.800873) (xy 295.794176 -288.774886) (xy 295.794773 -288.746379) (xy 295.804547 -288.690208)
			(xy 295.823802 -288.636543) (xy 295.851968 -288.586972) (xy 295.869614 -288.564574) (xy 295.879012 -288.553144)
			(xy 295.882822 -288.524188) (xy 295.837102 -288.427668) (xy 295.832638 -288.419141) (xy 295.818623 -288.40597)
			(xy 295.800744 -288.398882) (xy 295.791128 -288.398458) (xy 295.50868 -288.398458) (xy 295.499066 -288.398875)
			(xy 295.481193 -288.40597) (xy 295.467195 -288.419154) (xy 295.462706 -288.427668) (xy 295.416986 -288.524188)
			(xy 295.420796 -288.553144) (xy 295.430194 -288.564574) (xy 295.44785 -288.586964) (xy 295.476008 -288.636541)
			(xy 295.495262 -288.690208) (xy 295.505043 -288.746378) (xy 295.505632 -288.774886) (xy 295.505122 -288.800873)
			(xy 295.496992 -288.852208) (xy 295.480931 -288.901638) (xy 295.457335 -288.947948) (xy 295.426785 -288.989996)
			(xy 295.390034 -289.026747) (xy 295.347986 -289.057297) (xy 295.301676 -289.080893) (xy 295.252246 -289.096954)
			(xy 295.200911 -289.105084) (xy 295.148937 -289.105084) (xy 295.097602 -289.096954) (xy 295.048172 -289.080893)
			(xy 295.001862 -289.057297) (xy 294.959814 -289.026747) (xy 294.923063 -288.989996) (xy 294.892513 -288.947948)
			(xy 294.868917 -288.901638) (xy 294.852856 -288.852208) (xy 294.844726 -288.800873) (xy 294.844216 -288.774886)
			(xy 294.844814 -288.746379) (xy 294.854588 -288.690209) (xy 294.873845 -288.636546) (xy 294.902014 -288.586977)
			(xy 294.919654 -288.564574) (xy 294.929052 -288.553144) (xy 294.932862 -288.524188) (xy 294.887142 -288.427668)
			(xy 294.88268 -288.419136) (xy 294.868667 -288.405954) (xy 294.850787 -288.398853) (xy 294.841168 -288.398458)
			(xy 294.558466 -288.398458) (xy 294.548853 -288.398877) (xy 294.530985 -288.405975) (xy 294.516991 -288.41916)
			(xy 294.512492 -288.427668) (xy 294.466772 -288.524188) (xy 294.470582 -288.553144) (xy 294.47998 -288.564574)
			(xy 294.497637 -288.586964) (xy 294.525796 -288.636541) (xy 294.54505 -288.690207) (xy 294.554832 -288.746378)
			(xy 294.555418 -288.774886) (xy 294.554908 -288.800873) (xy 294.546778 -288.852208) (xy 294.530717 -288.901638)
			(xy 294.507121 -288.947948) (xy 294.476571 -288.989996) (xy 294.43982 -289.026747) (xy 294.397772 -289.057297)
			(xy 294.351462 -289.080893) (xy 294.302032 -289.096954) (xy 294.250697 -289.105084) (xy 294.198723 -289.105084)
			(xy 294.147388 -289.096954) (xy 294.097958 -289.080893) (xy 294.051648 -289.057297) (xy 294.0096 -289.026747)
			(xy 293.972849 -288.989996) (xy 293.942299 -288.947948) (xy 293.918703 -288.901638) (xy 293.902642 -288.852208)
			(xy 293.894512 -288.800873) (xy 293.894002 -288.774886) (xy 293.894599 -288.746379) (xy 293.904373 -288.690209)
			(xy 293.92363 -288.636545) (xy 293.951798 -288.586975) (xy 293.96944 -288.564574) (xy 293.978838 -288.553144)
			(xy 293.982648 -288.524188) (xy 293.936928 -288.427668) (xy 293.932465 -288.419138) (xy 293.918451 -288.40596)
			(xy 293.900572 -288.398863) (xy 293.890954 -288.398458) (xy 293.608506 -288.398458) (xy 293.598889 -288.39887)
			(xy 293.581009 -288.40596) (xy 293.567003 -288.419143) (xy 293.562532 -288.427668) (xy 293.516812 -288.524188)
			(xy 293.520622 -288.553144) (xy 293.53002 -288.564574) (xy 293.54768 -288.586962) (xy 293.575844 -288.636539)
			(xy 293.595102 -288.690205) (xy 293.604885 -288.746377) (xy 293.605458 -288.774886) (xy 293.604948 -288.800873)
			(xy 293.596818 -288.852208) (xy 293.580757 -288.901638) (xy 293.557161 -288.947948) (xy 293.526611 -288.989996)
			(xy 293.48986 -289.026747) (xy 293.447812 -289.057297) (xy 293.401502 -289.080893) (xy 293.352072 -289.096954)
			(xy 293.300737 -289.105084) (xy 293.248763 -289.105084) (xy 293.197428 -289.096954) (xy 293.147998 -289.080893)
			(xy 293.101688 -289.057297) (xy 293.05964 -289.026747) (xy 293.022889 -288.989996) (xy 292.992339 -288.947948)
			(xy 292.968743 -288.901638) (xy 292.952682 -288.852208) (xy 292.944552 -288.800873) (xy 292.944042 -288.774886)
			(xy 292.94464 -288.746379) (xy 292.954415 -288.69021) (xy 292.973673 -288.636547) (xy 293.001844 -288.58698)
			(xy 293.01948 -288.564574) (xy 293.028878 -288.553144) (xy 293.032688 -288.524188) (xy 292.986968 -288.427668)
			(xy 292.982502 -288.419145) (xy 292.968485 -288.405983) (xy 292.950608 -288.398907) (xy 292.940994 -288.398458)
			(xy 292.658546 -288.398458) (xy 292.648925 -288.398864) (xy 292.631033 -288.405945) (xy 292.617015 -288.419126)
			(xy 292.612572 -288.427668) (xy 292.566852 -288.524188) (xy 292.570662 -288.553144) (xy 292.58006 -288.564574)
			(xy 292.597718 -288.586963) (xy 292.625878 -288.63654) (xy 292.645134 -288.690207) (xy 292.654917 -288.746378)
			(xy 292.655498 -288.774886) (xy 292.654988 -288.800873) (xy 292.646858 -288.852208) (xy 292.630797 -288.901638)
			(xy 292.607201 -288.947948) (xy 292.576651 -288.989996) (xy 292.5399 -289.026747) (xy 292.497852 -289.057297)
			(xy 292.451542 -289.080893) (xy 292.402112 -289.096954) (xy 292.350777 -289.105084) (xy 292.298803 -289.105084)
			(xy 292.247468 -289.096954) (xy 292.198038 -289.080893) (xy 292.151728 -289.057297) (xy 292.10968 -289.026747)
			(xy 292.072929 -288.989996) (xy 292.042379 -288.947948) (xy 292.018783 -288.901638) (xy 292.002722 -288.852208)
			(xy 291.994592 -288.800873) (xy 291.994082 -288.774886) (xy 291.994679 -288.746379) (xy 292.004453 -288.690208)
			(xy 292.023708 -288.636544) (xy 292.051875 -288.586973) (xy 292.06952 -288.564574) (xy 292.078918 -288.553144)
			(xy 292.082728 -288.524188) (xy 292.037008 -288.427668) (xy 292.032544 -288.41914) (xy 292.018529 -288.405968)
			(xy 292.00065 -288.398877) (xy 291.991034 -288.398458) (xy 290.758626 -288.398458) (xy 290.749007 -288.398867)
			(xy 290.731121 -288.405952) (xy 290.717109 -288.419134) (xy 290.712652 -288.427668) (xy 290.666932 -288.524188)
			(xy 290.670742 -288.553144) (xy 290.68014 -288.564574) (xy 290.697799 -288.586963) (xy 290.725961 -288.636539)
			(xy 290.745218 -288.690206) (xy 290.755001 -288.746378) (xy 290.755578 -288.774886) (xy 290.755068 -288.800873)
			(xy 290.746938 -288.852208) (xy 290.730877 -288.901638) (xy 290.707281 -288.947948) (xy 290.676731 -288.989996)
			(xy 290.63998 -289.026747) (xy 290.597932 -289.057297) (xy 290.551622 -289.080893) (xy 290.502192 -289.096954)
			(xy 290.450857 -289.105084) (xy 290.398883 -289.105084) (xy 290.347548 -289.096954) (xy 290.298118 -289.080893)
			(xy 290.251808 -289.057297) (xy 290.20976 -289.026747) (xy 290.173009 -288.989996) (xy 290.142459 -288.947948)
			(xy 290.118863 -288.901638) (xy 290.102802 -288.852208) (xy 290.094672 -288.800873) (xy 290.094162 -288.774886)
			(xy 290.094759 -288.746379) (xy 290.104532 -288.690208) (xy 290.123787 -288.636543) (xy 290.151952 -288.586971)
			(xy 290.1696 -288.564574) (xy 290.178998 -288.553144) (xy 290.182808 -288.524188) (xy 290.137088 -288.427668)
			(xy 290.132624 -288.419142) (xy 290.118608 -288.405975) (xy 290.100729 -288.398892) (xy 290.091114 -288.398458)
			(xy 289.808666 -288.398458) (xy 289.799053 -288.398877) (xy 289.781185 -288.405975) (xy 289.767191 -288.41916)
			(xy 289.762692 -288.427668) (xy 289.716972 -288.524188) (xy 289.720782 -288.553144) (xy 289.73018 -288.564574)
			(xy 289.747837 -288.586964) (xy 289.775996 -288.636541) (xy 289.79525 -288.690207) (xy 289.805032 -288.746378)
			(xy 289.805618 -288.774886) (xy 289.805108 -288.800873) (xy 289.796978 -288.852208) (xy 289.780917 -288.901638)
			(xy 289.757321 -288.947948) (xy 289.726771 -288.989996) (xy 289.69002 -289.026747) (xy 289.647972 -289.057297)
			(xy 289.601662 -289.080893) (xy 289.552232 -289.096954) (xy 289.500897 -289.105084) (xy 289.448923 -289.105084)
			(xy 289.397588 -289.096954) (xy 289.348158 -289.080893) (xy 289.301848 -289.057297) (xy 289.2598 -289.026747)
			(xy 289.223049 -288.989996) (xy 289.192499 -288.947948) (xy 289.168903 -288.901638) (xy 289.152842 -288.852208)
			(xy 289.144712 -288.800873) (xy 289.144202 -288.774886) (xy 289.144799 -288.746379) (xy 289.154573 -288.690209)
			(xy 289.17383 -288.636545) (xy 289.201998 -288.586975) (xy 289.21964 -288.564574) (xy 289.229038 -288.553144)
			(xy 289.232848 -288.524188) (xy 289.187128 -288.427668) (xy 289.182665 -288.419138) (xy 289.168651 -288.40596)
			(xy 289.150772 -288.398863) (xy 289.141154 -288.398458) (xy 288.858452 -288.398458) (xy 288.84883 -288.398863)
			(xy 288.830937 -288.405942) (xy 288.816917 -288.419123) (xy 288.812478 -288.427668) (xy 288.766758 -288.524188)
			(xy 288.770568 -288.553144) (xy 288.779966 -288.564574) (xy 288.797623 -288.586963) (xy 288.825784 -288.63654)
			(xy 288.845039 -288.690207) (xy 288.854821 -288.746378) (xy 288.855404 -288.774886) (xy 288.854894 -288.800873)
			(xy 288.846764 -288.852208) (xy 288.830703 -288.901638) (xy 288.807107 -288.947948) (xy 288.776557 -288.989996)
			(xy 288.739806 -289.026747) (xy 288.697758 -289.057297) (xy 288.651448 -289.080893) (xy 288.602018 -289.096954)
			(xy 288.550683 -289.105084) (xy 288.498709 -289.105084) (xy 288.447374 -289.096954) (xy 288.397944 -289.080893)
			(xy 288.351634 -289.057297) (xy 288.309586 -289.026747) (xy 288.272835 -288.989996) (xy 288.242285 -288.947948)
			(xy 288.218689 -288.901638) (xy 288.202628 -288.852208) (xy 288.194498 -288.800873) (xy 288.193988 -288.774886)
			(xy 288.194585 -288.746379) (xy 288.204359 -288.690208) (xy 288.223614 -288.636544) (xy 288.251782 -288.586974)
			(xy 288.269426 -288.564574) (xy 288.278824 -288.553144) (xy 288.282634 -288.524188) (xy 288.236914 -288.427668)
			(xy 288.232451 -288.419139) (xy 288.218436 -288.405965) (xy 288.200557 -288.398873) (xy 288.19094 -288.398458)
			(xy 287.908492 -288.398458) (xy 287.898876 -288.398873) (xy 287.881001 -288.405965) (xy 287.866999 -288.419149)
			(xy 287.862518 -288.427668) (xy 287.816798 -288.524188) (xy 287.820608 -288.553144) (xy 287.830006 -288.564574)
			(xy 287.847662 -288.586964) (xy 287.875818 -288.636542) (xy 287.895071 -288.690208) (xy 287.904852 -288.746379)
			(xy 287.905444 -288.774886) (xy 287.904934 -288.800873) (xy 287.896804 -288.852208) (xy 287.880743 -288.901638)
			(xy 287.857147 -288.947948) (xy 287.826597 -288.989996) (xy 287.789846 -289.026747) (xy 287.747798 -289.057297)
			(xy 287.701488 -289.080893) (xy 287.652058 -289.096954) (xy 287.600723 -289.105084) (xy 287.548749 -289.105084)
			(xy 287.497414 -289.096954) (xy 287.447984 -289.080893) (xy 287.401674 -289.057297) (xy 287.359626 -289.026747)
			(xy 287.322875 -288.989996) (xy 287.292325 -288.947948) (xy 287.268729 -288.901638) (xy 287.252668 -288.852208)
			(xy 287.244538 -288.800873) (xy 287.244028 -288.774886) (xy 287.244626 -288.746379) (xy 287.254401 -288.690209)
			(xy 287.273658 -288.636546) (xy 287.301828 -288.586978) (xy 287.319466 -288.564574) (xy 287.328864 -288.553144)
			(xy 287.332674 -288.524188) (xy 287.286954 -288.427668) (xy 287.282488 -288.419146) (xy 287.26847 -288.405989)
			(xy 287.250593 -288.398917) (xy 287.24098 -288.398458) (xy 286.958532 -288.398458) (xy 286.948912 -288.398866)
			(xy 286.931025 -288.40595) (xy 286.917011 -288.419132) (xy 286.912558 -288.427668) (xy 286.866838 -288.524188)
			(xy 286.870648 -288.553144) (xy 286.880046 -288.564574) (xy 286.897704 -288.586963) (xy 286.925866 -288.63654)
			(xy 286.945123 -288.690206) (xy 286.954906 -288.746378) (xy 286.955484 -288.774886) (xy 286.954974 -288.800873)
			(xy 286.946844 -288.852208) (xy 286.930783 -288.901638) (xy 286.907187 -288.947948) (xy 286.876637 -288.989996)
			(xy 286.839886 -289.026747) (xy 286.797838 -289.057297) (xy 286.751528 -289.080893) (xy 286.702098 -289.096954)
			(xy 286.650763 -289.105084) (xy 286.598789 -289.105084) (xy 286.547454 -289.096954) (xy 286.498024 -289.080893)
			(xy 286.451714 -289.057297) (xy 286.409666 -289.026747) (xy 286.372915 -288.989996) (xy 286.342365 -288.947948)
			(xy 286.318769 -288.901638) (xy 286.302708 -288.852208) (xy 286.294578 -288.800873) (xy 286.294068 -288.774886)
			(xy 286.294665 -288.746379) (xy 286.304438 -288.690208) (xy 286.323693 -288.636543) (xy 286.351859 -288.586971)
			(xy 286.369506 -288.564574) (xy 286.378904 -288.553144) (xy 286.382714 -288.524188) (xy 286.336994 -288.427668)
			(xy 286.33253 -288.419141) (xy 286.318514 -288.405973) (xy 286.300636 -288.398888) (xy 286.29102 -288.398458)
			(xy 286.008572 -288.398458) (xy 285.998958 -288.398876) (xy 285.981089 -288.405973) (xy 285.967093 -288.419157)
			(xy 285.962598 -288.427668) (xy 285.916878 -288.524188) (xy 285.920688 -288.553144) (xy 285.930086 -288.564574)
			(xy 285.947743 -288.586964) (xy 285.975901 -288.636541) (xy 285.995155 -288.690208) (xy 286.004937 -288.746378)
			(xy 286.005524 -288.774886) (xy 286.005014 -288.800873) (xy 285.996884 -288.852208) (xy 285.980823 -288.901638)
			(xy 285.957227 -288.947948) (xy 285.926677 -288.989996) (xy 285.889926 -289.026747) (xy 285.847878 -289.057297)
			(xy 285.801568 -289.080893) (xy 285.752138 -289.096954) (xy 285.700803 -289.105084) (xy 285.648829 -289.105084)
			(xy 285.597494 -289.096954) (xy 285.548064 -289.080893) (xy 285.501754 -289.057297) (xy 285.459706 -289.026747)
			(xy 285.422955 -288.989996) (xy 285.392405 -288.947948) (xy 285.368809 -288.901638) (xy 285.352748 -288.852208)
			(xy 285.344618 -288.800873) (xy 285.344108 -288.774886) (xy 285.344705 -288.746379) (xy 285.35448 -288.690209)
			(xy 285.373736 -288.636545) (xy 285.401905 -288.586976) (xy 285.419546 -288.564574) (xy 285.428944 -288.553144)
			(xy 285.432754 -288.524188) (xy 285.387034 -288.427668) (xy 285.382571 -288.419137) (xy 285.368558 -288.405958)
			(xy 285.350678 -288.398859) (xy 285.34106 -288.398458) (xy 285.058612 -288.398458) (xy 285.048994 -288.398869)
			(xy 285.031113 -288.405958) (xy 285.017105 -288.41914) (xy 285.012638 -288.427668) (xy 284.966918 -288.524188)
			(xy 284.970728 -288.553144) (xy 284.980126 -288.564574) (xy 284.997785 -288.586963) (xy 285.025949 -288.636539)
			(xy 285.045207 -288.690206) (xy 285.05499 -288.746377) (xy 285.055564 -288.774886) (xy 285.055054 -288.800873)
			(xy 285.046924 -288.852208) (xy 285.030863 -288.901638) (xy 285.007267 -288.947948) (xy 284.976717 -288.989996)
			(xy 284.939966 -289.026747) (xy 284.897918 -289.057297) (xy 284.851608 -289.080893) (xy 284.802178 -289.096954)
			(xy 284.750843 -289.105084) (xy 284.698869 -289.105084) (xy 284.647534 -289.096954) (xy 284.598104 -289.080893)
			(xy 284.551794 -289.057297) (xy 284.509746 -289.026747) (xy 284.472995 -288.989996) (xy 284.442445 -288.947948)
			(xy 284.418849 -288.901638) (xy 284.402788 -288.852208) (xy 284.394658 -288.800873) (xy 284.394148 -288.774886)
			(xy 284.394745 -288.746379) (xy 284.404518 -288.690207) (xy 284.423771 -288.636542) (xy 284.451937 -288.586969)
			(xy 284.469586 -288.564574) (xy 284.478984 -288.553144) (xy 284.482794 -288.524188) (xy 284.437074 -288.427668)
			(xy 284.432609 -288.419144) (xy 284.418592 -288.405981) (xy 284.400714 -288.398902) (xy 284.3911 -288.398458)
			(xy 284.108652 -288.398458) (xy 284.09903 -288.398863) (xy 284.081137 -288.405942) (xy 284.067117 -288.419123)
			(xy 284.062678 -288.427668) (xy 284.016958 -288.524188) (xy 284.020768 -288.553144) (xy 284.030166 -288.564574)
			(xy 284.047823 -288.586963) (xy 284.075984 -288.63654) (xy 284.095239 -288.690207) (xy 284.105021 -288.746378)
			(xy 284.105604 -288.774886) (xy 284.105094 -288.800873) (xy 284.096964 -288.852208) (xy 284.080903 -288.901638)
			(xy 284.057307 -288.947948) (xy 284.026757 -288.989996) (xy 283.990006 -289.026747) (xy 283.947958 -289.057297)
			(xy 283.901648 -289.080893) (xy 283.852218 -289.096954) (xy 283.800883 -289.105084) (xy 283.748909 -289.105084)
			(xy 283.697574 -289.096954) (xy 283.648144 -289.080893) (xy 283.601834 -289.057297) (xy 283.559786 -289.026747)
			(xy 283.523035 -288.989996) (xy 283.492485 -288.947948) (xy 283.468889 -288.901638) (xy 283.452828 -288.852208)
			(xy 283.444698 -288.800873) (xy 283.444188 -288.774886) (xy 283.444785 -288.746379) (xy 283.454559 -288.690208)
			(xy 283.473814 -288.636544) (xy 283.501982 -288.586974) (xy 283.519626 -288.564574) (xy 283.529024 -288.553144)
			(xy 283.532834 -288.524188) (xy 283.487114 -288.427668) (xy 283.482651 -288.419139) (xy 283.468636 -288.405965)
			(xy 283.450757 -288.398873) (xy 283.44114 -288.398458) (xy 283.158692 -288.398458) (xy 283.149076 -288.398873)
			(xy 283.131201 -288.405965) (xy 283.117199 -288.419149) (xy 283.112718 -288.427668) (xy 283.066998 -288.524188)
			(xy 283.070808 -288.553144) (xy 283.080206 -288.564574) (xy 283.097862 -288.586964) (xy 283.126018 -288.636542)
			(xy 283.145271 -288.690208) (xy 283.155052 -288.746379) (xy 283.155644 -288.774886) (xy 283.155134 -288.800873)
			(xy 283.147004 -288.852208) (xy 283.130943 -288.901638) (xy 283.107347 -288.947948) (xy 283.076797 -288.989996)
			(xy 283.040046 -289.026747) (xy 282.997998 -289.057297) (xy 282.951688 -289.080893) (xy 282.902258 -289.096954)
			(xy 282.850923 -289.105084) (xy 282.798949 -289.105084) (xy 282.747614 -289.096954) (xy 282.698184 -289.080893)
			(xy 282.651874 -289.057297) (xy 282.609826 -289.026747) (xy 282.573075 -288.989996) (xy 282.542525 -288.947948)
			(xy 282.518929 -288.901638) (xy 282.502868 -288.852208) (xy 282.494738 -288.800873) (xy 282.494228 -288.774886)
			(xy 282.494826 -288.746379) (xy 282.504601 -288.690209) (xy 282.523858 -288.636546) (xy 282.552028 -288.586978)
			(xy 282.569666 -288.564574) (xy 282.579064 -288.553144) (xy 282.582874 -288.524188) (xy 282.537154 -288.427668)
			(xy 282.532688 -288.419146) (xy 282.51867 -288.405989) (xy 282.500793 -288.398917) (xy 282.49118 -288.398458)
			(xy 282.282646 -288.398458) (xy 282.272581 -288.398893) (xy 282.253997 -288.406627) (xy 282.246578 -288.413444)
			(xy 282.13304 -288.526982) (xy 282.130246 -288.564066) (xy 282.141422 -288.579306) (xy 282.1565 -288.600706)
			(xy 282.180421 -288.647268) (xy 282.196703 -288.697018) (xy 282.204941 -288.748712) (xy 282.20543 -288.774886)
			(xy 282.204922 -288.800875) (xy 282.196793 -288.852212) (xy 282.180733 -288.901646) (xy 282.157139 -288.947959)
			(xy 282.126589 -288.990011) (xy 282.089838 -289.026766) (xy 282.04779 -289.05732) (xy 282.001479 -289.08092)
			(xy 281.952047 -289.096984) (xy 281.90071 -289.105119) (xy 281.874722 -289.105594) (xy 281.848551 -289.105091)
			(xy 281.796863 -289.096838) (xy 281.747119 -289.080551) (xy 281.70056 -289.056635) (xy 281.679142 -289.041586)
			(xy 281.663902 -289.03041) (xy 281.626818 -289.033204) (xy 281.316176 -289.343846) (xy 281.308779 -289.350694)
			(xy 281.29018 -289.358429) (xy 281.280108 -289.358832) (xy 281.266646 -289.358832) (xy 281.257214 -289.359326)
			(xy 281.239656 -289.366245) (xy 281.225769 -289.379022) (xy 281.22118 -289.38728) (xy 281.174444 -289.482276)
			(xy 281.177492 -289.510978) (xy 281.186382 -289.522662) (xy 281.202592 -289.544525) (xy 281.228387 -289.592448)
			(xy 281.245983 -289.643948) (xy 281.254907 -289.697634) (xy 281.25547 -289.724846) (xy 281.25496 -289.750833)
			(xy 281.544524 -289.750833) (xy 281.544524 -289.698859) (xy 281.552654 -289.647524) (xy 281.568715 -289.598094)
			(xy 281.592311 -289.551784) (xy 281.622861 -289.509736) (xy 281.659612 -289.472985) (xy 281.70166 -289.442435)
			(xy 281.74797 -289.418839) (xy 281.7974 -289.402778) (xy 281.848735 -289.394648) (xy 281.900709 -289.394648)
			(xy 281.952044 -289.402778) (xy 282.001474 -289.418839) (xy 282.047784 -289.442435) (xy 282.089832 -289.472985)
			(xy 282.126583 -289.509736) (xy 282.157133 -289.551784) (xy 282.180729 -289.598094) (xy 282.19679 -289.647524)
			(xy 282.20492 -289.698859) (xy 282.20543 -289.724846) (xy 282.20492 -289.750833) (xy 282.494738 -289.750833)
			(xy 282.494738 -289.698859) (xy 282.502868 -289.647524) (xy 282.518929 -289.598094) (xy 282.542525 -289.551784)
			(xy 282.573075 -289.509736) (xy 282.609826 -289.472985) (xy 282.651874 -289.442435) (xy 282.698184 -289.418839)
			(xy 282.747614 -289.402778) (xy 282.798949 -289.394648) (xy 282.850923 -289.394648) (xy 282.902258 -289.402778)
			(xy 282.951688 -289.418839) (xy 282.997998 -289.442435) (xy 283.040046 -289.472985) (xy 283.076797 -289.509736)
			(xy 283.107347 -289.551784) (xy 283.130943 -289.598094) (xy 283.147004 -289.647524) (xy 283.155134 -289.698859)
			(xy 283.155644 -289.724846) (xy 283.155134 -289.750833) (xy 283.444698 -289.750833) (xy 283.444698 -289.698859)
			(xy 283.452828 -289.647524) (xy 283.468889 -289.598094) (xy 283.492485 -289.551784) (xy 283.523035 -289.509736)
			(xy 283.559786 -289.472985) (xy 283.601834 -289.442435) (xy 283.648144 -289.418839) (xy 283.697574 -289.402778)
			(xy 283.748909 -289.394648) (xy 283.800883 -289.394648) (xy 283.852218 -289.402778) (xy 283.901648 -289.418839)
			(xy 283.947958 -289.442435) (xy 283.990006 -289.472985) (xy 284.026757 -289.509736) (xy 284.057307 -289.551784)
			(xy 284.080903 -289.598094) (xy 284.096964 -289.647524) (xy 284.105094 -289.698859) (xy 284.105604 -289.724846)
			(xy 284.105094 -289.750833) (xy 284.394658 -289.750833) (xy 284.394658 -289.698859) (xy 284.402788 -289.647524)
			(xy 284.418849 -289.598094) (xy 284.442445 -289.551784) (xy 284.472995 -289.509736) (xy 284.509746 -289.472985)
			(xy 284.551794 -289.442435) (xy 284.598104 -289.418839) (xy 284.647534 -289.402778) (xy 284.698869 -289.394648)
			(xy 284.750843 -289.394648) (xy 284.802178 -289.402778) (xy 284.851608 -289.418839) (xy 284.897918 -289.442435)
			(xy 284.939966 -289.472985) (xy 284.976717 -289.509736) (xy 285.007267 -289.551784) (xy 285.030863 -289.598094)
			(xy 285.046924 -289.647524) (xy 285.055054 -289.698859) (xy 285.055564 -289.724846) (xy 285.055054 -289.750833)
			(xy 285.344618 -289.750833) (xy 285.344618 -289.698859) (xy 285.352748 -289.647524) (xy 285.368809 -289.598094)
			(xy 285.392405 -289.551784) (xy 285.422955 -289.509736) (xy 285.459706 -289.472985) (xy 285.501754 -289.442435)
			(xy 285.548064 -289.418839) (xy 285.597494 -289.402778) (xy 285.648829 -289.394648) (xy 285.700803 -289.394648)
			(xy 285.752138 -289.402778) (xy 285.801568 -289.418839) (xy 285.847878 -289.442435) (xy 285.889926 -289.472985)
			(xy 285.926677 -289.509736) (xy 285.957227 -289.551784) (xy 285.980823 -289.598094) (xy 285.996884 -289.647524)
			(xy 286.005014 -289.698859) (xy 286.005524 -289.724846) (xy 286.005014 -289.750833) (xy 286.294578 -289.750833)
			(xy 286.294578 -289.698859) (xy 286.302708 -289.647524) (xy 286.318769 -289.598094) (xy 286.342365 -289.551784)
			(xy 286.372915 -289.509736) (xy 286.409666 -289.472985) (xy 286.451714 -289.442435) (xy 286.498024 -289.418839)
			(xy 286.547454 -289.402778) (xy 286.598789 -289.394648) (xy 286.650763 -289.394648) (xy 286.702098 -289.402778)
			(xy 286.751528 -289.418839) (xy 286.797838 -289.442435) (xy 286.839886 -289.472985) (xy 286.876637 -289.509736)
			(xy 286.907187 -289.551784) (xy 286.930783 -289.598094) (xy 286.946844 -289.647524) (xy 286.954974 -289.698859)
			(xy 286.955484 -289.724846) (xy 286.954974 -289.750833) (xy 287.244538 -289.750833) (xy 287.244538 -289.698859)
			(xy 287.252668 -289.647524) (xy 287.268729 -289.598094) (xy 287.292325 -289.551784) (xy 287.322875 -289.509736)
			(xy 287.359626 -289.472985) (xy 287.401674 -289.442435) (xy 287.447984 -289.418839) (xy 287.497414 -289.402778)
			(xy 287.548749 -289.394648) (xy 287.600723 -289.394648) (xy 287.652058 -289.402778) (xy 287.701488 -289.418839)
			(xy 287.747798 -289.442435) (xy 287.789846 -289.472985) (xy 287.826597 -289.509736) (xy 287.857147 -289.551784)
			(xy 287.880743 -289.598094) (xy 287.896804 -289.647524) (xy 287.904934 -289.698859) (xy 287.905444 -289.724846)
			(xy 287.904934 -289.750833) (xy 288.194498 -289.750833) (xy 288.194498 -289.698859) (xy 288.202628 -289.647524)
			(xy 288.218689 -289.598094) (xy 288.242285 -289.551784) (xy 288.272835 -289.509736) (xy 288.309586 -289.472985)
			(xy 288.351634 -289.442435) (xy 288.397944 -289.418839) (xy 288.447374 -289.402778) (xy 288.498709 -289.394648)
			(xy 288.550683 -289.394648) (xy 288.602018 -289.402778) (xy 288.651448 -289.418839) (xy 288.697758 -289.442435)
			(xy 288.739806 -289.472985) (xy 288.776557 -289.509736) (xy 288.807107 -289.551784) (xy 288.830703 -289.598094)
			(xy 288.846764 -289.647524) (xy 288.854894 -289.698859) (xy 288.855404 -289.724846) (xy 288.854894 -289.750833)
			(xy 289.144712 -289.750833) (xy 289.144712 -289.698859) (xy 289.152842 -289.647524) (xy 289.168903 -289.598094)
			(xy 289.192499 -289.551784) (xy 289.223049 -289.509736) (xy 289.2598 -289.472985) (xy 289.301848 -289.442435)
			(xy 289.348158 -289.418839) (xy 289.397588 -289.402778) (xy 289.448923 -289.394648) (xy 289.500897 -289.394648)
			(xy 289.552232 -289.402778) (xy 289.601662 -289.418839) (xy 289.647972 -289.442435) (xy 289.69002 -289.472985)
			(xy 289.726771 -289.509736) (xy 289.757321 -289.551784) (xy 289.780917 -289.598094) (xy 289.796978 -289.647524)
			(xy 289.805108 -289.698859) (xy 289.805618 -289.724846) (xy 289.805108 -289.750833) (xy 290.094672 -289.750833)
			(xy 290.094672 -289.698859) (xy 290.102802 -289.647524) (xy 290.118863 -289.598094) (xy 290.142459 -289.551784)
			(xy 290.173009 -289.509736) (xy 290.20976 -289.472985) (xy 290.251808 -289.442435) (xy 290.298118 -289.418839)
			(xy 290.347548 -289.402778) (xy 290.398883 -289.394648) (xy 290.450857 -289.394648) (xy 290.502192 -289.402778)
			(xy 290.551622 -289.418839) (xy 290.597932 -289.442435) (xy 290.63998 -289.472985) (xy 290.676731 -289.509736)
			(xy 290.707281 -289.551784) (xy 290.730877 -289.598094) (xy 290.746938 -289.647524) (xy 290.755068 -289.698859)
			(xy 290.755578 -289.724846) (xy 290.755068 -289.750833) (xy 291.994592 -289.750833) (xy 291.994592 -289.698859)
			(xy 292.002722 -289.647524) (xy 292.018783 -289.598094) (xy 292.042379 -289.551784) (xy 292.072929 -289.509736)
			(xy 292.10968 -289.472985) (xy 292.151728 -289.442435) (xy 292.198038 -289.418839) (xy 292.247468 -289.402778)
			(xy 292.298803 -289.394648) (xy 292.350777 -289.394648) (xy 292.402112 -289.402778) (xy 292.451542 -289.418839)
			(xy 292.497852 -289.442435) (xy 292.5399 -289.472985) (xy 292.576651 -289.509736) (xy 292.607201 -289.551784)
			(xy 292.630797 -289.598094) (xy 292.646858 -289.647524) (xy 292.654988 -289.698859) (xy 292.655498 -289.724846)
			(xy 292.654988 -289.750833) (xy 292.944552 -289.750833) (xy 292.944552 -289.698859) (xy 292.952682 -289.647524)
			(xy 292.968743 -289.598094) (xy 292.992339 -289.551784) (xy 293.022889 -289.509736) (xy 293.05964 -289.472985)
			(xy 293.101688 -289.442435) (xy 293.147998 -289.418839) (xy 293.197428 -289.402778) (xy 293.248763 -289.394648)
			(xy 293.300737 -289.394648) (xy 293.352072 -289.402778) (xy 293.401502 -289.418839) (xy 293.447812 -289.442435)
			(xy 293.48986 -289.472985) (xy 293.526611 -289.509736) (xy 293.557161 -289.551784) (xy 293.580757 -289.598094)
			(xy 293.596818 -289.647524) (xy 293.604948 -289.698859) (xy 293.605458 -289.724846) (xy 293.604948 -289.750833)
			(xy 293.894512 -289.750833) (xy 293.894512 -289.698859) (xy 293.902642 -289.647524) (xy 293.918703 -289.598094)
			(xy 293.942299 -289.551784) (xy 293.972849 -289.509736) (xy 294.0096 -289.472985) (xy 294.051648 -289.442435)
			(xy 294.097958 -289.418839) (xy 294.147388 -289.402778) (xy 294.198723 -289.394648) (xy 294.250697 -289.394648)
			(xy 294.302032 -289.402778) (xy 294.351462 -289.418839) (xy 294.397772 -289.442435) (xy 294.43982 -289.472985)
			(xy 294.476571 -289.509736) (xy 294.507121 -289.551784) (xy 294.530717 -289.598094) (xy 294.546778 -289.647524)
			(xy 294.554908 -289.698859) (xy 294.555418 -289.724846) (xy 294.554908 -289.750833) (xy 294.844726 -289.750833)
			(xy 294.844726 -289.698859) (xy 294.852856 -289.647524) (xy 294.868917 -289.598094) (xy 294.892513 -289.551784)
			(xy 294.923063 -289.509736) (xy 294.959814 -289.472985) (xy 295.001862 -289.442435) (xy 295.048172 -289.418839)
			(xy 295.097602 -289.402778) (xy 295.148937 -289.394648) (xy 295.200911 -289.394648) (xy 295.252246 -289.402778)
			(xy 295.301676 -289.418839) (xy 295.347986 -289.442435) (xy 295.390034 -289.472985) (xy 295.426785 -289.509736)
			(xy 295.457335 -289.551784) (xy 295.480931 -289.598094) (xy 295.496992 -289.647524) (xy 295.505122 -289.698859)
			(xy 295.505632 -289.724846) (xy 295.505122 -289.750833) (xy 295.794686 -289.750833) (xy 295.794686 -289.698859)
			(xy 295.802816 -289.647524) (xy 295.818877 -289.598094) (xy 295.842473 -289.551784) (xy 295.873023 -289.509736)
			(xy 295.909774 -289.472985) (xy 295.951822 -289.442435) (xy 295.998132 -289.418839) (xy 296.047562 -289.402778)
			(xy 296.098897 -289.394648) (xy 296.150871 -289.394648) (xy 296.202206 -289.402778) (xy 296.251636 -289.418839)
			(xy 296.297946 -289.442435) (xy 296.339994 -289.472985) (xy 296.376745 -289.509736) (xy 296.407295 -289.551784)
			(xy 296.430891 -289.598094) (xy 296.446952 -289.647524) (xy 296.455082 -289.698859) (xy 296.455592 -289.724846)
			(xy 296.455082 -289.750833) (xy 296.744646 -289.750833) (xy 296.744646 -289.698859) (xy 296.752776 -289.647524)
			(xy 296.768837 -289.598094) (xy 296.792433 -289.551784) (xy 296.822983 -289.509736) (xy 296.859734 -289.472985)
			(xy 296.901782 -289.442435) (xy 296.948092 -289.418839) (xy 296.997522 -289.402778) (xy 297.048857 -289.394648)
			(xy 297.100831 -289.394648) (xy 297.152166 -289.402778) (xy 297.201596 -289.418839) (xy 297.247906 -289.442435)
			(xy 297.289954 -289.472985) (xy 297.326705 -289.509736) (xy 297.357255 -289.551784) (xy 297.380851 -289.598094)
			(xy 297.396912 -289.647524) (xy 297.405042 -289.698859) (xy 297.405552 -289.724846) (xy 297.405042 -289.750833)
			(xy 297.694606 -289.750833) (xy 297.694606 -289.698859) (xy 297.702736 -289.647524) (xy 297.718797 -289.598094)
			(xy 297.742393 -289.551784) (xy 297.772943 -289.509736) (xy 297.809694 -289.472985) (xy 297.851742 -289.442435)
			(xy 297.898052 -289.418839) (xy 297.947482 -289.402778) (xy 297.998817 -289.394648) (xy 298.050791 -289.394648)
			(xy 298.102126 -289.402778) (xy 298.151556 -289.418839) (xy 298.197866 -289.442435) (xy 298.239914 -289.472985)
			(xy 298.276665 -289.509736) (xy 298.307215 -289.551784) (xy 298.330811 -289.598094) (xy 298.346872 -289.647524)
			(xy 298.355002 -289.698859) (xy 298.355512 -289.724846) (xy 298.355002 -289.750833) (xy 298.644566 -289.750833)
			(xy 298.644566 -289.698859) (xy 298.652696 -289.647524) (xy 298.668757 -289.598094) (xy 298.692353 -289.551784)
			(xy 298.722903 -289.509736) (xy 298.759654 -289.472985) (xy 298.801702 -289.442435) (xy 298.848012 -289.418839)
			(xy 298.897442 -289.402778) (xy 298.948777 -289.394648) (xy 299.000751 -289.394648) (xy 299.052086 -289.402778)
			(xy 299.101516 -289.418839) (xy 299.147826 -289.442435) (xy 299.189874 -289.472985) (xy 299.226625 -289.509736)
			(xy 299.257175 -289.551784) (xy 299.280771 -289.598094) (xy 299.296832 -289.647524) (xy 299.304962 -289.698859)
			(xy 299.305472 -289.724846) (xy 299.304962 -289.750833) (xy 299.594526 -289.750833) (xy 299.594526 -289.698859)
			(xy 299.602656 -289.647524) (xy 299.618717 -289.598094) (xy 299.642313 -289.551784) (xy 299.672863 -289.509736)
			(xy 299.709614 -289.472985) (xy 299.751662 -289.442435) (xy 299.797972 -289.418839) (xy 299.847402 -289.402778)
			(xy 299.898737 -289.394648) (xy 299.950711 -289.394648) (xy 300.002046 -289.402778) (xy 300.051476 -289.418839)
			(xy 300.097786 -289.442435) (xy 300.139834 -289.472985) (xy 300.176585 -289.509736) (xy 300.207135 -289.551784)
			(xy 300.230731 -289.598094) (xy 300.246792 -289.647524) (xy 300.254922 -289.698859) (xy 300.255432 -289.724846)
			(xy 300.254922 -289.750833) (xy 300.544486 -289.750833) (xy 300.544486 -289.698859) (xy 300.552616 -289.647524)
			(xy 300.568677 -289.598094) (xy 300.592273 -289.551784) (xy 300.622823 -289.509736) (xy 300.659574 -289.472985)
			(xy 300.701622 -289.442435) (xy 300.747932 -289.418839) (xy 300.797362 -289.402778) (xy 300.848697 -289.394648)
			(xy 300.900671 -289.394648) (xy 300.952006 -289.402778) (xy 301.001436 -289.418839) (xy 301.047746 -289.442435)
			(xy 301.089794 -289.472985) (xy 301.126545 -289.509736) (xy 301.157095 -289.551784) (xy 301.180691 -289.598094)
			(xy 301.196752 -289.647524) (xy 301.204882 -289.698859) (xy 301.205392 -289.724846) (xy 301.204882 -289.750833)
			(xy 301.196752 -289.802168) (xy 301.180691 -289.851598) (xy 301.157095 -289.897908) (xy 301.126545 -289.939956)
			(xy 301.089794 -289.976707) (xy 301.047746 -290.007257) (xy 301.001436 -290.030853) (xy 300.952006 -290.046914)
			(xy 300.900671 -290.055044) (xy 300.848697 -290.055044) (xy 300.797362 -290.046914) (xy 300.747932 -290.030853)
			(xy 300.701622 -290.007257) (xy 300.659574 -289.976707) (xy 300.622823 -289.939956) (xy 300.592273 -289.897908)
			(xy 300.568677 -289.851598) (xy 300.552616 -289.802168) (xy 300.544486 -289.750833) (xy 300.254922 -289.750833)
			(xy 300.246792 -289.802168) (xy 300.230731 -289.851598) (xy 300.207135 -289.897908) (xy 300.176585 -289.939956)
			(xy 300.139834 -289.976707) (xy 300.097786 -290.007257) (xy 300.051476 -290.030853) (xy 300.002046 -290.046914)
			(xy 299.950711 -290.055044) (xy 299.898737 -290.055044) (xy 299.847402 -290.046914) (xy 299.797972 -290.030853)
			(xy 299.751662 -290.007257) (xy 299.709614 -289.976707) (xy 299.672863 -289.939956) (xy 299.642313 -289.897908)
			(xy 299.618717 -289.851598) (xy 299.602656 -289.802168) (xy 299.594526 -289.750833) (xy 299.304962 -289.750833)
			(xy 299.296832 -289.802168) (xy 299.280771 -289.851598) (xy 299.257175 -289.897908) (xy 299.226625 -289.939956)
			(xy 299.189874 -289.976707) (xy 299.147826 -290.007257) (xy 299.101516 -290.030853) (xy 299.052086 -290.046914)
			(xy 299.000751 -290.055044) (xy 298.948777 -290.055044) (xy 298.897442 -290.046914) (xy 298.848012 -290.030853)
			(xy 298.801702 -290.007257) (xy 298.759654 -289.976707) (xy 298.722903 -289.939956) (xy 298.692353 -289.897908)
			(xy 298.668757 -289.851598) (xy 298.652696 -289.802168) (xy 298.644566 -289.750833) (xy 298.355002 -289.750833)
			(xy 298.346872 -289.802168) (xy 298.330811 -289.851598) (xy 298.307215 -289.897908) (xy 298.276665 -289.939956)
			(xy 298.239914 -289.976707) (xy 298.197866 -290.007257) (xy 298.151556 -290.030853) (xy 298.102126 -290.046914)
			(xy 298.050791 -290.055044) (xy 297.998817 -290.055044) (xy 297.947482 -290.046914) (xy 297.898052 -290.030853)
			(xy 297.851742 -290.007257) (xy 297.809694 -289.976707) (xy 297.772943 -289.939956) (xy 297.742393 -289.897908)
			(xy 297.718797 -289.851598) (xy 297.702736 -289.802168) (xy 297.694606 -289.750833) (xy 297.405042 -289.750833)
			(xy 297.396912 -289.802168) (xy 297.380851 -289.851598) (xy 297.357255 -289.897908) (xy 297.326705 -289.939956)
			(xy 297.289954 -289.976707) (xy 297.247906 -290.007257) (xy 297.201596 -290.030853) (xy 297.152166 -290.046914)
			(xy 297.100831 -290.055044) (xy 297.048857 -290.055044) (xy 296.997522 -290.046914) (xy 296.948092 -290.030853)
			(xy 296.901782 -290.007257) (xy 296.859734 -289.976707) (xy 296.822983 -289.939956) (xy 296.792433 -289.897908)
			(xy 296.768837 -289.851598) (xy 296.752776 -289.802168) (xy 296.744646 -289.750833) (xy 296.455082 -289.750833)
			(xy 296.446952 -289.802168) (xy 296.430891 -289.851598) (xy 296.407295 -289.897908) (xy 296.376745 -289.939956)
			(xy 296.339994 -289.976707) (xy 296.297946 -290.007257) (xy 296.251636 -290.030853) (xy 296.202206 -290.046914)
			(xy 296.150871 -290.055044) (xy 296.098897 -290.055044) (xy 296.047562 -290.046914) (xy 295.998132 -290.030853)
			(xy 295.951822 -290.007257) (xy 295.909774 -289.976707) (xy 295.873023 -289.939956) (xy 295.842473 -289.897908)
			(xy 295.818877 -289.851598) (xy 295.802816 -289.802168) (xy 295.794686 -289.750833) (xy 295.505122 -289.750833)
			(xy 295.496992 -289.802168) (xy 295.480931 -289.851598) (xy 295.457335 -289.897908) (xy 295.426785 -289.939956)
			(xy 295.390034 -289.976707) (xy 295.347986 -290.007257) (xy 295.301676 -290.030853) (xy 295.252246 -290.046914)
			(xy 295.200911 -290.055044) (xy 295.148937 -290.055044) (xy 295.097602 -290.046914) (xy 295.048172 -290.030853)
			(xy 295.001862 -290.007257) (xy 294.959814 -289.976707) (xy 294.923063 -289.939956) (xy 294.892513 -289.897908)
			(xy 294.868917 -289.851598) (xy 294.852856 -289.802168) (xy 294.844726 -289.750833) (xy 294.554908 -289.750833)
			(xy 294.546778 -289.802168) (xy 294.530717 -289.851598) (xy 294.507121 -289.897908) (xy 294.476571 -289.939956)
			(xy 294.43982 -289.976707) (xy 294.397772 -290.007257) (xy 294.351462 -290.030853) (xy 294.302032 -290.046914)
			(xy 294.250697 -290.055044) (xy 294.198723 -290.055044) (xy 294.147388 -290.046914) (xy 294.097958 -290.030853)
			(xy 294.051648 -290.007257) (xy 294.0096 -289.976707) (xy 293.972849 -289.939956) (xy 293.942299 -289.897908)
			(xy 293.918703 -289.851598) (xy 293.902642 -289.802168) (xy 293.894512 -289.750833) (xy 293.604948 -289.750833)
			(xy 293.596818 -289.802168) (xy 293.580757 -289.851598) (xy 293.557161 -289.897908) (xy 293.526611 -289.939956)
			(xy 293.48986 -289.976707) (xy 293.447812 -290.007257) (xy 293.401502 -290.030853) (xy 293.352072 -290.046914)
			(xy 293.300737 -290.055044) (xy 293.248763 -290.055044) (xy 293.197428 -290.046914) (xy 293.147998 -290.030853)
			(xy 293.101688 -290.007257) (xy 293.05964 -289.976707) (xy 293.022889 -289.939956) (xy 292.992339 -289.897908)
			(xy 292.968743 -289.851598) (xy 292.952682 -289.802168) (xy 292.944552 -289.750833) (xy 292.654988 -289.750833)
			(xy 292.646858 -289.802168) (xy 292.630797 -289.851598) (xy 292.607201 -289.897908) (xy 292.576651 -289.939956)
			(xy 292.5399 -289.976707) (xy 292.497852 -290.007257) (xy 292.451542 -290.030853) (xy 292.402112 -290.046914)
			(xy 292.350777 -290.055044) (xy 292.298803 -290.055044) (xy 292.247468 -290.046914) (xy 292.198038 -290.030853)
			(xy 292.151728 -290.007257) (xy 292.10968 -289.976707) (xy 292.072929 -289.939956) (xy 292.042379 -289.897908)
			(xy 292.018783 -289.851598) (xy 292.002722 -289.802168) (xy 291.994592 -289.750833) (xy 290.755068 -289.750833)
			(xy 290.746938 -289.802168) (xy 290.730877 -289.851598) (xy 290.707281 -289.897908) (xy 290.676731 -289.939956)
			(xy 290.63998 -289.976707) (xy 290.597932 -290.007257) (xy 290.551622 -290.030853) (xy 290.502192 -290.046914)
			(xy 290.450857 -290.055044) (xy 290.398883 -290.055044) (xy 290.347548 -290.046914) (xy 290.298118 -290.030853)
			(xy 290.251808 -290.007257) (xy 290.20976 -289.976707) (xy 290.173009 -289.939956) (xy 290.142459 -289.897908)
			(xy 290.118863 -289.851598) (xy 290.102802 -289.802168) (xy 290.094672 -289.750833) (xy 289.805108 -289.750833)
			(xy 289.796978 -289.802168) (xy 289.780917 -289.851598) (xy 289.757321 -289.897908) (xy 289.726771 -289.939956)
			(xy 289.69002 -289.976707) (xy 289.647972 -290.007257) (xy 289.601662 -290.030853) (xy 289.552232 -290.046914)
			(xy 289.500897 -290.055044) (xy 289.448923 -290.055044) (xy 289.397588 -290.046914) (xy 289.348158 -290.030853)
			(xy 289.301848 -290.007257) (xy 289.2598 -289.976707) (xy 289.223049 -289.939956) (xy 289.192499 -289.897908)
			(xy 289.168903 -289.851598) (xy 289.152842 -289.802168) (xy 289.144712 -289.750833) (xy 288.854894 -289.750833)
			(xy 288.846764 -289.802168) (xy 288.830703 -289.851598) (xy 288.807107 -289.897908) (xy 288.776557 -289.939956)
			(xy 288.739806 -289.976707) (xy 288.697758 -290.007257) (xy 288.651448 -290.030853) (xy 288.602018 -290.046914)
			(xy 288.550683 -290.055044) (xy 288.498709 -290.055044) (xy 288.447374 -290.046914) (xy 288.397944 -290.030853)
			(xy 288.351634 -290.007257) (xy 288.309586 -289.976707) (xy 288.272835 -289.939956) (xy 288.242285 -289.897908)
			(xy 288.218689 -289.851598) (xy 288.202628 -289.802168) (xy 288.194498 -289.750833) (xy 287.904934 -289.750833)
			(xy 287.896804 -289.802168) (xy 287.880743 -289.851598) (xy 287.857147 -289.897908) (xy 287.826597 -289.939956)
			(xy 287.789846 -289.976707) (xy 287.747798 -290.007257) (xy 287.701488 -290.030853) (xy 287.652058 -290.046914)
			(xy 287.600723 -290.055044) (xy 287.548749 -290.055044) (xy 287.497414 -290.046914) (xy 287.447984 -290.030853)
			(xy 287.401674 -290.007257) (xy 287.359626 -289.976707) (xy 287.322875 -289.939956) (xy 287.292325 -289.897908)
			(xy 287.268729 -289.851598) (xy 287.252668 -289.802168) (xy 287.244538 -289.750833) (xy 286.954974 -289.750833)
			(xy 286.946844 -289.802168) (xy 286.930783 -289.851598) (xy 286.907187 -289.897908) (xy 286.876637 -289.939956)
			(xy 286.839886 -289.976707) (xy 286.797838 -290.007257) (xy 286.751528 -290.030853) (xy 286.702098 -290.046914)
			(xy 286.650763 -290.055044) (xy 286.598789 -290.055044) (xy 286.547454 -290.046914) (xy 286.498024 -290.030853)
			(xy 286.451714 -290.007257) (xy 286.409666 -289.976707) (xy 286.372915 -289.939956) (xy 286.342365 -289.897908)
			(xy 286.318769 -289.851598) (xy 286.302708 -289.802168) (xy 286.294578 -289.750833) (xy 286.005014 -289.750833)
			(xy 285.996884 -289.802168) (xy 285.980823 -289.851598) (xy 285.957227 -289.897908) (xy 285.926677 -289.939956)
			(xy 285.889926 -289.976707) (xy 285.847878 -290.007257) (xy 285.801568 -290.030853) (xy 285.752138 -290.046914)
			(xy 285.700803 -290.055044) (xy 285.648829 -290.055044) (xy 285.597494 -290.046914) (xy 285.548064 -290.030853)
			(xy 285.501754 -290.007257) (xy 285.459706 -289.976707) (xy 285.422955 -289.939956) (xy 285.392405 -289.897908)
			(xy 285.368809 -289.851598) (xy 285.352748 -289.802168) (xy 285.344618 -289.750833) (xy 285.055054 -289.750833)
			(xy 285.046924 -289.802168) (xy 285.030863 -289.851598) (xy 285.007267 -289.897908) (xy 284.976717 -289.939956)
			(xy 284.939966 -289.976707) (xy 284.897918 -290.007257) (xy 284.851608 -290.030853) (xy 284.802178 -290.046914)
			(xy 284.750843 -290.055044) (xy 284.698869 -290.055044) (xy 284.647534 -290.046914) (xy 284.598104 -290.030853)
			(xy 284.551794 -290.007257) (xy 284.509746 -289.976707) (xy 284.472995 -289.939956) (xy 284.442445 -289.897908)
			(xy 284.418849 -289.851598) (xy 284.402788 -289.802168) (xy 284.394658 -289.750833) (xy 284.105094 -289.750833)
			(xy 284.096964 -289.802168) (xy 284.080903 -289.851598) (xy 284.057307 -289.897908) (xy 284.026757 -289.939956)
			(xy 283.990006 -289.976707) (xy 283.947958 -290.007257) (xy 283.901648 -290.030853) (xy 283.852218 -290.046914)
			(xy 283.800883 -290.055044) (xy 283.748909 -290.055044) (xy 283.697574 -290.046914) (xy 283.648144 -290.030853)
			(xy 283.601834 -290.007257) (xy 283.559786 -289.976707) (xy 283.523035 -289.939956) (xy 283.492485 -289.897908)
			(xy 283.468889 -289.851598) (xy 283.452828 -289.802168) (xy 283.444698 -289.750833) (xy 283.155134 -289.750833)
			(xy 283.147004 -289.802168) (xy 283.130943 -289.851598) (xy 283.107347 -289.897908) (xy 283.076797 -289.939956)
			(xy 283.040046 -289.976707) (xy 282.997998 -290.007257) (xy 282.951688 -290.030853) (xy 282.902258 -290.046914)
			(xy 282.850923 -290.055044) (xy 282.798949 -290.055044) (xy 282.747614 -290.046914) (xy 282.698184 -290.030853)
			(xy 282.651874 -290.007257) (xy 282.609826 -289.976707) (xy 282.573075 -289.939956) (xy 282.542525 -289.897908)
			(xy 282.518929 -289.851598) (xy 282.502868 -289.802168) (xy 282.494738 -289.750833) (xy 282.20492 -289.750833)
			(xy 282.19679 -289.802168) (xy 282.180729 -289.851598) (xy 282.157133 -289.897908) (xy 282.126583 -289.939956)
			(xy 282.089832 -289.976707) (xy 282.047784 -290.007257) (xy 282.001474 -290.030853) (xy 281.952044 -290.046914)
			(xy 281.900709 -290.055044) (xy 281.848735 -290.055044) (xy 281.7974 -290.046914) (xy 281.74797 -290.030853)
			(xy 281.70166 -290.007257) (xy 281.659612 -289.976707) (xy 281.622861 -289.939956) (xy 281.592311 -289.897908)
			(xy 281.568715 -289.851598) (xy 281.552654 -289.802168) (xy 281.544524 -289.750833) (xy 281.25496 -289.750833)
			(xy 281.24683 -289.802168) (xy 281.230769 -289.851598) (xy 281.207173 -289.897908) (xy 281.176623 -289.939956)
			(xy 281.139872 -289.976707) (xy 281.097824 -290.007257) (xy 281.051514 -290.030853) (xy 281.002084 -290.046914)
			(xy 280.950749 -290.055044) (xy 280.898775 -290.055044) (xy 280.84744 -290.046914) (xy 280.79801 -290.030853)
			(xy 280.7517 -290.007257) (xy 280.709652 -289.976707) (xy 280.672901 -289.939956) (xy 280.642351 -289.897908)
			(xy 280.618755 -289.851598) (xy 280.602694 -289.802168) (xy 280.594564 -289.750833) (xy 280.594054 -289.724846)
			(xy 280.594605 -289.697633) (xy 280.603519 -289.643941) (xy 280.621114 -289.592436) (xy 280.646913 -289.544513)
			(xy 280.663142 -289.522662) (xy 280.672032 -289.510978) (xy 280.67508 -289.482276) (xy 280.628344 -289.38728)
			(xy 280.623856 -289.378947) (xy 280.609953 -289.366123) (xy 280.592335 -289.359243) (xy 280.582878 -289.358832)
			(xy 280.316686 -289.358832) (xy 280.30725 -289.35932) (xy 280.289681 -289.36623) (xy 280.275782 -289.379005)
			(xy 280.27122 -289.38728) (xy 280.224484 -289.482276) (xy 280.227532 -289.510978) (xy 280.236422 -289.522662)
			(xy 280.25263 -289.544526) (xy 280.278422 -289.592449) (xy 280.296016 -289.643949) (xy 280.304939 -289.697635)
			(xy 280.30551 -289.724846) (xy 280.305 -289.750833) (xy 280.29687 -289.802168) (xy 280.280809 -289.851598)
			(xy 280.257213 -289.897908) (xy 280.226663 -289.939956) (xy 280.189912 -289.976707) (xy 280.147864 -290.007257)
			(xy 280.101554 -290.030853) (xy 280.052124 -290.046914) (xy 280.000789 -290.055044) (xy 279.948815 -290.055044)
			(xy 279.89748 -290.046914) (xy 279.84805 -290.030853) (xy 279.80174 -290.007257) (xy 279.759692 -289.976707)
			(xy 279.722941 -289.939956) (xy 279.692391 -289.897908) (xy 279.668795 -289.851598) (xy 279.652734 -289.802168)
			(xy 279.644604 -289.750833) (xy 279.644094 -289.724846) (xy 279.644645 -289.697633) (xy 279.65356 -289.643942)
			(xy 279.671156 -289.592438) (xy 279.696958 -289.544517) (xy 279.713182 -289.522662) (xy 279.722072 -289.510978)
			(xy 279.72512 -289.482276) (xy 279.678384 -289.38728) (xy 279.673898 -289.378943) (xy 279.659997 -289.366108)
			(xy 279.642378 -289.359214) (xy 279.632918 -289.358832) (xy 279.366726 -289.358832) (xy 279.357296 -289.35933)
			(xy 279.339744 -289.366252) (xy 279.325862 -289.379031) (xy 279.32126 -289.38728) (xy 279.274524 -289.482276)
			(xy 279.277572 -289.510978) (xy 279.286462 -289.522662) (xy 279.302673 -289.544525) (xy 279.328469 -289.592447)
			(xy 279.346067 -289.643947) (xy 279.354991 -289.697634) (xy 279.35555 -289.724846) (xy 279.35504 -289.750833)
			(xy 279.34691 -289.802168) (xy 279.330849 -289.851598) (xy 279.307253 -289.897908) (xy 279.276703 -289.939956)
			(xy 279.239952 -289.976707) (xy 279.197904 -290.007257) (xy 279.151594 -290.030853) (xy 279.102164 -290.046914)
			(xy 279.050829 -290.055044) (xy 278.998855 -290.055044) (xy 278.94752 -290.046914) (xy 278.89809 -290.030853)
			(xy 278.85178 -290.007257) (xy 278.809732 -289.976707) (xy 278.772981 -289.939956) (xy 278.742431 -289.897908)
			(xy 278.718835 -289.851598) (xy 278.702774 -289.802168) (xy 278.694644 -289.750833) (xy 278.694134 -289.724846)
			(xy 278.694685 -289.697632) (xy 278.703599 -289.64394) (xy 278.721192 -289.592435) (xy 278.74699 -289.544511)
			(xy 278.763222 -289.522662) (xy 278.772112 -289.510978) (xy 278.77516 -289.482276) (xy 278.728424 -289.38728)
			(xy 278.72394 -289.378938) (xy 278.710041 -289.366092) (xy 278.692421 -289.359185) (xy 278.682958 -289.358832)
			(xy 278.416766 -289.358832) (xy 278.407332 -289.359323) (xy 278.389768 -289.366237) (xy 278.375875 -289.379014)
			(xy 278.3713 -289.38728) (xy 278.324564 -289.482276) (xy 278.327612 -289.510978) (xy 278.336502 -289.522662)
			(xy 278.352711 -289.544526) (xy 278.378504 -289.592448) (xy 278.3961 -289.643948) (xy 278.405023 -289.697635)
			(xy 278.40559 -289.724846) (xy 278.40508 -289.750833) (xy 278.39695 -289.802168) (xy 278.380889 -289.851598)
			(xy 278.357293 -289.897908) (xy 278.326743 -289.939956) (xy 278.289992 -289.976707) (xy 278.247944 -290.007257)
			(xy 278.201634 -290.030853) (xy 278.152204 -290.046914) (xy 278.100869 -290.055044) (xy 278.048895 -290.055044)
			(xy 277.99756 -290.046914) (xy 277.94813 -290.030853) (xy 277.90182 -290.007257) (xy 277.859772 -289.976707)
			(xy 277.823021 -289.939956) (xy 277.792471 -289.897908) (xy 277.768875 -289.851598) (xy 277.752814 -289.802168)
			(xy 277.744684 -289.750833) (xy 277.744174 -289.724846) (xy 277.744725 -289.697633) (xy 277.75364 -289.643941)
			(xy 277.771235 -289.592437) (xy 277.797035 -289.544515) (xy 277.813262 -289.522662) (xy 277.822152 -289.510978)
			(xy 277.8252 -289.482276) (xy 277.778464 -289.38728) (xy 277.773977 -289.378945) (xy 277.760075 -289.366115)
			(xy 277.742456 -289.359228) (xy 277.732998 -289.358832) (xy 277.466806 -289.358832) (xy 277.457367 -289.359316)
			(xy 277.439793 -289.366222) (xy 277.425888 -289.378997) (xy 277.42134 -289.38728) (xy 277.374604 -289.482276)
			(xy 277.377652 -289.510978) (xy 277.386542 -289.522662) (xy 277.402754 -289.544525) (xy 277.428552 -289.592446)
			(xy 277.446151 -289.643946) (xy 277.455075 -289.697634) (xy 277.45563 -289.724846) (xy 277.45512 -289.750833)
			(xy 277.44699 -289.802168) (xy 277.430929 -289.851598) (xy 277.407333 -289.897908) (xy 277.376783 -289.939956)
			(xy 277.340032 -289.976707) (xy 277.297984 -290.007257) (xy 277.251674 -290.030853) (xy 277.202244 -290.046914)
			(xy 277.150909 -290.055044) (xy 277.098935 -290.055044) (xy 277.0476 -290.046914) (xy 276.99817 -290.030853)
			(xy 276.95186 -290.007257) (xy 276.909812 -289.976707) (xy 276.873061 -289.939956) (xy 276.842511 -289.897908)
			(xy 276.818915 -289.851598) (xy 276.802854 -289.802168) (xy 276.794724 -289.750833) (xy 276.794214 -289.724846)
			(xy 276.794765 -289.697633) (xy 276.803681 -289.643942) (xy 276.821278 -289.592439) (xy 276.84708 -289.544519)
			(xy 276.863302 -289.522662) (xy 276.872192 -289.510978) (xy 276.87524 -289.482276) (xy 276.828504 -289.38728)
			(xy 276.824018 -289.37894) (xy 276.810119 -289.3661) (xy 276.792499 -289.3592) (xy 276.783038 -289.358832)
			(xy 276.516592 -289.358832) (xy 276.507155 -289.359319) (xy 276.489585 -289.366227) (xy 276.475684 -289.379003)
			(xy 276.471126 -289.38728) (xy 276.42439 -289.482276) (xy 276.427438 -289.510978) (xy 276.436328 -289.522662)
			(xy 276.452536 -289.544526) (xy 276.478327 -289.592449) (xy 276.495921 -289.643949) (xy 276.504843 -289.697635)
			(xy 276.505416 -289.724846) (xy 276.504906 -289.750833) (xy 276.496776 -289.802168) (xy 276.480715 -289.851598)
			(xy 276.457119 -289.897908) (xy 276.426569 -289.939956) (xy 276.389818 -289.976707) (xy 276.34777 -290.007257)
			(xy 276.30146 -290.030853) (xy 276.25203 -290.046914) (xy 276.200695 -290.055044) (xy 276.148721 -290.055044)
			(xy 276.097386 -290.046914) (xy 276.047956 -290.030853) (xy 276.001646 -290.007257) (xy 275.959598 -289.976707)
			(xy 275.922847 -289.939956) (xy 275.892297 -289.897908) (xy 275.868701 -289.851598) (xy 275.85264 -289.802168)
			(xy 275.84451 -289.750833) (xy 275.844 -289.724846) (xy 275.844551 -289.697633) (xy 275.853466 -289.643942)
			(xy 275.871063 -289.592439) (xy 275.896865 -289.544517) (xy 275.913088 -289.522662) (xy 275.921978 -289.510978)
			(xy 275.925026 -289.482276) (xy 275.87829 -289.38728) (xy 275.873804 -289.378942) (xy 275.859903 -289.366106)
			(xy 275.842284 -289.35921) (xy 275.832824 -289.358832) (xy 275.452078 -289.358832) (xy 275.44201 -289.35926)
			(xy 275.423415 -289.366983) (xy 275.41601 -289.373818) (xy 275.41093 -289.378898) (xy 275.404249 -289.38631)
			(xy 275.396656 -289.404741) (xy 275.396659 -289.424676) (xy 275.404258 -289.443105) (xy 275.41093 -289.450526)
			(xy 275.413978 -289.453574) (xy 275.41728 -289.456114) (xy 275.438268 -289.471749) (xy 275.475494 -289.508534)
			(xy 275.506457 -289.550725) (xy 275.530386 -289.597268) (xy 275.546681 -289.647) (xy 275.554936 -289.698679)
			(xy 275.555456 -289.724846) (xy 275.554923 -289.752243) (xy 275.545896 -289.806288) (xy 275.528082 -289.858105)
			(xy 275.501967 -289.906275) (xy 275.468266 -289.949479) (xy 275.427903 -289.986535) (xy 275.381981 -290.016427)
			(xy 275.357082 -290.027868) (xy 275.343112 -290.033964) (xy 275.326602 -290.059364) (xy 275.326602 -290.145724)
			(xy 275.326174 -290.155792) (xy 275.318454 -290.174391) (xy 275.311616 -290.181792) (xy 275.311616 -290.318952)
			(xy 275.311868 -290.326599) (xy 275.316379 -290.341212) (xy 275.320506 -290.347654) (xy 275.325078 -290.354258)
			(xy 275.336762 -290.363656) (xy 275.344128 -290.36645) (xy 275.368647 -290.376508) (xy 275.414378 -290.403284)
			(xy 275.455254 -290.43701) (xy 275.490227 -290.476824) (xy 275.518403 -290.521706) (xy 275.53906 -290.570508)
			(xy 275.551669 -290.621979) (xy 275.555908 -290.674802) (xy 275.553822 -290.700793) (xy 275.84451 -290.700793)
			(xy 275.84451 -290.648819) (xy 275.85264 -290.597484) (xy 275.868701 -290.548054) (xy 275.892297 -290.501744)
			(xy 275.922847 -290.459696) (xy 275.959598 -290.422945) (xy 276.001646 -290.392395) (xy 276.047956 -290.368799)
			(xy 276.097386 -290.352738) (xy 276.148721 -290.344608) (xy 276.200695 -290.344608) (xy 276.25203 -290.352738)
			(xy 276.30146 -290.368799) (xy 276.34777 -290.392395) (xy 276.389818 -290.422945) (xy 276.426569 -290.459696)
			(xy 276.457119 -290.501744) (xy 276.480715 -290.548054) (xy 276.496776 -290.597484) (xy 276.504906 -290.648819)
			(xy 276.505416 -290.674806) (xy 276.504906 -290.700793) (xy 277.744684 -290.700793) (xy 277.744684 -290.648819)
			(xy 277.752814 -290.597484) (xy 277.768875 -290.548054) (xy 277.792471 -290.501744) (xy 277.823021 -290.459696)
			(xy 277.859772 -290.422945) (xy 277.90182 -290.392395) (xy 277.94813 -290.368799) (xy 277.99756 -290.352738)
			(xy 278.048895 -290.344608) (xy 278.100869 -290.344608) (xy 278.152204 -290.352738) (xy 278.201634 -290.368799)
			(xy 278.247944 -290.392395) (xy 278.289992 -290.422945) (xy 278.326743 -290.459696) (xy 278.357293 -290.501744)
			(xy 278.380889 -290.548054) (xy 278.39695 -290.597484) (xy 278.40508 -290.648819) (xy 278.40559 -290.674806)
			(xy 278.40508 -290.700793) (xy 279.644604 -290.700793) (xy 279.644604 -290.648819) (xy 279.652734 -290.597484)
			(xy 279.668795 -290.548054) (xy 279.692391 -290.501744) (xy 279.722941 -290.459696) (xy 279.759692 -290.422945)
			(xy 279.80174 -290.392395) (xy 279.84805 -290.368799) (xy 279.89748 -290.352738) (xy 279.948815 -290.344608)
			(xy 280.000789 -290.344608) (xy 280.052124 -290.352738) (xy 280.101554 -290.368799) (xy 280.147864 -290.392395)
			(xy 280.189912 -290.422945) (xy 280.226663 -290.459696) (xy 280.257213 -290.501744) (xy 280.280809 -290.548054)
			(xy 280.29687 -290.597484) (xy 280.305 -290.648819) (xy 280.30551 -290.674806) (xy 280.305 -290.700793)
			(xy 280.594564 -290.700793) (xy 280.594564 -290.648819) (xy 280.602694 -290.597484) (xy 280.618755 -290.548054)
			(xy 280.642351 -290.501744) (xy 280.672901 -290.459696) (xy 280.709652 -290.422945) (xy 280.7517 -290.392395)
			(xy 280.79801 -290.368799) (xy 280.84744 -290.352738) (xy 280.898775 -290.344608) (xy 280.950749 -290.344608)
			(xy 281.002084 -290.352738) (xy 281.051514 -290.368799) (xy 281.097824 -290.392395) (xy 281.139872 -290.422945)
			(xy 281.176623 -290.459696) (xy 281.207173 -290.501744) (xy 281.230769 -290.548054) (xy 281.24683 -290.597484)
			(xy 281.25496 -290.648819) (xy 281.25547 -290.674806) (xy 281.25496 -290.700793) (xy 281.544524 -290.700793)
			(xy 281.544524 -290.648819) (xy 281.552654 -290.597484) (xy 281.568715 -290.548054) (xy 281.592311 -290.501744)
			(xy 281.622861 -290.459696) (xy 281.659612 -290.422945) (xy 281.70166 -290.392395) (xy 281.74797 -290.368799)
			(xy 281.7974 -290.352738) (xy 281.848735 -290.344608) (xy 281.900709 -290.344608) (xy 281.952044 -290.352738)
			(xy 282.001474 -290.368799) (xy 282.047784 -290.392395) (xy 282.089832 -290.422945) (xy 282.126583 -290.459696)
			(xy 282.157133 -290.501744) (xy 282.180729 -290.548054) (xy 282.19679 -290.597484) (xy 282.20492 -290.648819)
			(xy 282.20543 -290.674806) (xy 282.20492 -290.700793) (xy 282.494738 -290.700793) (xy 282.494738 -290.648819)
			(xy 282.502868 -290.597484) (xy 282.518929 -290.548054) (xy 282.542525 -290.501744) (xy 282.573075 -290.459696)
			(xy 282.609826 -290.422945) (xy 282.651874 -290.392395) (xy 282.698184 -290.368799) (xy 282.747614 -290.352738)
			(xy 282.798949 -290.344608) (xy 282.850923 -290.344608) (xy 282.902258 -290.352738) (xy 282.951688 -290.368799)
			(xy 282.997998 -290.392395) (xy 283.040046 -290.422945) (xy 283.076797 -290.459696) (xy 283.107347 -290.501744)
			(xy 283.130943 -290.548054) (xy 283.147004 -290.597484) (xy 283.155134 -290.648819) (xy 283.155644 -290.674806)
			(xy 283.155134 -290.700793) (xy 283.444698 -290.700793) (xy 283.444698 -290.648819) (xy 283.452828 -290.597484)
			(xy 283.468889 -290.548054) (xy 283.492485 -290.501744) (xy 283.523035 -290.459696) (xy 283.559786 -290.422945)
			(xy 283.601834 -290.392395) (xy 283.648144 -290.368799) (xy 283.697574 -290.352738) (xy 283.748909 -290.344608)
			(xy 283.800883 -290.344608) (xy 283.852218 -290.352738) (xy 283.901648 -290.368799) (xy 283.947958 -290.392395)
			(xy 283.990006 -290.422945) (xy 284.026757 -290.459696) (xy 284.057307 -290.501744) (xy 284.080903 -290.548054)
			(xy 284.096964 -290.597484) (xy 284.105094 -290.648819) (xy 284.105604 -290.674806) (xy 284.105094 -290.700793)
			(xy 284.394658 -290.700793) (xy 284.394658 -290.648819) (xy 284.402788 -290.597484) (xy 284.418849 -290.548054)
			(xy 284.442445 -290.501744) (xy 284.472995 -290.459696) (xy 284.509746 -290.422945) (xy 284.551794 -290.392395)
			(xy 284.598104 -290.368799) (xy 284.647534 -290.352738) (xy 284.698869 -290.344608) (xy 284.750843 -290.344608)
			(xy 284.802178 -290.352738) (xy 284.851608 -290.368799) (xy 284.897918 -290.392395) (xy 284.939966 -290.422945)
			(xy 284.976717 -290.459696) (xy 285.007267 -290.501744) (xy 285.030863 -290.548054) (xy 285.046924 -290.597484)
			(xy 285.055054 -290.648819) (xy 285.055564 -290.674806) (xy 285.055054 -290.700793) (xy 285.344618 -290.700793)
			(xy 285.344618 -290.648819) (xy 285.352748 -290.597484) (xy 285.368809 -290.548054) (xy 285.392405 -290.501744)
			(xy 285.422955 -290.459696) (xy 285.459706 -290.422945) (xy 285.501754 -290.392395) (xy 285.548064 -290.368799)
			(xy 285.597494 -290.352738) (xy 285.648829 -290.344608) (xy 285.700803 -290.344608) (xy 285.752138 -290.352738)
			(xy 285.801568 -290.368799) (xy 285.847878 -290.392395) (xy 285.889926 -290.422945) (xy 285.926677 -290.459696)
			(xy 285.957227 -290.501744) (xy 285.980823 -290.548054) (xy 285.996884 -290.597484) (xy 286.005014 -290.648819)
			(xy 286.005524 -290.674806) (xy 286.005014 -290.700793) (xy 286.294578 -290.700793) (xy 286.294578 -290.648819)
			(xy 286.302708 -290.597484) (xy 286.318769 -290.548054) (xy 286.342365 -290.501744) (xy 286.372915 -290.459696)
			(xy 286.409666 -290.422945) (xy 286.451714 -290.392395) (xy 286.498024 -290.368799) (xy 286.547454 -290.352738)
			(xy 286.598789 -290.344608) (xy 286.650763 -290.344608) (xy 286.702098 -290.352738) (xy 286.751528 -290.368799)
			(xy 286.797838 -290.392395) (xy 286.839886 -290.422945) (xy 286.876637 -290.459696) (xy 286.907187 -290.501744)
			(xy 286.930783 -290.548054) (xy 286.946844 -290.597484) (xy 286.954974 -290.648819) (xy 286.955484 -290.674806)
			(xy 286.954974 -290.700793) (xy 287.244538 -290.700793) (xy 287.244538 -290.648819) (xy 287.252668 -290.597484)
			(xy 287.268729 -290.548054) (xy 287.292325 -290.501744) (xy 287.322875 -290.459696) (xy 287.359626 -290.422945)
			(xy 287.401674 -290.392395) (xy 287.447984 -290.368799) (xy 287.497414 -290.352738) (xy 287.548749 -290.344608)
			(xy 287.600723 -290.344608) (xy 287.652058 -290.352738) (xy 287.701488 -290.368799) (xy 287.747798 -290.392395)
			(xy 287.789846 -290.422945) (xy 287.826597 -290.459696) (xy 287.857147 -290.501744) (xy 287.880743 -290.548054)
			(xy 287.896804 -290.597484) (xy 287.904934 -290.648819) (xy 287.905444 -290.674806) (xy 287.904934 -290.700793)
			(xy 288.194498 -290.700793) (xy 288.194498 -290.648819) (xy 288.202628 -290.597484) (xy 288.218689 -290.548054)
			(xy 288.242285 -290.501744) (xy 288.272835 -290.459696) (xy 288.309586 -290.422945) (xy 288.351634 -290.392395)
			(xy 288.397944 -290.368799) (xy 288.447374 -290.352738) (xy 288.498709 -290.344608) (xy 288.550683 -290.344608)
			(xy 288.602018 -290.352738) (xy 288.651448 -290.368799) (xy 288.697758 -290.392395) (xy 288.739806 -290.422945)
			(xy 288.776557 -290.459696) (xy 288.807107 -290.501744) (xy 288.830703 -290.548054) (xy 288.846764 -290.597484)
			(xy 288.854894 -290.648819) (xy 288.855404 -290.674806) (xy 288.854894 -290.700793) (xy 289.144712 -290.700793)
			(xy 289.144712 -290.648819) (xy 289.152842 -290.597484) (xy 289.168903 -290.548054) (xy 289.192499 -290.501744)
			(xy 289.223049 -290.459696) (xy 289.2598 -290.422945) (xy 289.301848 -290.392395) (xy 289.348158 -290.368799)
			(xy 289.397588 -290.352738) (xy 289.448923 -290.344608) (xy 289.500897 -290.344608) (xy 289.552232 -290.352738)
			(xy 289.601662 -290.368799) (xy 289.647972 -290.392395) (xy 289.69002 -290.422945) (xy 289.726771 -290.459696)
			(xy 289.757321 -290.501744) (xy 289.780917 -290.548054) (xy 289.796978 -290.597484) (xy 289.805108 -290.648819)
			(xy 289.805618 -290.674806) (xy 289.805108 -290.700793) (xy 290.094672 -290.700793) (xy 290.094672 -290.648819)
			(xy 290.102802 -290.597484) (xy 290.118863 -290.548054) (xy 290.142459 -290.501744) (xy 290.173009 -290.459696)
			(xy 290.20976 -290.422945) (xy 290.251808 -290.392395) (xy 290.298118 -290.368799) (xy 290.347548 -290.352738)
			(xy 290.398883 -290.344608) (xy 290.450857 -290.344608) (xy 290.502192 -290.352738) (xy 290.551622 -290.368799)
			(xy 290.597932 -290.392395) (xy 290.63998 -290.422945) (xy 290.676731 -290.459696) (xy 290.707281 -290.501744)
			(xy 290.730877 -290.548054) (xy 290.746938 -290.597484) (xy 290.755068 -290.648819) (xy 290.755578 -290.674806)
			(xy 290.755068 -290.700793) (xy 291.994592 -290.700793) (xy 291.994592 -290.648819) (xy 292.002722 -290.597484)
			(xy 292.018783 -290.548054) (xy 292.042379 -290.501744) (xy 292.072929 -290.459696) (xy 292.10968 -290.422945)
			(xy 292.151728 -290.392395) (xy 292.198038 -290.368799) (xy 292.247468 -290.352738) (xy 292.298803 -290.344608)
			(xy 292.350777 -290.344608) (xy 292.402112 -290.352738) (xy 292.451542 -290.368799) (xy 292.497852 -290.392395)
			(xy 292.5399 -290.422945) (xy 292.576651 -290.459696) (xy 292.607201 -290.501744) (xy 292.630797 -290.548054)
			(xy 292.646858 -290.597484) (xy 292.654988 -290.648819) (xy 292.655498 -290.674806) (xy 292.654988 -290.700793)
			(xy 292.944552 -290.700793) (xy 292.944552 -290.648819) (xy 292.952682 -290.597484) (xy 292.968743 -290.548054)
			(xy 292.992339 -290.501744) (xy 293.022889 -290.459696) (xy 293.05964 -290.422945) (xy 293.101688 -290.392395)
			(xy 293.147998 -290.368799) (xy 293.197428 -290.352738) (xy 293.248763 -290.344608) (xy 293.300737 -290.344608)
			(xy 293.352072 -290.352738) (xy 293.401502 -290.368799) (xy 293.447812 -290.392395) (xy 293.48986 -290.422945)
			(xy 293.526611 -290.459696) (xy 293.557161 -290.501744) (xy 293.580757 -290.548054) (xy 293.596818 -290.597484)
			(xy 293.604948 -290.648819) (xy 293.605458 -290.674806) (xy 293.604948 -290.700793) (xy 293.894512 -290.700793)
			(xy 293.894512 -290.648819) (xy 293.902642 -290.597484) (xy 293.918703 -290.548054) (xy 293.942299 -290.501744)
			(xy 293.972849 -290.459696) (xy 294.0096 -290.422945) (xy 294.051648 -290.392395) (xy 294.097958 -290.368799)
			(xy 294.147388 -290.352738) (xy 294.198723 -290.344608) (xy 294.250697 -290.344608) (xy 294.302032 -290.352738)
			(xy 294.351462 -290.368799) (xy 294.397772 -290.392395) (xy 294.43982 -290.422945) (xy 294.476571 -290.459696)
			(xy 294.507121 -290.501744) (xy 294.530717 -290.548054) (xy 294.546778 -290.597484) (xy 294.554908 -290.648819)
			(xy 294.555418 -290.674806) (xy 294.554908 -290.700793) (xy 294.844726 -290.700793) (xy 294.844726 -290.648819)
			(xy 294.852856 -290.597484) (xy 294.868917 -290.548054) (xy 294.892513 -290.501744) (xy 294.923063 -290.459696)
			(xy 294.959814 -290.422945) (xy 295.001862 -290.392395) (xy 295.048172 -290.368799) (xy 295.097602 -290.352738)
			(xy 295.148937 -290.344608) (xy 295.200911 -290.344608) (xy 295.252246 -290.352738) (xy 295.301676 -290.368799)
			(xy 295.347986 -290.392395) (xy 295.390034 -290.422945) (xy 295.426785 -290.459696) (xy 295.457335 -290.501744)
			(xy 295.480931 -290.548054) (xy 295.496992 -290.597484) (xy 295.505122 -290.648819) (xy 295.505632 -290.674806)
			(xy 295.505122 -290.700793) (xy 295.794686 -290.700793) (xy 295.794686 -290.648819) (xy 295.802816 -290.597484)
			(xy 295.818877 -290.548054) (xy 295.842473 -290.501744) (xy 295.873023 -290.459696) (xy 295.909774 -290.422945)
			(xy 295.951822 -290.392395) (xy 295.998132 -290.368799) (xy 296.047562 -290.352738) (xy 296.098897 -290.344608)
			(xy 296.150871 -290.344608) (xy 296.202206 -290.352738) (xy 296.251636 -290.368799) (xy 296.297946 -290.392395)
			(xy 296.339994 -290.422945) (xy 296.376745 -290.459696) (xy 296.407295 -290.501744) (xy 296.430891 -290.548054)
			(xy 296.446952 -290.597484) (xy 296.455082 -290.648819) (xy 296.455592 -290.674806) (xy 296.455082 -290.700793)
			(xy 296.744646 -290.700793) (xy 296.744646 -290.648819) (xy 296.752776 -290.597484) (xy 296.768837 -290.548054)
			(xy 296.792433 -290.501744) (xy 296.822983 -290.459696) (xy 296.859734 -290.422945) (xy 296.901782 -290.392395)
			(xy 296.948092 -290.368799) (xy 296.997522 -290.352738) (xy 297.048857 -290.344608) (xy 297.100831 -290.344608)
			(xy 297.152166 -290.352738) (xy 297.201596 -290.368799) (xy 297.247906 -290.392395) (xy 297.289954 -290.422945)
			(xy 297.326705 -290.459696) (xy 297.357255 -290.501744) (xy 297.380851 -290.548054) (xy 297.396912 -290.597484)
			(xy 297.405042 -290.648819) (xy 297.405552 -290.674806) (xy 297.405042 -290.700793) (xy 297.694606 -290.700793)
			(xy 297.694606 -290.648819) (xy 297.702736 -290.597484) (xy 297.718797 -290.548054) (xy 297.742393 -290.501744)
			(xy 297.772943 -290.459696) (xy 297.809694 -290.422945) (xy 297.851742 -290.392395) (xy 297.898052 -290.368799)
			(xy 297.947482 -290.352738) (xy 297.998817 -290.344608) (xy 298.050791 -290.344608) (xy 298.102126 -290.352738)
			(xy 298.151556 -290.368799) (xy 298.197866 -290.392395) (xy 298.239914 -290.422945) (xy 298.276665 -290.459696)
			(xy 298.307215 -290.501744) (xy 298.330811 -290.548054) (xy 298.346872 -290.597484) (xy 298.355002 -290.648819)
			(xy 298.355512 -290.674806) (xy 298.355002 -290.700793) (xy 298.644566 -290.700793) (xy 298.644566 -290.648819)
			(xy 298.652696 -290.597484) (xy 298.668757 -290.548054) (xy 298.692353 -290.501744) (xy 298.722903 -290.459696)
			(xy 298.759654 -290.422945) (xy 298.801702 -290.392395) (xy 298.848012 -290.368799) (xy 298.897442 -290.352738)
			(xy 298.948777 -290.344608) (xy 299.000751 -290.344608) (xy 299.052086 -290.352738) (xy 299.101516 -290.368799)
			(xy 299.147826 -290.392395) (xy 299.189874 -290.422945) (xy 299.226625 -290.459696) (xy 299.257175 -290.501744)
			(xy 299.280771 -290.548054) (xy 299.296832 -290.597484) (xy 299.304962 -290.648819) (xy 299.305472 -290.674806)
			(xy 299.304962 -290.700793) (xy 299.594526 -290.700793) (xy 299.594526 -290.648819) (xy 299.602656 -290.597484)
			(xy 299.618717 -290.548054) (xy 299.642313 -290.501744) (xy 299.672863 -290.459696) (xy 299.709614 -290.422945)
			(xy 299.751662 -290.392395) (xy 299.797972 -290.368799) (xy 299.847402 -290.352738) (xy 299.898737 -290.344608)
			(xy 299.950711 -290.344608) (xy 300.002046 -290.352738) (xy 300.051476 -290.368799) (xy 300.097786 -290.392395)
			(xy 300.139834 -290.422945) (xy 300.176585 -290.459696) (xy 300.207135 -290.501744) (xy 300.230731 -290.548054)
			(xy 300.246792 -290.597484) (xy 300.254922 -290.648819) (xy 300.255432 -290.674806) (xy 300.254922 -290.700793)
			(xy 300.544486 -290.700793) (xy 300.544486 -290.648819) (xy 300.552616 -290.597484) (xy 300.568677 -290.548054)
			(xy 300.592273 -290.501744) (xy 300.622823 -290.459696) (xy 300.659574 -290.422945) (xy 300.701622 -290.392395)
			(xy 300.747932 -290.368799) (xy 300.797362 -290.352738) (xy 300.848697 -290.344608) (xy 300.900671 -290.344608)
			(xy 300.952006 -290.352738) (xy 301.001436 -290.368799) (xy 301.047746 -290.392395) (xy 301.089794 -290.422945)
			(xy 301.126545 -290.459696) (xy 301.157095 -290.501744) (xy 301.180691 -290.548054) (xy 301.196752 -290.597484)
			(xy 301.204882 -290.648819) (xy 301.205392 -290.674806) (xy 301.204882 -290.700793) (xy 301.196752 -290.752128)
			(xy 301.180691 -290.801558) (xy 301.157095 -290.847868) (xy 301.126545 -290.889916) (xy 301.089794 -290.926667)
			(xy 301.047746 -290.957217) (xy 301.001436 -290.980813) (xy 300.952006 -290.996874) (xy 300.900671 -291.005004)
			(xy 300.848697 -291.005004) (xy 300.797362 -290.996874) (xy 300.747932 -290.980813) (xy 300.701622 -290.957217)
			(xy 300.659574 -290.926667) (xy 300.622823 -290.889916) (xy 300.592273 -290.847868) (xy 300.568677 -290.801558)
			(xy 300.552616 -290.752128) (xy 300.544486 -290.700793) (xy 300.254922 -290.700793) (xy 300.246792 -290.752128)
			(xy 300.230731 -290.801558) (xy 300.207135 -290.847868) (xy 300.176585 -290.889916) (xy 300.139834 -290.926667)
			(xy 300.097786 -290.957217) (xy 300.051476 -290.980813) (xy 300.002046 -290.996874) (xy 299.950711 -291.005004)
			(xy 299.898737 -291.005004) (xy 299.847402 -290.996874) (xy 299.797972 -290.980813) (xy 299.751662 -290.957217)
			(xy 299.709614 -290.926667) (xy 299.672863 -290.889916) (xy 299.642313 -290.847868) (xy 299.618717 -290.801558)
			(xy 299.602656 -290.752128) (xy 299.594526 -290.700793) (xy 299.304962 -290.700793) (xy 299.296832 -290.752128)
			(xy 299.280771 -290.801558) (xy 299.257175 -290.847868) (xy 299.226625 -290.889916) (xy 299.189874 -290.926667)
			(xy 299.147826 -290.957217) (xy 299.101516 -290.980813) (xy 299.052086 -290.996874) (xy 299.000751 -291.005004)
			(xy 298.948777 -291.005004) (xy 298.897442 -290.996874) (xy 298.848012 -290.980813) (xy 298.801702 -290.957217)
			(xy 298.759654 -290.926667) (xy 298.722903 -290.889916) (xy 298.692353 -290.847868) (xy 298.668757 -290.801558)
			(xy 298.652696 -290.752128) (xy 298.644566 -290.700793) (xy 298.355002 -290.700793) (xy 298.346872 -290.752128)
			(xy 298.330811 -290.801558) (xy 298.307215 -290.847868) (xy 298.276665 -290.889916) (xy 298.239914 -290.926667)
			(xy 298.197866 -290.957217) (xy 298.151556 -290.980813) (xy 298.102126 -290.996874) (xy 298.050791 -291.005004)
			(xy 297.998817 -291.005004) (xy 297.947482 -290.996874) (xy 297.898052 -290.980813) (xy 297.851742 -290.957217)
			(xy 297.809694 -290.926667) (xy 297.772943 -290.889916) (xy 297.742393 -290.847868) (xy 297.718797 -290.801558)
			(xy 297.702736 -290.752128) (xy 297.694606 -290.700793) (xy 297.405042 -290.700793) (xy 297.396912 -290.752128)
			(xy 297.380851 -290.801558) (xy 297.357255 -290.847868) (xy 297.326705 -290.889916) (xy 297.289954 -290.926667)
			(xy 297.247906 -290.957217) (xy 297.201596 -290.980813) (xy 297.152166 -290.996874) (xy 297.100831 -291.005004)
			(xy 297.048857 -291.005004) (xy 296.997522 -290.996874) (xy 296.948092 -290.980813) (xy 296.901782 -290.957217)
			(xy 296.859734 -290.926667) (xy 296.822983 -290.889916) (xy 296.792433 -290.847868) (xy 296.768837 -290.801558)
			(xy 296.752776 -290.752128) (xy 296.744646 -290.700793) (xy 296.455082 -290.700793) (xy 296.446952 -290.752128)
			(xy 296.430891 -290.801558) (xy 296.407295 -290.847868) (xy 296.376745 -290.889916) (xy 296.339994 -290.926667)
			(xy 296.297946 -290.957217) (xy 296.251636 -290.980813) (xy 296.202206 -290.996874) (xy 296.150871 -291.005004)
			(xy 296.098897 -291.005004) (xy 296.047562 -290.996874) (xy 295.998132 -290.980813) (xy 295.951822 -290.957217)
			(xy 295.909774 -290.926667) (xy 295.873023 -290.889916) (xy 295.842473 -290.847868) (xy 295.818877 -290.801558)
			(xy 295.802816 -290.752128) (xy 295.794686 -290.700793) (xy 295.505122 -290.700793) (xy 295.496992 -290.752128)
			(xy 295.480931 -290.801558) (xy 295.457335 -290.847868) (xy 295.426785 -290.889916) (xy 295.390034 -290.926667)
			(xy 295.347986 -290.957217) (xy 295.301676 -290.980813) (xy 295.252246 -290.996874) (xy 295.200911 -291.005004)
			(xy 295.148937 -291.005004) (xy 295.097602 -290.996874) (xy 295.048172 -290.980813) (xy 295.001862 -290.957217)
			(xy 294.959814 -290.926667) (xy 294.923063 -290.889916) (xy 294.892513 -290.847868) (xy 294.868917 -290.801558)
			(xy 294.852856 -290.752128) (xy 294.844726 -290.700793) (xy 294.554908 -290.700793) (xy 294.546778 -290.752128)
			(xy 294.530717 -290.801558) (xy 294.507121 -290.847868) (xy 294.476571 -290.889916) (xy 294.43982 -290.926667)
			(xy 294.397772 -290.957217) (xy 294.351462 -290.980813) (xy 294.302032 -290.996874) (xy 294.250697 -291.005004)
			(xy 294.198723 -291.005004) (xy 294.147388 -290.996874) (xy 294.097958 -290.980813) (xy 294.051648 -290.957217)
			(xy 294.0096 -290.926667) (xy 293.972849 -290.889916) (xy 293.942299 -290.847868) (xy 293.918703 -290.801558)
			(xy 293.902642 -290.752128) (xy 293.894512 -290.700793) (xy 293.604948 -290.700793) (xy 293.596818 -290.752128)
			(xy 293.580757 -290.801558) (xy 293.557161 -290.847868) (xy 293.526611 -290.889916) (xy 293.48986 -290.926667)
			(xy 293.447812 -290.957217) (xy 293.401502 -290.980813) (xy 293.352072 -290.996874) (xy 293.300737 -291.005004)
			(xy 293.248763 -291.005004) (xy 293.197428 -290.996874) (xy 293.147998 -290.980813) (xy 293.101688 -290.957217)
			(xy 293.05964 -290.926667) (xy 293.022889 -290.889916) (xy 292.992339 -290.847868) (xy 292.968743 -290.801558)
			(xy 292.952682 -290.752128) (xy 292.944552 -290.700793) (xy 292.654988 -290.700793) (xy 292.646858 -290.752128)
			(xy 292.630797 -290.801558) (xy 292.607201 -290.847868) (xy 292.576651 -290.889916) (xy 292.5399 -290.926667)
			(xy 292.497852 -290.957217) (xy 292.451542 -290.980813) (xy 292.402112 -290.996874) (xy 292.350777 -291.005004)
			(xy 292.298803 -291.005004) (xy 292.247468 -290.996874) (xy 292.198038 -290.980813) (xy 292.151728 -290.957217)
			(xy 292.10968 -290.926667) (xy 292.072929 -290.889916) (xy 292.042379 -290.847868) (xy 292.018783 -290.801558)
			(xy 292.002722 -290.752128) (xy 291.994592 -290.700793) (xy 290.755068 -290.700793) (xy 290.746938 -290.752128)
			(xy 290.730877 -290.801558) (xy 290.707281 -290.847868) (xy 290.676731 -290.889916) (xy 290.63998 -290.926667)
			(xy 290.597932 -290.957217) (xy 290.551622 -290.980813) (xy 290.502192 -290.996874) (xy 290.450857 -291.005004)
			(xy 290.398883 -291.005004) (xy 290.347548 -290.996874) (xy 290.298118 -290.980813) (xy 290.251808 -290.957217)
			(xy 290.20976 -290.926667) (xy 290.173009 -290.889916) (xy 290.142459 -290.847868) (xy 290.118863 -290.801558)
			(xy 290.102802 -290.752128) (xy 290.094672 -290.700793) (xy 289.805108 -290.700793) (xy 289.796978 -290.752128)
			(xy 289.780917 -290.801558) (xy 289.757321 -290.847868) (xy 289.726771 -290.889916) (xy 289.69002 -290.926667)
			(xy 289.647972 -290.957217) (xy 289.601662 -290.980813) (xy 289.552232 -290.996874) (xy 289.500897 -291.005004)
			(xy 289.448923 -291.005004) (xy 289.397588 -290.996874) (xy 289.348158 -290.980813) (xy 289.301848 -290.957217)
			(xy 289.2598 -290.926667) (xy 289.223049 -290.889916) (xy 289.192499 -290.847868) (xy 289.168903 -290.801558)
			(xy 289.152842 -290.752128) (xy 289.144712 -290.700793) (xy 288.854894 -290.700793) (xy 288.846764 -290.752128)
			(xy 288.830703 -290.801558) (xy 288.807107 -290.847868) (xy 288.776557 -290.889916) (xy 288.739806 -290.926667)
			(xy 288.697758 -290.957217) (xy 288.651448 -290.980813) (xy 288.602018 -290.996874) (xy 288.550683 -291.005004)
			(xy 288.498709 -291.005004) (xy 288.447374 -290.996874) (xy 288.397944 -290.980813) (xy 288.351634 -290.957217)
			(xy 288.309586 -290.926667) (xy 288.272835 -290.889916) (xy 288.242285 -290.847868) (xy 288.218689 -290.801558)
			(xy 288.202628 -290.752128) (xy 288.194498 -290.700793) (xy 287.904934 -290.700793) (xy 287.896804 -290.752128)
			(xy 287.880743 -290.801558) (xy 287.857147 -290.847868) (xy 287.826597 -290.889916) (xy 287.789846 -290.926667)
			(xy 287.747798 -290.957217) (xy 287.701488 -290.980813) (xy 287.652058 -290.996874) (xy 287.600723 -291.005004)
			(xy 287.548749 -291.005004) (xy 287.497414 -290.996874) (xy 287.447984 -290.980813) (xy 287.401674 -290.957217)
			(xy 287.359626 -290.926667) (xy 287.322875 -290.889916) (xy 287.292325 -290.847868) (xy 287.268729 -290.801558)
			(xy 287.252668 -290.752128) (xy 287.244538 -290.700793) (xy 286.954974 -290.700793) (xy 286.946844 -290.752128)
			(xy 286.930783 -290.801558) (xy 286.907187 -290.847868) (xy 286.876637 -290.889916) (xy 286.839886 -290.926667)
			(xy 286.797838 -290.957217) (xy 286.751528 -290.980813) (xy 286.702098 -290.996874) (xy 286.650763 -291.005004)
			(xy 286.598789 -291.005004) (xy 286.547454 -290.996874) (xy 286.498024 -290.980813) (xy 286.451714 -290.957217)
			(xy 286.409666 -290.926667) (xy 286.372915 -290.889916) (xy 286.342365 -290.847868) (xy 286.318769 -290.801558)
			(xy 286.302708 -290.752128) (xy 286.294578 -290.700793) (xy 286.005014 -290.700793) (xy 285.996884 -290.752128)
			(xy 285.980823 -290.801558) (xy 285.957227 -290.847868) (xy 285.926677 -290.889916) (xy 285.889926 -290.926667)
			(xy 285.847878 -290.957217) (xy 285.801568 -290.980813) (xy 285.752138 -290.996874) (xy 285.700803 -291.005004)
			(xy 285.648829 -291.005004) (xy 285.597494 -290.996874) (xy 285.548064 -290.980813) (xy 285.501754 -290.957217)
			(xy 285.459706 -290.926667) (xy 285.422955 -290.889916) (xy 285.392405 -290.847868) (xy 285.368809 -290.801558)
			(xy 285.352748 -290.752128) (xy 285.344618 -290.700793) (xy 285.055054 -290.700793) (xy 285.046924 -290.752128)
			(xy 285.030863 -290.801558) (xy 285.007267 -290.847868) (xy 284.976717 -290.889916) (xy 284.939966 -290.926667)
			(xy 284.897918 -290.957217) (xy 284.851608 -290.980813) (xy 284.802178 -290.996874) (xy 284.750843 -291.005004)
			(xy 284.698869 -291.005004) (xy 284.647534 -290.996874) (xy 284.598104 -290.980813) (xy 284.551794 -290.957217)
			(xy 284.509746 -290.926667) (xy 284.472995 -290.889916) (xy 284.442445 -290.847868) (xy 284.418849 -290.801558)
			(xy 284.402788 -290.752128) (xy 284.394658 -290.700793) (xy 284.105094 -290.700793) (xy 284.096964 -290.752128)
			(xy 284.080903 -290.801558) (xy 284.057307 -290.847868) (xy 284.026757 -290.889916) (xy 283.990006 -290.926667)
			(xy 283.947958 -290.957217) (xy 283.901648 -290.980813) (xy 283.852218 -290.996874) (xy 283.800883 -291.005004)
			(xy 283.748909 -291.005004) (xy 283.697574 -290.996874) (xy 283.648144 -290.980813) (xy 283.601834 -290.957217)
			(xy 283.559786 -290.926667) (xy 283.523035 -290.889916) (xy 283.492485 -290.847868) (xy 283.468889 -290.801558)
			(xy 283.452828 -290.752128) (xy 283.444698 -290.700793) (xy 283.155134 -290.700793) (xy 283.147004 -290.752128)
			(xy 283.130943 -290.801558) (xy 283.107347 -290.847868) (xy 283.076797 -290.889916) (xy 283.040046 -290.926667)
			(xy 282.997998 -290.957217) (xy 282.951688 -290.980813) (xy 282.902258 -290.996874) (xy 282.850923 -291.005004)
			(xy 282.798949 -291.005004) (xy 282.747614 -290.996874) (xy 282.698184 -290.980813) (xy 282.651874 -290.957217)
			(xy 282.609826 -290.926667) (xy 282.573075 -290.889916) (xy 282.542525 -290.847868) (xy 282.518929 -290.801558)
			(xy 282.502868 -290.752128) (xy 282.494738 -290.700793) (xy 282.20492 -290.700793) (xy 282.19679 -290.752128)
			(xy 282.180729 -290.801558) (xy 282.157133 -290.847868) (xy 282.126583 -290.889916) (xy 282.089832 -290.926667)
			(xy 282.047784 -290.957217) (xy 282.001474 -290.980813) (xy 281.952044 -290.996874) (xy 281.900709 -291.005004)
			(xy 281.848735 -291.005004) (xy 281.7974 -290.996874) (xy 281.74797 -290.980813) (xy 281.70166 -290.957217)
			(xy 281.659612 -290.926667) (xy 281.622861 -290.889916) (xy 281.592311 -290.847868) (xy 281.568715 -290.801558)
			(xy 281.552654 -290.752128) (xy 281.544524 -290.700793) (xy 281.25496 -290.700793) (xy 281.24683 -290.752128)
			(xy 281.230769 -290.801558) (xy 281.207173 -290.847868) (xy 281.176623 -290.889916) (xy 281.139872 -290.926667)
			(xy 281.097824 -290.957217) (xy 281.051514 -290.980813) (xy 281.002084 -290.996874) (xy 280.950749 -291.005004)
			(xy 280.898775 -291.005004) (xy 280.84744 -290.996874) (xy 280.79801 -290.980813) (xy 280.7517 -290.957217)
			(xy 280.709652 -290.926667) (xy 280.672901 -290.889916) (xy 280.642351 -290.847868) (xy 280.618755 -290.801558)
			(xy 280.602694 -290.752128) (xy 280.594564 -290.700793) (xy 280.305 -290.700793) (xy 280.29687 -290.752128)
			(xy 280.280809 -290.801558) (xy 280.257213 -290.847868) (xy 280.226663 -290.889916) (xy 280.189912 -290.926667)
			(xy 280.147864 -290.957217) (xy 280.101554 -290.980813) (xy 280.052124 -290.996874) (xy 280.000789 -291.005004)
			(xy 279.948815 -291.005004) (xy 279.89748 -290.996874) (xy 279.84805 -290.980813) (xy 279.80174 -290.957217)
			(xy 279.759692 -290.926667) (xy 279.722941 -290.889916) (xy 279.692391 -290.847868) (xy 279.668795 -290.801558)
			(xy 279.652734 -290.752128) (xy 279.644604 -290.700793) (xy 278.40508 -290.700793) (xy 278.39695 -290.752128)
			(xy 278.380889 -290.801558) (xy 278.357293 -290.847868) (xy 278.326743 -290.889916) (xy 278.289992 -290.926667)
			(xy 278.247944 -290.957217) (xy 278.201634 -290.980813) (xy 278.152204 -290.996874) (xy 278.100869 -291.005004)
			(xy 278.048895 -291.005004) (xy 277.99756 -290.996874) (xy 277.94813 -290.980813) (xy 277.90182 -290.957217)
			(xy 277.859772 -290.926667) (xy 277.823021 -290.889916) (xy 277.792471 -290.847868) (xy 277.768875 -290.801558)
			(xy 277.752814 -290.752128) (xy 277.744684 -290.700793) (xy 276.504906 -290.700793) (xy 276.496776 -290.752128)
			(xy 276.480715 -290.801558) (xy 276.457119 -290.847868) (xy 276.426569 -290.889916) (xy 276.389818 -290.926667)
			(xy 276.34777 -290.957217) (xy 276.30146 -290.980813) (xy 276.25203 -290.996874) (xy 276.200695 -291.005004)
			(xy 276.148721 -291.005004) (xy 276.097386 -290.996874) (xy 276.047956 -290.980813) (xy 276.001646 -290.957217)
			(xy 275.959598 -290.926667) (xy 275.922847 -290.889916) (xy 275.892297 -290.847868) (xy 275.868701 -290.801558)
			(xy 275.85264 -290.752128) (xy 275.84451 -290.700793) (xy 275.553822 -290.700793) (xy 275.551668 -290.727625)
			(xy 275.539058 -290.779096) (xy 275.518401 -290.827897) (xy 275.490224 -290.872779) (xy 275.45525 -290.912593)
			(xy 275.414375 -290.946319) (xy 275.368643 -290.973094) (xy 275.344128 -290.983162) (xy 275.336762 -290.985956)
			(xy 275.325078 -290.995354) (xy 275.320506 -291.001958) (xy 275.3164 -291.008412) (xy 275.311875 -291.023016)
			(xy 275.311616 -291.03066) (xy 275.311616 -291.268912) (xy 275.311876 -291.276556) (xy 275.316402 -291.291159)
			(xy 275.320506 -291.297614) (xy 275.325078 -291.304218) (xy 275.336762 -291.313616) (xy 275.344128 -291.31641)
			(xy 275.36865 -291.326468) (xy 275.414388 -291.353245) (xy 275.455269 -291.386973) (xy 275.490248 -291.42679)
			(xy 275.518429 -291.471676) (xy 275.53909 -291.520482) (xy 275.551704 -291.571959) (xy 275.555945 -291.624788)
			(xy 275.553863 -291.650753) (xy 275.84451 -291.650753) (xy 275.84451 -291.598779) (xy 275.85264 -291.547444)
			(xy 275.868701 -291.498014) (xy 275.892297 -291.451704) (xy 275.922847 -291.409656) (xy 275.959598 -291.372905)
			(xy 276.001646 -291.342355) (xy 276.047956 -291.318759) (xy 276.097386 -291.302698) (xy 276.148721 -291.294568)
			(xy 276.200695 -291.294568) (xy 276.25203 -291.302698) (xy 276.30146 -291.318759) (xy 276.34777 -291.342355)
			(xy 276.389818 -291.372905) (xy 276.426569 -291.409656) (xy 276.457119 -291.451704) (xy 276.480715 -291.498014)
			(xy 276.496776 -291.547444) (xy 276.504906 -291.598779) (xy 276.505416 -291.624766) (xy 276.504906 -291.650753)
			(xy 277.744684 -291.650753) (xy 277.744684 -291.598779) (xy 277.752814 -291.547444) (xy 277.768875 -291.498014)
			(xy 277.792471 -291.451704) (xy 277.823021 -291.409656) (xy 277.859772 -291.372905) (xy 277.90182 -291.342355)
			(xy 277.94813 -291.318759) (xy 277.99756 -291.302698) (xy 278.048895 -291.294568) (xy 278.100869 -291.294568)
			(xy 278.152204 -291.302698) (xy 278.201634 -291.318759) (xy 278.247944 -291.342355) (xy 278.289992 -291.372905)
			(xy 278.326743 -291.409656) (xy 278.357293 -291.451704) (xy 278.380889 -291.498014) (xy 278.39695 -291.547444)
			(xy 278.40508 -291.598779) (xy 278.40559 -291.624766) (xy 278.40508 -291.650753) (xy 278.694644 -291.650753)
			(xy 278.694644 -291.598779) (xy 278.702774 -291.547444) (xy 278.718835 -291.498014) (xy 278.742431 -291.451704)
			(xy 278.772981 -291.409656) (xy 278.809732 -291.372905) (xy 278.85178 -291.342355) (xy 278.89809 -291.318759)
			(xy 278.94752 -291.302698) (xy 278.998855 -291.294568) (xy 279.050829 -291.294568) (xy 279.102164 -291.302698)
			(xy 279.151594 -291.318759) (xy 279.197904 -291.342355) (xy 279.239952 -291.372905) (xy 279.276703 -291.409656)
			(xy 279.307253 -291.451704) (xy 279.330849 -291.498014) (xy 279.34691 -291.547444) (xy 279.35504 -291.598779)
			(xy 279.35555 -291.624766) (xy 279.35504 -291.650753) (xy 279.644604 -291.650753) (xy 279.644604 -291.598779)
			(xy 279.652734 -291.547444) (xy 279.668795 -291.498014) (xy 279.692391 -291.451704) (xy 279.722941 -291.409656)
			(xy 279.759692 -291.372905) (xy 279.80174 -291.342355) (xy 279.84805 -291.318759) (xy 279.89748 -291.302698)
			(xy 279.948815 -291.294568) (xy 280.000789 -291.294568) (xy 280.052124 -291.302698) (xy 280.101554 -291.318759)
			(xy 280.147864 -291.342355) (xy 280.189912 -291.372905) (xy 280.226663 -291.409656) (xy 280.257213 -291.451704)
			(xy 280.280809 -291.498014) (xy 280.29687 -291.547444) (xy 280.305 -291.598779) (xy 280.30551 -291.624766)
			(xy 280.305 -291.650753) (xy 280.594564 -291.650753) (xy 280.594564 -291.598779) (xy 280.602694 -291.547444)
			(xy 280.618755 -291.498014) (xy 280.642351 -291.451704) (xy 280.672901 -291.409656) (xy 280.709652 -291.372905)
			(xy 280.7517 -291.342355) (xy 280.79801 -291.318759) (xy 280.84744 -291.302698) (xy 280.898775 -291.294568)
			(xy 280.950749 -291.294568) (xy 281.002084 -291.302698) (xy 281.051514 -291.318759) (xy 281.097824 -291.342355)
			(xy 281.139872 -291.372905) (xy 281.176623 -291.409656) (xy 281.207173 -291.451704) (xy 281.230769 -291.498014)
			(xy 281.24683 -291.547444) (xy 281.25496 -291.598779) (xy 281.25547 -291.624766) (xy 281.25496 -291.650753)
			(xy 281.544524 -291.650753) (xy 281.544524 -291.598779) (xy 281.552654 -291.547444) (xy 281.568715 -291.498014)
			(xy 281.592311 -291.451704) (xy 281.622861 -291.409656) (xy 281.659612 -291.372905) (xy 281.70166 -291.342355)
			(xy 281.74797 -291.318759) (xy 281.7974 -291.302698) (xy 281.848735 -291.294568) (xy 281.900709 -291.294568)
			(xy 281.952044 -291.302698) (xy 282.001474 -291.318759) (xy 282.047784 -291.342355) (xy 282.089832 -291.372905)
			(xy 282.126583 -291.409656) (xy 282.157133 -291.451704) (xy 282.180729 -291.498014) (xy 282.19679 -291.547444)
			(xy 282.20492 -291.598779) (xy 282.20543 -291.624766) (xy 282.20492 -291.650753) (xy 282.494738 -291.650753)
			(xy 282.494738 -291.598779) (xy 282.502868 -291.547444) (xy 282.518929 -291.498014) (xy 282.542525 -291.451704)
			(xy 282.573075 -291.409656) (xy 282.609826 -291.372905) (xy 282.651874 -291.342355) (xy 282.698184 -291.318759)
			(xy 282.747614 -291.302698) (xy 282.798949 -291.294568) (xy 282.850923 -291.294568) (xy 282.902258 -291.302698)
			(xy 282.951688 -291.318759) (xy 282.997998 -291.342355) (xy 283.040046 -291.372905) (xy 283.076797 -291.409656)
			(xy 283.107347 -291.451704) (xy 283.130943 -291.498014) (xy 283.147004 -291.547444) (xy 283.155134 -291.598779)
			(xy 283.155644 -291.624766) (xy 283.155134 -291.650753) (xy 283.444698 -291.650753) (xy 283.444698 -291.598779)
			(xy 283.452828 -291.547444) (xy 283.468889 -291.498014) (xy 283.492485 -291.451704) (xy 283.523035 -291.409656)
			(xy 283.559786 -291.372905) (xy 283.601834 -291.342355) (xy 283.648144 -291.318759) (xy 283.697574 -291.302698)
			(xy 283.748909 -291.294568) (xy 283.800883 -291.294568) (xy 283.852218 -291.302698) (xy 283.901648 -291.318759)
			(xy 283.947958 -291.342355) (xy 283.990006 -291.372905) (xy 284.026757 -291.409656) (xy 284.057307 -291.451704)
			(xy 284.080903 -291.498014) (xy 284.096964 -291.547444) (xy 284.105094 -291.598779) (xy 284.105604 -291.624766)
			(xy 284.105094 -291.650753) (xy 284.394658 -291.650753) (xy 284.394658 -291.598779) (xy 284.402788 -291.547444)
			(xy 284.418849 -291.498014) (xy 284.442445 -291.451704) (xy 284.472995 -291.409656) (xy 284.509746 -291.372905)
			(xy 284.551794 -291.342355) (xy 284.598104 -291.318759) (xy 284.647534 -291.302698) (xy 284.698869 -291.294568)
			(xy 284.750843 -291.294568) (xy 284.802178 -291.302698) (xy 284.851608 -291.318759) (xy 284.897918 -291.342355)
			(xy 284.939966 -291.372905) (xy 284.976717 -291.409656) (xy 285.007267 -291.451704) (xy 285.030863 -291.498014)
			(xy 285.046924 -291.547444) (xy 285.055054 -291.598779) (xy 285.055564 -291.624766) (xy 285.055054 -291.650753)
			(xy 285.344618 -291.650753) (xy 285.344618 -291.598779) (xy 285.352748 -291.547444) (xy 285.368809 -291.498014)
			(xy 285.392405 -291.451704) (xy 285.422955 -291.409656) (xy 285.459706 -291.372905) (xy 285.501754 -291.342355)
			(xy 285.548064 -291.318759) (xy 285.597494 -291.302698) (xy 285.648829 -291.294568) (xy 285.700803 -291.294568)
			(xy 285.752138 -291.302698) (xy 285.801568 -291.318759) (xy 285.847878 -291.342355) (xy 285.889926 -291.372905)
			(xy 285.926677 -291.409656) (xy 285.957227 -291.451704) (xy 285.980823 -291.498014) (xy 285.996884 -291.547444)
			(xy 286.005014 -291.598779) (xy 286.005524 -291.624766) (xy 286.005014 -291.650753) (xy 286.294578 -291.650753)
			(xy 286.294578 -291.598779) (xy 286.302708 -291.547444) (xy 286.318769 -291.498014) (xy 286.342365 -291.451704)
			(xy 286.372915 -291.409656) (xy 286.409666 -291.372905) (xy 286.451714 -291.342355) (xy 286.498024 -291.318759)
			(xy 286.547454 -291.302698) (xy 286.598789 -291.294568) (xy 286.650763 -291.294568) (xy 286.702098 -291.302698)
			(xy 286.751528 -291.318759) (xy 286.797838 -291.342355) (xy 286.839886 -291.372905) (xy 286.876637 -291.409656)
			(xy 286.907187 -291.451704) (xy 286.930783 -291.498014) (xy 286.946844 -291.547444) (xy 286.954974 -291.598779)
			(xy 286.955484 -291.624766) (xy 286.954974 -291.650753) (xy 287.244538 -291.650753) (xy 287.244538 -291.598779)
			(xy 287.252668 -291.547444) (xy 287.268729 -291.498014) (xy 287.292325 -291.451704) (xy 287.322875 -291.409656)
			(xy 287.359626 -291.372905) (xy 287.401674 -291.342355) (xy 287.447984 -291.318759) (xy 287.497414 -291.302698)
			(xy 287.548749 -291.294568) (xy 287.600723 -291.294568) (xy 287.652058 -291.302698) (xy 287.701488 -291.318759)
			(xy 287.747798 -291.342355) (xy 287.789846 -291.372905) (xy 287.826597 -291.409656) (xy 287.857147 -291.451704)
			(xy 287.880743 -291.498014) (xy 287.896804 -291.547444) (xy 287.904934 -291.598779) (xy 287.905444 -291.624766)
			(xy 287.904934 -291.650753) (xy 288.194498 -291.650753) (xy 288.194498 -291.598779) (xy 288.202628 -291.547444)
			(xy 288.218689 -291.498014) (xy 288.242285 -291.451704) (xy 288.272835 -291.409656) (xy 288.309586 -291.372905)
			(xy 288.351634 -291.342355) (xy 288.397944 -291.318759) (xy 288.447374 -291.302698) (xy 288.498709 -291.294568)
			(xy 288.550683 -291.294568) (xy 288.602018 -291.302698) (xy 288.651448 -291.318759) (xy 288.697758 -291.342355)
			(xy 288.739806 -291.372905) (xy 288.776557 -291.409656) (xy 288.807107 -291.451704) (xy 288.830703 -291.498014)
			(xy 288.846764 -291.547444) (xy 288.854894 -291.598779) (xy 288.855404 -291.624766) (xy 288.854894 -291.650753)
			(xy 289.144712 -291.650753) (xy 289.144712 -291.598779) (xy 289.152842 -291.547444) (xy 289.168903 -291.498014)
			(xy 289.192499 -291.451704) (xy 289.223049 -291.409656) (xy 289.2598 -291.372905) (xy 289.301848 -291.342355)
			(xy 289.348158 -291.318759) (xy 289.397588 -291.302698) (xy 289.448923 -291.294568) (xy 289.500897 -291.294568)
			(xy 289.552232 -291.302698) (xy 289.601662 -291.318759) (xy 289.647972 -291.342355) (xy 289.69002 -291.372905)
			(xy 289.726771 -291.409656) (xy 289.757321 -291.451704) (xy 289.780917 -291.498014) (xy 289.796978 -291.547444)
			(xy 289.805108 -291.598779) (xy 289.805618 -291.624766) (xy 289.805108 -291.650753) (xy 290.094672 -291.650753)
			(xy 290.094672 -291.598779) (xy 290.102802 -291.547444) (xy 290.118863 -291.498014) (xy 290.142459 -291.451704)
			(xy 290.173009 -291.409656) (xy 290.20976 -291.372905) (xy 290.251808 -291.342355) (xy 290.298118 -291.318759)
			(xy 290.347548 -291.302698) (xy 290.398883 -291.294568) (xy 290.450857 -291.294568) (xy 290.502192 -291.302698)
			(xy 290.551622 -291.318759) (xy 290.597932 -291.342355) (xy 290.63998 -291.372905) (xy 290.676731 -291.409656)
			(xy 290.707281 -291.451704) (xy 290.730877 -291.498014) (xy 290.746938 -291.547444) (xy 290.755068 -291.598779)
			(xy 290.755578 -291.624766) (xy 290.755068 -291.650753) (xy 291.994592 -291.650753) (xy 291.994592 -291.598779)
			(xy 292.002722 -291.547444) (xy 292.018783 -291.498014) (xy 292.042379 -291.451704) (xy 292.072929 -291.409656)
			(xy 292.10968 -291.372905) (xy 292.151728 -291.342355) (xy 292.198038 -291.318759) (xy 292.247468 -291.302698)
			(xy 292.298803 -291.294568) (xy 292.350777 -291.294568) (xy 292.402112 -291.302698) (xy 292.451542 -291.318759)
			(xy 292.497852 -291.342355) (xy 292.5399 -291.372905) (xy 292.576651 -291.409656) (xy 292.607201 -291.451704)
			(xy 292.630797 -291.498014) (xy 292.646858 -291.547444) (xy 292.654988 -291.598779) (xy 292.655498 -291.624766)
			(xy 292.654988 -291.650753) (xy 292.944552 -291.650753) (xy 292.944552 -291.598779) (xy 292.952682 -291.547444)
			(xy 292.968743 -291.498014) (xy 292.992339 -291.451704) (xy 293.022889 -291.409656) (xy 293.05964 -291.372905)
			(xy 293.101688 -291.342355) (xy 293.147998 -291.318759) (xy 293.197428 -291.302698) (xy 293.248763 -291.294568)
			(xy 293.300737 -291.294568) (xy 293.352072 -291.302698) (xy 293.401502 -291.318759) (xy 293.447812 -291.342355)
			(xy 293.48986 -291.372905) (xy 293.526611 -291.409656) (xy 293.557161 -291.451704) (xy 293.580757 -291.498014)
			(xy 293.596818 -291.547444) (xy 293.604948 -291.598779) (xy 293.605458 -291.624766) (xy 293.604948 -291.650753)
			(xy 293.894512 -291.650753) (xy 293.894512 -291.598779) (xy 293.902642 -291.547444) (xy 293.918703 -291.498014)
			(xy 293.942299 -291.451704) (xy 293.972849 -291.409656) (xy 294.0096 -291.372905) (xy 294.051648 -291.342355)
			(xy 294.097958 -291.318759) (xy 294.147388 -291.302698) (xy 294.198723 -291.294568) (xy 294.250697 -291.294568)
			(xy 294.302032 -291.302698) (xy 294.351462 -291.318759) (xy 294.397772 -291.342355) (xy 294.43982 -291.372905)
			(xy 294.476571 -291.409656) (xy 294.507121 -291.451704) (xy 294.530717 -291.498014) (xy 294.546778 -291.547444)
			(xy 294.554908 -291.598779) (xy 294.555418 -291.624766) (xy 294.554908 -291.650753) (xy 294.844726 -291.650753)
			(xy 294.844726 -291.598779) (xy 294.852856 -291.547444) (xy 294.868917 -291.498014) (xy 294.892513 -291.451704)
			(xy 294.923063 -291.409656) (xy 294.959814 -291.372905) (xy 295.001862 -291.342355) (xy 295.048172 -291.318759)
			(xy 295.097602 -291.302698) (xy 295.148937 -291.294568) (xy 295.200911 -291.294568) (xy 295.252246 -291.302698)
			(xy 295.301676 -291.318759) (xy 295.347986 -291.342355) (xy 295.390034 -291.372905) (xy 295.426785 -291.409656)
			(xy 295.457335 -291.451704) (xy 295.480931 -291.498014) (xy 295.496992 -291.547444) (xy 295.505122 -291.598779)
			(xy 295.505632 -291.624766) (xy 295.505122 -291.650753) (xy 295.794686 -291.650753) (xy 295.794686 -291.598779)
			(xy 295.802816 -291.547444) (xy 295.818877 -291.498014) (xy 295.842473 -291.451704) (xy 295.873023 -291.409656)
			(xy 295.909774 -291.372905) (xy 295.951822 -291.342355) (xy 295.998132 -291.318759) (xy 296.047562 -291.302698)
			(xy 296.098897 -291.294568) (xy 296.150871 -291.294568) (xy 296.202206 -291.302698) (xy 296.251636 -291.318759)
			(xy 296.297946 -291.342355) (xy 296.339994 -291.372905) (xy 296.376745 -291.409656) (xy 296.407295 -291.451704)
			(xy 296.430891 -291.498014) (xy 296.446952 -291.547444) (xy 296.455082 -291.598779) (xy 296.455592 -291.624766)
			(xy 296.455082 -291.650753) (xy 296.744646 -291.650753) (xy 296.744646 -291.598779) (xy 296.752776 -291.547444)
			(xy 296.768837 -291.498014) (xy 296.792433 -291.451704) (xy 296.822983 -291.409656) (xy 296.859734 -291.372905)
			(xy 296.901782 -291.342355) (xy 296.948092 -291.318759) (xy 296.997522 -291.302698) (xy 297.048857 -291.294568)
			(xy 297.100831 -291.294568) (xy 297.152166 -291.302698) (xy 297.201596 -291.318759) (xy 297.247906 -291.342355)
			(xy 297.289954 -291.372905) (xy 297.326705 -291.409656) (xy 297.357255 -291.451704) (xy 297.380851 -291.498014)
			(xy 297.396912 -291.547444) (xy 297.405042 -291.598779) (xy 297.405552 -291.624766) (xy 297.405042 -291.650753)
			(xy 297.694606 -291.650753) (xy 297.694606 -291.598779) (xy 297.702736 -291.547444) (xy 297.718797 -291.498014)
			(xy 297.742393 -291.451704) (xy 297.772943 -291.409656) (xy 297.809694 -291.372905) (xy 297.851742 -291.342355)
			(xy 297.898052 -291.318759) (xy 297.947482 -291.302698) (xy 297.998817 -291.294568) (xy 298.050791 -291.294568)
			(xy 298.102126 -291.302698) (xy 298.151556 -291.318759) (xy 298.197866 -291.342355) (xy 298.239914 -291.372905)
			(xy 298.276665 -291.409656) (xy 298.307215 -291.451704) (xy 298.330811 -291.498014) (xy 298.346872 -291.547444)
			(xy 298.355002 -291.598779) (xy 298.355512 -291.624766) (xy 298.355002 -291.650753) (xy 298.644566 -291.650753)
			(xy 298.644566 -291.598779) (xy 298.652696 -291.547444) (xy 298.668757 -291.498014) (xy 298.692353 -291.451704)
			(xy 298.722903 -291.409656) (xy 298.759654 -291.372905) (xy 298.801702 -291.342355) (xy 298.848012 -291.318759)
			(xy 298.897442 -291.302698) (xy 298.948777 -291.294568) (xy 299.000751 -291.294568) (xy 299.052086 -291.302698)
			(xy 299.101516 -291.318759) (xy 299.147826 -291.342355) (xy 299.189874 -291.372905) (xy 299.226625 -291.409656)
			(xy 299.257175 -291.451704) (xy 299.280771 -291.498014) (xy 299.296832 -291.547444) (xy 299.304962 -291.598779)
			(xy 299.305472 -291.624766) (xy 299.304962 -291.650753) (xy 299.594526 -291.650753) (xy 299.594526 -291.598779)
			(xy 299.602656 -291.547444) (xy 299.618717 -291.498014) (xy 299.642313 -291.451704) (xy 299.672863 -291.409656)
			(xy 299.709614 -291.372905) (xy 299.751662 -291.342355) (xy 299.797972 -291.318759) (xy 299.847402 -291.302698)
			(xy 299.898737 -291.294568) (xy 299.950711 -291.294568) (xy 300.002046 -291.302698) (xy 300.051476 -291.318759)
			(xy 300.097786 -291.342355) (xy 300.139834 -291.372905) (xy 300.176585 -291.409656) (xy 300.207135 -291.451704)
			(xy 300.230731 -291.498014) (xy 300.246792 -291.547444) (xy 300.254922 -291.598779) (xy 300.255432 -291.624766)
			(xy 300.254922 -291.650753) (xy 300.544486 -291.650753) (xy 300.544486 -291.598779) (xy 300.552616 -291.547444)
			(xy 300.568677 -291.498014) (xy 300.592273 -291.451704) (xy 300.622823 -291.409656) (xy 300.659574 -291.372905)
			(xy 300.701622 -291.342355) (xy 300.747932 -291.318759) (xy 300.797362 -291.302698) (xy 300.848697 -291.294568)
			(xy 300.900671 -291.294568) (xy 300.952006 -291.302698) (xy 301.001436 -291.318759) (xy 301.047746 -291.342355)
			(xy 301.089794 -291.372905) (xy 301.126545 -291.409656) (xy 301.157095 -291.451704) (xy 301.180691 -291.498014)
			(xy 301.196752 -291.547444) (xy 301.204882 -291.598779) (xy 301.205392 -291.624766) (xy 301.204882 -291.650753)
			(xy 301.4947 -291.650753) (xy 301.4947 -291.598779) (xy 301.50283 -291.547444) (xy 301.518891 -291.498014)
			(xy 301.542487 -291.451704) (xy 301.573037 -291.409656) (xy 301.609788 -291.372905) (xy 301.651836 -291.342355)
			(xy 301.698146 -291.318759) (xy 301.747576 -291.302698) (xy 301.798911 -291.294568) (xy 301.850885 -291.294568)
			(xy 301.90222 -291.302698) (xy 301.95165 -291.318759) (xy 301.99796 -291.342355) (xy 302.040008 -291.372905)
			(xy 302.076759 -291.409656) (xy 302.107309 -291.451704) (xy 302.130905 -291.498014) (xy 302.146966 -291.547444)
			(xy 302.155096 -291.598779) (xy 302.155606 -291.624766) (xy 302.155096 -291.650753) (xy 302.146966 -291.702088)
			(xy 302.130905 -291.751518) (xy 302.107309 -291.797828) (xy 302.076759 -291.839876) (xy 302.040008 -291.876627)
			(xy 301.99796 -291.907177) (xy 301.95165 -291.930773) (xy 301.90222 -291.946834) (xy 301.850885 -291.954964)
			(xy 301.798911 -291.954964) (xy 301.747576 -291.946834) (xy 301.698146 -291.930773) (xy 301.651836 -291.907177)
			(xy 301.609788 -291.876627) (xy 301.573037 -291.839876) (xy 301.542487 -291.797828) (xy 301.518891 -291.751518)
			(xy 301.50283 -291.702088) (xy 301.4947 -291.650753) (xy 301.204882 -291.650753) (xy 301.196752 -291.702088)
			(xy 301.180691 -291.751518) (xy 301.157095 -291.797828) (xy 301.126545 -291.839876) (xy 301.089794 -291.876627)
			(xy 301.047746 -291.907177) (xy 301.001436 -291.930773) (xy 300.952006 -291.946834) (xy 300.900671 -291.954964)
			(xy 300.848697 -291.954964) (xy 300.797362 -291.946834) (xy 300.747932 -291.930773) (xy 300.701622 -291.907177)
			(xy 300.659574 -291.876627) (xy 300.622823 -291.839876) (xy 300.592273 -291.797828) (xy 300.568677 -291.751518)
			(xy 300.552616 -291.702088) (xy 300.544486 -291.650753) (xy 300.254922 -291.650753) (xy 300.246792 -291.702088)
			(xy 300.230731 -291.751518) (xy 300.207135 -291.797828) (xy 300.176585 -291.839876) (xy 300.139834 -291.876627)
			(xy 300.097786 -291.907177) (xy 300.051476 -291.930773) (xy 300.002046 -291.946834) (xy 299.950711 -291.954964)
			(xy 299.898737 -291.954964) (xy 299.847402 -291.946834) (xy 299.797972 -291.930773) (xy 299.751662 -291.907177)
			(xy 299.709614 -291.876627) (xy 299.672863 -291.839876) (xy 299.642313 -291.797828) (xy 299.618717 -291.751518)
			(xy 299.602656 -291.702088) (xy 299.594526 -291.650753) (xy 299.304962 -291.650753) (xy 299.296832 -291.702088)
			(xy 299.280771 -291.751518) (xy 299.257175 -291.797828) (xy 299.226625 -291.839876) (xy 299.189874 -291.876627)
			(xy 299.147826 -291.907177) (xy 299.101516 -291.930773) (xy 299.052086 -291.946834) (xy 299.000751 -291.954964)
			(xy 298.948777 -291.954964) (xy 298.897442 -291.946834) (xy 298.848012 -291.930773) (xy 298.801702 -291.907177)
			(xy 298.759654 -291.876627) (xy 298.722903 -291.839876) (xy 298.692353 -291.797828) (xy 298.668757 -291.751518)
			(xy 298.652696 -291.702088) (xy 298.644566 -291.650753) (xy 298.355002 -291.650753) (xy 298.346872 -291.702088)
			(xy 298.330811 -291.751518) (xy 298.307215 -291.797828) (xy 298.276665 -291.839876) (xy 298.239914 -291.876627)
			(xy 298.197866 -291.907177) (xy 298.151556 -291.930773) (xy 298.102126 -291.946834) (xy 298.050791 -291.954964)
			(xy 297.998817 -291.954964) (xy 297.947482 -291.946834) (xy 297.898052 -291.930773) (xy 297.851742 -291.907177)
			(xy 297.809694 -291.876627) (xy 297.772943 -291.839876) (xy 297.742393 -291.797828) (xy 297.718797 -291.751518)
			(xy 297.702736 -291.702088) (xy 297.694606 -291.650753) (xy 297.405042 -291.650753) (xy 297.396912 -291.702088)
			(xy 297.380851 -291.751518) (xy 297.357255 -291.797828) (xy 297.326705 -291.839876) (xy 297.289954 -291.876627)
			(xy 297.247906 -291.907177) (xy 297.201596 -291.930773) (xy 297.152166 -291.946834) (xy 297.100831 -291.954964)
			(xy 297.048857 -291.954964) (xy 296.997522 -291.946834) (xy 296.948092 -291.930773) (xy 296.901782 -291.907177)
			(xy 296.859734 -291.876627) (xy 296.822983 -291.839876) (xy 296.792433 -291.797828) (xy 296.768837 -291.751518)
			(xy 296.752776 -291.702088) (xy 296.744646 -291.650753) (xy 296.455082 -291.650753) (xy 296.446952 -291.702088)
			(xy 296.430891 -291.751518) (xy 296.407295 -291.797828) (xy 296.376745 -291.839876) (xy 296.339994 -291.876627)
			(xy 296.297946 -291.907177) (xy 296.251636 -291.930773) (xy 296.202206 -291.946834) (xy 296.150871 -291.954964)
			(xy 296.098897 -291.954964) (xy 296.047562 -291.946834) (xy 295.998132 -291.930773) (xy 295.951822 -291.907177)
			(xy 295.909774 -291.876627) (xy 295.873023 -291.839876) (xy 295.842473 -291.797828) (xy 295.818877 -291.751518)
			(xy 295.802816 -291.702088) (xy 295.794686 -291.650753) (xy 295.505122 -291.650753) (xy 295.496992 -291.702088)
			(xy 295.480931 -291.751518) (xy 295.457335 -291.797828) (xy 295.426785 -291.839876) (xy 295.390034 -291.876627)
			(xy 295.347986 -291.907177) (xy 295.301676 -291.930773) (xy 295.252246 -291.946834) (xy 295.200911 -291.954964)
			(xy 295.148937 -291.954964) (xy 295.097602 -291.946834) (xy 295.048172 -291.930773) (xy 295.001862 -291.907177)
			(xy 294.959814 -291.876627) (xy 294.923063 -291.839876) (xy 294.892513 -291.797828) (xy 294.868917 -291.751518)
			(xy 294.852856 -291.702088) (xy 294.844726 -291.650753) (xy 294.554908 -291.650753) (xy 294.546778 -291.702088)
			(xy 294.530717 -291.751518) (xy 294.507121 -291.797828) (xy 294.476571 -291.839876) (xy 294.43982 -291.876627)
			(xy 294.397772 -291.907177) (xy 294.351462 -291.930773) (xy 294.302032 -291.946834) (xy 294.250697 -291.954964)
			(xy 294.198723 -291.954964) (xy 294.147388 -291.946834) (xy 294.097958 -291.930773) (xy 294.051648 -291.907177)
			(xy 294.0096 -291.876627) (xy 293.972849 -291.839876) (xy 293.942299 -291.797828) (xy 293.918703 -291.751518)
			(xy 293.902642 -291.702088) (xy 293.894512 -291.650753) (xy 293.604948 -291.650753) (xy 293.596818 -291.702088)
			(xy 293.580757 -291.751518) (xy 293.557161 -291.797828) (xy 293.526611 -291.839876) (xy 293.48986 -291.876627)
			(xy 293.447812 -291.907177) (xy 293.401502 -291.930773) (xy 293.352072 -291.946834) (xy 293.300737 -291.954964)
			(xy 293.248763 -291.954964) (xy 293.197428 -291.946834) (xy 293.147998 -291.930773) (xy 293.101688 -291.907177)
			(xy 293.05964 -291.876627) (xy 293.022889 -291.839876) (xy 292.992339 -291.797828) (xy 292.968743 -291.751518)
			(xy 292.952682 -291.702088) (xy 292.944552 -291.650753) (xy 292.654988 -291.650753) (xy 292.646858 -291.702088)
			(xy 292.630797 -291.751518) (xy 292.607201 -291.797828) (xy 292.576651 -291.839876) (xy 292.5399 -291.876627)
			(xy 292.497852 -291.907177) (xy 292.451542 -291.930773) (xy 292.402112 -291.946834) (xy 292.350777 -291.954964)
			(xy 292.298803 -291.954964) (xy 292.247468 -291.946834) (xy 292.198038 -291.930773) (xy 292.151728 -291.907177)
			(xy 292.10968 -291.876627) (xy 292.072929 -291.839876) (xy 292.042379 -291.797828) (xy 292.018783 -291.751518)
			(xy 292.002722 -291.702088) (xy 291.994592 -291.650753) (xy 290.755068 -291.650753) (xy 290.746938 -291.702088)
			(xy 290.730877 -291.751518) (xy 290.707281 -291.797828) (xy 290.676731 -291.839876) (xy 290.63998 -291.876627)
			(xy 290.597932 -291.907177) (xy 290.551622 -291.930773) (xy 290.502192 -291.946834) (xy 290.450857 -291.954964)
			(xy 290.398883 -291.954964) (xy 290.347548 -291.946834) (xy 290.298118 -291.930773) (xy 290.251808 -291.907177)
			(xy 290.20976 -291.876627) (xy 290.173009 -291.839876) (xy 290.142459 -291.797828) (xy 290.118863 -291.751518)
			(xy 290.102802 -291.702088) (xy 290.094672 -291.650753) (xy 289.805108 -291.650753) (xy 289.796978 -291.702088)
			(xy 289.780917 -291.751518) (xy 289.757321 -291.797828) (xy 289.726771 -291.839876) (xy 289.69002 -291.876627)
			(xy 289.647972 -291.907177) (xy 289.601662 -291.930773) (xy 289.552232 -291.946834) (xy 289.500897 -291.954964)
			(xy 289.448923 -291.954964) (xy 289.397588 -291.946834) (xy 289.348158 -291.930773) (xy 289.301848 -291.907177)
			(xy 289.2598 -291.876627) (xy 289.223049 -291.839876) (xy 289.192499 -291.797828) (xy 289.168903 -291.751518)
			(xy 289.152842 -291.702088) (xy 289.144712 -291.650753) (xy 288.854894 -291.650753) (xy 288.846764 -291.702088)
			(xy 288.830703 -291.751518) (xy 288.807107 -291.797828) (xy 288.776557 -291.839876) (xy 288.739806 -291.876627)
			(xy 288.697758 -291.907177) (xy 288.651448 -291.930773) (xy 288.602018 -291.946834) (xy 288.550683 -291.954964)
			(xy 288.498709 -291.954964) (xy 288.447374 -291.946834) (xy 288.397944 -291.930773) (xy 288.351634 -291.907177)
			(xy 288.309586 -291.876627) (xy 288.272835 -291.839876) (xy 288.242285 -291.797828) (xy 288.218689 -291.751518)
			(xy 288.202628 -291.702088) (xy 288.194498 -291.650753) (xy 287.904934 -291.650753) (xy 287.896804 -291.702088)
			(xy 287.880743 -291.751518) (xy 287.857147 -291.797828) (xy 287.826597 -291.839876) (xy 287.789846 -291.876627)
			(xy 287.747798 -291.907177) (xy 287.701488 -291.930773) (xy 287.652058 -291.946834) (xy 287.600723 -291.954964)
			(xy 287.548749 -291.954964) (xy 287.497414 -291.946834) (xy 287.447984 -291.930773) (xy 287.401674 -291.907177)
			(xy 287.359626 -291.876627) (xy 287.322875 -291.839876) (xy 287.292325 -291.797828) (xy 287.268729 -291.751518)
			(xy 287.252668 -291.702088) (xy 287.244538 -291.650753) (xy 286.954974 -291.650753) (xy 286.946844 -291.702088)
			(xy 286.930783 -291.751518) (xy 286.907187 -291.797828) (xy 286.876637 -291.839876) (xy 286.839886 -291.876627)
			(xy 286.797838 -291.907177) (xy 286.751528 -291.930773) (xy 286.702098 -291.946834) (xy 286.650763 -291.954964)
			(xy 286.598789 -291.954964) (xy 286.547454 -291.946834) (xy 286.498024 -291.930773) (xy 286.451714 -291.907177)
			(xy 286.409666 -291.876627) (xy 286.372915 -291.839876) (xy 286.342365 -291.797828) (xy 286.318769 -291.751518)
			(xy 286.302708 -291.702088) (xy 286.294578 -291.650753) (xy 286.005014 -291.650753) (xy 285.996884 -291.702088)
			(xy 285.980823 -291.751518) (xy 285.957227 -291.797828) (xy 285.926677 -291.839876) (xy 285.889926 -291.876627)
			(xy 285.847878 -291.907177) (xy 285.801568 -291.930773) (xy 285.752138 -291.946834) (xy 285.700803 -291.954964)
			(xy 285.648829 -291.954964) (xy 285.597494 -291.946834) (xy 285.548064 -291.930773) (xy 285.501754 -291.907177)
			(xy 285.459706 -291.876627) (xy 285.422955 -291.839876) (xy 285.392405 -291.797828) (xy 285.368809 -291.751518)
			(xy 285.352748 -291.702088) (xy 285.344618 -291.650753) (xy 285.055054 -291.650753) (xy 285.046924 -291.702088)
			(xy 285.030863 -291.751518) (xy 285.007267 -291.797828) (xy 284.976717 -291.839876) (xy 284.939966 -291.876627)
			(xy 284.897918 -291.907177) (xy 284.851608 -291.930773) (xy 284.802178 -291.946834) (xy 284.750843 -291.954964)
			(xy 284.698869 -291.954964) (xy 284.647534 -291.946834) (xy 284.598104 -291.930773) (xy 284.551794 -291.907177)
			(xy 284.509746 -291.876627) (xy 284.472995 -291.839876) (xy 284.442445 -291.797828) (xy 284.418849 -291.751518)
			(xy 284.402788 -291.702088) (xy 284.394658 -291.650753) (xy 284.105094 -291.650753) (xy 284.096964 -291.702088)
			(xy 284.080903 -291.751518) (xy 284.057307 -291.797828) (xy 284.026757 -291.839876) (xy 283.990006 -291.876627)
			(xy 283.947958 -291.907177) (xy 283.901648 -291.930773) (xy 283.852218 -291.946834) (xy 283.800883 -291.954964)
			(xy 283.748909 -291.954964) (xy 283.697574 -291.946834) (xy 283.648144 -291.930773) (xy 283.601834 -291.907177)
			(xy 283.559786 -291.876627) (xy 283.523035 -291.839876) (xy 283.492485 -291.797828) (xy 283.468889 -291.751518)
			(xy 283.452828 -291.702088) (xy 283.444698 -291.650753) (xy 283.155134 -291.650753) (xy 283.147004 -291.702088)
			(xy 283.130943 -291.751518) (xy 283.107347 -291.797828) (xy 283.076797 -291.839876) (xy 283.040046 -291.876627)
			(xy 282.997998 -291.907177) (xy 282.951688 -291.930773) (xy 282.902258 -291.946834) (xy 282.850923 -291.954964)
			(xy 282.798949 -291.954964) (xy 282.747614 -291.946834) (xy 282.698184 -291.930773) (xy 282.651874 -291.907177)
			(xy 282.609826 -291.876627) (xy 282.573075 -291.839876) (xy 282.542525 -291.797828) (xy 282.518929 -291.751518)
			(xy 282.502868 -291.702088) (xy 282.494738 -291.650753) (xy 282.20492 -291.650753) (xy 282.19679 -291.702088)
			(xy 282.180729 -291.751518) (xy 282.157133 -291.797828) (xy 282.126583 -291.839876) (xy 282.089832 -291.876627)
			(xy 282.047784 -291.907177) (xy 282.001474 -291.930773) (xy 281.952044 -291.946834) (xy 281.900709 -291.954964)
			(xy 281.848735 -291.954964) (xy 281.7974 -291.946834) (xy 281.74797 -291.930773) (xy 281.70166 -291.907177)
			(xy 281.659612 -291.876627) (xy 281.622861 -291.839876) (xy 281.592311 -291.797828) (xy 281.568715 -291.751518)
			(xy 281.552654 -291.702088) (xy 281.544524 -291.650753) (xy 281.25496 -291.650753) (xy 281.24683 -291.702088)
			(xy 281.230769 -291.751518) (xy 281.207173 -291.797828) (xy 281.176623 -291.839876) (xy 281.139872 -291.876627)
			(xy 281.097824 -291.907177) (xy 281.051514 -291.930773) (xy 281.002084 -291.946834) (xy 280.950749 -291.954964)
			(xy 280.898775 -291.954964) (xy 280.84744 -291.946834) (xy 280.79801 -291.930773) (xy 280.7517 -291.907177)
			(xy 280.709652 -291.876627) (xy 280.672901 -291.839876) (xy 280.642351 -291.797828) (xy 280.618755 -291.751518)
			(xy 280.602694 -291.702088) (xy 280.594564 -291.650753) (xy 280.305 -291.650753) (xy 280.29687 -291.702088)
			(xy 280.280809 -291.751518) (xy 280.257213 -291.797828) (xy 280.226663 -291.839876) (xy 280.189912 -291.876627)
			(xy 280.147864 -291.907177) (xy 280.101554 -291.930773) (xy 280.052124 -291.946834) (xy 280.000789 -291.954964)
			(xy 279.948815 -291.954964) (xy 279.89748 -291.946834) (xy 279.84805 -291.930773) (xy 279.80174 -291.907177)
			(xy 279.759692 -291.876627) (xy 279.722941 -291.839876) (xy 279.692391 -291.797828) (xy 279.668795 -291.751518)
			(xy 279.652734 -291.702088) (xy 279.644604 -291.650753) (xy 279.35504 -291.650753) (xy 279.34691 -291.702088)
			(xy 279.330849 -291.751518) (xy 279.307253 -291.797828) (xy 279.276703 -291.839876) (xy 279.239952 -291.876627)
			(xy 279.197904 -291.907177) (xy 279.151594 -291.930773) (xy 279.102164 -291.946834) (xy 279.050829 -291.954964)
			(xy 278.998855 -291.954964) (xy 278.94752 -291.946834) (xy 278.89809 -291.930773) (xy 278.85178 -291.907177)
			(xy 278.809732 -291.876627) (xy 278.772981 -291.839876) (xy 278.742431 -291.797828) (xy 278.718835 -291.751518)
			(xy 278.702774 -291.702088) (xy 278.694644 -291.650753) (xy 278.40508 -291.650753) (xy 278.39695 -291.702088)
			(xy 278.380889 -291.751518) (xy 278.357293 -291.797828) (xy 278.326743 -291.839876) (xy 278.289992 -291.876627)
			(xy 278.247944 -291.907177) (xy 278.201634 -291.930773) (xy 278.152204 -291.946834) (xy 278.100869 -291.954964)
			(xy 278.048895 -291.954964) (xy 277.99756 -291.946834) (xy 277.94813 -291.930773) (xy 277.90182 -291.907177)
			(xy 277.859772 -291.876627) (xy 277.823021 -291.839876) (xy 277.792471 -291.797828) (xy 277.768875 -291.751518)
			(xy 277.752814 -291.702088) (xy 277.744684 -291.650753) (xy 276.504906 -291.650753) (xy 276.496776 -291.702088)
			(xy 276.480715 -291.751518) (xy 276.457119 -291.797828) (xy 276.426569 -291.839876) (xy 276.389818 -291.876627)
			(xy 276.34777 -291.907177) (xy 276.30146 -291.930773) (xy 276.25203 -291.946834) (xy 276.200695 -291.954964)
			(xy 276.148721 -291.954964) (xy 276.097386 -291.946834) (xy 276.047956 -291.930773) (xy 276.001646 -291.907177)
			(xy 275.959598 -291.876627) (xy 275.922847 -291.839876) (xy 275.892297 -291.797828) (xy 275.868701 -291.751518)
			(xy 275.85264 -291.702088) (xy 275.84451 -291.650753) (xy 275.553863 -291.650753) (xy 275.551708 -291.677617)
			(xy 275.539098 -291.729094) (xy 275.51844 -291.777902) (xy 275.490263 -291.82279) (xy 275.455287 -291.862609)
			(xy 275.414408 -291.896341) (xy 275.368672 -291.923121) (xy 275.344128 -291.933122) (xy 275.336762 -291.935916)
			(xy 275.325078 -291.945314) (xy 275.320506 -291.951918) (xy 275.316408 -291.958374) (xy 275.3119 -291.972978)
			(xy 275.311616 -291.98062) (xy 275.311616 -292.219126) (xy 275.311878 -292.226769) (xy 275.316408 -292.24137)
			(xy 275.320506 -292.247828) (xy 275.325078 -292.254432) (xy 275.336762 -292.26383) (xy 275.344128 -292.266624)
			(xy 275.368649 -292.276682) (xy 275.414384 -292.303458) (xy 275.455264 -292.337186) (xy 275.490241 -292.377002)
			(xy 275.51842 -292.421887) (xy 275.53908 -292.470691) (xy 275.551692 -292.522166) (xy 275.555932 -292.574993)
			(xy 275.553848 -292.600967) (xy 275.84451 -292.600967) (xy 275.84451 -292.548993) (xy 275.85264 -292.497658)
			(xy 275.868701 -292.448228) (xy 275.892297 -292.401918) (xy 275.922847 -292.35987) (xy 275.959598 -292.323119)
			(xy 276.001646 -292.292569) (xy 276.047956 -292.268973) (xy 276.097386 -292.252912) (xy 276.148721 -292.244782)
			(xy 276.200695 -292.244782) (xy 276.25203 -292.252912) (xy 276.30146 -292.268973) (xy 276.34777 -292.292569)
			(xy 276.389818 -292.323119) (xy 276.426569 -292.35987) (xy 276.457119 -292.401918) (xy 276.480715 -292.448228)
			(xy 276.496776 -292.497658) (xy 276.504906 -292.548993) (xy 276.505416 -292.57498) (xy 276.504906 -292.600967)
			(xy 277.744684 -292.600967) (xy 277.744684 -292.548993) (xy 277.752814 -292.497658) (xy 277.768875 -292.448228)
			(xy 277.792471 -292.401918) (xy 277.823021 -292.35987) (xy 277.859772 -292.323119) (xy 277.90182 -292.292569)
			(xy 277.94813 -292.268973) (xy 277.99756 -292.252912) (xy 278.048895 -292.244782) (xy 278.100869 -292.244782)
			(xy 278.152204 -292.252912) (xy 278.201634 -292.268973) (xy 278.247944 -292.292569) (xy 278.289992 -292.323119)
			(xy 278.326743 -292.35987) (xy 278.357293 -292.401918) (xy 278.380889 -292.448228) (xy 278.39695 -292.497658)
			(xy 278.40508 -292.548993) (xy 278.40559 -292.57498) (xy 278.40508 -292.600967) (xy 278.694644 -292.600967)
			(xy 278.694644 -292.548993) (xy 278.702774 -292.497658) (xy 278.718835 -292.448228) (xy 278.742431 -292.401918)
			(xy 278.772981 -292.35987) (xy 278.809732 -292.323119) (xy 278.85178 -292.292569) (xy 278.89809 -292.268973)
			(xy 278.94752 -292.252912) (xy 278.998855 -292.244782) (xy 279.050829 -292.244782) (xy 279.102164 -292.252912)
			(xy 279.151594 -292.268973) (xy 279.197904 -292.292569) (xy 279.239952 -292.323119) (xy 279.276703 -292.35987)
			(xy 279.307253 -292.401918) (xy 279.330849 -292.448228) (xy 279.34691 -292.497658) (xy 279.35504 -292.548993)
			(xy 279.35555 -292.57498) (xy 279.35504 -292.600967) (xy 279.644604 -292.600967) (xy 279.644604 -292.548993)
			(xy 279.652734 -292.497658) (xy 279.668795 -292.448228) (xy 279.692391 -292.401918) (xy 279.722941 -292.35987)
			(xy 279.759692 -292.323119) (xy 279.80174 -292.292569) (xy 279.84805 -292.268973) (xy 279.89748 -292.252912)
			(xy 279.948815 -292.244782) (xy 280.000789 -292.244782) (xy 280.052124 -292.252912) (xy 280.101554 -292.268973)
			(xy 280.147864 -292.292569) (xy 280.189912 -292.323119) (xy 280.226663 -292.35987) (xy 280.257213 -292.401918)
			(xy 280.280809 -292.448228) (xy 280.29687 -292.497658) (xy 280.305 -292.548993) (xy 280.30551 -292.57498)
			(xy 280.305005 -292.600713) (xy 280.594564 -292.600713) (xy 280.594564 -292.548739) (xy 280.602694 -292.497404)
			(xy 280.618755 -292.447974) (xy 280.642351 -292.401664) (xy 280.672901 -292.359616) (xy 280.709652 -292.322865)
			(xy 280.7517 -292.292315) (xy 280.79801 -292.268719) (xy 280.84744 -292.252658) (xy 280.898775 -292.244528)
			(xy 280.950749 -292.244528) (xy 281.002084 -292.252658) (xy 281.051514 -292.268719) (xy 281.097824 -292.292315)
			(xy 281.139872 -292.322865) (xy 281.176623 -292.359616) (xy 281.207173 -292.401664) (xy 281.230769 -292.447974)
			(xy 281.24683 -292.497404) (xy 281.25496 -292.548739) (xy 281.25547 -292.574726) (xy 281.25496 -292.600713)
			(xy 281.544524 -292.600713) (xy 281.544524 -292.548739) (xy 281.552654 -292.497404) (xy 281.568715 -292.447974)
			(xy 281.592311 -292.401664) (xy 281.622861 -292.359616) (xy 281.659612 -292.322865) (xy 281.70166 -292.292315)
			(xy 281.74797 -292.268719) (xy 281.7974 -292.252658) (xy 281.848735 -292.244528) (xy 281.900709 -292.244528)
			(xy 281.952044 -292.252658) (xy 282.001474 -292.268719) (xy 282.047784 -292.292315) (xy 282.089832 -292.322865)
			(xy 282.126583 -292.359616) (xy 282.157133 -292.401664) (xy 282.180729 -292.447974) (xy 282.19679 -292.497404)
			(xy 282.20492 -292.548739) (xy 282.20543 -292.574726) (xy 282.20492 -292.600713) (xy 282.20488 -292.600967)
			(xy 282.494738 -292.600967) (xy 282.494738 -292.548993) (xy 282.502868 -292.497658) (xy 282.518929 -292.448228)
			(xy 282.542525 -292.401918) (xy 282.573075 -292.35987) (xy 282.609826 -292.323119) (xy 282.651874 -292.292569)
			(xy 282.698184 -292.268973) (xy 282.747614 -292.252912) (xy 282.798949 -292.244782) (xy 282.850923 -292.244782)
			(xy 282.902258 -292.252912) (xy 282.951688 -292.268973) (xy 282.997998 -292.292569) (xy 283.040046 -292.323119)
			(xy 283.076797 -292.35987) (xy 283.107347 -292.401918) (xy 283.130943 -292.448228) (xy 283.147004 -292.497658)
			(xy 283.155134 -292.548993) (xy 283.155644 -292.57498) (xy 283.155134 -292.600967) (xy 283.444698 -292.600967)
			(xy 283.444698 -292.548993) (xy 283.452828 -292.497658) (xy 283.468889 -292.448228) (xy 283.492485 -292.401918)
			(xy 283.523035 -292.35987) (xy 283.559786 -292.323119) (xy 283.601834 -292.292569) (xy 283.648144 -292.268973)
			(xy 283.697574 -292.252912) (xy 283.748909 -292.244782) (xy 283.800883 -292.244782) (xy 283.852218 -292.252912)
			(xy 283.901648 -292.268973) (xy 283.947958 -292.292569) (xy 283.990006 -292.323119) (xy 284.026757 -292.35987)
			(xy 284.057307 -292.401918) (xy 284.080903 -292.448228) (xy 284.096964 -292.497658) (xy 284.105094 -292.548993)
			(xy 284.105604 -292.57498) (xy 284.105094 -292.600967) (xy 284.394658 -292.600967) (xy 284.394658 -292.548993)
			(xy 284.402788 -292.497658) (xy 284.418849 -292.448228) (xy 284.442445 -292.401918) (xy 284.472995 -292.35987)
			(xy 284.509746 -292.323119) (xy 284.551794 -292.292569) (xy 284.598104 -292.268973) (xy 284.647534 -292.252912)
			(xy 284.698869 -292.244782) (xy 284.750843 -292.244782) (xy 284.802178 -292.252912) (xy 284.851608 -292.268973)
			(xy 284.897918 -292.292569) (xy 284.939966 -292.323119) (xy 284.976717 -292.35987) (xy 285.007267 -292.401918)
			(xy 285.030863 -292.448228) (xy 285.046924 -292.497658) (xy 285.055054 -292.548993) (xy 285.055564 -292.57498)
			(xy 285.055054 -292.600967) (xy 285.344618 -292.600967) (xy 285.344618 -292.548993) (xy 285.352748 -292.497658)
			(xy 285.368809 -292.448228) (xy 285.392405 -292.401918) (xy 285.422955 -292.35987) (xy 285.459706 -292.323119)
			(xy 285.501754 -292.292569) (xy 285.548064 -292.268973) (xy 285.597494 -292.252912) (xy 285.648829 -292.244782)
			(xy 285.700803 -292.244782) (xy 285.752138 -292.252912) (xy 285.801568 -292.268973) (xy 285.847878 -292.292569)
			(xy 285.889926 -292.323119) (xy 285.926677 -292.35987) (xy 285.957227 -292.401918) (xy 285.980823 -292.448228)
			(xy 285.996884 -292.497658) (xy 286.005014 -292.548993) (xy 286.005524 -292.57498) (xy 286.005014 -292.600967)
			(xy 286.294578 -292.600967) (xy 286.294578 -292.548993) (xy 286.302708 -292.497658) (xy 286.318769 -292.448228)
			(xy 286.342365 -292.401918) (xy 286.372915 -292.35987) (xy 286.409666 -292.323119) (xy 286.451714 -292.292569)
			(xy 286.498024 -292.268973) (xy 286.547454 -292.252912) (xy 286.598789 -292.244782) (xy 286.650763 -292.244782)
			(xy 286.702098 -292.252912) (xy 286.751528 -292.268973) (xy 286.797838 -292.292569) (xy 286.839886 -292.323119)
			(xy 286.876637 -292.35987) (xy 286.907187 -292.401918) (xy 286.930783 -292.448228) (xy 286.946844 -292.497658)
			(xy 286.954974 -292.548993) (xy 286.955484 -292.57498) (xy 286.954974 -292.600967) (xy 287.244538 -292.600967)
			(xy 287.244538 -292.548993) (xy 287.252668 -292.497658) (xy 287.268729 -292.448228) (xy 287.292325 -292.401918)
			(xy 287.322875 -292.35987) (xy 287.359626 -292.323119) (xy 287.401674 -292.292569) (xy 287.447984 -292.268973)
			(xy 287.497414 -292.252912) (xy 287.548749 -292.244782) (xy 287.600723 -292.244782) (xy 287.652058 -292.252912)
			(xy 287.701488 -292.268973) (xy 287.747798 -292.292569) (xy 287.789846 -292.323119) (xy 287.826597 -292.35987)
			(xy 287.857147 -292.401918) (xy 287.880743 -292.448228) (xy 287.896804 -292.497658) (xy 287.904934 -292.548993)
			(xy 287.905444 -292.57498) (xy 287.904934 -292.600967) (xy 288.194752 -292.600967) (xy 288.194752 -292.548993)
			(xy 288.202882 -292.497658) (xy 288.218943 -292.448228) (xy 288.242539 -292.401918) (xy 288.273089 -292.35987)
			(xy 288.30984 -292.323119) (xy 288.351888 -292.292569) (xy 288.398198 -292.268973) (xy 288.447628 -292.252912)
			(xy 288.498963 -292.244782) (xy 288.550937 -292.244782) (xy 288.602272 -292.252912) (xy 288.651702 -292.268973)
			(xy 288.698012 -292.292569) (xy 288.74006 -292.323119) (xy 288.776811 -292.35987) (xy 288.807361 -292.401918)
			(xy 288.830957 -292.448228) (xy 288.847018 -292.497658) (xy 288.855148 -292.548993) (xy 288.855658 -292.57498)
			(xy 288.855148 -292.600967) (xy 289.144712 -292.600967) (xy 289.144712 -292.548993) (xy 289.152842 -292.497658)
			(xy 289.168903 -292.448228) (xy 289.192499 -292.401918) (xy 289.223049 -292.35987) (xy 289.2598 -292.323119)
			(xy 289.301848 -292.292569) (xy 289.348158 -292.268973) (xy 289.397588 -292.252912) (xy 289.448923 -292.244782)
			(xy 289.500897 -292.244782) (xy 289.552232 -292.252912) (xy 289.601662 -292.268973) (xy 289.647972 -292.292569)
			(xy 289.69002 -292.323119) (xy 289.726771 -292.35987) (xy 289.757321 -292.401918) (xy 289.780917 -292.448228)
			(xy 289.796978 -292.497658) (xy 289.805108 -292.548993) (xy 289.805618 -292.57498) (xy 289.805108 -292.600967)
			(xy 290.094672 -292.600967) (xy 290.094672 -292.548993) (xy 290.102802 -292.497658) (xy 290.118863 -292.448228)
			(xy 290.142459 -292.401918) (xy 290.173009 -292.35987) (xy 290.20976 -292.323119) (xy 290.251808 -292.292569)
			(xy 290.298118 -292.268973) (xy 290.347548 -292.252912) (xy 290.398883 -292.244782) (xy 290.450857 -292.244782)
			(xy 290.502192 -292.252912) (xy 290.551622 -292.268973) (xy 290.597932 -292.292569) (xy 290.63998 -292.323119)
			(xy 290.676731 -292.35987) (xy 290.707281 -292.401918) (xy 290.730877 -292.448228) (xy 290.746938 -292.497658)
			(xy 290.755068 -292.548993) (xy 290.755578 -292.57498) (xy 290.755073 -292.600713) (xy 291.994592 -292.600713)
			(xy 291.994592 -292.548739) (xy 292.002722 -292.497404) (xy 292.018783 -292.447974) (xy 292.042379 -292.401664)
			(xy 292.072929 -292.359616) (xy 292.10968 -292.322865) (xy 292.151728 -292.292315) (xy 292.198038 -292.268719)
			(xy 292.247468 -292.252658) (xy 292.298803 -292.244528) (xy 292.350777 -292.244528) (xy 292.402112 -292.252658)
			(xy 292.451542 -292.268719) (xy 292.497852 -292.292315) (xy 292.5399 -292.322865) (xy 292.576651 -292.359616)
			(xy 292.607201 -292.401664) (xy 292.630797 -292.447974) (xy 292.646858 -292.497404) (xy 292.654988 -292.548739)
			(xy 292.655498 -292.574726) (xy 292.654988 -292.600713) (xy 292.944552 -292.600713) (xy 292.944552 -292.548739)
			(xy 292.952682 -292.497404) (xy 292.968743 -292.447974) (xy 292.992339 -292.401664) (xy 293.022889 -292.359616)
			(xy 293.05964 -292.322865) (xy 293.101688 -292.292315) (xy 293.147998 -292.268719) (xy 293.197428 -292.252658)
			(xy 293.248763 -292.244528) (xy 293.300737 -292.244528) (xy 293.352072 -292.252658) (xy 293.401502 -292.268719)
			(xy 293.447812 -292.292315) (xy 293.48986 -292.322865) (xy 293.526611 -292.359616) (xy 293.557161 -292.401664)
			(xy 293.580757 -292.447974) (xy 293.596818 -292.497404) (xy 293.604948 -292.548739) (xy 293.605458 -292.574726)
			(xy 293.604948 -292.600713) (xy 293.894512 -292.600713) (xy 293.894512 -292.548739) (xy 293.902642 -292.497404)
			(xy 293.918703 -292.447974) (xy 293.942299 -292.401664) (xy 293.972849 -292.359616) (xy 294.0096 -292.322865)
			(xy 294.051648 -292.292315) (xy 294.097958 -292.268719) (xy 294.147388 -292.252658) (xy 294.198723 -292.244528)
			(xy 294.250697 -292.244528) (xy 294.302032 -292.252658) (xy 294.351462 -292.268719) (xy 294.397772 -292.292315)
			(xy 294.43982 -292.322865) (xy 294.476571 -292.359616) (xy 294.507121 -292.401664) (xy 294.530717 -292.447974)
			(xy 294.546778 -292.497404) (xy 294.554908 -292.548739) (xy 294.555418 -292.574726) (xy 294.554908 -292.600713)
			(xy 294.844726 -292.600713) (xy 294.844726 -292.548739) (xy 294.852856 -292.497404) (xy 294.868917 -292.447974)
			(xy 294.892513 -292.401664) (xy 294.923063 -292.359616) (xy 294.959814 -292.322865) (xy 295.001862 -292.292315)
			(xy 295.048172 -292.268719) (xy 295.097602 -292.252658) (xy 295.148937 -292.244528) (xy 295.200911 -292.244528)
			(xy 295.252246 -292.252658) (xy 295.301676 -292.268719) (xy 295.347986 -292.292315) (xy 295.390034 -292.322865)
			(xy 295.426785 -292.359616) (xy 295.457335 -292.401664) (xy 295.480931 -292.447974) (xy 295.496992 -292.497404)
			(xy 295.505122 -292.548739) (xy 295.505632 -292.574726) (xy 295.505122 -292.600713) (xy 295.794686 -292.600713)
			(xy 295.794686 -292.548739) (xy 295.802816 -292.497404) (xy 295.818877 -292.447974) (xy 295.842473 -292.401664)
			(xy 295.873023 -292.359616) (xy 295.909774 -292.322865) (xy 295.951822 -292.292315) (xy 295.998132 -292.268719)
			(xy 296.047562 -292.252658) (xy 296.098897 -292.244528) (xy 296.150871 -292.244528) (xy 296.202206 -292.252658)
			(xy 296.251636 -292.268719) (xy 296.297946 -292.292315) (xy 296.339994 -292.322865) (xy 296.376745 -292.359616)
			(xy 296.407295 -292.401664) (xy 296.430891 -292.447974) (xy 296.446952 -292.497404) (xy 296.455082 -292.548739)
			(xy 296.455592 -292.574726) (xy 296.455082 -292.600713) (xy 296.744646 -292.600713) (xy 296.744646 -292.548739)
			(xy 296.752776 -292.497404) (xy 296.768837 -292.447974) (xy 296.792433 -292.401664) (xy 296.822983 -292.359616)
			(xy 296.859734 -292.322865) (xy 296.901782 -292.292315) (xy 296.948092 -292.268719) (xy 296.997522 -292.252658)
			(xy 297.048857 -292.244528) (xy 297.100831 -292.244528) (xy 297.152166 -292.252658) (xy 297.201596 -292.268719)
			(xy 297.247906 -292.292315) (xy 297.289954 -292.322865) (xy 297.326705 -292.359616) (xy 297.357255 -292.401664)
			(xy 297.380851 -292.447974) (xy 297.396912 -292.497404) (xy 297.405042 -292.548739) (xy 297.405552 -292.574726)
			(xy 297.405042 -292.600713) (xy 297.694606 -292.600713) (xy 297.694606 -292.548739) (xy 297.702736 -292.497404)
			(xy 297.718797 -292.447974) (xy 297.742393 -292.401664) (xy 297.772943 -292.359616) (xy 297.809694 -292.322865)
			(xy 297.851742 -292.292315) (xy 297.898052 -292.268719) (xy 297.947482 -292.252658) (xy 297.998817 -292.244528)
			(xy 298.050791 -292.244528) (xy 298.102126 -292.252658) (xy 298.151556 -292.268719) (xy 298.197866 -292.292315)
			(xy 298.239914 -292.322865) (xy 298.276665 -292.359616) (xy 298.307215 -292.401664) (xy 298.330811 -292.447974)
			(xy 298.346872 -292.497404) (xy 298.355002 -292.548739) (xy 298.355512 -292.574726) (xy 298.355002 -292.600713)
			(xy 298.644566 -292.600713) (xy 298.644566 -292.548739) (xy 298.652696 -292.497404) (xy 298.668757 -292.447974)
			(xy 298.692353 -292.401664) (xy 298.722903 -292.359616) (xy 298.759654 -292.322865) (xy 298.801702 -292.292315)
			(xy 298.848012 -292.268719) (xy 298.897442 -292.252658) (xy 298.948777 -292.244528) (xy 299.000751 -292.244528)
			(xy 299.052086 -292.252658) (xy 299.101516 -292.268719) (xy 299.147826 -292.292315) (xy 299.189874 -292.322865)
			(xy 299.226625 -292.359616) (xy 299.257175 -292.401664) (xy 299.280771 -292.447974) (xy 299.296832 -292.497404)
			(xy 299.304962 -292.548739) (xy 299.305472 -292.574726) (xy 299.304962 -292.600713) (xy 299.594526 -292.600713)
			(xy 299.594526 -292.548739) (xy 299.602656 -292.497404) (xy 299.618717 -292.447974) (xy 299.642313 -292.401664)
			(xy 299.672863 -292.359616) (xy 299.709614 -292.322865) (xy 299.751662 -292.292315) (xy 299.797972 -292.268719)
			(xy 299.847402 -292.252658) (xy 299.898737 -292.244528) (xy 299.950711 -292.244528) (xy 300.002046 -292.252658)
			(xy 300.051476 -292.268719) (xy 300.097786 -292.292315) (xy 300.139834 -292.322865) (xy 300.176585 -292.359616)
			(xy 300.207135 -292.401664) (xy 300.230731 -292.447974) (xy 300.246792 -292.497404) (xy 300.254922 -292.548739)
			(xy 300.255432 -292.574726) (xy 300.254922 -292.600713) (xy 300.544486 -292.600713) (xy 300.544486 -292.548739)
			(xy 300.552616 -292.497404) (xy 300.568677 -292.447974) (xy 300.592273 -292.401664) (xy 300.622823 -292.359616)
			(xy 300.659574 -292.322865) (xy 300.701622 -292.292315) (xy 300.747932 -292.268719) (xy 300.797362 -292.252658)
			(xy 300.848697 -292.244528) (xy 300.900671 -292.244528) (xy 300.952006 -292.252658) (xy 301.001436 -292.268719)
			(xy 301.047746 -292.292315) (xy 301.089794 -292.322865) (xy 301.126545 -292.359616) (xy 301.157095 -292.401664)
			(xy 301.180691 -292.447974) (xy 301.196752 -292.497404) (xy 301.204882 -292.548739) (xy 301.205392 -292.574726)
			(xy 301.204882 -292.600713) (xy 301.4947 -292.600713) (xy 301.4947 -292.548739) (xy 301.50283 -292.497404)
			(xy 301.518891 -292.447974) (xy 301.542487 -292.401664) (xy 301.573037 -292.359616) (xy 301.609788 -292.322865)
			(xy 301.651836 -292.292315) (xy 301.698146 -292.268719) (xy 301.747576 -292.252658) (xy 301.798911 -292.244528)
			(xy 301.850885 -292.244528) (xy 301.90222 -292.252658) (xy 301.95165 -292.268719) (xy 301.99796 -292.292315)
			(xy 302.040008 -292.322865) (xy 302.076759 -292.359616) (xy 302.107309 -292.401664) (xy 302.130905 -292.447974)
			(xy 302.146966 -292.497404) (xy 302.155096 -292.548739) (xy 302.155606 -292.574726) (xy 302.155096 -292.600713)
			(xy 302.146966 -292.652048) (xy 302.130905 -292.701478) (xy 302.107309 -292.747788) (xy 302.076759 -292.789836)
			(xy 302.040008 -292.826587) (xy 301.99796 -292.857137) (xy 301.95165 -292.880733) (xy 301.90222 -292.896794)
			(xy 301.850885 -292.904924) (xy 301.798911 -292.904924) (xy 301.747576 -292.896794) (xy 301.698146 -292.880733)
			(xy 301.651836 -292.857137) (xy 301.609788 -292.826587) (xy 301.573037 -292.789836) (xy 301.542487 -292.747788)
			(xy 301.518891 -292.701478) (xy 301.50283 -292.652048) (xy 301.4947 -292.600713) (xy 301.204882 -292.600713)
			(xy 301.196752 -292.652048) (xy 301.180691 -292.701478) (xy 301.157095 -292.747788) (xy 301.126545 -292.789836)
			(xy 301.089794 -292.826587) (xy 301.047746 -292.857137) (xy 301.001436 -292.880733) (xy 300.952006 -292.896794)
			(xy 300.900671 -292.904924) (xy 300.848697 -292.904924) (xy 300.797362 -292.896794) (xy 300.747932 -292.880733)
			(xy 300.701622 -292.857137) (xy 300.659574 -292.826587) (xy 300.622823 -292.789836) (xy 300.592273 -292.747788)
			(xy 300.568677 -292.701478) (xy 300.552616 -292.652048) (xy 300.544486 -292.600713) (xy 300.254922 -292.600713)
			(xy 300.246792 -292.652048) (xy 300.230731 -292.701478) (xy 300.207135 -292.747788) (xy 300.176585 -292.789836)
			(xy 300.139834 -292.826587) (xy 300.097786 -292.857137) (xy 300.051476 -292.880733) (xy 300.002046 -292.896794)
			(xy 299.950711 -292.904924) (xy 299.898737 -292.904924) (xy 299.847402 -292.896794) (xy 299.797972 -292.880733)
			(xy 299.751662 -292.857137) (xy 299.709614 -292.826587) (xy 299.672863 -292.789836) (xy 299.642313 -292.747788)
			(xy 299.618717 -292.701478) (xy 299.602656 -292.652048) (xy 299.594526 -292.600713) (xy 299.304962 -292.600713)
			(xy 299.296832 -292.652048) (xy 299.280771 -292.701478) (xy 299.257175 -292.747788) (xy 299.226625 -292.789836)
			(xy 299.189874 -292.826587) (xy 299.147826 -292.857137) (xy 299.101516 -292.880733) (xy 299.052086 -292.896794)
			(xy 299.000751 -292.904924) (xy 298.948777 -292.904924) (xy 298.897442 -292.896794) (xy 298.848012 -292.880733)
			(xy 298.801702 -292.857137) (xy 298.759654 -292.826587) (xy 298.722903 -292.789836) (xy 298.692353 -292.747788)
			(xy 298.668757 -292.701478) (xy 298.652696 -292.652048) (xy 298.644566 -292.600713) (xy 298.355002 -292.600713)
			(xy 298.346872 -292.652048) (xy 298.330811 -292.701478) (xy 298.307215 -292.747788) (xy 298.276665 -292.789836)
			(xy 298.239914 -292.826587) (xy 298.197866 -292.857137) (xy 298.151556 -292.880733) (xy 298.102126 -292.896794)
			(xy 298.050791 -292.904924) (xy 297.998817 -292.904924) (xy 297.947482 -292.896794) (xy 297.898052 -292.880733)
			(xy 297.851742 -292.857137) (xy 297.809694 -292.826587) (xy 297.772943 -292.789836) (xy 297.742393 -292.747788)
			(xy 297.718797 -292.701478) (xy 297.702736 -292.652048) (xy 297.694606 -292.600713) (xy 297.405042 -292.600713)
			(xy 297.396912 -292.652048) (xy 297.380851 -292.701478) (xy 297.357255 -292.747788) (xy 297.326705 -292.789836)
			(xy 297.289954 -292.826587) (xy 297.247906 -292.857137) (xy 297.201596 -292.880733) (xy 297.152166 -292.896794)
			(xy 297.100831 -292.904924) (xy 297.048857 -292.904924) (xy 296.997522 -292.896794) (xy 296.948092 -292.880733)
			(xy 296.901782 -292.857137) (xy 296.859734 -292.826587) (xy 296.822983 -292.789836) (xy 296.792433 -292.747788)
			(xy 296.768837 -292.701478) (xy 296.752776 -292.652048) (xy 296.744646 -292.600713) (xy 296.455082 -292.600713)
			(xy 296.446952 -292.652048) (xy 296.430891 -292.701478) (xy 296.407295 -292.747788) (xy 296.376745 -292.789836)
			(xy 296.339994 -292.826587) (xy 296.297946 -292.857137) (xy 296.251636 -292.880733) (xy 296.202206 -292.896794)
			(xy 296.150871 -292.904924) (xy 296.098897 -292.904924) (xy 296.047562 -292.896794) (xy 295.998132 -292.880733)
			(xy 295.951822 -292.857137) (xy 295.909774 -292.826587) (xy 295.873023 -292.789836) (xy 295.842473 -292.747788)
			(xy 295.818877 -292.701478) (xy 295.802816 -292.652048) (xy 295.794686 -292.600713) (xy 295.505122 -292.600713)
			(xy 295.496992 -292.652048) (xy 295.480931 -292.701478) (xy 295.457335 -292.747788) (xy 295.426785 -292.789836)
			(xy 295.390034 -292.826587) (xy 295.347986 -292.857137) (xy 295.301676 -292.880733) (xy 295.252246 -292.896794)
			(xy 295.200911 -292.904924) (xy 295.148937 -292.904924) (xy 295.097602 -292.896794) (xy 295.048172 -292.880733)
			(xy 295.001862 -292.857137) (xy 294.959814 -292.826587) (xy 294.923063 -292.789836) (xy 294.892513 -292.747788)
			(xy 294.868917 -292.701478) (xy 294.852856 -292.652048) (xy 294.844726 -292.600713) (xy 294.554908 -292.600713)
			(xy 294.546778 -292.652048) (xy 294.530717 -292.701478) (xy 294.507121 -292.747788) (xy 294.476571 -292.789836)
			(xy 294.43982 -292.826587) (xy 294.397772 -292.857137) (xy 294.351462 -292.880733) (xy 294.302032 -292.896794)
			(xy 294.250697 -292.904924) (xy 294.198723 -292.904924) (xy 294.147388 -292.896794) (xy 294.097958 -292.880733)
			(xy 294.051648 -292.857137) (xy 294.0096 -292.826587) (xy 293.972849 -292.789836) (xy 293.942299 -292.747788)
			(xy 293.918703 -292.701478) (xy 293.902642 -292.652048) (xy 293.894512 -292.600713) (xy 293.604948 -292.600713)
			(xy 293.596818 -292.652048) (xy 293.580757 -292.701478) (xy 293.557161 -292.747788) (xy 293.526611 -292.789836)
			(xy 293.48986 -292.826587) (xy 293.447812 -292.857137) (xy 293.401502 -292.880733) (xy 293.352072 -292.896794)
			(xy 293.300737 -292.904924) (xy 293.248763 -292.904924) (xy 293.197428 -292.896794) (xy 293.147998 -292.880733)
			(xy 293.101688 -292.857137) (xy 293.05964 -292.826587) (xy 293.022889 -292.789836) (xy 292.992339 -292.747788)
			(xy 292.968743 -292.701478) (xy 292.952682 -292.652048) (xy 292.944552 -292.600713) (xy 292.654988 -292.600713)
			(xy 292.646858 -292.652048) (xy 292.630797 -292.701478) (xy 292.607201 -292.747788) (xy 292.576651 -292.789836)
			(xy 292.5399 -292.826587) (xy 292.497852 -292.857137) (xy 292.451542 -292.880733) (xy 292.402112 -292.896794)
			(xy 292.350777 -292.904924) (xy 292.298803 -292.904924) (xy 292.247468 -292.896794) (xy 292.198038 -292.880733)
			(xy 292.151728 -292.857137) (xy 292.10968 -292.826587) (xy 292.072929 -292.789836) (xy 292.042379 -292.747788)
			(xy 292.018783 -292.701478) (xy 292.002722 -292.652048) (xy 291.994592 -292.600713) (xy 290.755073 -292.600713)
			(xy 290.755068 -292.600967) (xy 290.746938 -292.652302) (xy 290.730877 -292.701732) (xy 290.707281 -292.748042)
			(xy 290.676731 -292.79009) (xy 290.63998 -292.826841) (xy 290.597932 -292.857391) (xy 290.551622 -292.880987)
			(xy 290.502192 -292.897048) (xy 290.450857 -292.905178) (xy 290.398883 -292.905178) (xy 290.347548 -292.897048)
			(xy 290.298118 -292.880987) (xy 290.251808 -292.857391) (xy 290.20976 -292.826841) (xy 290.173009 -292.79009)
			(xy 290.142459 -292.748042) (xy 290.118863 -292.701732) (xy 290.102802 -292.652302) (xy 290.094672 -292.600967)
			(xy 289.805108 -292.600967) (xy 289.796978 -292.652302) (xy 289.780917 -292.701732) (xy 289.757321 -292.748042)
			(xy 289.726771 -292.79009) (xy 289.69002 -292.826841) (xy 289.647972 -292.857391) (xy 289.601662 -292.880987)
			(xy 289.552232 -292.897048) (xy 289.500897 -292.905178) (xy 289.448923 -292.905178) (xy 289.397588 -292.897048)
			(xy 289.348158 -292.880987) (xy 289.301848 -292.857391) (xy 289.2598 -292.826841) (xy 289.223049 -292.79009)
			(xy 289.192499 -292.748042) (xy 289.168903 -292.701732) (xy 289.152842 -292.652302) (xy 289.144712 -292.600967)
			(xy 288.855148 -292.600967) (xy 288.847018 -292.652302) (xy 288.830957 -292.701732) (xy 288.807361 -292.748042)
			(xy 288.776811 -292.79009) (xy 288.74006 -292.826841) (xy 288.698012 -292.857391) (xy 288.651702 -292.880987)
			(xy 288.602272 -292.897048) (xy 288.550937 -292.905178) (xy 288.498963 -292.905178) (xy 288.447628 -292.897048)
			(xy 288.398198 -292.880987) (xy 288.351888 -292.857391) (xy 288.30984 -292.826841) (xy 288.273089 -292.79009)
			(xy 288.242539 -292.748042) (xy 288.218943 -292.701732) (xy 288.202882 -292.652302) (xy 288.194752 -292.600967)
			(xy 287.904934 -292.600967) (xy 287.896804 -292.652302) (xy 287.880743 -292.701732) (xy 287.857147 -292.748042)
			(xy 287.826597 -292.79009) (xy 287.789846 -292.826841) (xy 287.747798 -292.857391) (xy 287.701488 -292.880987)
			(xy 287.652058 -292.897048) (xy 287.600723 -292.905178) (xy 287.548749 -292.905178) (xy 287.497414 -292.897048)
			(xy 287.447984 -292.880987) (xy 287.401674 -292.857391) (xy 287.359626 -292.826841) (xy 287.322875 -292.79009)
			(xy 287.292325 -292.748042) (xy 287.268729 -292.701732) (xy 287.252668 -292.652302) (xy 287.244538 -292.600967)
			(xy 286.954974 -292.600967) (xy 286.946844 -292.652302) (xy 286.930783 -292.701732) (xy 286.907187 -292.748042)
			(xy 286.876637 -292.79009) (xy 286.839886 -292.826841) (xy 286.797838 -292.857391) (xy 286.751528 -292.880987)
			(xy 286.702098 -292.897048) (xy 286.650763 -292.905178) (xy 286.598789 -292.905178) (xy 286.547454 -292.897048)
			(xy 286.498024 -292.880987) (xy 286.451714 -292.857391) (xy 286.409666 -292.826841) (xy 286.372915 -292.79009)
			(xy 286.342365 -292.748042) (xy 286.318769 -292.701732) (xy 286.302708 -292.652302) (xy 286.294578 -292.600967)
			(xy 286.005014 -292.600967) (xy 285.996884 -292.652302) (xy 285.980823 -292.701732) (xy 285.957227 -292.748042)
			(xy 285.926677 -292.79009) (xy 285.889926 -292.826841) (xy 285.847878 -292.857391) (xy 285.801568 -292.880987)
			(xy 285.752138 -292.897048) (xy 285.700803 -292.905178) (xy 285.648829 -292.905178) (xy 285.597494 -292.897048)
			(xy 285.548064 -292.880987) (xy 285.501754 -292.857391) (xy 285.459706 -292.826841) (xy 285.422955 -292.79009)
			(xy 285.392405 -292.748042) (xy 285.368809 -292.701732) (xy 285.352748 -292.652302) (xy 285.344618 -292.600967)
			(xy 285.055054 -292.600967) (xy 285.046924 -292.652302) (xy 285.030863 -292.701732) (xy 285.007267 -292.748042)
			(xy 284.976717 -292.79009) (xy 284.939966 -292.826841) (xy 284.897918 -292.857391) (xy 284.851608 -292.880987)
			(xy 284.802178 -292.897048) (xy 284.750843 -292.905178) (xy 284.698869 -292.905178) (xy 284.647534 -292.897048)
			(xy 284.598104 -292.880987) (xy 284.551794 -292.857391) (xy 284.509746 -292.826841) (xy 284.472995 -292.79009)
			(xy 284.442445 -292.748042) (xy 284.418849 -292.701732) (xy 284.402788 -292.652302) (xy 284.394658 -292.600967)
			(xy 284.105094 -292.600967) (xy 284.096964 -292.652302) (xy 284.080903 -292.701732) (xy 284.057307 -292.748042)
			(xy 284.026757 -292.79009) (xy 283.990006 -292.826841) (xy 283.947958 -292.857391) (xy 283.901648 -292.880987)
			(xy 283.852218 -292.897048) (xy 283.800883 -292.905178) (xy 283.748909 -292.905178) (xy 283.697574 -292.897048)
			(xy 283.648144 -292.880987) (xy 283.601834 -292.857391) (xy 283.559786 -292.826841) (xy 283.523035 -292.79009)
			(xy 283.492485 -292.748042) (xy 283.468889 -292.701732) (xy 283.452828 -292.652302) (xy 283.444698 -292.600967)
			(xy 283.155134 -292.600967) (xy 283.147004 -292.652302) (xy 283.130943 -292.701732) (xy 283.107347 -292.748042)
			(xy 283.076797 -292.79009) (xy 283.040046 -292.826841) (xy 282.997998 -292.857391) (xy 282.951688 -292.880987)
			(xy 282.902258 -292.897048) (xy 282.850923 -292.905178) (xy 282.798949 -292.905178) (xy 282.747614 -292.897048)
			(xy 282.698184 -292.880987) (xy 282.651874 -292.857391) (xy 282.609826 -292.826841) (xy 282.573075 -292.79009)
			(xy 282.542525 -292.748042) (xy 282.518929 -292.701732) (xy 282.502868 -292.652302) (xy 282.494738 -292.600967)
			(xy 282.20488 -292.600967) (xy 282.19679 -292.652048) (xy 282.180729 -292.701478) (xy 282.157133 -292.747788)
			(xy 282.126583 -292.789836) (xy 282.089832 -292.826587) (xy 282.047784 -292.857137) (xy 282.001474 -292.880733)
			(xy 281.952044 -292.896794) (xy 281.900709 -292.904924) (xy 281.848735 -292.904924) (xy 281.7974 -292.896794)
			(xy 281.74797 -292.880733) (xy 281.70166 -292.857137) (xy 281.659612 -292.826587) (xy 281.622861 -292.789836)
			(xy 281.592311 -292.747788) (xy 281.568715 -292.701478) (xy 281.552654 -292.652048) (xy 281.544524 -292.600713)
			(xy 281.25496 -292.600713) (xy 281.24683 -292.652048) (xy 281.230769 -292.701478) (xy 281.207173 -292.747788)
			(xy 281.176623 -292.789836) (xy 281.139872 -292.826587) (xy 281.097824 -292.857137) (xy 281.051514 -292.880733)
			(xy 281.002084 -292.896794) (xy 280.950749 -292.904924) (xy 280.898775 -292.904924) (xy 280.84744 -292.896794)
			(xy 280.79801 -292.880733) (xy 280.7517 -292.857137) (xy 280.709652 -292.826587) (xy 280.672901 -292.789836)
			(xy 280.642351 -292.747788) (xy 280.618755 -292.701478) (xy 280.602694 -292.652048) (xy 280.594564 -292.600713)
			(xy 280.305005 -292.600713) (xy 280.305 -292.600967) (xy 280.29687 -292.652302) (xy 280.280809 -292.701732)
			(xy 280.257213 -292.748042) (xy 280.226663 -292.79009) (xy 280.189912 -292.826841) (xy 280.147864 -292.857391)
			(xy 280.101554 -292.880987) (xy 280.052124 -292.897048) (xy 280.000789 -292.905178) (xy 279.948815 -292.905178)
			(xy 279.89748 -292.897048) (xy 279.84805 -292.880987) (xy 279.80174 -292.857391) (xy 279.759692 -292.826841)
			(xy 279.722941 -292.79009) (xy 279.692391 -292.748042) (xy 279.668795 -292.701732) (xy 279.652734 -292.652302)
			(xy 279.644604 -292.600967) (xy 279.35504 -292.600967) (xy 279.34691 -292.652302) (xy 279.330849 -292.701732)
			(xy 279.307253 -292.748042) (xy 279.276703 -292.79009) (xy 279.239952 -292.826841) (xy 279.197904 -292.857391)
			(xy 279.151594 -292.880987) (xy 279.102164 -292.897048) (xy 279.050829 -292.905178) (xy 278.998855 -292.905178)
			(xy 278.94752 -292.897048) (xy 278.89809 -292.880987) (xy 278.85178 -292.857391) (xy 278.809732 -292.826841)
			(xy 278.772981 -292.79009) (xy 278.742431 -292.748042) (xy 278.718835 -292.701732) (xy 278.702774 -292.652302)
			(xy 278.694644 -292.600967) (xy 278.40508 -292.600967) (xy 278.39695 -292.652302) (xy 278.380889 -292.701732)
			(xy 278.357293 -292.748042) (xy 278.326743 -292.79009) (xy 278.289992 -292.826841) (xy 278.247944 -292.857391)
			(xy 278.201634 -292.880987) (xy 278.152204 -292.897048) (xy 278.100869 -292.905178) (xy 278.048895 -292.905178)
			(xy 277.99756 -292.897048) (xy 277.94813 -292.880987) (xy 277.90182 -292.857391) (xy 277.859772 -292.826841)
			(xy 277.823021 -292.79009) (xy 277.792471 -292.748042) (xy 277.768875 -292.701732) (xy 277.752814 -292.652302)
			(xy 277.744684 -292.600967) (xy 276.504906 -292.600967) (xy 276.496776 -292.652302) (xy 276.480715 -292.701732)
			(xy 276.457119 -292.748042) (xy 276.426569 -292.79009) (xy 276.389818 -292.826841) (xy 276.34777 -292.857391)
			(xy 276.30146 -292.880987) (xy 276.25203 -292.897048) (xy 276.200695 -292.905178) (xy 276.148721 -292.905178)
			(xy 276.097386 -292.897048) (xy 276.047956 -292.880987) (xy 276.001646 -292.857391) (xy 275.959598 -292.826841)
			(xy 275.922847 -292.79009) (xy 275.892297 -292.748042) (xy 275.868701 -292.701732) (xy 275.85264 -292.652302)
			(xy 275.84451 -292.600967) (xy 275.553848 -292.600967) (xy 275.551694 -292.62782) (xy 275.539084 -292.679295)
			(xy 275.518426 -292.7281) (xy 275.490249 -292.772986) (xy 275.455274 -292.812804) (xy 275.414396 -292.846533)
			(xy 275.368662 -292.873312) (xy 275.344128 -292.883336) (xy 275.336762 -292.88613) (xy 275.325078 -292.895528)
			(xy 275.320506 -292.902132) (xy 275.316397 -292.908585) (xy 275.311864 -292.923189) (xy 275.311616 -292.930834)
			(xy 275.311616 -293.131494) (xy 275.330666 -293.15791) (xy 275.34616 -293.163244) (xy 275.372541 -293.172623)
			(xy 275.422442 -293.198015) (xy 275.468096 -293.230427) (xy 275.508522 -293.269164) (xy 275.542853 -293.313394)
			(xy 275.57035 -293.362166) (xy 275.590423 -293.414433) (xy 275.602641 -293.469074) (xy 275.606742 -293.524913)
			(xy 275.60483 -293.550927) (xy 275.84451 -293.550927) (xy 275.84451 -293.498953) (xy 275.85264 -293.447618)
			(xy 275.868701 -293.398188) (xy 275.892297 -293.351878) (xy 275.922847 -293.30983) (xy 275.959598 -293.273079)
			(xy 276.001646 -293.242529) (xy 276.047956 -293.218933) (xy 276.097386 -293.202872) (xy 276.148721 -293.194742)
			(xy 276.200695 -293.194742) (xy 276.25203 -293.202872) (xy 276.30146 -293.218933) (xy 276.34777 -293.242529)
			(xy 276.389818 -293.273079) (xy 276.426569 -293.30983) (xy 276.457119 -293.351878) (xy 276.480715 -293.398188)
			(xy 276.496776 -293.447618) (xy 276.504906 -293.498953) (xy 276.505416 -293.52494) (xy 276.504906 -293.550927)
			(xy 277.744684 -293.550927) (xy 277.744684 -293.498953) (xy 277.752814 -293.447618) (xy 277.768875 -293.398188)
			(xy 277.792471 -293.351878) (xy 277.823021 -293.30983) (xy 277.859772 -293.273079) (xy 277.90182 -293.242529)
			(xy 277.94813 -293.218933) (xy 277.99756 -293.202872) (xy 278.048895 -293.194742) (xy 278.100869 -293.194742)
			(xy 278.152204 -293.202872) (xy 278.201634 -293.218933) (xy 278.247944 -293.242529) (xy 278.289992 -293.273079)
			(xy 278.326743 -293.30983) (xy 278.357293 -293.351878) (xy 278.380889 -293.398188) (xy 278.39695 -293.447618)
			(xy 278.40508 -293.498953) (xy 278.40559 -293.52494) (xy 278.40508 -293.550927) (xy 278.694644 -293.550927)
			(xy 278.694644 -293.498953) (xy 278.702774 -293.447618) (xy 278.718835 -293.398188) (xy 278.742431 -293.351878)
			(xy 278.772981 -293.30983) (xy 278.809732 -293.273079) (xy 278.85178 -293.242529) (xy 278.89809 -293.218933)
			(xy 278.94752 -293.202872) (xy 278.998855 -293.194742) (xy 279.050829 -293.194742) (xy 279.102164 -293.202872)
			(xy 279.151594 -293.218933) (xy 279.197904 -293.242529) (xy 279.239952 -293.273079) (xy 279.276703 -293.30983)
			(xy 279.307253 -293.351878) (xy 279.330849 -293.398188) (xy 279.34691 -293.447618) (xy 279.35504 -293.498953)
			(xy 279.35555 -293.52494) (xy 279.35504 -293.550927) (xy 279.644604 -293.550927) (xy 279.644604 -293.498953)
			(xy 279.652734 -293.447618) (xy 279.668795 -293.398188) (xy 279.692391 -293.351878) (xy 279.722941 -293.30983)
			(xy 279.759692 -293.273079) (xy 279.80174 -293.242529) (xy 279.84805 -293.218933) (xy 279.89748 -293.202872)
			(xy 279.948815 -293.194742) (xy 280.000789 -293.194742) (xy 280.052124 -293.202872) (xy 280.101554 -293.218933)
			(xy 280.147864 -293.242529) (xy 280.189912 -293.273079) (xy 280.226663 -293.30983) (xy 280.257213 -293.351878)
			(xy 280.280809 -293.398188) (xy 280.29687 -293.447618) (xy 280.305 -293.498953) (xy 280.30551 -293.52494)
			(xy 280.305 -293.550927) (xy 280.594564 -293.550927) (xy 280.594564 -293.498953) (xy 280.602694 -293.447618)
			(xy 280.618755 -293.398188) (xy 280.642351 -293.351878) (xy 280.672901 -293.30983) (xy 280.709652 -293.273079)
			(xy 280.7517 -293.242529) (xy 280.79801 -293.218933) (xy 280.84744 -293.202872) (xy 280.898775 -293.194742)
			(xy 280.950749 -293.194742) (xy 281.002084 -293.202872) (xy 281.051514 -293.218933) (xy 281.097824 -293.242529)
			(xy 281.139872 -293.273079) (xy 281.176623 -293.30983) (xy 281.207173 -293.351878) (xy 281.230769 -293.398188)
			(xy 281.24683 -293.447618) (xy 281.25496 -293.498953) (xy 281.25547 -293.52494) (xy 281.25496 -293.550927)
			(xy 281.544524 -293.550927) (xy 281.544524 -293.498953) (xy 281.552654 -293.447618) (xy 281.568715 -293.398188)
			(xy 281.592311 -293.351878) (xy 281.622861 -293.30983) (xy 281.659612 -293.273079) (xy 281.70166 -293.242529)
			(xy 281.74797 -293.218933) (xy 281.7974 -293.202872) (xy 281.848735 -293.194742) (xy 281.900709 -293.194742)
			(xy 281.952044 -293.202872) (xy 282.001474 -293.218933) (xy 282.047784 -293.242529) (xy 282.089832 -293.273079)
			(xy 282.126583 -293.30983) (xy 282.157133 -293.351878) (xy 282.180729 -293.398188) (xy 282.19679 -293.447618)
			(xy 282.20492 -293.498953) (xy 282.20543 -293.52494) (xy 282.20492 -293.550927) (xy 282.494738 -293.550927)
			(xy 282.494738 -293.498953) (xy 282.502868 -293.447618) (xy 282.518929 -293.398188) (xy 282.542525 -293.351878)
			(xy 282.573075 -293.30983) (xy 282.609826 -293.273079) (xy 282.651874 -293.242529) (xy 282.698184 -293.218933)
			(xy 282.747614 -293.202872) (xy 282.798949 -293.194742) (xy 282.850923 -293.194742) (xy 282.902258 -293.202872)
			(xy 282.951688 -293.218933) (xy 282.997998 -293.242529) (xy 283.040046 -293.273079) (xy 283.076797 -293.30983)
			(xy 283.107347 -293.351878) (xy 283.130943 -293.398188) (xy 283.147004 -293.447618) (xy 283.155134 -293.498953)
			(xy 283.155644 -293.52494) (xy 283.155134 -293.550927) (xy 283.444698 -293.550927) (xy 283.444698 -293.498953)
			(xy 283.452828 -293.447618) (xy 283.468889 -293.398188) (xy 283.492485 -293.351878) (xy 283.523035 -293.30983)
			(xy 283.559786 -293.273079) (xy 283.601834 -293.242529) (xy 283.648144 -293.218933) (xy 283.697574 -293.202872)
			(xy 283.748909 -293.194742) (xy 283.800883 -293.194742) (xy 283.852218 -293.202872) (xy 283.901648 -293.218933)
			(xy 283.947958 -293.242529) (xy 283.990006 -293.273079) (xy 284.026757 -293.30983) (xy 284.057307 -293.351878)
			(xy 284.080903 -293.398188) (xy 284.096964 -293.447618) (xy 284.105094 -293.498953) (xy 284.105604 -293.52494)
			(xy 284.105094 -293.550927) (xy 284.394658 -293.550927) (xy 284.394658 -293.498953) (xy 284.402788 -293.447618)
			(xy 284.418849 -293.398188) (xy 284.442445 -293.351878) (xy 284.472995 -293.30983) (xy 284.509746 -293.273079)
			(xy 284.551794 -293.242529) (xy 284.598104 -293.218933) (xy 284.647534 -293.202872) (xy 284.698869 -293.194742)
			(xy 284.750843 -293.194742) (xy 284.802178 -293.202872) (xy 284.851608 -293.218933) (xy 284.897918 -293.242529)
			(xy 284.939966 -293.273079) (xy 284.976717 -293.30983) (xy 285.007267 -293.351878) (xy 285.030863 -293.398188)
			(xy 285.046924 -293.447618) (xy 285.055054 -293.498953) (xy 285.055564 -293.52494) (xy 285.055054 -293.550927)
			(xy 285.344618 -293.550927) (xy 285.344618 -293.498953) (xy 285.352748 -293.447618) (xy 285.368809 -293.398188)
			(xy 285.392405 -293.351878) (xy 285.422955 -293.30983) (xy 285.459706 -293.273079) (xy 285.501754 -293.242529)
			(xy 285.548064 -293.218933) (xy 285.597494 -293.202872) (xy 285.648829 -293.194742) (xy 285.700803 -293.194742)
			(xy 285.752138 -293.202872) (xy 285.801568 -293.218933) (xy 285.847878 -293.242529) (xy 285.889926 -293.273079)
			(xy 285.926677 -293.30983) (xy 285.957227 -293.351878) (xy 285.980823 -293.398188) (xy 285.996884 -293.447618)
			(xy 286.005014 -293.498953) (xy 286.005524 -293.52494) (xy 286.005014 -293.550927) (xy 286.294578 -293.550927)
			(xy 286.294578 -293.498953) (xy 286.302708 -293.447618) (xy 286.318769 -293.398188) (xy 286.342365 -293.351878)
			(xy 286.372915 -293.30983) (xy 286.409666 -293.273079) (xy 286.451714 -293.242529) (xy 286.498024 -293.218933)
			(xy 286.547454 -293.202872) (xy 286.598789 -293.194742) (xy 286.650763 -293.194742) (xy 286.702098 -293.202872)
			(xy 286.751528 -293.218933) (xy 286.797838 -293.242529) (xy 286.839886 -293.273079) (xy 286.876637 -293.30983)
			(xy 286.907187 -293.351878) (xy 286.930783 -293.398188) (xy 286.946844 -293.447618) (xy 286.954974 -293.498953)
			(xy 286.955484 -293.52494) (xy 286.954974 -293.550927) (xy 287.244538 -293.550927) (xy 287.244538 -293.498953)
			(xy 287.252668 -293.447618) (xy 287.268729 -293.398188) (xy 287.292325 -293.351878) (xy 287.322875 -293.30983)
			(xy 287.359626 -293.273079) (xy 287.401674 -293.242529) (xy 287.447984 -293.218933) (xy 287.497414 -293.202872)
			(xy 287.548749 -293.194742) (xy 287.600723 -293.194742) (xy 287.652058 -293.202872) (xy 287.701488 -293.218933)
			(xy 287.747798 -293.242529) (xy 287.789846 -293.273079) (xy 287.826597 -293.30983) (xy 287.857147 -293.351878)
			(xy 287.880743 -293.398188) (xy 287.896804 -293.447618) (xy 287.904934 -293.498953) (xy 287.905444 -293.52494)
			(xy 287.904934 -293.550927) (xy 288.194498 -293.550927) (xy 288.194498 -293.498953) (xy 288.202628 -293.447618)
			(xy 288.218689 -293.398188) (xy 288.242285 -293.351878) (xy 288.272835 -293.30983) (xy 288.309586 -293.273079)
			(xy 288.351634 -293.242529) (xy 288.397944 -293.218933) (xy 288.447374 -293.202872) (xy 288.498709 -293.194742)
			(xy 288.550683 -293.194742) (xy 288.602018 -293.202872) (xy 288.651448 -293.218933) (xy 288.697758 -293.242529)
			(xy 288.739806 -293.273079) (xy 288.776557 -293.30983) (xy 288.807107 -293.351878) (xy 288.830703 -293.398188)
			(xy 288.846764 -293.447618) (xy 288.854894 -293.498953) (xy 288.855404 -293.52494) (xy 288.854894 -293.550927)
			(xy 289.144712 -293.550927) (xy 289.144712 -293.498953) (xy 289.152842 -293.447618) (xy 289.168903 -293.398188)
			(xy 289.192499 -293.351878) (xy 289.223049 -293.30983) (xy 289.2598 -293.273079) (xy 289.301848 -293.242529)
			(xy 289.348158 -293.218933) (xy 289.397588 -293.202872) (xy 289.448923 -293.194742) (xy 289.500897 -293.194742)
			(xy 289.552232 -293.202872) (xy 289.601662 -293.218933) (xy 289.647972 -293.242529) (xy 289.69002 -293.273079)
			(xy 289.726771 -293.30983) (xy 289.757321 -293.351878) (xy 289.780917 -293.398188) (xy 289.796978 -293.447618)
			(xy 289.805108 -293.498953) (xy 289.805618 -293.52494) (xy 289.805108 -293.550927) (xy 290.094672 -293.550927)
			(xy 290.094672 -293.498953) (xy 290.102802 -293.447618) (xy 290.118863 -293.398188) (xy 290.142459 -293.351878)
			(xy 290.173009 -293.30983) (xy 290.20976 -293.273079) (xy 290.251808 -293.242529) (xy 290.298118 -293.218933)
			(xy 290.347548 -293.202872) (xy 290.398883 -293.194742) (xy 290.450857 -293.194742) (xy 290.502192 -293.202872)
			(xy 290.551622 -293.218933) (xy 290.597932 -293.242529) (xy 290.63998 -293.273079) (xy 290.676731 -293.30983)
			(xy 290.707281 -293.351878) (xy 290.730877 -293.398188) (xy 290.746938 -293.447618) (xy 290.755068 -293.498953)
			(xy 290.755578 -293.52494) (xy 290.755068 -293.550927) (xy 291.994592 -293.550927) (xy 291.994592 -293.498953)
			(xy 292.002722 -293.447618) (xy 292.018783 -293.398188) (xy 292.042379 -293.351878) (xy 292.072929 -293.30983)
			(xy 292.10968 -293.273079) (xy 292.151728 -293.242529) (xy 292.198038 -293.218933) (xy 292.247468 -293.202872)
			(xy 292.298803 -293.194742) (xy 292.350777 -293.194742) (xy 292.402112 -293.202872) (xy 292.451542 -293.218933)
			(xy 292.497852 -293.242529) (xy 292.5399 -293.273079) (xy 292.576651 -293.30983) (xy 292.607201 -293.351878)
			(xy 292.630797 -293.398188) (xy 292.646858 -293.447618) (xy 292.654988 -293.498953) (xy 292.655498 -293.52494)
			(xy 292.654988 -293.550927) (xy 292.944552 -293.550927) (xy 292.944552 -293.498953) (xy 292.952682 -293.447618)
			(xy 292.968743 -293.398188) (xy 292.992339 -293.351878) (xy 293.022889 -293.30983) (xy 293.05964 -293.273079)
			(xy 293.101688 -293.242529) (xy 293.147998 -293.218933) (xy 293.197428 -293.202872) (xy 293.248763 -293.194742)
			(xy 293.300737 -293.194742) (xy 293.352072 -293.202872) (xy 293.401502 -293.218933) (xy 293.447812 -293.242529)
			(xy 293.48986 -293.273079) (xy 293.526611 -293.30983) (xy 293.557161 -293.351878) (xy 293.580757 -293.398188)
			(xy 293.596818 -293.447618) (xy 293.604948 -293.498953) (xy 293.605458 -293.52494) (xy 293.604948 -293.550927)
			(xy 293.894512 -293.550927) (xy 293.894512 -293.498953) (xy 293.902642 -293.447618) (xy 293.918703 -293.398188)
			(xy 293.942299 -293.351878) (xy 293.972849 -293.30983) (xy 294.0096 -293.273079) (xy 294.051648 -293.242529)
			(xy 294.097958 -293.218933) (xy 294.147388 -293.202872) (xy 294.198723 -293.194742) (xy 294.250697 -293.194742)
			(xy 294.302032 -293.202872) (xy 294.351462 -293.218933) (xy 294.397772 -293.242529) (xy 294.43982 -293.273079)
			(xy 294.476571 -293.30983) (xy 294.507121 -293.351878) (xy 294.530717 -293.398188) (xy 294.546778 -293.447618)
			(xy 294.554908 -293.498953) (xy 294.555418 -293.52494) (xy 294.554908 -293.550927) (xy 294.844726 -293.550927)
			(xy 294.844726 -293.498953) (xy 294.852856 -293.447618) (xy 294.868917 -293.398188) (xy 294.892513 -293.351878)
			(xy 294.923063 -293.30983) (xy 294.959814 -293.273079) (xy 295.001862 -293.242529) (xy 295.048172 -293.218933)
			(xy 295.097602 -293.202872) (xy 295.148937 -293.194742) (xy 295.200911 -293.194742) (xy 295.252246 -293.202872)
			(xy 295.301676 -293.218933) (xy 295.347986 -293.242529) (xy 295.390034 -293.273079) (xy 295.426785 -293.30983)
			(xy 295.457335 -293.351878) (xy 295.480931 -293.398188) (xy 295.496992 -293.447618) (xy 295.505122 -293.498953)
			(xy 295.505632 -293.52494) (xy 295.505122 -293.550927) (xy 295.794686 -293.550927) (xy 295.794686 -293.498953)
			(xy 295.802816 -293.447618) (xy 295.818877 -293.398188) (xy 295.842473 -293.351878) (xy 295.873023 -293.30983)
			(xy 295.909774 -293.273079) (xy 295.951822 -293.242529) (xy 295.998132 -293.218933) (xy 296.047562 -293.202872)
			(xy 296.098897 -293.194742) (xy 296.150871 -293.194742) (xy 296.202206 -293.202872) (xy 296.251636 -293.218933)
			(xy 296.297946 -293.242529) (xy 296.339994 -293.273079) (xy 296.376745 -293.30983) (xy 296.407295 -293.351878)
			(xy 296.430891 -293.398188) (xy 296.446952 -293.447618) (xy 296.455082 -293.498953) (xy 296.455592 -293.52494)
			(xy 296.455082 -293.550927) (xy 296.744646 -293.550927) (xy 296.744646 -293.498953) (xy 296.752776 -293.447618)
			(xy 296.768837 -293.398188) (xy 296.792433 -293.351878) (xy 296.822983 -293.30983) (xy 296.859734 -293.273079)
			(xy 296.901782 -293.242529) (xy 296.948092 -293.218933) (xy 296.997522 -293.202872) (xy 297.048857 -293.194742)
			(xy 297.100831 -293.194742) (xy 297.152166 -293.202872) (xy 297.201596 -293.218933) (xy 297.247906 -293.242529)
			(xy 297.289954 -293.273079) (xy 297.326705 -293.30983) (xy 297.357255 -293.351878) (xy 297.380851 -293.398188)
			(xy 297.396912 -293.447618) (xy 297.405042 -293.498953) (xy 297.405552 -293.52494) (xy 297.405042 -293.550927)
			(xy 297.694606 -293.550927) (xy 297.694606 -293.498953) (xy 297.702736 -293.447618) (xy 297.718797 -293.398188)
			(xy 297.742393 -293.351878) (xy 297.772943 -293.30983) (xy 297.809694 -293.273079) (xy 297.851742 -293.242529)
			(xy 297.898052 -293.218933) (xy 297.947482 -293.202872) (xy 297.998817 -293.194742) (xy 298.050791 -293.194742)
			(xy 298.102126 -293.202872) (xy 298.151556 -293.218933) (xy 298.197866 -293.242529) (xy 298.239914 -293.273079)
			(xy 298.276665 -293.30983) (xy 298.307215 -293.351878) (xy 298.330811 -293.398188) (xy 298.346872 -293.447618)
			(xy 298.355002 -293.498953) (xy 298.355512 -293.52494) (xy 298.355002 -293.550927) (xy 298.644566 -293.550927)
			(xy 298.644566 -293.498953) (xy 298.652696 -293.447618) (xy 298.668757 -293.398188) (xy 298.692353 -293.351878)
			(xy 298.722903 -293.30983) (xy 298.759654 -293.273079) (xy 298.801702 -293.242529) (xy 298.848012 -293.218933)
			(xy 298.897442 -293.202872) (xy 298.948777 -293.194742) (xy 299.000751 -293.194742) (xy 299.052086 -293.202872)
			(xy 299.101516 -293.218933) (xy 299.147826 -293.242529) (xy 299.189874 -293.273079) (xy 299.226625 -293.30983)
			(xy 299.257175 -293.351878) (xy 299.280771 -293.398188) (xy 299.296832 -293.447618) (xy 299.304962 -293.498953)
			(xy 299.305472 -293.52494) (xy 299.304962 -293.550927) (xy 299.594526 -293.550927) (xy 299.594526 -293.498953)
			(xy 299.602656 -293.447618) (xy 299.618717 -293.398188) (xy 299.642313 -293.351878) (xy 299.672863 -293.30983)
			(xy 299.709614 -293.273079) (xy 299.751662 -293.242529) (xy 299.797972 -293.218933) (xy 299.847402 -293.202872)
			(xy 299.898737 -293.194742) (xy 299.950711 -293.194742) (xy 300.002046 -293.202872) (xy 300.051476 -293.218933)
			(xy 300.097786 -293.242529) (xy 300.139834 -293.273079) (xy 300.176585 -293.30983) (xy 300.207135 -293.351878)
			(xy 300.230731 -293.398188) (xy 300.246792 -293.447618) (xy 300.254922 -293.498953) (xy 300.255432 -293.52494)
			(xy 300.254922 -293.550927) (xy 300.544486 -293.550927) (xy 300.544486 -293.498953) (xy 300.552616 -293.447618)
			(xy 300.568677 -293.398188) (xy 300.592273 -293.351878) (xy 300.622823 -293.30983) (xy 300.659574 -293.273079)
			(xy 300.701622 -293.242529) (xy 300.747932 -293.218933) (xy 300.797362 -293.202872) (xy 300.848697 -293.194742)
			(xy 300.900671 -293.194742) (xy 300.952006 -293.202872) (xy 301.001436 -293.218933) (xy 301.047746 -293.242529)
			(xy 301.089794 -293.273079) (xy 301.126545 -293.30983) (xy 301.157095 -293.351878) (xy 301.180691 -293.398188)
			(xy 301.196752 -293.447618) (xy 301.204882 -293.498953) (xy 301.205392 -293.52494) (xy 301.204882 -293.550927)
			(xy 301.4947 -293.550927) (xy 301.4947 -293.498953) (xy 301.50283 -293.447618) (xy 301.518891 -293.398188)
			(xy 301.542487 -293.351878) (xy 301.573037 -293.30983) (xy 301.609788 -293.273079) (xy 301.651836 -293.242529)
			(xy 301.698146 -293.218933) (xy 301.747576 -293.202872) (xy 301.798911 -293.194742) (xy 301.850885 -293.194742)
			(xy 301.90222 -293.202872) (xy 301.95165 -293.218933) (xy 301.99796 -293.242529) (xy 302.040008 -293.273079)
			(xy 302.076759 -293.30983) (xy 302.107309 -293.351878) (xy 302.130905 -293.398188) (xy 302.146966 -293.447618)
			(xy 302.155096 -293.498953) (xy 302.155606 -293.52494) (xy 302.155096 -293.550927) (xy 302.146966 -293.602262)
			(xy 302.130905 -293.651692) (xy 302.107309 -293.698002) (xy 302.076759 -293.74005) (xy 302.040008 -293.776801)
			(xy 301.99796 -293.807351) (xy 301.95165 -293.830947) (xy 301.90222 -293.847008) (xy 301.850885 -293.855138)
			(xy 301.798911 -293.855138) (xy 301.747576 -293.847008) (xy 301.698146 -293.830947) (xy 301.651836 -293.807351)
			(xy 301.609788 -293.776801) (xy 301.573037 -293.74005) (xy 301.542487 -293.698002) (xy 301.518891 -293.651692)
			(xy 301.50283 -293.602262) (xy 301.4947 -293.550927) (xy 301.204882 -293.550927) (xy 301.196752 -293.602262)
			(xy 301.180691 -293.651692) (xy 301.157095 -293.698002) (xy 301.126545 -293.74005) (xy 301.089794 -293.776801)
			(xy 301.047746 -293.807351) (xy 301.001436 -293.830947) (xy 300.952006 -293.847008) (xy 300.900671 -293.855138)
			(xy 300.848697 -293.855138) (xy 300.797362 -293.847008) (xy 300.747932 -293.830947) (xy 300.701622 -293.807351)
			(xy 300.659574 -293.776801) (xy 300.622823 -293.74005) (xy 300.592273 -293.698002) (xy 300.568677 -293.651692)
			(xy 300.552616 -293.602262) (xy 300.544486 -293.550927) (xy 300.254922 -293.550927) (xy 300.246792 -293.602262)
			(xy 300.230731 -293.651692) (xy 300.207135 -293.698002) (xy 300.176585 -293.74005) (xy 300.139834 -293.776801)
			(xy 300.097786 -293.807351) (xy 300.051476 -293.830947) (xy 300.002046 -293.847008) (xy 299.950711 -293.855138)
			(xy 299.898737 -293.855138) (xy 299.847402 -293.847008) (xy 299.797972 -293.830947) (xy 299.751662 -293.807351)
			(xy 299.709614 -293.776801) (xy 299.672863 -293.74005) (xy 299.642313 -293.698002) (xy 299.618717 -293.651692)
			(xy 299.602656 -293.602262) (xy 299.594526 -293.550927) (xy 299.304962 -293.550927) (xy 299.296832 -293.602262)
			(xy 299.280771 -293.651692) (xy 299.257175 -293.698002) (xy 299.226625 -293.74005) (xy 299.189874 -293.776801)
			(xy 299.147826 -293.807351) (xy 299.101516 -293.830947) (xy 299.052086 -293.847008) (xy 299.000751 -293.855138)
			(xy 298.948777 -293.855138) (xy 298.897442 -293.847008) (xy 298.848012 -293.830947) (xy 298.801702 -293.807351)
			(xy 298.759654 -293.776801) (xy 298.722903 -293.74005) (xy 298.692353 -293.698002) (xy 298.668757 -293.651692)
			(xy 298.652696 -293.602262) (xy 298.644566 -293.550927) (xy 298.355002 -293.550927) (xy 298.346872 -293.602262)
			(xy 298.330811 -293.651692) (xy 298.307215 -293.698002) (xy 298.276665 -293.74005) (xy 298.239914 -293.776801)
			(xy 298.197866 -293.807351) (xy 298.151556 -293.830947) (xy 298.102126 -293.847008) (xy 298.050791 -293.855138)
			(xy 297.998817 -293.855138) (xy 297.947482 -293.847008) (xy 297.898052 -293.830947) (xy 297.851742 -293.807351)
			(xy 297.809694 -293.776801) (xy 297.772943 -293.74005) (xy 297.742393 -293.698002) (xy 297.718797 -293.651692)
			(xy 297.702736 -293.602262) (xy 297.694606 -293.550927) (xy 297.405042 -293.550927) (xy 297.396912 -293.602262)
			(xy 297.380851 -293.651692) (xy 297.357255 -293.698002) (xy 297.326705 -293.74005) (xy 297.289954 -293.776801)
			(xy 297.247906 -293.807351) (xy 297.201596 -293.830947) (xy 297.152166 -293.847008) (xy 297.100831 -293.855138)
			(xy 297.048857 -293.855138) (xy 296.997522 -293.847008) (xy 296.948092 -293.830947) (xy 296.901782 -293.807351)
			(xy 296.859734 -293.776801) (xy 296.822983 -293.74005) (xy 296.792433 -293.698002) (xy 296.768837 -293.651692)
			(xy 296.752776 -293.602262) (xy 296.744646 -293.550927) (xy 296.455082 -293.550927) (xy 296.446952 -293.602262)
			(xy 296.430891 -293.651692) (xy 296.407295 -293.698002) (xy 296.376745 -293.74005) (xy 296.339994 -293.776801)
			(xy 296.297946 -293.807351) (xy 296.251636 -293.830947) (xy 296.202206 -293.847008) (xy 296.150871 -293.855138)
			(xy 296.098897 -293.855138) (xy 296.047562 -293.847008) (xy 295.998132 -293.830947) (xy 295.951822 -293.807351)
			(xy 295.909774 -293.776801) (xy 295.873023 -293.74005) (xy 295.842473 -293.698002) (xy 295.818877 -293.651692)
			(xy 295.802816 -293.602262) (xy 295.794686 -293.550927) (xy 295.505122 -293.550927) (xy 295.496992 -293.602262)
			(xy 295.480931 -293.651692) (xy 295.457335 -293.698002) (xy 295.426785 -293.74005) (xy 295.390034 -293.776801)
			(xy 295.347986 -293.807351) (xy 295.301676 -293.830947) (xy 295.252246 -293.847008) (xy 295.200911 -293.855138)
			(xy 295.148937 -293.855138) (xy 295.097602 -293.847008) (xy 295.048172 -293.830947) (xy 295.001862 -293.807351)
			(xy 294.959814 -293.776801) (xy 294.923063 -293.74005) (xy 294.892513 -293.698002) (xy 294.868917 -293.651692)
			(xy 294.852856 -293.602262) (xy 294.844726 -293.550927) (xy 294.554908 -293.550927) (xy 294.546778 -293.602262)
			(xy 294.530717 -293.651692) (xy 294.507121 -293.698002) (xy 294.476571 -293.74005) (xy 294.43982 -293.776801)
			(xy 294.397772 -293.807351) (xy 294.351462 -293.830947) (xy 294.302032 -293.847008) (xy 294.250697 -293.855138)
			(xy 294.198723 -293.855138) (xy 294.147388 -293.847008) (xy 294.097958 -293.830947) (xy 294.051648 -293.807351)
			(xy 294.0096 -293.776801) (xy 293.972849 -293.74005) (xy 293.942299 -293.698002) (xy 293.918703 -293.651692)
			(xy 293.902642 -293.602262) (xy 293.894512 -293.550927) (xy 293.604948 -293.550927) (xy 293.596818 -293.602262)
			(xy 293.580757 -293.651692) (xy 293.557161 -293.698002) (xy 293.526611 -293.74005) (xy 293.48986 -293.776801)
			(xy 293.447812 -293.807351) (xy 293.401502 -293.830947) (xy 293.352072 -293.847008) (xy 293.300737 -293.855138)
			(xy 293.248763 -293.855138) (xy 293.197428 -293.847008) (xy 293.147998 -293.830947) (xy 293.101688 -293.807351)
			(xy 293.05964 -293.776801) (xy 293.022889 -293.74005) (xy 292.992339 -293.698002) (xy 292.968743 -293.651692)
			(xy 292.952682 -293.602262) (xy 292.944552 -293.550927) (xy 292.654988 -293.550927) (xy 292.646858 -293.602262)
			(xy 292.630797 -293.651692) (xy 292.607201 -293.698002) (xy 292.576651 -293.74005) (xy 292.5399 -293.776801)
			(xy 292.497852 -293.807351) (xy 292.451542 -293.830947) (xy 292.402112 -293.847008) (xy 292.350777 -293.855138)
			(xy 292.298803 -293.855138) (xy 292.247468 -293.847008) (xy 292.198038 -293.830947) (xy 292.151728 -293.807351)
			(xy 292.10968 -293.776801) (xy 292.072929 -293.74005) (xy 292.042379 -293.698002) (xy 292.018783 -293.651692)
			(xy 292.002722 -293.602262) (xy 291.994592 -293.550927) (xy 290.755068 -293.550927) (xy 290.746938 -293.602262)
			(xy 290.730877 -293.651692) (xy 290.707281 -293.698002) (xy 290.676731 -293.74005) (xy 290.63998 -293.776801)
			(xy 290.597932 -293.807351) (xy 290.551622 -293.830947) (xy 290.502192 -293.847008) (xy 290.450857 -293.855138)
			(xy 290.398883 -293.855138) (xy 290.347548 -293.847008) (xy 290.298118 -293.830947) (xy 290.251808 -293.807351)
			(xy 290.20976 -293.776801) (xy 290.173009 -293.74005) (xy 290.142459 -293.698002) (xy 290.118863 -293.651692)
			(xy 290.102802 -293.602262) (xy 290.094672 -293.550927) (xy 289.805108 -293.550927) (xy 289.796978 -293.602262)
			(xy 289.780917 -293.651692) (xy 289.757321 -293.698002) (xy 289.726771 -293.74005) (xy 289.69002 -293.776801)
			(xy 289.647972 -293.807351) (xy 289.601662 -293.830947) (xy 289.552232 -293.847008) (xy 289.500897 -293.855138)
			(xy 289.448923 -293.855138) (xy 289.397588 -293.847008) (xy 289.348158 -293.830947) (xy 289.301848 -293.807351)
			(xy 289.2598 -293.776801) (xy 289.223049 -293.74005) (xy 289.192499 -293.698002) (xy 289.168903 -293.651692)
			(xy 289.152842 -293.602262) (xy 289.144712 -293.550927) (xy 288.854894 -293.550927) (xy 288.846764 -293.602262)
			(xy 288.830703 -293.651692) (xy 288.807107 -293.698002) (xy 288.776557 -293.74005) (xy 288.739806 -293.776801)
			(xy 288.697758 -293.807351) (xy 288.651448 -293.830947) (xy 288.602018 -293.847008) (xy 288.550683 -293.855138)
			(xy 288.498709 -293.855138) (xy 288.447374 -293.847008) (xy 288.397944 -293.830947) (xy 288.351634 -293.807351)
			(xy 288.309586 -293.776801) (xy 288.272835 -293.74005) (xy 288.242285 -293.698002) (xy 288.218689 -293.651692)
			(xy 288.202628 -293.602262) (xy 288.194498 -293.550927) (xy 287.904934 -293.550927) (xy 287.896804 -293.602262)
			(xy 287.880743 -293.651692) (xy 287.857147 -293.698002) (xy 287.826597 -293.74005) (xy 287.789846 -293.776801)
			(xy 287.747798 -293.807351) (xy 287.701488 -293.830947) (xy 287.652058 -293.847008) (xy 287.600723 -293.855138)
			(xy 287.548749 -293.855138) (xy 287.497414 -293.847008) (xy 287.447984 -293.830947) (xy 287.401674 -293.807351)
			(xy 287.359626 -293.776801) (xy 287.322875 -293.74005) (xy 287.292325 -293.698002) (xy 287.268729 -293.651692)
			(xy 287.252668 -293.602262) (xy 287.244538 -293.550927) (xy 286.954974 -293.550927) (xy 286.946844 -293.602262)
			(xy 286.930783 -293.651692) (xy 286.907187 -293.698002) (xy 286.876637 -293.74005) (xy 286.839886 -293.776801)
			(xy 286.797838 -293.807351) (xy 286.751528 -293.830947) (xy 286.702098 -293.847008) (xy 286.650763 -293.855138)
			(xy 286.598789 -293.855138) (xy 286.547454 -293.847008) (xy 286.498024 -293.830947) (xy 286.451714 -293.807351)
			(xy 286.409666 -293.776801) (xy 286.372915 -293.74005) (xy 286.342365 -293.698002) (xy 286.318769 -293.651692)
			(xy 286.302708 -293.602262) (xy 286.294578 -293.550927) (xy 286.005014 -293.550927) (xy 285.996884 -293.602262)
			(xy 285.980823 -293.651692) (xy 285.957227 -293.698002) (xy 285.926677 -293.74005) (xy 285.889926 -293.776801)
			(xy 285.847878 -293.807351) (xy 285.801568 -293.830947) (xy 285.752138 -293.847008) (xy 285.700803 -293.855138)
			(xy 285.648829 -293.855138) (xy 285.597494 -293.847008) (xy 285.548064 -293.830947) (xy 285.501754 -293.807351)
			(xy 285.459706 -293.776801) (xy 285.422955 -293.74005) (xy 285.392405 -293.698002) (xy 285.368809 -293.651692)
			(xy 285.352748 -293.602262) (xy 285.344618 -293.550927) (xy 285.055054 -293.550927) (xy 285.046924 -293.602262)
			(xy 285.030863 -293.651692) (xy 285.007267 -293.698002) (xy 284.976717 -293.74005) (xy 284.939966 -293.776801)
			(xy 284.897918 -293.807351) (xy 284.851608 -293.830947) (xy 284.802178 -293.847008) (xy 284.750843 -293.855138)
			(xy 284.698869 -293.855138) (xy 284.647534 -293.847008) (xy 284.598104 -293.830947) (xy 284.551794 -293.807351)
			(xy 284.509746 -293.776801) (xy 284.472995 -293.74005) (xy 284.442445 -293.698002) (xy 284.418849 -293.651692)
			(xy 284.402788 -293.602262) (xy 284.394658 -293.550927) (xy 284.105094 -293.550927) (xy 284.096964 -293.602262)
			(xy 284.080903 -293.651692) (xy 284.057307 -293.698002) (xy 284.026757 -293.74005) (xy 283.990006 -293.776801)
			(xy 283.947958 -293.807351) (xy 283.901648 -293.830947) (xy 283.852218 -293.847008) (xy 283.800883 -293.855138)
			(xy 283.748909 -293.855138) (xy 283.697574 -293.847008) (xy 283.648144 -293.830947) (xy 283.601834 -293.807351)
			(xy 283.559786 -293.776801) (xy 283.523035 -293.74005) (xy 283.492485 -293.698002) (xy 283.468889 -293.651692)
			(xy 283.452828 -293.602262) (xy 283.444698 -293.550927) (xy 283.155134 -293.550927) (xy 283.147004 -293.602262)
			(xy 283.130943 -293.651692) (xy 283.107347 -293.698002) (xy 283.076797 -293.74005) (xy 283.040046 -293.776801)
			(xy 282.997998 -293.807351) (xy 282.951688 -293.830947) (xy 282.902258 -293.847008) (xy 282.850923 -293.855138)
			(xy 282.798949 -293.855138) (xy 282.747614 -293.847008) (xy 282.698184 -293.830947) (xy 282.651874 -293.807351)
			(xy 282.609826 -293.776801) (xy 282.573075 -293.74005) (xy 282.542525 -293.698002) (xy 282.518929 -293.651692)
			(xy 282.502868 -293.602262) (xy 282.494738 -293.550927) (xy 282.20492 -293.550927) (xy 282.19679 -293.602262)
			(xy 282.180729 -293.651692) (xy 282.157133 -293.698002) (xy 282.126583 -293.74005) (xy 282.089832 -293.776801)
			(xy 282.047784 -293.807351) (xy 282.001474 -293.830947) (xy 281.952044 -293.847008) (xy 281.900709 -293.855138)
			(xy 281.848735 -293.855138) (xy 281.7974 -293.847008) (xy 281.74797 -293.830947) (xy 281.70166 -293.807351)
			(xy 281.659612 -293.776801) (xy 281.622861 -293.74005) (xy 281.592311 -293.698002) (xy 281.568715 -293.651692)
			(xy 281.552654 -293.602262) (xy 281.544524 -293.550927) (xy 281.25496 -293.550927) (xy 281.24683 -293.602262)
			(xy 281.230769 -293.651692) (xy 281.207173 -293.698002) (xy 281.176623 -293.74005) (xy 281.139872 -293.776801)
			(xy 281.097824 -293.807351) (xy 281.051514 -293.830947) (xy 281.002084 -293.847008) (xy 280.950749 -293.855138)
			(xy 280.898775 -293.855138) (xy 280.84744 -293.847008) (xy 280.79801 -293.830947) (xy 280.7517 -293.807351)
			(xy 280.709652 -293.776801) (xy 280.672901 -293.74005) (xy 280.642351 -293.698002) (xy 280.618755 -293.651692)
			(xy 280.602694 -293.602262) (xy 280.594564 -293.550927) (xy 280.305 -293.550927) (xy 280.29687 -293.602262)
			(xy 280.280809 -293.651692) (xy 280.257213 -293.698002) (xy 280.226663 -293.74005) (xy 280.189912 -293.776801)
			(xy 280.147864 -293.807351) (xy 280.101554 -293.830947) (xy 280.052124 -293.847008) (xy 280.000789 -293.855138)
			(xy 279.948815 -293.855138) (xy 279.89748 -293.847008) (xy 279.84805 -293.830947) (xy 279.80174 -293.807351)
			(xy 279.759692 -293.776801) (xy 279.722941 -293.74005) (xy 279.692391 -293.698002) (xy 279.668795 -293.651692)
			(xy 279.652734 -293.602262) (xy 279.644604 -293.550927) (xy 279.35504 -293.550927) (xy 279.34691 -293.602262)
			(xy 279.330849 -293.651692) (xy 279.307253 -293.698002) (xy 279.276703 -293.74005) (xy 279.239952 -293.776801)
			(xy 279.197904 -293.807351) (xy 279.151594 -293.830947) (xy 279.102164 -293.847008) (xy 279.050829 -293.855138)
			(xy 278.998855 -293.855138) (xy 278.94752 -293.847008) (xy 278.89809 -293.830947) (xy 278.85178 -293.807351)
			(xy 278.809732 -293.776801) (xy 278.772981 -293.74005) (xy 278.742431 -293.698002) (xy 278.718835 -293.651692)
			(xy 278.702774 -293.602262) (xy 278.694644 -293.550927) (xy 278.40508 -293.550927) (xy 278.39695 -293.602262)
			(xy 278.380889 -293.651692) (xy 278.357293 -293.698002) (xy 278.326743 -293.74005) (xy 278.289992 -293.776801)
			(xy 278.247944 -293.807351) (xy 278.201634 -293.830947) (xy 278.152204 -293.847008) (xy 278.100869 -293.855138)
			(xy 278.048895 -293.855138) (xy 277.99756 -293.847008) (xy 277.94813 -293.830947) (xy 277.90182 -293.807351)
			(xy 277.859772 -293.776801) (xy 277.823021 -293.74005) (xy 277.792471 -293.698002) (xy 277.768875 -293.651692)
			(xy 277.752814 -293.602262) (xy 277.744684 -293.550927) (xy 276.504906 -293.550927) (xy 276.496776 -293.602262)
			(xy 276.480715 -293.651692) (xy 276.457119 -293.698002) (xy 276.426569 -293.74005) (xy 276.389818 -293.776801)
			(xy 276.34777 -293.807351) (xy 276.30146 -293.830947) (xy 276.25203 -293.847008) (xy 276.200695 -293.855138)
			(xy 276.148721 -293.855138) (xy 276.097386 -293.847008) (xy 276.047956 -293.830947) (xy 276.001646 -293.807351)
			(xy 275.959598 -293.776801) (xy 275.922847 -293.74005) (xy 275.892297 -293.698002) (xy 275.868701 -293.651692)
			(xy 275.85264 -293.602262) (xy 275.84451 -293.550927) (xy 275.60483 -293.550927) (xy 275.602637 -293.580752)
			(xy 275.590416 -293.635391) (xy 275.570339 -293.687657) (xy 275.542839 -293.736428) (xy 275.508505 -293.780655)
			(xy 275.468077 -293.819389) (xy 275.422421 -293.851799) (xy 275.372518 -293.877187) (xy 275.34616 -293.886636)
			(xy 275.330666 -293.89197) (xy 275.311616 -293.918386) (xy 275.311616 -294.119046) (xy 275.311881 -294.126688)
			(xy 275.316415 -294.141286) (xy 275.320506 -294.147748) (xy 275.325078 -294.154352) (xy 275.336762 -294.16375)
			(xy 275.344128 -294.166544) (xy 275.368647 -294.176602) (xy 275.41438 -294.203378) (xy 275.455256 -294.237105)
			(xy 275.49023 -294.276919) (xy 275.518407 -294.321802) (xy 275.539064 -294.370604) (xy 275.551674 -294.422076)
			(xy 275.555914 -294.4749) (xy 275.553828 -294.500887) (xy 275.84451 -294.500887) (xy 275.84451 -294.448913)
			(xy 275.85264 -294.397578) (xy 275.868701 -294.348148) (xy 275.892297 -294.301838) (xy 275.922847 -294.25979)
			(xy 275.959598 -294.223039) (xy 276.001646 -294.192489) (xy 276.047956 -294.168893) (xy 276.097386 -294.152832)
			(xy 276.148721 -294.144702) (xy 276.200695 -294.144702) (xy 276.25203 -294.152832) (xy 276.30146 -294.168893)
			(xy 276.34777 -294.192489) (xy 276.389818 -294.223039) (xy 276.426569 -294.25979) (xy 276.457119 -294.301838)
			(xy 276.480715 -294.348148) (xy 276.496776 -294.397578) (xy 276.504906 -294.448913) (xy 276.505416 -294.4749)
			(xy 276.504906 -294.500887) (xy 277.744684 -294.500887) (xy 277.744684 -294.448913) (xy 277.752814 -294.397578)
			(xy 277.768875 -294.348148) (xy 277.792471 -294.301838) (xy 277.823021 -294.25979) (xy 277.859772 -294.223039)
			(xy 277.90182 -294.192489) (xy 277.94813 -294.168893) (xy 277.99756 -294.152832) (xy 278.048895 -294.144702)
			(xy 278.100869 -294.144702) (xy 278.152204 -294.152832) (xy 278.201634 -294.168893) (xy 278.247944 -294.192489)
			(xy 278.289992 -294.223039) (xy 278.326743 -294.25979) (xy 278.357293 -294.301838) (xy 278.380889 -294.348148)
			(xy 278.39695 -294.397578) (xy 278.40508 -294.448913) (xy 278.40559 -294.4749) (xy 278.40508 -294.500887)
			(xy 278.694644 -294.500887) (xy 278.694644 -294.448913) (xy 278.702774 -294.397578) (xy 278.718835 -294.348148)
			(xy 278.742431 -294.301838) (xy 278.772981 -294.25979) (xy 278.809732 -294.223039) (xy 278.85178 -294.192489)
			(xy 278.89809 -294.168893) (xy 278.94752 -294.152832) (xy 278.998855 -294.144702) (xy 279.050829 -294.144702)
			(xy 279.102164 -294.152832) (xy 279.151594 -294.168893) (xy 279.197904 -294.192489) (xy 279.239952 -294.223039)
			(xy 279.276703 -294.25979) (xy 279.307253 -294.301838) (xy 279.330849 -294.348148) (xy 279.34691 -294.397578)
			(xy 279.35504 -294.448913) (xy 279.35555 -294.4749) (xy 279.35504 -294.500887) (xy 279.644604 -294.500887)
			(xy 279.644604 -294.448913) (xy 279.652734 -294.397578) (xy 279.668795 -294.348148) (xy 279.692391 -294.301838)
			(xy 279.722941 -294.25979) (xy 279.759692 -294.223039) (xy 279.80174 -294.192489) (xy 279.84805 -294.168893)
			(xy 279.89748 -294.152832) (xy 279.948815 -294.144702) (xy 280.000789 -294.144702) (xy 280.052124 -294.152832)
			(xy 280.101554 -294.168893) (xy 280.147864 -294.192489) (xy 280.189912 -294.223039) (xy 280.226663 -294.25979)
			(xy 280.257213 -294.301838) (xy 280.280809 -294.348148) (xy 280.29687 -294.397578) (xy 280.305 -294.448913)
			(xy 280.30551 -294.4749) (xy 280.305 -294.500887) (xy 280.594564 -294.500887) (xy 280.594564 -294.448913)
			(xy 280.602694 -294.397578) (xy 280.618755 -294.348148) (xy 280.642351 -294.301838) (xy 280.672901 -294.25979)
			(xy 280.709652 -294.223039) (xy 280.7517 -294.192489) (xy 280.79801 -294.168893) (xy 280.84744 -294.152832)
			(xy 280.898775 -294.144702) (xy 280.950749 -294.144702) (xy 281.002084 -294.152832) (xy 281.051514 -294.168893)
			(xy 281.097824 -294.192489) (xy 281.139872 -294.223039) (xy 281.176623 -294.25979) (xy 281.207173 -294.301838)
			(xy 281.230769 -294.348148) (xy 281.24683 -294.397578) (xy 281.25496 -294.448913) (xy 281.25547 -294.4749)
			(xy 281.25496 -294.500887) (xy 281.544524 -294.500887) (xy 281.544524 -294.448913) (xy 281.552654 -294.397578)
			(xy 281.568715 -294.348148) (xy 281.592311 -294.301838) (xy 281.622861 -294.25979) (xy 281.659612 -294.223039)
			(xy 281.70166 -294.192489) (xy 281.74797 -294.168893) (xy 281.7974 -294.152832) (xy 281.848735 -294.144702)
			(xy 281.900709 -294.144702) (xy 281.952044 -294.152832) (xy 282.001474 -294.168893) (xy 282.047784 -294.192489)
			(xy 282.089832 -294.223039) (xy 282.126583 -294.25979) (xy 282.157133 -294.301838) (xy 282.180729 -294.348148)
			(xy 282.19679 -294.397578) (xy 282.20492 -294.448913) (xy 282.20543 -294.4749) (xy 282.20492 -294.500887)
			(xy 282.494738 -294.500887) (xy 282.494738 -294.448913) (xy 282.502868 -294.397578) (xy 282.518929 -294.348148)
			(xy 282.542525 -294.301838) (xy 282.573075 -294.25979) (xy 282.609826 -294.223039) (xy 282.651874 -294.192489)
			(xy 282.698184 -294.168893) (xy 282.747614 -294.152832) (xy 282.798949 -294.144702) (xy 282.850923 -294.144702)
			(xy 282.902258 -294.152832) (xy 282.951688 -294.168893) (xy 282.997998 -294.192489) (xy 283.040046 -294.223039)
			(xy 283.076797 -294.25979) (xy 283.107347 -294.301838) (xy 283.130943 -294.348148) (xy 283.147004 -294.397578)
			(xy 283.155134 -294.448913) (xy 283.155644 -294.4749) (xy 283.155134 -294.500887) (xy 283.444698 -294.500887)
			(xy 283.444698 -294.448913) (xy 283.452828 -294.397578) (xy 283.468889 -294.348148) (xy 283.492485 -294.301838)
			(xy 283.523035 -294.25979) (xy 283.559786 -294.223039) (xy 283.601834 -294.192489) (xy 283.648144 -294.168893)
			(xy 283.697574 -294.152832) (xy 283.748909 -294.144702) (xy 283.800883 -294.144702) (xy 283.852218 -294.152832)
			(xy 283.901648 -294.168893) (xy 283.947958 -294.192489) (xy 283.990006 -294.223039) (xy 284.026757 -294.25979)
			(xy 284.057307 -294.301838) (xy 284.080903 -294.348148) (xy 284.096964 -294.397578) (xy 284.105094 -294.448913)
			(xy 284.105604 -294.4749) (xy 284.105094 -294.500887) (xy 284.394658 -294.500887) (xy 284.394658 -294.448913)
			(xy 284.402788 -294.397578) (xy 284.418849 -294.348148) (xy 284.442445 -294.301838) (xy 284.472995 -294.25979)
			(xy 284.509746 -294.223039) (xy 284.551794 -294.192489) (xy 284.598104 -294.168893) (xy 284.647534 -294.152832)
			(xy 284.698869 -294.144702) (xy 284.750843 -294.144702) (xy 284.802178 -294.152832) (xy 284.851608 -294.168893)
			(xy 284.897918 -294.192489) (xy 284.939966 -294.223039) (xy 284.976717 -294.25979) (xy 285.007267 -294.301838)
			(xy 285.030863 -294.348148) (xy 285.046924 -294.397578) (xy 285.055054 -294.448913) (xy 285.055564 -294.4749)
			(xy 285.055054 -294.500887) (xy 285.344618 -294.500887) (xy 285.344618 -294.448913) (xy 285.352748 -294.397578)
			(xy 285.368809 -294.348148) (xy 285.392405 -294.301838) (xy 285.422955 -294.25979) (xy 285.459706 -294.223039)
			(xy 285.501754 -294.192489) (xy 285.548064 -294.168893) (xy 285.597494 -294.152832) (xy 285.648829 -294.144702)
			(xy 285.700803 -294.144702) (xy 285.752138 -294.152832) (xy 285.801568 -294.168893) (xy 285.847878 -294.192489)
			(xy 285.889926 -294.223039) (xy 285.926677 -294.25979) (xy 285.957227 -294.301838) (xy 285.980823 -294.348148)
			(xy 285.996884 -294.397578) (xy 286.005014 -294.448913) (xy 286.005524 -294.4749) (xy 286.005014 -294.500887)
			(xy 286.294578 -294.500887) (xy 286.294578 -294.448913) (xy 286.302708 -294.397578) (xy 286.318769 -294.348148)
			(xy 286.342365 -294.301838) (xy 286.372915 -294.25979) (xy 286.409666 -294.223039) (xy 286.451714 -294.192489)
			(xy 286.498024 -294.168893) (xy 286.547454 -294.152832) (xy 286.598789 -294.144702) (xy 286.650763 -294.144702)
			(xy 286.702098 -294.152832) (xy 286.751528 -294.168893) (xy 286.797838 -294.192489) (xy 286.839886 -294.223039)
			(xy 286.876637 -294.25979) (xy 286.907187 -294.301838) (xy 286.930783 -294.348148) (xy 286.946844 -294.397578)
			(xy 286.954974 -294.448913) (xy 286.955484 -294.4749) (xy 286.954974 -294.500887) (xy 287.244538 -294.500887)
			(xy 287.244538 -294.448913) (xy 287.252668 -294.397578) (xy 287.268729 -294.348148) (xy 287.292325 -294.301838)
			(xy 287.322875 -294.25979) (xy 287.359626 -294.223039) (xy 287.401674 -294.192489) (xy 287.447984 -294.168893)
			(xy 287.497414 -294.152832) (xy 287.548749 -294.144702) (xy 287.600723 -294.144702) (xy 287.652058 -294.152832)
			(xy 287.701488 -294.168893) (xy 287.747798 -294.192489) (xy 287.789846 -294.223039) (xy 287.826597 -294.25979)
			(xy 287.857147 -294.301838) (xy 287.880743 -294.348148) (xy 287.896804 -294.397578) (xy 287.904934 -294.448913)
			(xy 287.905444 -294.4749) (xy 287.904934 -294.500887) (xy 288.194498 -294.500887) (xy 288.194498 -294.448913)
			(xy 288.202628 -294.397578) (xy 288.218689 -294.348148) (xy 288.242285 -294.301838) (xy 288.272835 -294.25979)
			(xy 288.309586 -294.223039) (xy 288.351634 -294.192489) (xy 288.397944 -294.168893) (xy 288.447374 -294.152832)
			(xy 288.498709 -294.144702) (xy 288.550683 -294.144702) (xy 288.602018 -294.152832) (xy 288.651448 -294.168893)
			(xy 288.697758 -294.192489) (xy 288.739806 -294.223039) (xy 288.776557 -294.25979) (xy 288.807107 -294.301838)
			(xy 288.830703 -294.348148) (xy 288.846764 -294.397578) (xy 288.854894 -294.448913) (xy 288.855404 -294.4749)
			(xy 288.854894 -294.500887) (xy 289.144712 -294.500887) (xy 289.144712 -294.448913) (xy 289.152842 -294.397578)
			(xy 289.168903 -294.348148) (xy 289.192499 -294.301838) (xy 289.223049 -294.25979) (xy 289.2598 -294.223039)
			(xy 289.301848 -294.192489) (xy 289.348158 -294.168893) (xy 289.397588 -294.152832) (xy 289.448923 -294.144702)
			(xy 289.500897 -294.144702) (xy 289.552232 -294.152832) (xy 289.601662 -294.168893) (xy 289.647972 -294.192489)
			(xy 289.69002 -294.223039) (xy 289.726771 -294.25979) (xy 289.757321 -294.301838) (xy 289.780917 -294.348148)
			(xy 289.796978 -294.397578) (xy 289.805108 -294.448913) (xy 289.805618 -294.4749) (xy 289.805108 -294.500887)
			(xy 290.094672 -294.500887) (xy 290.094672 -294.448913) (xy 290.102802 -294.397578) (xy 290.118863 -294.348148)
			(xy 290.142459 -294.301838) (xy 290.173009 -294.25979) (xy 290.20976 -294.223039) (xy 290.251808 -294.192489)
			(xy 290.298118 -294.168893) (xy 290.347548 -294.152832) (xy 290.398883 -294.144702) (xy 290.450857 -294.144702)
			(xy 290.502192 -294.152832) (xy 290.551622 -294.168893) (xy 290.597932 -294.192489) (xy 290.63998 -294.223039)
			(xy 290.676731 -294.25979) (xy 290.707281 -294.301838) (xy 290.730877 -294.348148) (xy 290.746938 -294.397578)
			(xy 290.755068 -294.448913) (xy 290.755578 -294.4749) (xy 290.755068 -294.500887) (xy 291.994592 -294.500887)
			(xy 291.994592 -294.448913) (xy 292.002722 -294.397578) (xy 292.018783 -294.348148) (xy 292.042379 -294.301838)
			(xy 292.072929 -294.25979) (xy 292.10968 -294.223039) (xy 292.151728 -294.192489) (xy 292.198038 -294.168893)
			(xy 292.247468 -294.152832) (xy 292.298803 -294.144702) (xy 292.350777 -294.144702) (xy 292.402112 -294.152832)
			(xy 292.451542 -294.168893) (xy 292.497852 -294.192489) (xy 292.5399 -294.223039) (xy 292.576651 -294.25979)
			(xy 292.607201 -294.301838) (xy 292.630797 -294.348148) (xy 292.646858 -294.397578) (xy 292.654988 -294.448913)
			(xy 292.655498 -294.4749) (xy 292.654988 -294.500887) (xy 292.944552 -294.500887) (xy 292.944552 -294.448913)
			(xy 292.952682 -294.397578) (xy 292.968743 -294.348148) (xy 292.992339 -294.301838) (xy 293.022889 -294.25979)
			(xy 293.05964 -294.223039) (xy 293.101688 -294.192489) (xy 293.147998 -294.168893) (xy 293.197428 -294.152832)
			(xy 293.248763 -294.144702) (xy 293.300737 -294.144702) (xy 293.352072 -294.152832) (xy 293.401502 -294.168893)
			(xy 293.447812 -294.192489) (xy 293.48986 -294.223039) (xy 293.526611 -294.25979) (xy 293.557161 -294.301838)
			(xy 293.580757 -294.348148) (xy 293.596818 -294.397578) (xy 293.604948 -294.448913) (xy 293.605458 -294.4749)
			(xy 293.604948 -294.500887) (xy 293.894512 -294.500887) (xy 293.894512 -294.448913) (xy 293.902642 -294.397578)
			(xy 293.918703 -294.348148) (xy 293.942299 -294.301838) (xy 293.972849 -294.25979) (xy 294.0096 -294.223039)
			(xy 294.051648 -294.192489) (xy 294.097958 -294.168893) (xy 294.147388 -294.152832) (xy 294.198723 -294.144702)
			(xy 294.250697 -294.144702) (xy 294.302032 -294.152832) (xy 294.351462 -294.168893) (xy 294.397772 -294.192489)
			(xy 294.43982 -294.223039) (xy 294.476571 -294.25979) (xy 294.507121 -294.301838) (xy 294.530717 -294.348148)
			(xy 294.546778 -294.397578) (xy 294.554908 -294.448913) (xy 294.555418 -294.4749) (xy 294.554908 -294.500887)
			(xy 294.844726 -294.500887) (xy 294.844726 -294.448913) (xy 294.852856 -294.397578) (xy 294.868917 -294.348148)
			(xy 294.892513 -294.301838) (xy 294.923063 -294.25979) (xy 294.959814 -294.223039) (xy 295.001862 -294.192489)
			(xy 295.048172 -294.168893) (xy 295.097602 -294.152832) (xy 295.148937 -294.144702) (xy 295.200911 -294.144702)
			(xy 295.252246 -294.152832) (xy 295.301676 -294.168893) (xy 295.347986 -294.192489) (xy 295.390034 -294.223039)
			(xy 295.426785 -294.25979) (xy 295.457335 -294.301838) (xy 295.480931 -294.348148) (xy 295.496992 -294.397578)
			(xy 295.505122 -294.448913) (xy 295.505632 -294.4749) (xy 295.505122 -294.500887) (xy 295.794686 -294.500887)
			(xy 295.794686 -294.448913) (xy 295.802816 -294.397578) (xy 295.818877 -294.348148) (xy 295.842473 -294.301838)
			(xy 295.873023 -294.25979) (xy 295.909774 -294.223039) (xy 295.951822 -294.192489) (xy 295.998132 -294.168893)
			(xy 296.047562 -294.152832) (xy 296.098897 -294.144702) (xy 296.150871 -294.144702) (xy 296.202206 -294.152832)
			(xy 296.251636 -294.168893) (xy 296.297946 -294.192489) (xy 296.339994 -294.223039) (xy 296.376745 -294.25979)
			(xy 296.407295 -294.301838) (xy 296.430891 -294.348148) (xy 296.446952 -294.397578) (xy 296.455082 -294.448913)
			(xy 296.455592 -294.4749) (xy 296.455082 -294.500887) (xy 296.744646 -294.500887) (xy 296.744646 -294.448913)
			(xy 296.752776 -294.397578) (xy 296.768837 -294.348148) (xy 296.792433 -294.301838) (xy 296.822983 -294.25979)
			(xy 296.859734 -294.223039) (xy 296.901782 -294.192489) (xy 296.948092 -294.168893) (xy 296.997522 -294.152832)
			(xy 297.048857 -294.144702) (xy 297.100831 -294.144702) (xy 297.152166 -294.152832) (xy 297.201596 -294.168893)
			(xy 297.247906 -294.192489) (xy 297.289954 -294.223039) (xy 297.326705 -294.25979) (xy 297.357255 -294.301838)
			(xy 297.380851 -294.348148) (xy 297.396912 -294.397578) (xy 297.405042 -294.448913) (xy 297.405552 -294.4749)
			(xy 297.405042 -294.500887) (xy 297.694606 -294.500887) (xy 297.694606 -294.448913) (xy 297.702736 -294.397578)
			(xy 297.718797 -294.348148) (xy 297.742393 -294.301838) (xy 297.772943 -294.25979) (xy 297.809694 -294.223039)
			(xy 297.851742 -294.192489) (xy 297.898052 -294.168893) (xy 297.947482 -294.152832) (xy 297.998817 -294.144702)
			(xy 298.050791 -294.144702) (xy 298.102126 -294.152832) (xy 298.151556 -294.168893) (xy 298.197866 -294.192489)
			(xy 298.239914 -294.223039) (xy 298.276665 -294.25979) (xy 298.307215 -294.301838) (xy 298.330811 -294.348148)
			(xy 298.346872 -294.397578) (xy 298.355002 -294.448913) (xy 298.355512 -294.4749) (xy 298.355002 -294.500887)
			(xy 298.644566 -294.500887) (xy 298.644566 -294.448913) (xy 298.652696 -294.397578) (xy 298.668757 -294.348148)
			(xy 298.692353 -294.301838) (xy 298.722903 -294.25979) (xy 298.759654 -294.223039) (xy 298.801702 -294.192489)
			(xy 298.848012 -294.168893) (xy 298.897442 -294.152832) (xy 298.948777 -294.144702) (xy 299.000751 -294.144702)
			(xy 299.052086 -294.152832) (xy 299.101516 -294.168893) (xy 299.147826 -294.192489) (xy 299.189874 -294.223039)
			(xy 299.226625 -294.25979) (xy 299.257175 -294.301838) (xy 299.280771 -294.348148) (xy 299.296832 -294.397578)
			(xy 299.304962 -294.448913) (xy 299.305472 -294.4749) (xy 299.304962 -294.500887) (xy 299.594526 -294.500887)
			(xy 299.594526 -294.448913) (xy 299.602656 -294.397578) (xy 299.618717 -294.348148) (xy 299.642313 -294.301838)
			(xy 299.672863 -294.25979) (xy 299.709614 -294.223039) (xy 299.751662 -294.192489) (xy 299.797972 -294.168893)
			(xy 299.847402 -294.152832) (xy 299.898737 -294.144702) (xy 299.950711 -294.144702) (xy 300.002046 -294.152832)
			(xy 300.051476 -294.168893) (xy 300.097786 -294.192489) (xy 300.139834 -294.223039) (xy 300.176585 -294.25979)
			(xy 300.207135 -294.301838) (xy 300.230731 -294.348148) (xy 300.246792 -294.397578) (xy 300.254922 -294.448913)
			(xy 300.255432 -294.4749) (xy 300.254922 -294.500887) (xy 300.544486 -294.500887) (xy 300.544486 -294.448913)
			(xy 300.552616 -294.397578) (xy 300.568677 -294.348148) (xy 300.592273 -294.301838) (xy 300.622823 -294.25979)
			(xy 300.659574 -294.223039) (xy 300.701622 -294.192489) (xy 300.747932 -294.168893) (xy 300.797362 -294.152832)
			(xy 300.848697 -294.144702) (xy 300.900671 -294.144702) (xy 300.952006 -294.152832) (xy 301.001436 -294.168893)
			(xy 301.047746 -294.192489) (xy 301.089794 -294.223039) (xy 301.126545 -294.25979) (xy 301.157095 -294.301838)
			(xy 301.180691 -294.348148) (xy 301.196752 -294.397578) (xy 301.204882 -294.448913) (xy 301.205392 -294.4749)
			(xy 301.204882 -294.500887) (xy 301.4947 -294.500887) (xy 301.4947 -294.448913) (xy 301.50283 -294.397578)
			(xy 301.518891 -294.348148) (xy 301.542487 -294.301838) (xy 301.573037 -294.25979) (xy 301.609788 -294.223039)
			(xy 301.651836 -294.192489) (xy 301.698146 -294.168893) (xy 301.747576 -294.152832) (xy 301.798911 -294.144702)
			(xy 301.850885 -294.144702) (xy 301.90222 -294.152832) (xy 301.95165 -294.168893) (xy 301.99796 -294.192489)
			(xy 302.040008 -294.223039) (xy 302.076759 -294.25979) (xy 302.107309 -294.301838) (xy 302.130905 -294.348148)
			(xy 302.146966 -294.397578) (xy 302.155096 -294.448913) (xy 302.155606 -294.4749) (xy 302.155096 -294.500887)
			(xy 302.146966 -294.552222) (xy 302.130905 -294.601652) (xy 302.107309 -294.647962) (xy 302.076759 -294.69001)
			(xy 302.040008 -294.726761) (xy 301.99796 -294.757311) (xy 301.95165 -294.780907) (xy 301.90222 -294.796968)
			(xy 301.850885 -294.805098) (xy 301.798911 -294.805098) (xy 301.747576 -294.796968) (xy 301.698146 -294.780907)
			(xy 301.651836 -294.757311) (xy 301.609788 -294.726761) (xy 301.573037 -294.69001) (xy 301.542487 -294.647962)
			(xy 301.518891 -294.601652) (xy 301.50283 -294.552222) (xy 301.4947 -294.500887) (xy 301.204882 -294.500887)
			(xy 301.196752 -294.552222) (xy 301.180691 -294.601652) (xy 301.157095 -294.647962) (xy 301.126545 -294.69001)
			(xy 301.089794 -294.726761) (xy 301.047746 -294.757311) (xy 301.001436 -294.780907) (xy 300.952006 -294.796968)
			(xy 300.900671 -294.805098) (xy 300.848697 -294.805098) (xy 300.797362 -294.796968) (xy 300.747932 -294.780907)
			(xy 300.701622 -294.757311) (xy 300.659574 -294.726761) (xy 300.622823 -294.69001) (xy 300.592273 -294.647962)
			(xy 300.568677 -294.601652) (xy 300.552616 -294.552222) (xy 300.544486 -294.500887) (xy 300.254922 -294.500887)
			(xy 300.246792 -294.552222) (xy 300.230731 -294.601652) (xy 300.207135 -294.647962) (xy 300.176585 -294.69001)
			(xy 300.139834 -294.726761) (xy 300.097786 -294.757311) (xy 300.051476 -294.780907) (xy 300.002046 -294.796968)
			(xy 299.950711 -294.805098) (xy 299.898737 -294.805098) (xy 299.847402 -294.796968) (xy 299.797972 -294.780907)
			(xy 299.751662 -294.757311) (xy 299.709614 -294.726761) (xy 299.672863 -294.69001) (xy 299.642313 -294.647962)
			(xy 299.618717 -294.601652) (xy 299.602656 -294.552222) (xy 299.594526 -294.500887) (xy 299.304962 -294.500887)
			(xy 299.296832 -294.552222) (xy 299.280771 -294.601652) (xy 299.257175 -294.647962) (xy 299.226625 -294.69001)
			(xy 299.189874 -294.726761) (xy 299.147826 -294.757311) (xy 299.101516 -294.780907) (xy 299.052086 -294.796968)
			(xy 299.000751 -294.805098) (xy 298.948777 -294.805098) (xy 298.897442 -294.796968) (xy 298.848012 -294.780907)
			(xy 298.801702 -294.757311) (xy 298.759654 -294.726761) (xy 298.722903 -294.69001) (xy 298.692353 -294.647962)
			(xy 298.668757 -294.601652) (xy 298.652696 -294.552222) (xy 298.644566 -294.500887) (xy 298.355002 -294.500887)
			(xy 298.346872 -294.552222) (xy 298.330811 -294.601652) (xy 298.307215 -294.647962) (xy 298.276665 -294.69001)
			(xy 298.239914 -294.726761) (xy 298.197866 -294.757311) (xy 298.151556 -294.780907) (xy 298.102126 -294.796968)
			(xy 298.050791 -294.805098) (xy 297.998817 -294.805098) (xy 297.947482 -294.796968) (xy 297.898052 -294.780907)
			(xy 297.851742 -294.757311) (xy 297.809694 -294.726761) (xy 297.772943 -294.69001) (xy 297.742393 -294.647962)
			(xy 297.718797 -294.601652) (xy 297.702736 -294.552222) (xy 297.694606 -294.500887) (xy 297.405042 -294.500887)
			(xy 297.396912 -294.552222) (xy 297.380851 -294.601652) (xy 297.357255 -294.647962) (xy 297.326705 -294.69001)
			(xy 297.289954 -294.726761) (xy 297.247906 -294.757311) (xy 297.201596 -294.780907) (xy 297.152166 -294.796968)
			(xy 297.100831 -294.805098) (xy 297.048857 -294.805098) (xy 296.997522 -294.796968) (xy 296.948092 -294.780907)
			(xy 296.901782 -294.757311) (xy 296.859734 -294.726761) (xy 296.822983 -294.69001) (xy 296.792433 -294.647962)
			(xy 296.768837 -294.601652) (xy 296.752776 -294.552222) (xy 296.744646 -294.500887) (xy 296.455082 -294.500887)
			(xy 296.446952 -294.552222) (xy 296.430891 -294.601652) (xy 296.407295 -294.647962) (xy 296.376745 -294.69001)
			(xy 296.339994 -294.726761) (xy 296.297946 -294.757311) (xy 296.251636 -294.780907) (xy 296.202206 -294.796968)
			(xy 296.150871 -294.805098) (xy 296.098897 -294.805098) (xy 296.047562 -294.796968) (xy 295.998132 -294.780907)
			(xy 295.951822 -294.757311) (xy 295.909774 -294.726761) (xy 295.873023 -294.69001) (xy 295.842473 -294.647962)
			(xy 295.818877 -294.601652) (xy 295.802816 -294.552222) (xy 295.794686 -294.500887) (xy 295.505122 -294.500887)
			(xy 295.496992 -294.552222) (xy 295.480931 -294.601652) (xy 295.457335 -294.647962) (xy 295.426785 -294.69001)
			(xy 295.390034 -294.726761) (xy 295.347986 -294.757311) (xy 295.301676 -294.780907) (xy 295.252246 -294.796968)
			(xy 295.200911 -294.805098) (xy 295.148937 -294.805098) (xy 295.097602 -294.796968) (xy 295.048172 -294.780907)
			(xy 295.001862 -294.757311) (xy 294.959814 -294.726761) (xy 294.923063 -294.69001) (xy 294.892513 -294.647962)
			(xy 294.868917 -294.601652) (xy 294.852856 -294.552222) (xy 294.844726 -294.500887) (xy 294.554908 -294.500887)
			(xy 294.546778 -294.552222) (xy 294.530717 -294.601652) (xy 294.507121 -294.647962) (xy 294.476571 -294.69001)
			(xy 294.43982 -294.726761) (xy 294.397772 -294.757311) (xy 294.351462 -294.780907) (xy 294.302032 -294.796968)
			(xy 294.250697 -294.805098) (xy 294.198723 -294.805098) (xy 294.147388 -294.796968) (xy 294.097958 -294.780907)
			(xy 294.051648 -294.757311) (xy 294.0096 -294.726761) (xy 293.972849 -294.69001) (xy 293.942299 -294.647962)
			(xy 293.918703 -294.601652) (xy 293.902642 -294.552222) (xy 293.894512 -294.500887) (xy 293.604948 -294.500887)
			(xy 293.596818 -294.552222) (xy 293.580757 -294.601652) (xy 293.557161 -294.647962) (xy 293.526611 -294.69001)
			(xy 293.48986 -294.726761) (xy 293.447812 -294.757311) (xy 293.401502 -294.780907) (xy 293.352072 -294.796968)
			(xy 293.300737 -294.805098) (xy 293.248763 -294.805098) (xy 293.197428 -294.796968) (xy 293.147998 -294.780907)
			(xy 293.101688 -294.757311) (xy 293.05964 -294.726761) (xy 293.022889 -294.69001) (xy 292.992339 -294.647962)
			(xy 292.968743 -294.601652) (xy 292.952682 -294.552222) (xy 292.944552 -294.500887) (xy 292.654988 -294.500887)
			(xy 292.646858 -294.552222) (xy 292.630797 -294.601652) (xy 292.607201 -294.647962) (xy 292.576651 -294.69001)
			(xy 292.5399 -294.726761) (xy 292.497852 -294.757311) (xy 292.451542 -294.780907) (xy 292.402112 -294.796968)
			(xy 292.350777 -294.805098) (xy 292.298803 -294.805098) (xy 292.247468 -294.796968) (xy 292.198038 -294.780907)
			(xy 292.151728 -294.757311) (xy 292.10968 -294.726761) (xy 292.072929 -294.69001) (xy 292.042379 -294.647962)
			(xy 292.018783 -294.601652) (xy 292.002722 -294.552222) (xy 291.994592 -294.500887) (xy 290.755068 -294.500887)
			(xy 290.746938 -294.552222) (xy 290.730877 -294.601652) (xy 290.707281 -294.647962) (xy 290.676731 -294.69001)
			(xy 290.63998 -294.726761) (xy 290.597932 -294.757311) (xy 290.551622 -294.780907) (xy 290.502192 -294.796968)
			(xy 290.450857 -294.805098) (xy 290.398883 -294.805098) (xy 290.347548 -294.796968) (xy 290.298118 -294.780907)
			(xy 290.251808 -294.757311) (xy 290.20976 -294.726761) (xy 290.173009 -294.69001) (xy 290.142459 -294.647962)
			(xy 290.118863 -294.601652) (xy 290.102802 -294.552222) (xy 290.094672 -294.500887) (xy 289.805108 -294.500887)
			(xy 289.796978 -294.552222) (xy 289.780917 -294.601652) (xy 289.757321 -294.647962) (xy 289.726771 -294.69001)
			(xy 289.69002 -294.726761) (xy 289.647972 -294.757311) (xy 289.601662 -294.780907) (xy 289.552232 -294.796968)
			(xy 289.500897 -294.805098) (xy 289.448923 -294.805098) (xy 289.397588 -294.796968) (xy 289.348158 -294.780907)
			(xy 289.301848 -294.757311) (xy 289.2598 -294.726761) (xy 289.223049 -294.69001) (xy 289.192499 -294.647962)
			(xy 289.168903 -294.601652) (xy 289.152842 -294.552222) (xy 289.144712 -294.500887) (xy 288.854894 -294.500887)
			(xy 288.846764 -294.552222) (xy 288.830703 -294.601652) (xy 288.807107 -294.647962) (xy 288.776557 -294.69001)
			(xy 288.739806 -294.726761) (xy 288.697758 -294.757311) (xy 288.651448 -294.780907) (xy 288.602018 -294.796968)
			(xy 288.550683 -294.805098) (xy 288.498709 -294.805098) (xy 288.447374 -294.796968) (xy 288.397944 -294.780907)
			(xy 288.351634 -294.757311) (xy 288.309586 -294.726761) (xy 288.272835 -294.69001) (xy 288.242285 -294.647962)
			(xy 288.218689 -294.601652) (xy 288.202628 -294.552222) (xy 288.194498 -294.500887) (xy 287.904934 -294.500887)
			(xy 287.896804 -294.552222) (xy 287.880743 -294.601652) (xy 287.857147 -294.647962) (xy 287.826597 -294.69001)
			(xy 287.789846 -294.726761) (xy 287.747798 -294.757311) (xy 287.701488 -294.780907) (xy 287.652058 -294.796968)
			(xy 287.600723 -294.805098) (xy 287.548749 -294.805098) (xy 287.497414 -294.796968) (xy 287.447984 -294.780907)
			(xy 287.401674 -294.757311) (xy 287.359626 -294.726761) (xy 287.322875 -294.69001) (xy 287.292325 -294.647962)
			(xy 287.268729 -294.601652) (xy 287.252668 -294.552222) (xy 287.244538 -294.500887) (xy 286.954974 -294.500887)
			(xy 286.946844 -294.552222) (xy 286.930783 -294.601652) (xy 286.907187 -294.647962) (xy 286.876637 -294.69001)
			(xy 286.839886 -294.726761) (xy 286.797838 -294.757311) (xy 286.751528 -294.780907) (xy 286.702098 -294.796968)
			(xy 286.650763 -294.805098) (xy 286.598789 -294.805098) (xy 286.547454 -294.796968) (xy 286.498024 -294.780907)
			(xy 286.451714 -294.757311) (xy 286.409666 -294.726761) (xy 286.372915 -294.69001) (xy 286.342365 -294.647962)
			(xy 286.318769 -294.601652) (xy 286.302708 -294.552222) (xy 286.294578 -294.500887) (xy 286.005014 -294.500887)
			(xy 285.996884 -294.552222) (xy 285.980823 -294.601652) (xy 285.957227 -294.647962) (xy 285.926677 -294.69001)
			(xy 285.889926 -294.726761) (xy 285.847878 -294.757311) (xy 285.801568 -294.780907) (xy 285.752138 -294.796968)
			(xy 285.700803 -294.805098) (xy 285.648829 -294.805098) (xy 285.597494 -294.796968) (xy 285.548064 -294.780907)
			(xy 285.501754 -294.757311) (xy 285.459706 -294.726761) (xy 285.422955 -294.69001) (xy 285.392405 -294.647962)
			(xy 285.368809 -294.601652) (xy 285.352748 -294.552222) (xy 285.344618 -294.500887) (xy 285.055054 -294.500887)
			(xy 285.046924 -294.552222) (xy 285.030863 -294.601652) (xy 285.007267 -294.647962) (xy 284.976717 -294.69001)
			(xy 284.939966 -294.726761) (xy 284.897918 -294.757311) (xy 284.851608 -294.780907) (xy 284.802178 -294.796968)
			(xy 284.750843 -294.805098) (xy 284.698869 -294.805098) (xy 284.647534 -294.796968) (xy 284.598104 -294.780907)
			(xy 284.551794 -294.757311) (xy 284.509746 -294.726761) (xy 284.472995 -294.69001) (xy 284.442445 -294.647962)
			(xy 284.418849 -294.601652) (xy 284.402788 -294.552222) (xy 284.394658 -294.500887) (xy 284.105094 -294.500887)
			(xy 284.096964 -294.552222) (xy 284.080903 -294.601652) (xy 284.057307 -294.647962) (xy 284.026757 -294.69001)
			(xy 283.990006 -294.726761) (xy 283.947958 -294.757311) (xy 283.901648 -294.780907) (xy 283.852218 -294.796968)
			(xy 283.800883 -294.805098) (xy 283.748909 -294.805098) (xy 283.697574 -294.796968) (xy 283.648144 -294.780907)
			(xy 283.601834 -294.757311) (xy 283.559786 -294.726761) (xy 283.523035 -294.69001) (xy 283.492485 -294.647962)
			(xy 283.468889 -294.601652) (xy 283.452828 -294.552222) (xy 283.444698 -294.500887) (xy 283.155134 -294.500887)
			(xy 283.147004 -294.552222) (xy 283.130943 -294.601652) (xy 283.107347 -294.647962) (xy 283.076797 -294.69001)
			(xy 283.040046 -294.726761) (xy 282.997998 -294.757311) (xy 282.951688 -294.780907) (xy 282.902258 -294.796968)
			(xy 282.850923 -294.805098) (xy 282.798949 -294.805098) (xy 282.747614 -294.796968) (xy 282.698184 -294.780907)
			(xy 282.651874 -294.757311) (xy 282.609826 -294.726761) (xy 282.573075 -294.69001) (xy 282.542525 -294.647962)
			(xy 282.518929 -294.601652) (xy 282.502868 -294.552222) (xy 282.494738 -294.500887) (xy 282.20492 -294.500887)
			(xy 282.19679 -294.552222) (xy 282.180729 -294.601652) (xy 282.157133 -294.647962) (xy 282.126583 -294.69001)
			(xy 282.089832 -294.726761) (xy 282.047784 -294.757311) (xy 282.001474 -294.780907) (xy 281.952044 -294.796968)
			(xy 281.900709 -294.805098) (xy 281.848735 -294.805098) (xy 281.7974 -294.796968) (xy 281.74797 -294.780907)
			(xy 281.70166 -294.757311) (xy 281.659612 -294.726761) (xy 281.622861 -294.69001) (xy 281.592311 -294.647962)
			(xy 281.568715 -294.601652) (xy 281.552654 -294.552222) (xy 281.544524 -294.500887) (xy 281.25496 -294.500887)
			(xy 281.24683 -294.552222) (xy 281.230769 -294.601652) (xy 281.207173 -294.647962) (xy 281.176623 -294.69001)
			(xy 281.139872 -294.726761) (xy 281.097824 -294.757311) (xy 281.051514 -294.780907) (xy 281.002084 -294.796968)
			(xy 280.950749 -294.805098) (xy 280.898775 -294.805098) (xy 280.84744 -294.796968) (xy 280.79801 -294.780907)
			(xy 280.7517 -294.757311) (xy 280.709652 -294.726761) (xy 280.672901 -294.69001) (xy 280.642351 -294.647962)
			(xy 280.618755 -294.601652) (xy 280.602694 -294.552222) (xy 280.594564 -294.500887) (xy 280.305 -294.500887)
			(xy 280.29687 -294.552222) (xy 280.280809 -294.601652) (xy 280.257213 -294.647962) (xy 280.226663 -294.69001)
			(xy 280.189912 -294.726761) (xy 280.147864 -294.757311) (xy 280.101554 -294.780907) (xy 280.052124 -294.796968)
			(xy 280.000789 -294.805098) (xy 279.948815 -294.805098) (xy 279.89748 -294.796968) (xy 279.84805 -294.780907)
			(xy 279.80174 -294.757311) (xy 279.759692 -294.726761) (xy 279.722941 -294.69001) (xy 279.692391 -294.647962)
			(xy 279.668795 -294.601652) (xy 279.652734 -294.552222) (xy 279.644604 -294.500887) (xy 279.35504 -294.500887)
			(xy 279.34691 -294.552222) (xy 279.330849 -294.601652) (xy 279.307253 -294.647962) (xy 279.276703 -294.69001)
			(xy 279.239952 -294.726761) (xy 279.197904 -294.757311) (xy 279.151594 -294.780907) (xy 279.102164 -294.796968)
			(xy 279.050829 -294.805098) (xy 278.998855 -294.805098) (xy 278.94752 -294.796968) (xy 278.89809 -294.780907)
			(xy 278.85178 -294.757311) (xy 278.809732 -294.726761) (xy 278.772981 -294.69001) (xy 278.742431 -294.647962)
			(xy 278.718835 -294.601652) (xy 278.702774 -294.552222) (xy 278.694644 -294.500887) (xy 278.40508 -294.500887)
			(xy 278.39695 -294.552222) (xy 278.380889 -294.601652) (xy 278.357293 -294.647962) (xy 278.326743 -294.69001)
			(xy 278.289992 -294.726761) (xy 278.247944 -294.757311) (xy 278.201634 -294.780907) (xy 278.152204 -294.796968)
			(xy 278.100869 -294.805098) (xy 278.048895 -294.805098) (xy 277.99756 -294.796968) (xy 277.94813 -294.780907)
			(xy 277.90182 -294.757311) (xy 277.859772 -294.726761) (xy 277.823021 -294.69001) (xy 277.792471 -294.647962)
			(xy 277.768875 -294.601652) (xy 277.752814 -294.552222) (xy 277.744684 -294.500887) (xy 276.504906 -294.500887)
			(xy 276.496776 -294.552222) (xy 276.480715 -294.601652) (xy 276.457119 -294.647962) (xy 276.426569 -294.69001)
			(xy 276.389818 -294.726761) (xy 276.34777 -294.757311) (xy 276.30146 -294.780907) (xy 276.25203 -294.796968)
			(xy 276.200695 -294.805098) (xy 276.148721 -294.805098) (xy 276.097386 -294.796968) (xy 276.047956 -294.780907)
			(xy 276.001646 -294.757311) (xy 275.959598 -294.726761) (xy 275.922847 -294.69001) (xy 275.892297 -294.647962)
			(xy 275.868701 -294.601652) (xy 275.85264 -294.552222) (xy 275.84451 -294.500887) (xy 275.553828 -294.500887)
			(xy 275.551674 -294.527724) (xy 275.539064 -294.579196) (xy 275.518407 -294.627998) (xy 275.49023 -294.672881)
			(xy 275.455256 -294.712695) (xy 275.41438 -294.746422) (xy 275.368647 -294.773198) (xy 275.344128 -294.783256)
			(xy 275.336762 -294.78605) (xy 275.325078 -294.795448) (xy 275.320506 -294.802052) (xy 275.316399 -294.808505)
			(xy 275.311872 -294.823109) (xy 275.311616 -294.830754) (xy 275.311616 -296.400807) (xy 275.84451 -296.400807)
			(xy 275.84451 -296.348833) (xy 275.85264 -296.297498) (xy 275.868701 -296.248068) (xy 275.892297 -296.201758)
			(xy 275.922847 -296.15971) (xy 275.959598 -296.122959) (xy 276.001646 -296.092409) (xy 276.047956 -296.068813)
			(xy 276.097386 -296.052752) (xy 276.148721 -296.044622) (xy 276.200695 -296.044622) (xy 276.25203 -296.052752)
			(xy 276.30146 -296.068813) (xy 276.34777 -296.092409) (xy 276.389818 -296.122959) (xy 276.426569 -296.15971)
			(xy 276.457119 -296.201758) (xy 276.480715 -296.248068) (xy 276.496776 -296.297498) (xy 276.504906 -296.348833)
			(xy 276.505416 -296.37482) (xy 276.504906 -296.400807) (xy 277.744684 -296.400807) (xy 277.744684 -296.348833)
			(xy 277.752814 -296.297498) (xy 277.768875 -296.248068) (xy 277.792471 -296.201758) (xy 277.823021 -296.15971)
			(xy 277.859772 -296.122959) (xy 277.90182 -296.092409) (xy 277.94813 -296.068813) (xy 277.99756 -296.052752)
			(xy 278.048895 -296.044622) (xy 278.100869 -296.044622) (xy 278.152204 -296.052752) (xy 278.201634 -296.068813)
			(xy 278.247944 -296.092409) (xy 278.289992 -296.122959) (xy 278.326743 -296.15971) (xy 278.357293 -296.201758)
			(xy 278.380889 -296.248068) (xy 278.39695 -296.297498) (xy 278.40508 -296.348833) (xy 278.40559 -296.37482)
			(xy 278.40508 -296.400807) (xy 278.694644 -296.400807) (xy 278.694644 -296.348833) (xy 278.702774 -296.297498)
			(xy 278.718835 -296.248068) (xy 278.742431 -296.201758) (xy 278.772981 -296.15971) (xy 278.809732 -296.122959)
			(xy 278.85178 -296.092409) (xy 278.89809 -296.068813) (xy 278.94752 -296.052752) (xy 278.998855 -296.044622)
			(xy 279.050829 -296.044622) (xy 279.102164 -296.052752) (xy 279.151594 -296.068813) (xy 279.197904 -296.092409)
			(xy 279.239952 -296.122959) (xy 279.276703 -296.15971) (xy 279.307253 -296.201758) (xy 279.330849 -296.248068)
			(xy 279.34691 -296.297498) (xy 279.35504 -296.348833) (xy 279.35555 -296.37482) (xy 279.35504 -296.400807)
			(xy 279.644604 -296.400807) (xy 279.644604 -296.348833) (xy 279.652734 -296.297498) (xy 279.668795 -296.248068)
			(xy 279.692391 -296.201758) (xy 279.722941 -296.15971) (xy 279.759692 -296.122959) (xy 279.80174 -296.092409)
			(xy 279.84805 -296.068813) (xy 279.89748 -296.052752) (xy 279.948815 -296.044622) (xy 280.000789 -296.044622)
			(xy 280.052124 -296.052752) (xy 280.101554 -296.068813) (xy 280.147864 -296.092409) (xy 280.189912 -296.122959)
			(xy 280.226663 -296.15971) (xy 280.257213 -296.201758) (xy 280.280809 -296.248068) (xy 280.29687 -296.297498)
			(xy 280.305 -296.348833) (xy 280.30551 -296.37482) (xy 280.305 -296.400807) (xy 280.594564 -296.400807)
			(xy 280.594564 -296.348833) (xy 280.602694 -296.297498) (xy 280.618755 -296.248068) (xy 280.642351 -296.201758)
			(xy 280.672901 -296.15971) (xy 280.709652 -296.122959) (xy 280.7517 -296.092409) (xy 280.79801 -296.068813)
			(xy 280.84744 -296.052752) (xy 280.898775 -296.044622) (xy 280.950749 -296.044622) (xy 281.002084 -296.052752)
			(xy 281.051514 -296.068813) (xy 281.097824 -296.092409) (xy 281.139872 -296.122959) (xy 281.176623 -296.15971)
			(xy 281.207173 -296.201758) (xy 281.230769 -296.248068) (xy 281.24683 -296.297498) (xy 281.25496 -296.348833)
			(xy 281.25547 -296.37482) (xy 281.25496 -296.400807) (xy 281.544524 -296.400807) (xy 281.544524 -296.348833)
			(xy 281.552654 -296.297498) (xy 281.568715 -296.248068) (xy 281.592311 -296.201758) (xy 281.622861 -296.15971)
			(xy 281.659612 -296.122959) (xy 281.70166 -296.092409) (xy 281.74797 -296.068813) (xy 281.7974 -296.052752)
			(xy 281.848735 -296.044622) (xy 281.900709 -296.044622) (xy 281.952044 -296.052752) (xy 282.001474 -296.068813)
			(xy 282.047784 -296.092409) (xy 282.089832 -296.122959) (xy 282.126583 -296.15971) (xy 282.157133 -296.201758)
			(xy 282.180729 -296.248068) (xy 282.19679 -296.297498) (xy 282.20492 -296.348833) (xy 282.20543 -296.37482)
			(xy 282.20492 -296.400807) (xy 282.494738 -296.400807) (xy 282.494738 -296.348833) (xy 282.502868 -296.297498)
			(xy 282.518929 -296.248068) (xy 282.542525 -296.201758) (xy 282.573075 -296.15971) (xy 282.609826 -296.122959)
			(xy 282.651874 -296.092409) (xy 282.698184 -296.068813) (xy 282.747614 -296.052752) (xy 282.798949 -296.044622)
			(xy 282.850923 -296.044622) (xy 282.902258 -296.052752) (xy 282.951688 -296.068813) (xy 282.997998 -296.092409)
			(xy 283.040046 -296.122959) (xy 283.076797 -296.15971) (xy 283.107347 -296.201758) (xy 283.130943 -296.248068)
			(xy 283.147004 -296.297498) (xy 283.155134 -296.348833) (xy 283.155644 -296.37482) (xy 283.155134 -296.400807)
			(xy 283.444698 -296.400807) (xy 283.444698 -296.348833) (xy 283.452828 -296.297498) (xy 283.468889 -296.248068)
			(xy 283.492485 -296.201758) (xy 283.523035 -296.15971) (xy 283.559786 -296.122959) (xy 283.601834 -296.092409)
			(xy 283.648144 -296.068813) (xy 283.697574 -296.052752) (xy 283.748909 -296.044622) (xy 283.800883 -296.044622)
			(xy 283.852218 -296.052752) (xy 283.901648 -296.068813) (xy 283.947958 -296.092409) (xy 283.990006 -296.122959)
			(xy 284.026757 -296.15971) (xy 284.057307 -296.201758) (xy 284.080903 -296.248068) (xy 284.096964 -296.297498)
			(xy 284.105094 -296.348833) (xy 284.105604 -296.37482) (xy 284.105094 -296.400807) (xy 284.394658 -296.400807)
			(xy 284.394658 -296.348833) (xy 284.402788 -296.297498) (xy 284.418849 -296.248068) (xy 284.442445 -296.201758)
			(xy 284.472995 -296.15971) (xy 284.509746 -296.122959) (xy 284.551794 -296.092409) (xy 284.598104 -296.068813)
			(xy 284.647534 -296.052752) (xy 284.698869 -296.044622) (xy 284.750843 -296.044622) (xy 284.802178 -296.052752)
			(xy 284.851608 -296.068813) (xy 284.897918 -296.092409) (xy 284.939966 -296.122959) (xy 284.976717 -296.15971)
			(xy 285.007267 -296.201758) (xy 285.030863 -296.248068) (xy 285.046924 -296.297498) (xy 285.055054 -296.348833)
			(xy 285.055564 -296.37482) (xy 285.055054 -296.400807) (xy 285.344618 -296.400807) (xy 285.344618 -296.348833)
			(xy 285.352748 -296.297498) (xy 285.368809 -296.248068) (xy 285.392405 -296.201758) (xy 285.422955 -296.15971)
			(xy 285.459706 -296.122959) (xy 285.501754 -296.092409) (xy 285.548064 -296.068813) (xy 285.597494 -296.052752)
			(xy 285.648829 -296.044622) (xy 285.700803 -296.044622) (xy 285.752138 -296.052752) (xy 285.801568 -296.068813)
			(xy 285.847878 -296.092409) (xy 285.889926 -296.122959) (xy 285.926677 -296.15971) (xy 285.957227 -296.201758)
			(xy 285.980823 -296.248068) (xy 285.996884 -296.297498) (xy 286.005014 -296.348833) (xy 286.005524 -296.37482)
			(xy 286.005014 -296.400807) (xy 286.294578 -296.400807) (xy 286.294578 -296.348833) (xy 286.302708 -296.297498)
			(xy 286.318769 -296.248068) (xy 286.342365 -296.201758) (xy 286.372915 -296.15971) (xy 286.409666 -296.122959)
			(xy 286.451714 -296.092409) (xy 286.498024 -296.068813) (xy 286.547454 -296.052752) (xy 286.598789 -296.044622)
			(xy 286.650763 -296.044622) (xy 286.702098 -296.052752) (xy 286.751528 -296.068813) (xy 286.797838 -296.092409)
			(xy 286.839886 -296.122959) (xy 286.876637 -296.15971) (xy 286.907187 -296.201758) (xy 286.930783 -296.248068)
			(xy 286.946844 -296.297498) (xy 286.954974 -296.348833) (xy 286.955484 -296.37482) (xy 286.954974 -296.400807)
			(xy 287.244538 -296.400807) (xy 287.244538 -296.348833) (xy 287.252668 -296.297498) (xy 287.268729 -296.248068)
			(xy 287.292325 -296.201758) (xy 287.322875 -296.15971) (xy 287.359626 -296.122959) (xy 287.401674 -296.092409)
			(xy 287.447984 -296.068813) (xy 287.497414 -296.052752) (xy 287.548749 -296.044622) (xy 287.600723 -296.044622)
			(xy 287.652058 -296.052752) (xy 287.701488 -296.068813) (xy 287.747798 -296.092409) (xy 287.789846 -296.122959)
			(xy 287.826597 -296.15971) (xy 287.857147 -296.201758) (xy 287.880743 -296.248068) (xy 287.896804 -296.297498)
			(xy 287.904934 -296.348833) (xy 287.905444 -296.37482) (xy 287.904934 -296.400807) (xy 288.194752 -296.400807)
			(xy 288.194752 -296.348833) (xy 288.202882 -296.297498) (xy 288.218943 -296.248068) (xy 288.242539 -296.201758)
			(xy 288.273089 -296.15971) (xy 288.30984 -296.122959) (xy 288.351888 -296.092409) (xy 288.398198 -296.068813)
			(xy 288.447628 -296.052752) (xy 288.498963 -296.044622) (xy 288.550937 -296.044622) (xy 288.602272 -296.052752)
			(xy 288.651702 -296.068813) (xy 288.698012 -296.092409) (xy 288.74006 -296.122959) (xy 288.776811 -296.15971)
			(xy 288.807361 -296.201758) (xy 288.830957 -296.248068) (xy 288.847018 -296.297498) (xy 288.855148 -296.348833)
			(xy 288.855658 -296.37482) (xy 288.855148 -296.400807) (xy 289.144712 -296.400807) (xy 289.144712 -296.348833)
			(xy 289.152842 -296.297498) (xy 289.168903 -296.248068) (xy 289.192499 -296.201758) (xy 289.223049 -296.15971)
			(xy 289.2598 -296.122959) (xy 289.301848 -296.092409) (xy 289.348158 -296.068813) (xy 289.397588 -296.052752)
			(xy 289.448923 -296.044622) (xy 289.500897 -296.044622) (xy 289.552232 -296.052752) (xy 289.601662 -296.068813)
			(xy 289.647972 -296.092409) (xy 289.69002 -296.122959) (xy 289.726771 -296.15971) (xy 289.757321 -296.201758)
			(xy 289.780917 -296.248068) (xy 289.796978 -296.297498) (xy 289.805108 -296.348833) (xy 289.805618 -296.37482)
			(xy 289.805108 -296.400807) (xy 290.094672 -296.400807) (xy 290.094672 -296.348833) (xy 290.102802 -296.297498)
			(xy 290.118863 -296.248068) (xy 290.142459 -296.201758) (xy 290.173009 -296.15971) (xy 290.20976 -296.122959)
			(xy 290.251808 -296.092409) (xy 290.298118 -296.068813) (xy 290.347548 -296.052752) (xy 290.398883 -296.044622)
			(xy 290.450857 -296.044622) (xy 290.502192 -296.052752) (xy 290.551622 -296.068813) (xy 290.597932 -296.092409)
			(xy 290.63998 -296.122959) (xy 290.676731 -296.15971) (xy 290.707281 -296.201758) (xy 290.730877 -296.248068)
			(xy 290.746938 -296.297498) (xy 290.755068 -296.348833) (xy 290.755578 -296.37482) (xy 290.755068 -296.400807)
			(xy 291.994592 -296.400807) (xy 291.994592 -296.348833) (xy 292.002722 -296.297498) (xy 292.018783 -296.248068)
			(xy 292.042379 -296.201758) (xy 292.072929 -296.15971) (xy 292.10968 -296.122959) (xy 292.151728 -296.092409)
			(xy 292.198038 -296.068813) (xy 292.247468 -296.052752) (xy 292.298803 -296.044622) (xy 292.350777 -296.044622)
			(xy 292.402112 -296.052752) (xy 292.451542 -296.068813) (xy 292.497852 -296.092409) (xy 292.5399 -296.122959)
			(xy 292.576651 -296.15971) (xy 292.607201 -296.201758) (xy 292.630797 -296.248068) (xy 292.646858 -296.297498)
			(xy 292.654988 -296.348833) (xy 292.655498 -296.37482) (xy 292.654988 -296.400807) (xy 292.944552 -296.400807)
			(xy 292.944552 -296.348833) (xy 292.952682 -296.297498) (xy 292.968743 -296.248068) (xy 292.992339 -296.201758)
			(xy 293.022889 -296.15971) (xy 293.05964 -296.122959) (xy 293.101688 -296.092409) (xy 293.147998 -296.068813)
			(xy 293.197428 -296.052752) (xy 293.248763 -296.044622) (xy 293.300737 -296.044622) (xy 293.352072 -296.052752)
			(xy 293.401502 -296.068813) (xy 293.447812 -296.092409) (xy 293.48986 -296.122959) (xy 293.526611 -296.15971)
			(xy 293.557161 -296.201758) (xy 293.580757 -296.248068) (xy 293.596818 -296.297498) (xy 293.604948 -296.348833)
			(xy 293.605458 -296.37482) (xy 293.604948 -296.400807) (xy 293.894512 -296.400807) (xy 293.894512 -296.348833)
			(xy 293.902642 -296.297498) (xy 293.918703 -296.248068) (xy 293.942299 -296.201758) (xy 293.972849 -296.15971)
			(xy 294.0096 -296.122959) (xy 294.051648 -296.092409) (xy 294.097958 -296.068813) (xy 294.147388 -296.052752)
			(xy 294.198723 -296.044622) (xy 294.250697 -296.044622) (xy 294.302032 -296.052752) (xy 294.351462 -296.068813)
			(xy 294.397772 -296.092409) (xy 294.43982 -296.122959) (xy 294.476571 -296.15971) (xy 294.507121 -296.201758)
			(xy 294.530717 -296.248068) (xy 294.546778 -296.297498) (xy 294.554908 -296.348833) (xy 294.555418 -296.37482)
			(xy 294.554908 -296.400807) (xy 294.844726 -296.400807) (xy 294.844726 -296.348833) (xy 294.852856 -296.297498)
			(xy 294.868917 -296.248068) (xy 294.892513 -296.201758) (xy 294.923063 -296.15971) (xy 294.959814 -296.122959)
			(xy 295.001862 -296.092409) (xy 295.048172 -296.068813) (xy 295.097602 -296.052752) (xy 295.148937 -296.044622)
			(xy 295.200911 -296.044622) (xy 295.252246 -296.052752) (xy 295.301676 -296.068813) (xy 295.347986 -296.092409)
			(xy 295.390034 -296.122959) (xy 295.426785 -296.15971) (xy 295.457335 -296.201758) (xy 295.480931 -296.248068)
			(xy 295.496992 -296.297498) (xy 295.505122 -296.348833) (xy 295.505632 -296.37482) (xy 295.505122 -296.400807)
			(xy 295.794686 -296.400807) (xy 295.794686 -296.348833) (xy 295.802816 -296.297498) (xy 295.818877 -296.248068)
			(xy 295.842473 -296.201758) (xy 295.873023 -296.15971) (xy 295.909774 -296.122959) (xy 295.951822 -296.092409)
			(xy 295.998132 -296.068813) (xy 296.047562 -296.052752) (xy 296.098897 -296.044622) (xy 296.150871 -296.044622)
			(xy 296.202206 -296.052752) (xy 296.251636 -296.068813) (xy 296.297946 -296.092409) (xy 296.339994 -296.122959)
			(xy 296.376745 -296.15971) (xy 296.407295 -296.201758) (xy 296.430891 -296.248068) (xy 296.446952 -296.297498)
			(xy 296.455082 -296.348833) (xy 296.455592 -296.37482) (xy 296.455082 -296.400807) (xy 296.744646 -296.400807)
			(xy 296.744646 -296.348833) (xy 296.752776 -296.297498) (xy 296.768837 -296.248068) (xy 296.792433 -296.201758)
			(xy 296.822983 -296.15971) (xy 296.859734 -296.122959) (xy 296.901782 -296.092409) (xy 296.948092 -296.068813)
			(xy 296.997522 -296.052752) (xy 297.048857 -296.044622) (xy 297.100831 -296.044622) (xy 297.152166 -296.052752)
			(xy 297.201596 -296.068813) (xy 297.247906 -296.092409) (xy 297.289954 -296.122959) (xy 297.326705 -296.15971)
			(xy 297.357255 -296.201758) (xy 297.380851 -296.248068) (xy 297.396912 -296.297498) (xy 297.405042 -296.348833)
			(xy 297.405552 -296.37482) (xy 297.405042 -296.400807) (xy 297.694606 -296.400807) (xy 297.694606 -296.348833)
			(xy 297.702736 -296.297498) (xy 297.718797 -296.248068) (xy 297.742393 -296.201758) (xy 297.772943 -296.15971)
			(xy 297.809694 -296.122959) (xy 297.851742 -296.092409) (xy 297.898052 -296.068813) (xy 297.947482 -296.052752)
			(xy 297.998817 -296.044622) (xy 298.050791 -296.044622) (xy 298.102126 -296.052752) (xy 298.151556 -296.068813)
			(xy 298.197866 -296.092409) (xy 298.239914 -296.122959) (xy 298.276665 -296.15971) (xy 298.307215 -296.201758)
			(xy 298.330811 -296.248068) (xy 298.346872 -296.297498) (xy 298.355002 -296.348833) (xy 298.355512 -296.37482)
			(xy 298.355002 -296.400807) (xy 298.644566 -296.400807) (xy 298.644566 -296.348833) (xy 298.652696 -296.297498)
			(xy 298.668757 -296.248068) (xy 298.692353 -296.201758) (xy 298.722903 -296.15971) (xy 298.759654 -296.122959)
			(xy 298.801702 -296.092409) (xy 298.848012 -296.068813) (xy 298.897442 -296.052752) (xy 298.948777 -296.044622)
			(xy 299.000751 -296.044622) (xy 299.052086 -296.052752) (xy 299.101516 -296.068813) (xy 299.147826 -296.092409)
			(xy 299.189874 -296.122959) (xy 299.226625 -296.15971) (xy 299.257175 -296.201758) (xy 299.280771 -296.248068)
			(xy 299.296832 -296.297498) (xy 299.304962 -296.348833) (xy 299.305472 -296.37482) (xy 299.304962 -296.400807)
			(xy 299.594526 -296.400807) (xy 299.594526 -296.348833) (xy 299.602656 -296.297498) (xy 299.618717 -296.248068)
			(xy 299.642313 -296.201758) (xy 299.672863 -296.15971) (xy 299.709614 -296.122959) (xy 299.751662 -296.092409)
			(xy 299.797972 -296.068813) (xy 299.847402 -296.052752) (xy 299.898737 -296.044622) (xy 299.950711 -296.044622)
			(xy 300.002046 -296.052752) (xy 300.051476 -296.068813) (xy 300.097786 -296.092409) (xy 300.139834 -296.122959)
			(xy 300.176585 -296.15971) (xy 300.207135 -296.201758) (xy 300.230731 -296.248068) (xy 300.246792 -296.297498)
			(xy 300.254922 -296.348833) (xy 300.255432 -296.37482) (xy 300.254922 -296.400807) (xy 300.544486 -296.400807)
			(xy 300.544486 -296.348833) (xy 300.552616 -296.297498) (xy 300.568677 -296.248068) (xy 300.592273 -296.201758)
			(xy 300.622823 -296.15971) (xy 300.659574 -296.122959) (xy 300.701622 -296.092409) (xy 300.747932 -296.068813)
			(xy 300.797362 -296.052752) (xy 300.848697 -296.044622) (xy 300.900671 -296.044622) (xy 300.952006 -296.052752)
			(xy 301.001436 -296.068813) (xy 301.047746 -296.092409) (xy 301.089794 -296.122959) (xy 301.126545 -296.15971)
			(xy 301.157095 -296.201758) (xy 301.180691 -296.248068) (xy 301.196752 -296.297498) (xy 301.204882 -296.348833)
			(xy 301.205392 -296.37482) (xy 301.204882 -296.400807) (xy 301.4947 -296.400807) (xy 301.4947 -296.348833)
			(xy 301.50283 -296.297498) (xy 301.518891 -296.248068) (xy 301.542487 -296.201758) (xy 301.573037 -296.15971)
			(xy 301.609788 -296.122959) (xy 301.651836 -296.092409) (xy 301.698146 -296.068813) (xy 301.747576 -296.052752)
			(xy 301.798911 -296.044622) (xy 301.850885 -296.044622) (xy 301.90222 -296.052752) (xy 301.95165 -296.068813)
			(xy 301.99796 -296.092409) (xy 302.040008 -296.122959) (xy 302.076759 -296.15971) (xy 302.107309 -296.201758)
			(xy 302.130905 -296.248068) (xy 302.146966 -296.297498) (xy 302.155096 -296.348833) (xy 302.155606 -296.37482)
			(xy 302.155096 -296.400807) (xy 302.146966 -296.452142) (xy 302.130905 -296.501572) (xy 302.107309 -296.547882)
			(xy 302.076759 -296.58993) (xy 302.040008 -296.626681) (xy 301.99796 -296.657231) (xy 301.95165 -296.680827)
			(xy 301.90222 -296.696888) (xy 301.850885 -296.705018) (xy 301.798911 -296.705018) (xy 301.747576 -296.696888)
			(xy 301.698146 -296.680827) (xy 301.651836 -296.657231) (xy 301.609788 -296.626681) (xy 301.573037 -296.58993)
			(xy 301.542487 -296.547882) (xy 301.518891 -296.501572) (xy 301.50283 -296.452142) (xy 301.4947 -296.400807)
			(xy 301.204882 -296.400807) (xy 301.196752 -296.452142) (xy 301.180691 -296.501572) (xy 301.157095 -296.547882)
			(xy 301.126545 -296.58993) (xy 301.089794 -296.626681) (xy 301.047746 -296.657231) (xy 301.001436 -296.680827)
			(xy 300.952006 -296.696888) (xy 300.900671 -296.705018) (xy 300.848697 -296.705018) (xy 300.797362 -296.696888)
			(xy 300.747932 -296.680827) (xy 300.701622 -296.657231) (xy 300.659574 -296.626681) (xy 300.622823 -296.58993)
			(xy 300.592273 -296.547882) (xy 300.568677 -296.501572) (xy 300.552616 -296.452142) (xy 300.544486 -296.400807)
			(xy 300.254922 -296.400807) (xy 300.246792 -296.452142) (xy 300.230731 -296.501572) (xy 300.207135 -296.547882)
			(xy 300.176585 -296.58993) (xy 300.139834 -296.626681) (xy 300.097786 -296.657231) (xy 300.051476 -296.680827)
			(xy 300.002046 -296.696888) (xy 299.950711 -296.705018) (xy 299.898737 -296.705018) (xy 299.847402 -296.696888)
			(xy 299.797972 -296.680827) (xy 299.751662 -296.657231) (xy 299.709614 -296.626681) (xy 299.672863 -296.58993)
			(xy 299.642313 -296.547882) (xy 299.618717 -296.501572) (xy 299.602656 -296.452142) (xy 299.594526 -296.400807)
			(xy 299.304962 -296.400807) (xy 299.296832 -296.452142) (xy 299.280771 -296.501572) (xy 299.257175 -296.547882)
			(xy 299.226625 -296.58993) (xy 299.189874 -296.626681) (xy 299.147826 -296.657231) (xy 299.101516 -296.680827)
			(xy 299.052086 -296.696888) (xy 299.000751 -296.705018) (xy 298.948777 -296.705018) (xy 298.897442 -296.696888)
			(xy 298.848012 -296.680827) (xy 298.801702 -296.657231) (xy 298.759654 -296.626681) (xy 298.722903 -296.58993)
			(xy 298.692353 -296.547882) (xy 298.668757 -296.501572) (xy 298.652696 -296.452142) (xy 298.644566 -296.400807)
			(xy 298.355002 -296.400807) (xy 298.346872 -296.452142) (xy 298.330811 -296.501572) (xy 298.307215 -296.547882)
			(xy 298.276665 -296.58993) (xy 298.239914 -296.626681) (xy 298.197866 -296.657231) (xy 298.151556 -296.680827)
			(xy 298.102126 -296.696888) (xy 298.050791 -296.705018) (xy 297.998817 -296.705018) (xy 297.947482 -296.696888)
			(xy 297.898052 -296.680827) (xy 297.851742 -296.657231) (xy 297.809694 -296.626681) (xy 297.772943 -296.58993)
			(xy 297.742393 -296.547882) (xy 297.718797 -296.501572) (xy 297.702736 -296.452142) (xy 297.694606 -296.400807)
			(xy 297.405042 -296.400807) (xy 297.396912 -296.452142) (xy 297.380851 -296.501572) (xy 297.357255 -296.547882)
			(xy 297.326705 -296.58993) (xy 297.289954 -296.626681) (xy 297.247906 -296.657231) (xy 297.201596 -296.680827)
			(xy 297.152166 -296.696888) (xy 297.100831 -296.705018) (xy 297.048857 -296.705018) (xy 296.997522 -296.696888)
			(xy 296.948092 -296.680827) (xy 296.901782 -296.657231) (xy 296.859734 -296.626681) (xy 296.822983 -296.58993)
			(xy 296.792433 -296.547882) (xy 296.768837 -296.501572) (xy 296.752776 -296.452142) (xy 296.744646 -296.400807)
			(xy 296.455082 -296.400807) (xy 296.446952 -296.452142) (xy 296.430891 -296.501572) (xy 296.407295 -296.547882)
			(xy 296.376745 -296.58993) (xy 296.339994 -296.626681) (xy 296.297946 -296.657231) (xy 296.251636 -296.680827)
			(xy 296.202206 -296.696888) (xy 296.150871 -296.705018) (xy 296.098897 -296.705018) (xy 296.047562 -296.696888)
			(xy 295.998132 -296.680827) (xy 295.951822 -296.657231) (xy 295.909774 -296.626681) (xy 295.873023 -296.58993)
			(xy 295.842473 -296.547882) (xy 295.818877 -296.501572) (xy 295.802816 -296.452142) (xy 295.794686 -296.400807)
			(xy 295.505122 -296.400807) (xy 295.496992 -296.452142) (xy 295.480931 -296.501572) (xy 295.457335 -296.547882)
			(xy 295.426785 -296.58993) (xy 295.390034 -296.626681) (xy 295.347986 -296.657231) (xy 295.301676 -296.680827)
			(xy 295.252246 -296.696888) (xy 295.200911 -296.705018) (xy 295.148937 -296.705018) (xy 295.097602 -296.696888)
			(xy 295.048172 -296.680827) (xy 295.001862 -296.657231) (xy 294.959814 -296.626681) (xy 294.923063 -296.58993)
			(xy 294.892513 -296.547882) (xy 294.868917 -296.501572) (xy 294.852856 -296.452142) (xy 294.844726 -296.400807)
			(xy 294.554908 -296.400807) (xy 294.546778 -296.452142) (xy 294.530717 -296.501572) (xy 294.507121 -296.547882)
			(xy 294.476571 -296.58993) (xy 294.43982 -296.626681) (xy 294.397772 -296.657231) (xy 294.351462 -296.680827)
			(xy 294.302032 -296.696888) (xy 294.250697 -296.705018) (xy 294.198723 -296.705018) (xy 294.147388 -296.696888)
			(xy 294.097958 -296.680827) (xy 294.051648 -296.657231) (xy 294.0096 -296.626681) (xy 293.972849 -296.58993)
			(xy 293.942299 -296.547882) (xy 293.918703 -296.501572) (xy 293.902642 -296.452142) (xy 293.894512 -296.400807)
			(xy 293.604948 -296.400807) (xy 293.596818 -296.452142) (xy 293.580757 -296.501572) (xy 293.557161 -296.547882)
			(xy 293.526611 -296.58993) (xy 293.48986 -296.626681) (xy 293.447812 -296.657231) (xy 293.401502 -296.680827)
			(xy 293.352072 -296.696888) (xy 293.300737 -296.705018) (xy 293.248763 -296.705018) (xy 293.197428 -296.696888)
			(xy 293.147998 -296.680827) (xy 293.101688 -296.657231) (xy 293.05964 -296.626681) (xy 293.022889 -296.58993)
			(xy 292.992339 -296.547882) (xy 292.968743 -296.501572) (xy 292.952682 -296.452142) (xy 292.944552 -296.400807)
			(xy 292.654988 -296.400807) (xy 292.646858 -296.452142) (xy 292.630797 -296.501572) (xy 292.607201 -296.547882)
			(xy 292.576651 -296.58993) (xy 292.5399 -296.626681) (xy 292.497852 -296.657231) (xy 292.451542 -296.680827)
			(xy 292.402112 -296.696888) (xy 292.350777 -296.705018) (xy 292.298803 -296.705018) (xy 292.247468 -296.696888)
			(xy 292.198038 -296.680827) (xy 292.151728 -296.657231) (xy 292.10968 -296.626681) (xy 292.072929 -296.58993)
			(xy 292.042379 -296.547882) (xy 292.018783 -296.501572) (xy 292.002722 -296.452142) (xy 291.994592 -296.400807)
			(xy 290.755068 -296.400807) (xy 290.746938 -296.452142) (xy 290.730877 -296.501572) (xy 290.707281 -296.547882)
			(xy 290.676731 -296.58993) (xy 290.63998 -296.626681) (xy 290.597932 -296.657231) (xy 290.551622 -296.680827)
			(xy 290.502192 -296.696888) (xy 290.450857 -296.705018) (xy 290.398883 -296.705018) (xy 290.347548 -296.696888)
			(xy 290.298118 -296.680827) (xy 290.251808 -296.657231) (xy 290.20976 -296.626681) (xy 290.173009 -296.58993)
			(xy 290.142459 -296.547882) (xy 290.118863 -296.501572) (xy 290.102802 -296.452142) (xy 290.094672 -296.400807)
			(xy 289.805108 -296.400807) (xy 289.796978 -296.452142) (xy 289.780917 -296.501572) (xy 289.757321 -296.547882)
			(xy 289.726771 -296.58993) (xy 289.69002 -296.626681) (xy 289.647972 -296.657231) (xy 289.601662 -296.680827)
			(xy 289.552232 -296.696888) (xy 289.500897 -296.705018) (xy 289.448923 -296.705018) (xy 289.397588 -296.696888)
			(xy 289.348158 -296.680827) (xy 289.301848 -296.657231) (xy 289.2598 -296.626681) (xy 289.223049 -296.58993)
			(xy 289.192499 -296.547882) (xy 289.168903 -296.501572) (xy 289.152842 -296.452142) (xy 289.144712 -296.400807)
			(xy 288.855148 -296.400807) (xy 288.847018 -296.452142) (xy 288.830957 -296.501572) (xy 288.807361 -296.547882)
			(xy 288.776811 -296.58993) (xy 288.74006 -296.626681) (xy 288.698012 -296.657231) (xy 288.651702 -296.680827)
			(xy 288.602272 -296.696888) (xy 288.550937 -296.705018) (xy 288.498963 -296.705018) (xy 288.447628 -296.696888)
			(xy 288.398198 -296.680827) (xy 288.351888 -296.657231) (xy 288.30984 -296.626681) (xy 288.273089 -296.58993)
			(xy 288.242539 -296.547882) (xy 288.218943 -296.501572) (xy 288.202882 -296.452142) (xy 288.194752 -296.400807)
			(xy 287.904934 -296.400807) (xy 287.896804 -296.452142) (xy 287.880743 -296.501572) (xy 287.857147 -296.547882)
			(xy 287.826597 -296.58993) (xy 287.789846 -296.626681) (xy 287.747798 -296.657231) (xy 287.701488 -296.680827)
			(xy 287.652058 -296.696888) (xy 287.600723 -296.705018) (xy 287.548749 -296.705018) (xy 287.497414 -296.696888)
			(xy 287.447984 -296.680827) (xy 287.401674 -296.657231) (xy 287.359626 -296.626681) (xy 287.322875 -296.58993)
			(xy 287.292325 -296.547882) (xy 287.268729 -296.501572) (xy 287.252668 -296.452142) (xy 287.244538 -296.400807)
			(xy 286.954974 -296.400807) (xy 286.946844 -296.452142) (xy 286.930783 -296.501572) (xy 286.907187 -296.547882)
			(xy 286.876637 -296.58993) (xy 286.839886 -296.626681) (xy 286.797838 -296.657231) (xy 286.751528 -296.680827)
			(xy 286.702098 -296.696888) (xy 286.650763 -296.705018) (xy 286.598789 -296.705018) (xy 286.547454 -296.696888)
			(xy 286.498024 -296.680827) (xy 286.451714 -296.657231) (xy 286.409666 -296.626681) (xy 286.372915 -296.58993)
			(xy 286.342365 -296.547882) (xy 286.318769 -296.501572) (xy 286.302708 -296.452142) (xy 286.294578 -296.400807)
			(xy 286.005014 -296.400807) (xy 285.996884 -296.452142) (xy 285.980823 -296.501572) (xy 285.957227 -296.547882)
			(xy 285.926677 -296.58993) (xy 285.889926 -296.626681) (xy 285.847878 -296.657231) (xy 285.801568 -296.680827)
			(xy 285.752138 -296.696888) (xy 285.700803 -296.705018) (xy 285.648829 -296.705018) (xy 285.597494 -296.696888)
			(xy 285.548064 -296.680827) (xy 285.501754 -296.657231) (xy 285.459706 -296.626681) (xy 285.422955 -296.58993)
			(xy 285.392405 -296.547882) (xy 285.368809 -296.501572) (xy 285.352748 -296.452142) (xy 285.344618 -296.400807)
			(xy 285.055054 -296.400807) (xy 285.046924 -296.452142) (xy 285.030863 -296.501572) (xy 285.007267 -296.547882)
			(xy 284.976717 -296.58993) (xy 284.939966 -296.626681) (xy 284.897918 -296.657231) (xy 284.851608 -296.680827)
			(xy 284.802178 -296.696888) (xy 284.750843 -296.705018) (xy 284.698869 -296.705018) (xy 284.647534 -296.696888)
			(xy 284.598104 -296.680827) (xy 284.551794 -296.657231) (xy 284.509746 -296.626681) (xy 284.472995 -296.58993)
			(xy 284.442445 -296.547882) (xy 284.418849 -296.501572) (xy 284.402788 -296.452142) (xy 284.394658 -296.400807)
			(xy 284.105094 -296.400807) (xy 284.096964 -296.452142) (xy 284.080903 -296.501572) (xy 284.057307 -296.547882)
			(xy 284.026757 -296.58993) (xy 283.990006 -296.626681) (xy 283.947958 -296.657231) (xy 283.901648 -296.680827)
			(xy 283.852218 -296.696888) (xy 283.800883 -296.705018) (xy 283.748909 -296.705018) (xy 283.697574 -296.696888)
			(xy 283.648144 -296.680827) (xy 283.601834 -296.657231) (xy 283.559786 -296.626681) (xy 283.523035 -296.58993)
			(xy 283.492485 -296.547882) (xy 283.468889 -296.501572) (xy 283.452828 -296.452142) (xy 283.444698 -296.400807)
			(xy 283.155134 -296.400807) (xy 283.147004 -296.452142) (xy 283.130943 -296.501572) (xy 283.107347 -296.547882)
			(xy 283.076797 -296.58993) (xy 283.040046 -296.626681) (xy 282.997998 -296.657231) (xy 282.951688 -296.680827)
			(xy 282.902258 -296.696888) (xy 282.850923 -296.705018) (xy 282.798949 -296.705018) (xy 282.747614 -296.696888)
			(xy 282.698184 -296.680827) (xy 282.651874 -296.657231) (xy 282.609826 -296.626681) (xy 282.573075 -296.58993)
			(xy 282.542525 -296.547882) (xy 282.518929 -296.501572) (xy 282.502868 -296.452142) (xy 282.494738 -296.400807)
			(xy 282.20492 -296.400807) (xy 282.19679 -296.452142) (xy 282.180729 -296.501572) (xy 282.157133 -296.547882)
			(xy 282.126583 -296.58993) (xy 282.089832 -296.626681) (xy 282.047784 -296.657231) (xy 282.001474 -296.680827)
			(xy 281.952044 -296.696888) (xy 281.900709 -296.705018) (xy 281.848735 -296.705018) (xy 281.7974 -296.696888)
			(xy 281.74797 -296.680827) (xy 281.70166 -296.657231) (xy 281.659612 -296.626681) (xy 281.622861 -296.58993)
			(xy 281.592311 -296.547882) (xy 281.568715 -296.501572) (xy 281.552654 -296.452142) (xy 281.544524 -296.400807)
			(xy 281.25496 -296.400807) (xy 281.24683 -296.452142) (xy 281.230769 -296.501572) (xy 281.207173 -296.547882)
			(xy 281.176623 -296.58993) (xy 281.139872 -296.626681) (xy 281.097824 -296.657231) (xy 281.051514 -296.680827)
			(xy 281.002084 -296.696888) (xy 280.950749 -296.705018) (xy 280.898775 -296.705018) (xy 280.84744 -296.696888)
			(xy 280.79801 -296.680827) (xy 280.7517 -296.657231) (xy 280.709652 -296.626681) (xy 280.672901 -296.58993)
			(xy 280.642351 -296.547882) (xy 280.618755 -296.501572) (xy 280.602694 -296.452142) (xy 280.594564 -296.400807)
			(xy 280.305 -296.400807) (xy 280.29687 -296.452142) (xy 280.280809 -296.501572) (xy 280.257213 -296.547882)
			(xy 280.226663 -296.58993) (xy 280.189912 -296.626681) (xy 280.147864 -296.657231) (xy 280.101554 -296.680827)
			(xy 280.052124 -296.696888) (xy 280.000789 -296.705018) (xy 279.948815 -296.705018) (xy 279.89748 -296.696888)
			(xy 279.84805 -296.680827) (xy 279.80174 -296.657231) (xy 279.759692 -296.626681) (xy 279.722941 -296.58993)
			(xy 279.692391 -296.547882) (xy 279.668795 -296.501572) (xy 279.652734 -296.452142) (xy 279.644604 -296.400807)
			(xy 279.35504 -296.400807) (xy 279.34691 -296.452142) (xy 279.330849 -296.501572) (xy 279.307253 -296.547882)
			(xy 279.276703 -296.58993) (xy 279.239952 -296.626681) (xy 279.197904 -296.657231) (xy 279.151594 -296.680827)
			(xy 279.102164 -296.696888) (xy 279.050829 -296.705018) (xy 278.998855 -296.705018) (xy 278.94752 -296.696888)
			(xy 278.89809 -296.680827) (xy 278.85178 -296.657231) (xy 278.809732 -296.626681) (xy 278.772981 -296.58993)
			(xy 278.742431 -296.547882) (xy 278.718835 -296.501572) (xy 278.702774 -296.452142) (xy 278.694644 -296.400807)
			(xy 278.40508 -296.400807) (xy 278.39695 -296.452142) (xy 278.380889 -296.501572) (xy 278.357293 -296.547882)
			(xy 278.326743 -296.58993) (xy 278.289992 -296.626681) (xy 278.247944 -296.657231) (xy 278.201634 -296.680827)
			(xy 278.152204 -296.696888) (xy 278.100869 -296.705018) (xy 278.048895 -296.705018) (xy 277.99756 -296.696888)
			(xy 277.94813 -296.680827) (xy 277.90182 -296.657231) (xy 277.859772 -296.626681) (xy 277.823021 -296.58993)
			(xy 277.792471 -296.547882) (xy 277.768875 -296.501572) (xy 277.752814 -296.452142) (xy 277.744684 -296.400807)
			(xy 276.504906 -296.400807) (xy 276.496776 -296.452142) (xy 276.480715 -296.501572) (xy 276.457119 -296.547882)
			(xy 276.426569 -296.58993) (xy 276.389818 -296.626681) (xy 276.34777 -296.657231) (xy 276.30146 -296.680827)
			(xy 276.25203 -296.696888) (xy 276.200695 -296.705018) (xy 276.148721 -296.705018) (xy 276.097386 -296.696888)
			(xy 276.047956 -296.680827) (xy 276.001646 -296.657231) (xy 275.959598 -296.626681) (xy 275.922847 -296.58993)
			(xy 275.892297 -296.547882) (xy 275.868701 -296.501572) (xy 275.85264 -296.452142) (xy 275.84451 -296.400807)
			(xy 275.311616 -296.400807) (xy 275.311616 -296.950384) (xy 275.312088 -296.960256) (xy 275.31955 -296.978536)
			(xy 275.326094 -296.985944) (xy 275.326348 -296.986198) (xy 275.708364 -297.368214) (xy 275.71338 -297.372949)
			(xy 275.725354 -297.379782) (xy 275.731986 -297.381676) (xy 275.74494 -297.384724) (xy 275.76907 -297.378628)
			(xy 275.778722 -297.369992) (xy 275.83638 -297.317922) (xy 275.844762 -297.301412) (xy 275.845524 -297.29176)
			(xy 275.848577 -297.266325) (xy 275.861523 -297.216761) (xy 275.881953 -297.169785) (xy 275.909379 -297.126519)
			(xy 275.943145 -297.087996) (xy 275.982446 -297.055139) (xy 276.026341 -297.028731) (xy 276.073782 -297.009405)
			(xy 276.123635 -296.997621) (xy 276.174708 -296.993661) (xy 276.225781 -296.997621) (xy 276.275634 -297.009405)
			(xy 276.323075 -297.028731) (xy 276.36697 -297.055139) (xy 276.406271 -297.087996) (xy 276.440037 -297.126519)
			(xy 276.467463 -297.169785) (xy 276.487893 -297.216761) (xy 276.500839 -297.266325) (xy 276.503892 -297.29176)
			(xy 276.504654 -297.301412) (xy 276.513036 -297.317922) (xy 276.570694 -297.369992) (xy 276.577919 -297.376084)
			(xy 276.595539 -297.382882) (xy 276.604984 -297.3832) (xy 276.704298 -297.3832) (xy 276.721824 -297.376342)
			(xy 276.728936 -297.369992) (xy 276.786594 -297.317922) (xy 276.794976 -297.301412) (xy 276.795738 -297.29176)
			(xy 276.798791 -297.266325) (xy 276.811737 -297.216761) (xy 276.832167 -297.169785) (xy 276.859593 -297.126519)
			(xy 276.893359 -297.087996) (xy 276.93266 -297.055139) (xy 276.976555 -297.028731) (xy 277.023996 -297.009405)
			(xy 277.073849 -296.997621) (xy 277.124922 -296.993661) (xy 277.175995 -296.997621) (xy 277.225848 -297.009405)
			(xy 277.273289 -297.028731) (xy 277.317184 -297.055139) (xy 277.356485 -297.087996) (xy 277.390251 -297.126519)
			(xy 277.417677 -297.169785) (xy 277.438107 -297.216761) (xy 277.451053 -297.266325) (xy 277.454106 -297.29176)
			(xy 277.454868 -297.301412) (xy 277.46325 -297.317922) (xy 277.520908 -297.369992) (xy 277.528134 -297.376082)
			(xy 277.545754 -297.382875) (xy 277.555198 -297.3832) (xy 277.654258 -297.3832) (xy 277.671784 -297.376342)
			(xy 277.678896 -297.369992) (xy 277.736554 -297.317922) (xy 277.744936 -297.301412) (xy 277.745698 -297.29176)
			(xy 277.748955 -297.26491) (xy 277.763074 -297.212703) (xy 277.78549 -297.163484) (xy 277.815608 -297.118564)
			(xy 277.852626 -297.079135) (xy 277.89556 -297.046247) (xy 277.943269 -297.020775) (xy 277.994483 -297.003395)
			(xy 278.047841 -296.99457) (xy 278.074882 -296.994072) (xy 278.100871 -296.99458) (xy 278.152209 -297.002708)
			(xy 278.201643 -297.018768) (xy 278.247956 -297.042362) (xy 278.290008 -297.072911) (xy 278.326764 -297.109663)
			(xy 278.357318 -297.151711) (xy 278.380918 -297.198022) (xy 278.396983 -297.247454) (xy 278.405117 -297.298791)
			(xy 278.40559 -297.32478) (xy 278.405143 -297.349642) (xy 278.404973 -297.350767) (xy 278.694644 -297.350767)
			(xy 278.694644 -297.298793) (xy 278.702774 -297.247458) (xy 278.718835 -297.198028) (xy 278.742431 -297.151718)
			(xy 278.772981 -297.10967) (xy 278.809732 -297.072919) (xy 278.85178 -297.042369) (xy 278.89809 -297.018773)
			(xy 278.94752 -297.002712) (xy 278.998855 -296.994582) (xy 279.050829 -296.994582) (xy 279.102164 -297.002712)
			(xy 279.151594 -297.018773) (xy 279.197904 -297.042369) (xy 279.239952 -297.072919) (xy 279.276703 -297.10967)
			(xy 279.307253 -297.151718) (xy 279.330849 -297.198028) (xy 279.34691 -297.247458) (xy 279.35504 -297.298793)
			(xy 279.35555 -297.32478) (xy 279.35504 -297.350767) (xy 279.644604 -297.350767) (xy 279.644604 -297.298793)
			(xy 279.652734 -297.247458) (xy 279.668795 -297.198028) (xy 279.692391 -297.151718) (xy 279.722941 -297.10967)
			(xy 279.759692 -297.072919) (xy 279.80174 -297.042369) (xy 279.84805 -297.018773) (xy 279.89748 -297.002712)
			(xy 279.948815 -296.994582) (xy 280.000789 -296.994582) (xy 280.052124 -297.002712) (xy 280.101554 -297.018773)
			(xy 280.147864 -297.042369) (xy 280.189912 -297.072919) (xy 280.226663 -297.10967) (xy 280.257213 -297.151718)
			(xy 280.280809 -297.198028) (xy 280.29687 -297.247458) (xy 280.305 -297.298793) (xy 280.30551 -297.32478)
			(xy 280.305 -297.350767) (xy 280.594564 -297.350767) (xy 280.594564 -297.298793) (xy 280.602694 -297.247458)
			(xy 280.618755 -297.198028) (xy 280.642351 -297.151718) (xy 280.672901 -297.10967) (xy 280.709652 -297.072919)
			(xy 280.7517 -297.042369) (xy 280.79801 -297.018773) (xy 280.84744 -297.002712) (xy 280.898775 -296.994582)
			(xy 280.950749 -296.994582) (xy 281.002084 -297.002712) (xy 281.051514 -297.018773) (xy 281.097824 -297.042369)
			(xy 281.139872 -297.072919) (xy 281.176623 -297.10967) (xy 281.207173 -297.151718) (xy 281.230769 -297.198028)
			(xy 281.24683 -297.247458) (xy 281.25496 -297.298793) (xy 281.25547 -297.32478) (xy 281.25496 -297.350767)
			(xy 281.544524 -297.350767) (xy 281.544524 -297.298793) (xy 281.552654 -297.247458) (xy 281.568715 -297.198028)
			(xy 281.592311 -297.151718) (xy 281.622861 -297.10967) (xy 281.659612 -297.072919) (xy 281.70166 -297.042369)
			(xy 281.74797 -297.018773) (xy 281.7974 -297.002712) (xy 281.848735 -296.994582) (xy 281.900709 -296.994582)
			(xy 281.952044 -297.002712) (xy 282.001474 -297.018773) (xy 282.047784 -297.042369) (xy 282.089832 -297.072919)
			(xy 282.126583 -297.10967) (xy 282.157133 -297.151718) (xy 282.180729 -297.198028) (xy 282.19679 -297.247458)
			(xy 282.20492 -297.298793) (xy 282.20543 -297.32478) (xy 282.20492 -297.350767) (xy 282.494738 -297.350767)
			(xy 282.494738 -297.298793) (xy 282.502868 -297.247458) (xy 282.518929 -297.198028) (xy 282.542525 -297.151718)
			(xy 282.573075 -297.10967) (xy 282.609826 -297.072919) (xy 282.651874 -297.042369) (xy 282.698184 -297.018773)
			(xy 282.747614 -297.002712) (xy 282.798949 -296.994582) (xy 282.850923 -296.994582) (xy 282.902258 -297.002712)
			(xy 282.951688 -297.018773) (xy 282.997998 -297.042369) (xy 283.040046 -297.072919) (xy 283.076797 -297.10967)
			(xy 283.107347 -297.151718) (xy 283.130943 -297.198028) (xy 283.147004 -297.247458) (xy 283.155134 -297.298793)
			(xy 283.155644 -297.32478) (xy 283.155134 -297.350767) (xy 283.444698 -297.350767) (xy 283.444698 -297.298793)
			(xy 283.452828 -297.247458) (xy 283.468889 -297.198028) (xy 283.492485 -297.151718) (xy 283.523035 -297.10967)
			(xy 283.559786 -297.072919) (xy 283.601834 -297.042369) (xy 283.648144 -297.018773) (xy 283.697574 -297.002712)
			(xy 283.748909 -296.994582) (xy 283.800883 -296.994582) (xy 283.852218 -297.002712) (xy 283.901648 -297.018773)
			(xy 283.947958 -297.042369) (xy 283.990006 -297.072919) (xy 284.026757 -297.10967) (xy 284.057307 -297.151718)
			(xy 284.080903 -297.198028) (xy 284.096964 -297.247458) (xy 284.105094 -297.298793) (xy 284.105604 -297.32478)
			(xy 284.105094 -297.350767) (xy 284.394658 -297.350767) (xy 284.394658 -297.298793) (xy 284.402788 -297.247458)
			(xy 284.418849 -297.198028) (xy 284.442445 -297.151718) (xy 284.472995 -297.10967) (xy 284.509746 -297.072919)
			(xy 284.551794 -297.042369) (xy 284.598104 -297.018773) (xy 284.647534 -297.002712) (xy 284.698869 -296.994582)
			(xy 284.750843 -296.994582) (xy 284.802178 -297.002712) (xy 284.851608 -297.018773) (xy 284.897918 -297.042369)
			(xy 284.939966 -297.072919) (xy 284.976717 -297.10967) (xy 285.007267 -297.151718) (xy 285.030863 -297.198028)
			(xy 285.046924 -297.247458) (xy 285.055054 -297.298793) (xy 285.055564 -297.32478) (xy 285.055054 -297.350767)
			(xy 285.344618 -297.350767) (xy 285.344618 -297.298793) (xy 285.352748 -297.247458) (xy 285.368809 -297.198028)
			(xy 285.392405 -297.151718) (xy 285.422955 -297.10967) (xy 285.459706 -297.072919) (xy 285.501754 -297.042369)
			(xy 285.548064 -297.018773) (xy 285.597494 -297.002712) (xy 285.648829 -296.994582) (xy 285.700803 -296.994582)
			(xy 285.752138 -297.002712) (xy 285.801568 -297.018773) (xy 285.847878 -297.042369) (xy 285.889926 -297.072919)
			(xy 285.926677 -297.10967) (xy 285.957227 -297.151718) (xy 285.980823 -297.198028) (xy 285.996884 -297.247458)
			(xy 286.005014 -297.298793) (xy 286.005524 -297.32478) (xy 286.005014 -297.350767) (xy 286.294578 -297.350767)
			(xy 286.294578 -297.298793) (xy 286.302708 -297.247458) (xy 286.318769 -297.198028) (xy 286.342365 -297.151718)
			(xy 286.372915 -297.10967) (xy 286.409666 -297.072919) (xy 286.451714 -297.042369) (xy 286.498024 -297.018773)
			(xy 286.547454 -297.002712) (xy 286.598789 -296.994582) (xy 286.650763 -296.994582) (xy 286.702098 -297.002712)
			(xy 286.751528 -297.018773) (xy 286.797838 -297.042369) (xy 286.839886 -297.072919) (xy 286.876637 -297.10967)
			(xy 286.907187 -297.151718) (xy 286.930783 -297.198028) (xy 286.946844 -297.247458) (xy 286.954974 -297.298793)
			(xy 286.955484 -297.32478) (xy 286.954974 -297.350767) (xy 287.244538 -297.350767) (xy 287.244538 -297.298793)
			(xy 287.252668 -297.247458) (xy 287.268729 -297.198028) (xy 287.292325 -297.151718) (xy 287.322875 -297.10967)
			(xy 287.359626 -297.072919) (xy 287.401674 -297.042369) (xy 287.447984 -297.018773) (xy 287.497414 -297.002712)
			(xy 287.548749 -296.994582) (xy 287.600723 -296.994582) (xy 287.652058 -297.002712) (xy 287.701488 -297.018773)
			(xy 287.747798 -297.042369) (xy 287.789846 -297.072919) (xy 287.826597 -297.10967) (xy 287.857147 -297.151718)
			(xy 287.880743 -297.198028) (xy 287.896804 -297.247458) (xy 287.904934 -297.298793) (xy 287.905444 -297.32478)
			(xy 287.904934 -297.350767) (xy 288.194498 -297.350767) (xy 288.194498 -297.298793) (xy 288.202628 -297.247458)
			(xy 288.218689 -297.198028) (xy 288.242285 -297.151718) (xy 288.272835 -297.10967) (xy 288.309586 -297.072919)
			(xy 288.351634 -297.042369) (xy 288.397944 -297.018773) (xy 288.447374 -297.002712) (xy 288.498709 -296.994582)
			(xy 288.550683 -296.994582) (xy 288.602018 -297.002712) (xy 288.651448 -297.018773) (xy 288.697758 -297.042369)
			(xy 288.739806 -297.072919) (xy 288.776557 -297.10967) (xy 288.807107 -297.151718) (xy 288.830703 -297.198028)
			(xy 288.846764 -297.247458) (xy 288.854894 -297.298793) (xy 288.855404 -297.32478) (xy 288.854894 -297.350767)
			(xy 289.144712 -297.350767) (xy 289.144712 -297.298793) (xy 289.152842 -297.247458) (xy 289.168903 -297.198028)
			(xy 289.192499 -297.151718) (xy 289.223049 -297.10967) (xy 289.2598 -297.072919) (xy 289.301848 -297.042369)
			(xy 289.348158 -297.018773) (xy 289.397588 -297.002712) (xy 289.448923 -296.994582) (xy 289.500897 -296.994582)
			(xy 289.552232 -297.002712) (xy 289.601662 -297.018773) (xy 289.647972 -297.042369) (xy 289.69002 -297.072919)
			(xy 289.726771 -297.10967) (xy 289.757321 -297.151718) (xy 289.780917 -297.198028) (xy 289.796978 -297.247458)
			(xy 289.805108 -297.298793) (xy 289.805618 -297.32478) (xy 289.805108 -297.350767) (xy 290.094672 -297.350767)
			(xy 290.094672 -297.298793) (xy 290.102802 -297.247458) (xy 290.118863 -297.198028) (xy 290.142459 -297.151718)
			(xy 290.173009 -297.10967) (xy 290.20976 -297.072919) (xy 290.251808 -297.042369) (xy 290.298118 -297.018773)
			(xy 290.347548 -297.002712) (xy 290.398883 -296.994582) (xy 290.450857 -296.994582) (xy 290.502192 -297.002712)
			(xy 290.551622 -297.018773) (xy 290.597932 -297.042369) (xy 290.63998 -297.072919) (xy 290.676731 -297.10967)
			(xy 290.707281 -297.151718) (xy 290.730877 -297.198028) (xy 290.746938 -297.247458) (xy 290.755068 -297.298793)
			(xy 290.755578 -297.32478) (xy 290.755068 -297.350767) (xy 291.994592 -297.350767) (xy 291.994592 -297.298793)
			(xy 292.002722 -297.247458) (xy 292.018783 -297.198028) (xy 292.042379 -297.151718) (xy 292.072929 -297.10967)
			(xy 292.10968 -297.072919) (xy 292.151728 -297.042369) (xy 292.198038 -297.018773) (xy 292.247468 -297.002712)
			(xy 292.298803 -296.994582) (xy 292.350777 -296.994582) (xy 292.402112 -297.002712) (xy 292.451542 -297.018773)
			(xy 292.497852 -297.042369) (xy 292.5399 -297.072919) (xy 292.576651 -297.10967) (xy 292.607201 -297.151718)
			(xy 292.630797 -297.198028) (xy 292.646858 -297.247458) (xy 292.654988 -297.298793) (xy 292.655498 -297.32478)
			(xy 292.654988 -297.350767) (xy 292.944552 -297.350767) (xy 292.944552 -297.298793) (xy 292.952682 -297.247458)
			(xy 292.968743 -297.198028) (xy 292.992339 -297.151718) (xy 293.022889 -297.10967) (xy 293.05964 -297.072919)
			(xy 293.101688 -297.042369) (xy 293.147998 -297.018773) (xy 293.197428 -297.002712) (xy 293.248763 -296.994582)
			(xy 293.300737 -296.994582) (xy 293.352072 -297.002712) (xy 293.401502 -297.018773) (xy 293.447812 -297.042369)
			(xy 293.48986 -297.072919) (xy 293.526611 -297.10967) (xy 293.557161 -297.151718) (xy 293.580757 -297.198028)
			(xy 293.596818 -297.247458) (xy 293.604948 -297.298793) (xy 293.605458 -297.32478) (xy 293.604948 -297.350767)
			(xy 293.894512 -297.350767) (xy 293.894512 -297.298793) (xy 293.902642 -297.247458) (xy 293.918703 -297.198028)
			(xy 293.942299 -297.151718) (xy 293.972849 -297.10967) (xy 294.0096 -297.072919) (xy 294.051648 -297.042369)
			(xy 294.097958 -297.018773) (xy 294.147388 -297.002712) (xy 294.198723 -296.994582) (xy 294.250697 -296.994582)
			(xy 294.302032 -297.002712) (xy 294.351462 -297.018773) (xy 294.397772 -297.042369) (xy 294.43982 -297.072919)
			(xy 294.476571 -297.10967) (xy 294.507121 -297.151718) (xy 294.530717 -297.198028) (xy 294.546778 -297.247458)
			(xy 294.554908 -297.298793) (xy 294.555418 -297.32478) (xy 294.554908 -297.350767) (xy 294.844726 -297.350767)
			(xy 294.844726 -297.298793) (xy 294.852856 -297.247458) (xy 294.868917 -297.198028) (xy 294.892513 -297.151718)
			(xy 294.923063 -297.10967) (xy 294.959814 -297.072919) (xy 295.001862 -297.042369) (xy 295.048172 -297.018773)
			(xy 295.097602 -297.002712) (xy 295.148937 -296.994582) (xy 295.200911 -296.994582) (xy 295.252246 -297.002712)
			(xy 295.301676 -297.018773) (xy 295.347986 -297.042369) (xy 295.390034 -297.072919) (xy 295.426785 -297.10967)
			(xy 295.457335 -297.151718) (xy 295.480931 -297.198028) (xy 295.496992 -297.247458) (xy 295.505122 -297.298793)
			(xy 295.505632 -297.32478) (xy 295.505122 -297.350767) (xy 295.794686 -297.350767) (xy 295.794686 -297.298793)
			(xy 295.802816 -297.247458) (xy 295.818877 -297.198028) (xy 295.842473 -297.151718) (xy 295.873023 -297.10967)
			(xy 295.909774 -297.072919) (xy 295.951822 -297.042369) (xy 295.998132 -297.018773) (xy 296.047562 -297.002712)
			(xy 296.098897 -296.994582) (xy 296.150871 -296.994582) (xy 296.202206 -297.002712) (xy 296.251636 -297.018773)
			(xy 296.297946 -297.042369) (xy 296.339994 -297.072919) (xy 296.376745 -297.10967) (xy 296.407295 -297.151718)
			(xy 296.430891 -297.198028) (xy 296.446952 -297.247458) (xy 296.455082 -297.298793) (xy 296.455592 -297.32478)
			(xy 296.455082 -297.350767) (xy 296.744646 -297.350767) (xy 296.744646 -297.298793) (xy 296.752776 -297.247458)
			(xy 296.768837 -297.198028) (xy 296.792433 -297.151718) (xy 296.822983 -297.10967) (xy 296.859734 -297.072919)
			(xy 296.901782 -297.042369) (xy 296.948092 -297.018773) (xy 296.997522 -297.002712) (xy 297.048857 -296.994582)
			(xy 297.100831 -296.994582) (xy 297.152166 -297.002712) (xy 297.201596 -297.018773) (xy 297.247906 -297.042369)
			(xy 297.289954 -297.072919) (xy 297.326705 -297.10967) (xy 297.357255 -297.151718) (xy 297.380851 -297.198028)
			(xy 297.396912 -297.247458) (xy 297.405042 -297.298793) (xy 297.405552 -297.32478) (xy 297.405042 -297.350767)
			(xy 297.694606 -297.350767) (xy 297.694606 -297.298793) (xy 297.702736 -297.247458) (xy 297.718797 -297.198028)
			(xy 297.742393 -297.151718) (xy 297.772943 -297.10967) (xy 297.809694 -297.072919) (xy 297.851742 -297.042369)
			(xy 297.898052 -297.018773) (xy 297.947482 -297.002712) (xy 297.998817 -296.994582) (xy 298.050791 -296.994582)
			(xy 298.102126 -297.002712) (xy 298.151556 -297.018773) (xy 298.197866 -297.042369) (xy 298.239914 -297.072919)
			(xy 298.276665 -297.10967) (xy 298.307215 -297.151718) (xy 298.330811 -297.198028) (xy 298.346872 -297.247458)
			(xy 298.355002 -297.298793) (xy 298.355512 -297.32478) (xy 298.355002 -297.350767) (xy 298.644566 -297.350767)
			(xy 298.644566 -297.298793) (xy 298.652696 -297.247458) (xy 298.668757 -297.198028) (xy 298.692353 -297.151718)
			(xy 298.722903 -297.10967) (xy 298.759654 -297.072919) (xy 298.801702 -297.042369) (xy 298.848012 -297.018773)
			(xy 298.897442 -297.002712) (xy 298.948777 -296.994582) (xy 299.000751 -296.994582) (xy 299.052086 -297.002712)
			(xy 299.101516 -297.018773) (xy 299.147826 -297.042369) (xy 299.189874 -297.072919) (xy 299.226625 -297.10967)
			(xy 299.257175 -297.151718) (xy 299.280771 -297.198028) (xy 299.296832 -297.247458) (xy 299.304962 -297.298793)
			(xy 299.305472 -297.32478) (xy 299.304962 -297.350767) (xy 299.594526 -297.350767) (xy 299.594526 -297.298793)
			(xy 299.602656 -297.247458) (xy 299.618717 -297.198028) (xy 299.642313 -297.151718) (xy 299.672863 -297.10967)
			(xy 299.709614 -297.072919) (xy 299.751662 -297.042369) (xy 299.797972 -297.018773) (xy 299.847402 -297.002712)
			(xy 299.898737 -296.994582) (xy 299.950711 -296.994582) (xy 300.002046 -297.002712) (xy 300.051476 -297.018773)
			(xy 300.097786 -297.042369) (xy 300.139834 -297.072919) (xy 300.176585 -297.10967) (xy 300.207135 -297.151718)
			(xy 300.230731 -297.198028) (xy 300.246792 -297.247458) (xy 300.254922 -297.298793) (xy 300.255432 -297.32478)
			(xy 300.254922 -297.350767) (xy 300.246792 -297.402102) (xy 300.230731 -297.451532) (xy 300.207135 -297.497842)
			(xy 300.176585 -297.53989) (xy 300.139834 -297.576641) (xy 300.097786 -297.607191) (xy 300.051476 -297.630787)
			(xy 300.002046 -297.646848) (xy 299.950711 -297.654978) (xy 299.898737 -297.654978) (xy 299.847402 -297.646848)
			(xy 299.797972 -297.630787) (xy 299.751662 -297.607191) (xy 299.709614 -297.576641) (xy 299.672863 -297.53989)
			(xy 299.642313 -297.497842) (xy 299.618717 -297.451532) (xy 299.602656 -297.402102) (xy 299.594526 -297.350767)
			(xy 299.304962 -297.350767) (xy 299.296832 -297.402102) (xy 299.280771 -297.451532) (xy 299.257175 -297.497842)
			(xy 299.226625 -297.53989) (xy 299.189874 -297.576641) (xy 299.147826 -297.607191) (xy 299.101516 -297.630787)
			(xy 299.052086 -297.646848) (xy 299.000751 -297.654978) (xy 298.948777 -297.654978) (xy 298.897442 -297.646848)
			(xy 298.848012 -297.630787) (xy 298.801702 -297.607191) (xy 298.759654 -297.576641) (xy 298.722903 -297.53989)
			(xy 298.692353 -297.497842) (xy 298.668757 -297.451532) (xy 298.652696 -297.402102) (xy 298.644566 -297.350767)
			(xy 298.355002 -297.350767) (xy 298.346872 -297.402102) (xy 298.330811 -297.451532) (xy 298.307215 -297.497842)
			(xy 298.276665 -297.53989) (xy 298.239914 -297.576641) (xy 298.197866 -297.607191) (xy 298.151556 -297.630787)
			(xy 298.102126 -297.646848) (xy 298.050791 -297.654978) (xy 297.998817 -297.654978) (xy 297.947482 -297.646848)
			(xy 297.898052 -297.630787) (xy 297.851742 -297.607191) (xy 297.809694 -297.576641) (xy 297.772943 -297.53989)
			(xy 297.742393 -297.497842) (xy 297.718797 -297.451532) (xy 297.702736 -297.402102) (xy 297.694606 -297.350767)
			(xy 297.405042 -297.350767) (xy 297.396912 -297.402102) (xy 297.380851 -297.451532) (xy 297.357255 -297.497842)
			(xy 297.326705 -297.53989) (xy 297.289954 -297.576641) (xy 297.247906 -297.607191) (xy 297.201596 -297.630787)
			(xy 297.152166 -297.646848) (xy 297.100831 -297.654978) (xy 297.048857 -297.654978) (xy 296.997522 -297.646848)
			(xy 296.948092 -297.630787) (xy 296.901782 -297.607191) (xy 296.859734 -297.576641) (xy 296.822983 -297.53989)
			(xy 296.792433 -297.497842) (xy 296.768837 -297.451532) (xy 296.752776 -297.402102) (xy 296.744646 -297.350767)
			(xy 296.455082 -297.350767) (xy 296.446952 -297.402102) (xy 296.430891 -297.451532) (xy 296.407295 -297.497842)
			(xy 296.376745 -297.53989) (xy 296.339994 -297.576641) (xy 296.297946 -297.607191) (xy 296.251636 -297.630787)
			(xy 296.202206 -297.646848) (xy 296.150871 -297.654978) (xy 296.098897 -297.654978) (xy 296.047562 -297.646848)
			(xy 295.998132 -297.630787) (xy 295.951822 -297.607191) (xy 295.909774 -297.576641) (xy 295.873023 -297.53989)
			(xy 295.842473 -297.497842) (xy 295.818877 -297.451532) (xy 295.802816 -297.402102) (xy 295.794686 -297.350767)
			(xy 295.505122 -297.350767) (xy 295.496992 -297.402102) (xy 295.480931 -297.451532) (xy 295.457335 -297.497842)
			(xy 295.426785 -297.53989) (xy 295.390034 -297.576641) (xy 295.347986 -297.607191) (xy 295.301676 -297.630787)
			(xy 295.252246 -297.646848) (xy 295.200911 -297.654978) (xy 295.148937 -297.654978) (xy 295.097602 -297.646848)
			(xy 295.048172 -297.630787) (xy 295.001862 -297.607191) (xy 294.959814 -297.576641) (xy 294.923063 -297.53989)
			(xy 294.892513 -297.497842) (xy 294.868917 -297.451532) (xy 294.852856 -297.402102) (xy 294.844726 -297.350767)
			(xy 294.554908 -297.350767) (xy 294.546778 -297.402102) (xy 294.530717 -297.451532) (xy 294.507121 -297.497842)
			(xy 294.476571 -297.53989) (xy 294.43982 -297.576641) (xy 294.397772 -297.607191) (xy 294.351462 -297.630787)
			(xy 294.302032 -297.646848) (xy 294.250697 -297.654978) (xy 294.198723 -297.654978) (xy 294.147388 -297.646848)
			(xy 294.097958 -297.630787) (xy 294.051648 -297.607191) (xy 294.0096 -297.576641) (xy 293.972849 -297.53989)
			(xy 293.942299 -297.497842) (xy 293.918703 -297.451532) (xy 293.902642 -297.402102) (xy 293.894512 -297.350767)
			(xy 293.604948 -297.350767) (xy 293.596818 -297.402102) (xy 293.580757 -297.451532) (xy 293.557161 -297.497842)
			(xy 293.526611 -297.53989) (xy 293.48986 -297.576641) (xy 293.447812 -297.607191) (xy 293.401502 -297.630787)
			(xy 293.352072 -297.646848) (xy 293.300737 -297.654978) (xy 293.248763 -297.654978) (xy 293.197428 -297.646848)
			(xy 293.147998 -297.630787) (xy 293.101688 -297.607191) (xy 293.05964 -297.576641) (xy 293.022889 -297.53989)
			(xy 292.992339 -297.497842) (xy 292.968743 -297.451532) (xy 292.952682 -297.402102) (xy 292.944552 -297.350767)
			(xy 292.654988 -297.350767) (xy 292.646858 -297.402102) (xy 292.630797 -297.451532) (xy 292.607201 -297.497842)
			(xy 292.576651 -297.53989) (xy 292.5399 -297.576641) (xy 292.497852 -297.607191) (xy 292.451542 -297.630787)
			(xy 292.402112 -297.646848) (xy 292.350777 -297.654978) (xy 292.298803 -297.654978) (xy 292.247468 -297.646848)
			(xy 292.198038 -297.630787) (xy 292.151728 -297.607191) (xy 292.10968 -297.576641) (xy 292.072929 -297.53989)
			(xy 292.042379 -297.497842) (xy 292.018783 -297.451532) (xy 292.002722 -297.402102) (xy 291.994592 -297.350767)
			(xy 290.755068 -297.350767) (xy 290.746938 -297.402102) (xy 290.730877 -297.451532) (xy 290.707281 -297.497842)
			(xy 290.676731 -297.53989) (xy 290.63998 -297.576641) (xy 290.597932 -297.607191) (xy 290.551622 -297.630787)
			(xy 290.502192 -297.646848) (xy 290.450857 -297.654978) (xy 290.398883 -297.654978) (xy 290.347548 -297.646848)
			(xy 290.298118 -297.630787) (xy 290.251808 -297.607191) (xy 290.20976 -297.576641) (xy 290.173009 -297.53989)
			(xy 290.142459 -297.497842) (xy 290.118863 -297.451532) (xy 290.102802 -297.402102) (xy 290.094672 -297.350767)
			(xy 289.805108 -297.350767) (xy 289.796978 -297.402102) (xy 289.780917 -297.451532) (xy 289.757321 -297.497842)
			(xy 289.726771 -297.53989) (xy 289.69002 -297.576641) (xy 289.647972 -297.607191) (xy 289.601662 -297.630787)
			(xy 289.552232 -297.646848) (xy 289.500897 -297.654978) (xy 289.448923 -297.654978) (xy 289.397588 -297.646848)
			(xy 289.348158 -297.630787) (xy 289.301848 -297.607191) (xy 289.2598 -297.576641) (xy 289.223049 -297.53989)
			(xy 289.192499 -297.497842) (xy 289.168903 -297.451532) (xy 289.152842 -297.402102) (xy 289.144712 -297.350767)
			(xy 288.854894 -297.350767) (xy 288.846764 -297.402102) (xy 288.830703 -297.451532) (xy 288.807107 -297.497842)
			(xy 288.776557 -297.53989) (xy 288.739806 -297.576641) (xy 288.697758 -297.607191) (xy 288.651448 -297.630787)
			(xy 288.602018 -297.646848) (xy 288.550683 -297.654978) (xy 288.498709 -297.654978) (xy 288.447374 -297.646848)
			(xy 288.397944 -297.630787) (xy 288.351634 -297.607191) (xy 288.309586 -297.576641) (xy 288.272835 -297.53989)
			(xy 288.242285 -297.497842) (xy 288.218689 -297.451532) (xy 288.202628 -297.402102) (xy 288.194498 -297.350767)
			(xy 287.904934 -297.350767) (xy 287.896804 -297.402102) (xy 287.880743 -297.451532) (xy 287.857147 -297.497842)
			(xy 287.826597 -297.53989) (xy 287.789846 -297.576641) (xy 287.747798 -297.607191) (xy 287.701488 -297.630787)
			(xy 287.652058 -297.646848) (xy 287.600723 -297.654978) (xy 287.548749 -297.654978) (xy 287.497414 -297.646848)
			(xy 287.447984 -297.630787) (xy 287.401674 -297.607191) (xy 287.359626 -297.576641) (xy 287.322875 -297.53989)
			(xy 287.292325 -297.497842) (xy 287.268729 -297.451532) (xy 287.252668 -297.402102) (xy 287.244538 -297.350767)
			(xy 286.954974 -297.350767) (xy 286.946844 -297.402102) (xy 286.930783 -297.451532) (xy 286.907187 -297.497842)
			(xy 286.876637 -297.53989) (xy 286.839886 -297.576641) (xy 286.797838 -297.607191) (xy 286.751528 -297.630787)
			(xy 286.702098 -297.646848) (xy 286.650763 -297.654978) (xy 286.598789 -297.654978) (xy 286.547454 -297.646848)
			(xy 286.498024 -297.630787) (xy 286.451714 -297.607191) (xy 286.409666 -297.576641) (xy 286.372915 -297.53989)
			(xy 286.342365 -297.497842) (xy 286.318769 -297.451532) (xy 286.302708 -297.402102) (xy 286.294578 -297.350767)
			(xy 286.005014 -297.350767) (xy 285.996884 -297.402102) (xy 285.980823 -297.451532) (xy 285.957227 -297.497842)
			(xy 285.926677 -297.53989) (xy 285.889926 -297.576641) (xy 285.847878 -297.607191) (xy 285.801568 -297.630787)
			(xy 285.752138 -297.646848) (xy 285.700803 -297.654978) (xy 285.648829 -297.654978) (xy 285.597494 -297.646848)
			(xy 285.548064 -297.630787) (xy 285.501754 -297.607191) (xy 285.459706 -297.576641) (xy 285.422955 -297.53989)
			(xy 285.392405 -297.497842) (xy 285.368809 -297.451532) (xy 285.352748 -297.402102) (xy 285.344618 -297.350767)
			(xy 285.055054 -297.350767) (xy 285.046924 -297.402102) (xy 285.030863 -297.451532) (xy 285.007267 -297.497842)
			(xy 284.976717 -297.53989) (xy 284.939966 -297.576641) (xy 284.897918 -297.607191) (xy 284.851608 -297.630787)
			(xy 284.802178 -297.646848) (xy 284.750843 -297.654978) (xy 284.698869 -297.654978) (xy 284.647534 -297.646848)
			(xy 284.598104 -297.630787) (xy 284.551794 -297.607191) (xy 284.509746 -297.576641) (xy 284.472995 -297.53989)
			(xy 284.442445 -297.497842) (xy 284.418849 -297.451532) (xy 284.402788 -297.402102) (xy 284.394658 -297.350767)
			(xy 284.105094 -297.350767) (xy 284.096964 -297.402102) (xy 284.080903 -297.451532) (xy 284.057307 -297.497842)
			(xy 284.026757 -297.53989) (xy 283.990006 -297.576641) (xy 283.947958 -297.607191) (xy 283.901648 -297.630787)
			(xy 283.852218 -297.646848) (xy 283.800883 -297.654978) (xy 283.748909 -297.654978) (xy 283.697574 -297.646848)
			(xy 283.648144 -297.630787) (xy 283.601834 -297.607191) (xy 283.559786 -297.576641) (xy 283.523035 -297.53989)
			(xy 283.492485 -297.497842) (xy 283.468889 -297.451532) (xy 283.452828 -297.402102) (xy 283.444698 -297.350767)
			(xy 283.155134 -297.350767) (xy 283.147004 -297.402102) (xy 283.130943 -297.451532) (xy 283.107347 -297.497842)
			(xy 283.076797 -297.53989) (xy 283.040046 -297.576641) (xy 282.997998 -297.607191) (xy 282.951688 -297.630787)
			(xy 282.902258 -297.646848) (xy 282.850923 -297.654978) (xy 282.798949 -297.654978) (xy 282.747614 -297.646848)
			(xy 282.698184 -297.630787) (xy 282.651874 -297.607191) (xy 282.609826 -297.576641) (xy 282.573075 -297.53989)
			(xy 282.542525 -297.497842) (xy 282.518929 -297.451532) (xy 282.502868 -297.402102) (xy 282.494738 -297.350767)
			(xy 282.20492 -297.350767) (xy 282.19679 -297.402102) (xy 282.180729 -297.451532) (xy 282.157133 -297.497842)
			(xy 282.126583 -297.53989) (xy 282.089832 -297.576641) (xy 282.047784 -297.607191) (xy 282.001474 -297.630787)
			(xy 281.952044 -297.646848) (xy 281.900709 -297.654978) (xy 281.848735 -297.654978) (xy 281.7974 -297.646848)
			(xy 281.74797 -297.630787) (xy 281.70166 -297.607191) (xy 281.659612 -297.576641) (xy 281.622861 -297.53989)
			(xy 281.592311 -297.497842) (xy 281.568715 -297.451532) (xy 281.552654 -297.402102) (xy 281.544524 -297.350767)
			(xy 281.25496 -297.350767) (xy 281.24683 -297.402102) (xy 281.230769 -297.451532) (xy 281.207173 -297.497842)
			(xy 281.176623 -297.53989) (xy 281.139872 -297.576641) (xy 281.097824 -297.607191) (xy 281.051514 -297.630787)
			(xy 281.002084 -297.646848) (xy 280.950749 -297.654978) (xy 280.898775 -297.654978) (xy 280.84744 -297.646848)
			(xy 280.79801 -297.630787) (xy 280.7517 -297.607191) (xy 280.709652 -297.576641) (xy 280.672901 -297.53989)
			(xy 280.642351 -297.497842) (xy 280.618755 -297.451532) (xy 280.602694 -297.402102) (xy 280.594564 -297.350767)
			(xy 280.305 -297.350767) (xy 280.29687 -297.402102) (xy 280.280809 -297.451532) (xy 280.257213 -297.497842)
			(xy 280.226663 -297.53989) (xy 280.189912 -297.576641) (xy 280.147864 -297.607191) (xy 280.101554 -297.630787)
			(xy 280.052124 -297.646848) (xy 280.000789 -297.654978) (xy 279.948815 -297.654978) (xy 279.89748 -297.646848)
			(xy 279.84805 -297.630787) (xy 279.80174 -297.607191) (xy 279.759692 -297.576641) (xy 279.722941 -297.53989)
			(xy 279.692391 -297.497842) (xy 279.668795 -297.451532) (xy 279.652734 -297.402102) (xy 279.644604 -297.350767)
			(xy 279.35504 -297.350767) (xy 279.34691 -297.402102) (xy 279.330849 -297.451532) (xy 279.307253 -297.497842)
			(xy 279.276703 -297.53989) (xy 279.239952 -297.576641) (xy 279.197904 -297.607191) (xy 279.151594 -297.630787)
			(xy 279.102164 -297.646848) (xy 279.050829 -297.654978) (xy 278.998855 -297.654978) (xy 278.94752 -297.646848)
			(xy 278.89809 -297.630787) (xy 278.85178 -297.607191) (xy 278.809732 -297.576641) (xy 278.772981 -297.53989)
			(xy 278.742431 -297.497842) (xy 278.718835 -297.451532) (xy 278.702774 -297.402102) (xy 278.694644 -297.350767)
			(xy 278.404973 -297.350767) (xy 278.397702 -297.398806) (xy 278.382983 -297.446301) (xy 278.36132 -297.491058)
			(xy 278.333199 -297.532067) (xy 278.299256 -297.568403) (xy 278.260255 -297.599247) (xy 278.217076 -297.623905)
			(xy 278.170691 -297.64182) (xy 278.14651 -297.647614) (xy 278.128984 -297.651424) (xy 278.106632 -297.679364)
			(xy 278.106632 -297.920156) (xy 278.128984 -297.948096) (xy 278.14651 -297.951906) (xy 278.172096 -297.958104)
			(xy 278.221032 -297.977504) (xy 278.266276 -298.004413) (xy 278.306685 -298.038151) (xy 278.341238 -298.077865)
			(xy 278.369062 -298.122552) (xy 278.389453 -298.171084) (xy 278.401897 -298.222234) (xy 278.40608 -298.274709)
			(xy 278.404005 -298.300727) (xy 278.694644 -298.300727) (xy 278.694644 -298.248753) (xy 278.702774 -298.197418)
			(xy 278.718835 -298.147988) (xy 278.742431 -298.101678) (xy 278.772981 -298.05963) (xy 278.809732 -298.022879)
			(xy 278.85178 -297.992329) (xy 278.89809 -297.968733) (xy 278.94752 -297.952672) (xy 278.998855 -297.944542)
			(xy 279.050829 -297.944542) (xy 279.102164 -297.952672) (xy 279.151594 -297.968733) (xy 279.197904 -297.992329)
			(xy 279.239952 -298.022879) (xy 279.276703 -298.05963) (xy 279.307253 -298.101678) (xy 279.330849 -298.147988)
			(xy 279.34691 -298.197418) (xy 279.35504 -298.248753) (xy 279.35555 -298.27474) (xy 279.35504 -298.300727)
			(xy 279.644604 -298.300727) (xy 279.644604 -298.248753) (xy 279.652734 -298.197418) (xy 279.668795 -298.147988)
			(xy 279.692391 -298.101678) (xy 279.722941 -298.05963) (xy 279.759692 -298.022879) (xy 279.80174 -297.992329)
			(xy 279.84805 -297.968733) (xy 279.89748 -297.952672) (xy 279.948815 -297.944542) (xy 280.000789 -297.944542)
			(xy 280.052124 -297.952672) (xy 280.101554 -297.968733) (xy 280.147864 -297.992329) (xy 280.189912 -298.022879)
			(xy 280.226663 -298.05963) (xy 280.257213 -298.101678) (xy 280.280809 -298.147988) (xy 280.29687 -298.197418)
			(xy 280.305 -298.248753) (xy 280.30551 -298.27474) (xy 280.305 -298.300727) (xy 280.594564 -298.300727)
			(xy 280.594564 -298.248753) (xy 280.602694 -298.197418) (xy 280.618755 -298.147988) (xy 280.642351 -298.101678)
			(xy 280.672901 -298.05963) (xy 280.709652 -298.022879) (xy 280.7517 -297.992329) (xy 280.79801 -297.968733)
			(xy 280.84744 -297.952672) (xy 280.898775 -297.944542) (xy 280.950749 -297.944542) (xy 281.002084 -297.952672)
			(xy 281.051514 -297.968733) (xy 281.097824 -297.992329) (xy 281.139872 -298.022879) (xy 281.176623 -298.05963)
			(xy 281.207173 -298.101678) (xy 281.230769 -298.147988) (xy 281.24683 -298.197418) (xy 281.25496 -298.248753)
			(xy 281.25547 -298.27474) (xy 281.25496 -298.300727) (xy 281.544524 -298.300727) (xy 281.544524 -298.248753)
			(xy 281.552654 -298.197418) (xy 281.568715 -298.147988) (xy 281.592311 -298.101678) (xy 281.622861 -298.05963)
			(xy 281.659612 -298.022879) (xy 281.70166 -297.992329) (xy 281.74797 -297.968733) (xy 281.7974 -297.952672)
			(xy 281.848735 -297.944542) (xy 281.900709 -297.944542) (xy 281.952044 -297.952672) (xy 282.001474 -297.968733)
			(xy 282.047784 -297.992329) (xy 282.089832 -298.022879) (xy 282.126583 -298.05963) (xy 282.157133 -298.101678)
			(xy 282.180729 -298.147988) (xy 282.19679 -298.197418) (xy 282.20492 -298.248753) (xy 282.20543 -298.27474)
			(xy 282.20492 -298.300727) (xy 282.494738 -298.300727) (xy 282.494738 -298.248753) (xy 282.502868 -298.197418)
			(xy 282.518929 -298.147988) (xy 282.542525 -298.101678) (xy 282.573075 -298.05963) (xy 282.609826 -298.022879)
			(xy 282.651874 -297.992329) (xy 282.698184 -297.968733) (xy 282.747614 -297.952672) (xy 282.798949 -297.944542)
			(xy 282.850923 -297.944542) (xy 282.902258 -297.952672) (xy 282.951688 -297.968733) (xy 282.997998 -297.992329)
			(xy 283.040046 -298.022879) (xy 283.076797 -298.05963) (xy 283.107347 -298.101678) (xy 283.130943 -298.147988)
			(xy 283.147004 -298.197418) (xy 283.155134 -298.248753) (xy 283.155644 -298.27474) (xy 283.155134 -298.300727)
			(xy 283.444698 -298.300727) (xy 283.444698 -298.248753) (xy 283.452828 -298.197418) (xy 283.468889 -298.147988)
			(xy 283.492485 -298.101678) (xy 283.523035 -298.05963) (xy 283.559786 -298.022879) (xy 283.601834 -297.992329)
			(xy 283.648144 -297.968733) (xy 283.697574 -297.952672) (xy 283.748909 -297.944542) (xy 283.800883 -297.944542)
			(xy 283.852218 -297.952672) (xy 283.901648 -297.968733) (xy 283.947958 -297.992329) (xy 283.990006 -298.022879)
			(xy 284.026757 -298.05963) (xy 284.057307 -298.101678) (xy 284.080903 -298.147988) (xy 284.096964 -298.197418)
			(xy 284.105094 -298.248753) (xy 284.105604 -298.27474) (xy 284.105094 -298.300727) (xy 284.394658 -298.300727)
			(xy 284.394658 -298.248753) (xy 284.402788 -298.197418) (xy 284.418849 -298.147988) (xy 284.442445 -298.101678)
			(xy 284.472995 -298.05963) (xy 284.509746 -298.022879) (xy 284.551794 -297.992329) (xy 284.598104 -297.968733)
			(xy 284.647534 -297.952672) (xy 284.698869 -297.944542) (xy 284.750843 -297.944542) (xy 284.802178 -297.952672)
			(xy 284.851608 -297.968733) (xy 284.897918 -297.992329) (xy 284.939966 -298.022879) (xy 284.976717 -298.05963)
			(xy 285.007267 -298.101678) (xy 285.030863 -298.147988) (xy 285.046924 -298.197418) (xy 285.055054 -298.248753)
			(xy 285.055564 -298.27474) (xy 285.055054 -298.300727) (xy 285.344618 -298.300727) (xy 285.344618 -298.248753)
			(xy 285.352748 -298.197418) (xy 285.368809 -298.147988) (xy 285.392405 -298.101678) (xy 285.422955 -298.05963)
			(xy 285.459706 -298.022879) (xy 285.501754 -297.992329) (xy 285.548064 -297.968733) (xy 285.597494 -297.952672)
			(xy 285.648829 -297.944542) (xy 285.700803 -297.944542) (xy 285.752138 -297.952672) (xy 285.801568 -297.968733)
			(xy 285.847878 -297.992329) (xy 285.889926 -298.022879) (xy 285.926677 -298.05963) (xy 285.957227 -298.101678)
			(xy 285.980823 -298.147988) (xy 285.996884 -298.197418) (xy 286.005014 -298.248753) (xy 286.005524 -298.27474)
			(xy 286.005014 -298.300727) (xy 286.294578 -298.300727) (xy 286.294578 -298.248753) (xy 286.302708 -298.197418)
			(xy 286.318769 -298.147988) (xy 286.342365 -298.101678) (xy 286.372915 -298.05963) (xy 286.409666 -298.022879)
			(xy 286.451714 -297.992329) (xy 286.498024 -297.968733) (xy 286.547454 -297.952672) (xy 286.598789 -297.944542)
			(xy 286.650763 -297.944542) (xy 286.702098 -297.952672) (xy 286.751528 -297.968733) (xy 286.797838 -297.992329)
			(xy 286.839886 -298.022879) (xy 286.876637 -298.05963) (xy 286.907187 -298.101678) (xy 286.930783 -298.147988)
			(xy 286.946844 -298.197418) (xy 286.954974 -298.248753) (xy 286.955484 -298.27474) (xy 286.954974 -298.300727)
			(xy 287.244538 -298.300727) (xy 287.244538 -298.248753) (xy 287.252668 -298.197418) (xy 287.268729 -298.147988)
			(xy 287.292325 -298.101678) (xy 287.322875 -298.05963) (xy 287.359626 -298.022879) (xy 287.401674 -297.992329)
			(xy 287.447984 -297.968733) (xy 287.497414 -297.952672) (xy 287.548749 -297.944542) (xy 287.600723 -297.944542)
			(xy 287.652058 -297.952672) (xy 287.701488 -297.968733) (xy 287.747798 -297.992329) (xy 287.789846 -298.022879)
			(xy 287.826597 -298.05963) (xy 287.857147 -298.101678) (xy 287.880743 -298.147988) (xy 287.896804 -298.197418)
			(xy 287.904934 -298.248753) (xy 287.905444 -298.27474) (xy 287.904934 -298.300727) (xy 288.194498 -298.300727)
			(xy 288.194498 -298.248753) (xy 288.202628 -298.197418) (xy 288.218689 -298.147988) (xy 288.242285 -298.101678)
			(xy 288.272835 -298.05963) (xy 288.309586 -298.022879) (xy 288.351634 -297.992329) (xy 288.397944 -297.968733)
			(xy 288.447374 -297.952672) (xy 288.498709 -297.944542) (xy 288.550683 -297.944542) (xy 288.602018 -297.952672)
			(xy 288.651448 -297.968733) (xy 288.697758 -297.992329) (xy 288.739806 -298.022879) (xy 288.776557 -298.05963)
			(xy 288.807107 -298.101678) (xy 288.830703 -298.147988) (xy 288.846764 -298.197418) (xy 288.854894 -298.248753)
			(xy 288.855404 -298.27474) (xy 288.854894 -298.300727) (xy 289.144712 -298.300727) (xy 289.144712 -298.248753)
			(xy 289.152842 -298.197418) (xy 289.168903 -298.147988) (xy 289.192499 -298.101678) (xy 289.223049 -298.05963)
			(xy 289.2598 -298.022879) (xy 289.301848 -297.992329) (xy 289.348158 -297.968733) (xy 289.397588 -297.952672)
			(xy 289.448923 -297.944542) (xy 289.500897 -297.944542) (xy 289.552232 -297.952672) (xy 289.601662 -297.968733)
			(xy 289.647972 -297.992329) (xy 289.69002 -298.022879) (xy 289.726771 -298.05963) (xy 289.757321 -298.101678)
			(xy 289.780917 -298.147988) (xy 289.796978 -298.197418) (xy 289.805108 -298.248753) (xy 289.805618 -298.27474)
			(xy 289.805108 -298.300727) (xy 290.094672 -298.300727) (xy 290.094672 -298.248753) (xy 290.102802 -298.197418)
			(xy 290.118863 -298.147988) (xy 290.142459 -298.101678) (xy 290.173009 -298.05963) (xy 290.20976 -298.022879)
			(xy 290.251808 -297.992329) (xy 290.298118 -297.968733) (xy 290.347548 -297.952672) (xy 290.398883 -297.944542)
			(xy 290.450857 -297.944542) (xy 290.502192 -297.952672) (xy 290.551622 -297.968733) (xy 290.597932 -297.992329)
			(xy 290.63998 -298.022879) (xy 290.676731 -298.05963) (xy 290.707281 -298.101678) (xy 290.730877 -298.147988)
			(xy 290.746938 -298.197418) (xy 290.755068 -298.248753) (xy 290.755578 -298.27474) (xy 290.755068 -298.300727)
			(xy 291.994592 -298.300727) (xy 291.994592 -298.248753) (xy 292.002722 -298.197418) (xy 292.018783 -298.147988)
			(xy 292.042379 -298.101678) (xy 292.072929 -298.05963) (xy 292.10968 -298.022879) (xy 292.151728 -297.992329)
			(xy 292.198038 -297.968733) (xy 292.247468 -297.952672) (xy 292.298803 -297.944542) (xy 292.350777 -297.944542)
			(xy 292.402112 -297.952672) (xy 292.451542 -297.968733) (xy 292.497852 -297.992329) (xy 292.5399 -298.022879)
			(xy 292.576651 -298.05963) (xy 292.607201 -298.101678) (xy 292.630797 -298.147988) (xy 292.646858 -298.197418)
			(xy 292.654988 -298.248753) (xy 292.655498 -298.27474) (xy 292.654988 -298.300727) (xy 292.944552 -298.300727)
			(xy 292.944552 -298.248753) (xy 292.952682 -298.197418) (xy 292.968743 -298.147988) (xy 292.992339 -298.101678)
			(xy 293.022889 -298.05963) (xy 293.05964 -298.022879) (xy 293.101688 -297.992329) (xy 293.147998 -297.968733)
			(xy 293.197428 -297.952672) (xy 293.248763 -297.944542) (xy 293.300737 -297.944542) (xy 293.352072 -297.952672)
			(xy 293.401502 -297.968733) (xy 293.447812 -297.992329) (xy 293.48986 -298.022879) (xy 293.526611 -298.05963)
			(xy 293.557161 -298.101678) (xy 293.580757 -298.147988) (xy 293.596818 -298.197418) (xy 293.604948 -298.248753)
			(xy 293.605458 -298.27474) (xy 293.604948 -298.300727) (xy 293.894512 -298.300727) (xy 293.894512 -298.248753)
			(xy 293.902642 -298.197418) (xy 293.918703 -298.147988) (xy 293.942299 -298.101678) (xy 293.972849 -298.05963)
			(xy 294.0096 -298.022879) (xy 294.051648 -297.992329) (xy 294.097958 -297.968733) (xy 294.147388 -297.952672)
			(xy 294.198723 -297.944542) (xy 294.250697 -297.944542) (xy 294.302032 -297.952672) (xy 294.351462 -297.968733)
			(xy 294.397772 -297.992329) (xy 294.43982 -298.022879) (xy 294.476571 -298.05963) (xy 294.507121 -298.101678)
			(xy 294.530717 -298.147988) (xy 294.546778 -298.197418) (xy 294.554908 -298.248753) (xy 294.555418 -298.27474)
			(xy 294.554908 -298.300727) (xy 294.844726 -298.300727) (xy 294.844726 -298.248753) (xy 294.852856 -298.197418)
			(xy 294.868917 -298.147988) (xy 294.892513 -298.101678) (xy 294.923063 -298.05963) (xy 294.959814 -298.022879)
			(xy 295.001862 -297.992329) (xy 295.048172 -297.968733) (xy 295.097602 -297.952672) (xy 295.148937 -297.944542)
			(xy 295.200911 -297.944542) (xy 295.252246 -297.952672) (xy 295.301676 -297.968733) (xy 295.347986 -297.992329)
			(xy 295.390034 -298.022879) (xy 295.426785 -298.05963) (xy 295.457335 -298.101678) (xy 295.480931 -298.147988)
			(xy 295.496992 -298.197418) (xy 295.505122 -298.248753) (xy 295.505632 -298.27474) (xy 295.505122 -298.300727)
			(xy 295.794686 -298.300727) (xy 295.794686 -298.248753) (xy 295.802816 -298.197418) (xy 295.818877 -298.147988)
			(xy 295.842473 -298.101678) (xy 295.873023 -298.05963) (xy 295.909774 -298.022879) (xy 295.951822 -297.992329)
			(xy 295.998132 -297.968733) (xy 296.047562 -297.952672) (xy 296.098897 -297.944542) (xy 296.150871 -297.944542)
			(xy 296.202206 -297.952672) (xy 296.251636 -297.968733) (xy 296.297946 -297.992329) (xy 296.339994 -298.022879)
			(xy 296.376745 -298.05963) (xy 296.407295 -298.101678) (xy 296.430891 -298.147988) (xy 296.446952 -298.197418)
			(xy 296.455082 -298.248753) (xy 296.455592 -298.27474) (xy 296.455082 -298.300727) (xy 296.744646 -298.300727)
			(xy 296.744646 -298.248753) (xy 296.752776 -298.197418) (xy 296.768837 -298.147988) (xy 296.792433 -298.101678)
			(xy 296.822983 -298.05963) (xy 296.859734 -298.022879) (xy 296.901782 -297.992329) (xy 296.948092 -297.968733)
			(xy 296.997522 -297.952672) (xy 297.048857 -297.944542) (xy 297.100831 -297.944542) (xy 297.152166 -297.952672)
			(xy 297.201596 -297.968733) (xy 297.247906 -297.992329) (xy 297.289954 -298.022879) (xy 297.326705 -298.05963)
			(xy 297.357255 -298.101678) (xy 297.380851 -298.147988) (xy 297.396912 -298.197418) (xy 297.405042 -298.248753)
			(xy 297.405552 -298.27474) (xy 297.405042 -298.300727) (xy 297.694606 -298.300727) (xy 297.694606 -298.248753)
			(xy 297.702736 -298.197418) (xy 297.718797 -298.147988) (xy 297.742393 -298.101678) (xy 297.772943 -298.05963)
			(xy 297.809694 -298.022879) (xy 297.851742 -297.992329) (xy 297.898052 -297.968733) (xy 297.947482 -297.952672)
			(xy 297.998817 -297.944542) (xy 298.050791 -297.944542) (xy 298.102126 -297.952672) (xy 298.151556 -297.968733)
			(xy 298.197866 -297.992329) (xy 298.239914 -298.022879) (xy 298.276665 -298.05963) (xy 298.307215 -298.101678)
			(xy 298.330811 -298.147988) (xy 298.346872 -298.197418) (xy 298.355002 -298.248753) (xy 298.355512 -298.27474)
			(xy 298.355002 -298.300727) (xy 298.644566 -298.300727) (xy 298.644566 -298.248753) (xy 298.652696 -298.197418)
			(xy 298.668757 -298.147988) (xy 298.692353 -298.101678) (xy 298.722903 -298.05963) (xy 298.759654 -298.022879)
			(xy 298.801702 -297.992329) (xy 298.848012 -297.968733) (xy 298.897442 -297.952672) (xy 298.948777 -297.944542)
			(xy 299.000751 -297.944542) (xy 299.052086 -297.952672) (xy 299.101516 -297.968733) (xy 299.147826 -297.992329)
			(xy 299.189874 -298.022879) (xy 299.226625 -298.05963) (xy 299.257175 -298.101678) (xy 299.280771 -298.147988)
			(xy 299.296832 -298.197418) (xy 299.304962 -298.248753) (xy 299.305472 -298.27474) (xy 299.304962 -298.300727)
			(xy 299.594526 -298.300727) (xy 299.594526 -298.248753) (xy 299.602656 -298.197418) (xy 299.618717 -298.147988)
			(xy 299.642313 -298.101678) (xy 299.672863 -298.05963) (xy 299.709614 -298.022879) (xy 299.751662 -297.992329)
			(xy 299.797972 -297.968733) (xy 299.847402 -297.952672) (xy 299.898737 -297.944542) (xy 299.950711 -297.944542)
			(xy 300.002046 -297.952672) (xy 300.051476 -297.968733) (xy 300.097786 -297.992329) (xy 300.139834 -298.022879)
			(xy 300.176585 -298.05963) (xy 300.207135 -298.101678) (xy 300.230731 -298.147988) (xy 300.246792 -298.197418)
			(xy 300.254922 -298.248753) (xy 300.255432 -298.27474) (xy 300.254922 -298.300727) (xy 300.246792 -298.352062)
			(xy 300.230731 -298.401492) (xy 300.207135 -298.447802) (xy 300.176585 -298.48985) (xy 300.139834 -298.526601)
			(xy 300.097786 -298.557151) (xy 300.051476 -298.580747) (xy 300.002046 -298.596808) (xy 299.950711 -298.604938)
			(xy 299.898737 -298.604938) (xy 299.847402 -298.596808) (xy 299.797972 -298.580747) (xy 299.751662 -298.557151)
			(xy 299.709614 -298.526601) (xy 299.672863 -298.48985) (xy 299.642313 -298.447802) (xy 299.618717 -298.401492)
			(xy 299.602656 -298.352062) (xy 299.594526 -298.300727) (xy 299.304962 -298.300727) (xy 299.296832 -298.352062)
			(xy 299.280771 -298.401492) (xy 299.257175 -298.447802) (xy 299.226625 -298.48985) (xy 299.189874 -298.526601)
			(xy 299.147826 -298.557151) (xy 299.101516 -298.580747) (xy 299.052086 -298.596808) (xy 299.000751 -298.604938)
			(xy 298.948777 -298.604938) (xy 298.897442 -298.596808) (xy 298.848012 -298.580747) (xy 298.801702 -298.557151)
			(xy 298.759654 -298.526601) (xy 298.722903 -298.48985) (xy 298.692353 -298.447802) (xy 298.668757 -298.401492)
			(xy 298.652696 -298.352062) (xy 298.644566 -298.300727) (xy 298.355002 -298.300727) (xy 298.346872 -298.352062)
			(xy 298.330811 -298.401492) (xy 298.307215 -298.447802) (xy 298.276665 -298.48985) (xy 298.239914 -298.526601)
			(xy 298.197866 -298.557151) (xy 298.151556 -298.580747) (xy 298.102126 -298.596808) (xy 298.050791 -298.604938)
			(xy 297.998817 -298.604938) (xy 297.947482 -298.596808) (xy 297.898052 -298.580747) (xy 297.851742 -298.557151)
			(xy 297.809694 -298.526601) (xy 297.772943 -298.48985) (xy 297.742393 -298.447802) (xy 297.718797 -298.401492)
			(xy 297.702736 -298.352062) (xy 297.694606 -298.300727) (xy 297.405042 -298.300727) (xy 297.396912 -298.352062)
			(xy 297.380851 -298.401492) (xy 297.357255 -298.447802) (xy 297.326705 -298.48985) (xy 297.289954 -298.526601)
			(xy 297.247906 -298.557151) (xy 297.201596 -298.580747) (xy 297.152166 -298.596808) (xy 297.100831 -298.604938)
			(xy 297.048857 -298.604938) (xy 296.997522 -298.596808) (xy 296.948092 -298.580747) (xy 296.901782 -298.557151)
			(xy 296.859734 -298.526601) (xy 296.822983 -298.48985) (xy 296.792433 -298.447802) (xy 296.768837 -298.401492)
			(xy 296.752776 -298.352062) (xy 296.744646 -298.300727) (xy 296.455082 -298.300727) (xy 296.446952 -298.352062)
			(xy 296.430891 -298.401492) (xy 296.407295 -298.447802) (xy 296.376745 -298.48985) (xy 296.339994 -298.526601)
			(xy 296.297946 -298.557151) (xy 296.251636 -298.580747) (xy 296.202206 -298.596808) (xy 296.150871 -298.604938)
			(xy 296.098897 -298.604938) (xy 296.047562 -298.596808) (xy 295.998132 -298.580747) (xy 295.951822 -298.557151)
			(xy 295.909774 -298.526601) (xy 295.873023 -298.48985) (xy 295.842473 -298.447802) (xy 295.818877 -298.401492)
			(xy 295.802816 -298.352062) (xy 295.794686 -298.300727) (xy 295.505122 -298.300727) (xy 295.496992 -298.352062)
			(xy 295.480931 -298.401492) (xy 295.457335 -298.447802) (xy 295.426785 -298.48985) (xy 295.390034 -298.526601)
			(xy 295.347986 -298.557151) (xy 295.301676 -298.580747) (xy 295.252246 -298.596808) (xy 295.200911 -298.604938)
			(xy 295.148937 -298.604938) (xy 295.097602 -298.596808) (xy 295.048172 -298.580747) (xy 295.001862 -298.557151)
			(xy 294.959814 -298.526601) (xy 294.923063 -298.48985) (xy 294.892513 -298.447802) (xy 294.868917 -298.401492)
			(xy 294.852856 -298.352062) (xy 294.844726 -298.300727) (xy 294.554908 -298.300727) (xy 294.546778 -298.352062)
			(xy 294.530717 -298.401492) (xy 294.507121 -298.447802) (xy 294.476571 -298.48985) (xy 294.43982 -298.526601)
			(xy 294.397772 -298.557151) (xy 294.351462 -298.580747) (xy 294.302032 -298.596808) (xy 294.250697 -298.604938)
			(xy 294.198723 -298.604938) (xy 294.147388 -298.596808) (xy 294.097958 -298.580747) (xy 294.051648 -298.557151)
			(xy 294.0096 -298.526601) (xy 293.972849 -298.48985) (xy 293.942299 -298.447802) (xy 293.918703 -298.401492)
			(xy 293.902642 -298.352062) (xy 293.894512 -298.300727) (xy 293.604948 -298.300727) (xy 293.596818 -298.352062)
			(xy 293.580757 -298.401492) (xy 293.557161 -298.447802) (xy 293.526611 -298.48985) (xy 293.48986 -298.526601)
			(xy 293.447812 -298.557151) (xy 293.401502 -298.580747) (xy 293.352072 -298.596808) (xy 293.300737 -298.604938)
			(xy 293.248763 -298.604938) (xy 293.197428 -298.596808) (xy 293.147998 -298.580747) (xy 293.101688 -298.557151)
			(xy 293.05964 -298.526601) (xy 293.022889 -298.48985) (xy 292.992339 -298.447802) (xy 292.968743 -298.401492)
			(xy 292.952682 -298.352062) (xy 292.944552 -298.300727) (xy 292.654988 -298.300727) (xy 292.646858 -298.352062)
			(xy 292.630797 -298.401492) (xy 292.607201 -298.447802) (xy 292.576651 -298.48985) (xy 292.5399 -298.526601)
			(xy 292.497852 -298.557151) (xy 292.451542 -298.580747) (xy 292.402112 -298.596808) (xy 292.350777 -298.604938)
			(xy 292.298803 -298.604938) (xy 292.247468 -298.596808) (xy 292.198038 -298.580747) (xy 292.151728 -298.557151)
			(xy 292.10968 -298.526601) (xy 292.072929 -298.48985) (xy 292.042379 -298.447802) (xy 292.018783 -298.401492)
			(xy 292.002722 -298.352062) (xy 291.994592 -298.300727) (xy 290.755068 -298.300727) (xy 290.746938 -298.352062)
			(xy 290.730877 -298.401492) (xy 290.707281 -298.447802) (xy 290.676731 -298.48985) (xy 290.63998 -298.526601)
			(xy 290.597932 -298.557151) (xy 290.551622 -298.580747) (xy 290.502192 -298.596808) (xy 290.450857 -298.604938)
			(xy 290.398883 -298.604938) (xy 290.347548 -298.596808) (xy 290.298118 -298.580747) (xy 290.251808 -298.557151)
			(xy 290.20976 -298.526601) (xy 290.173009 -298.48985) (xy 290.142459 -298.447802) (xy 290.118863 -298.401492)
			(xy 290.102802 -298.352062) (xy 290.094672 -298.300727) (xy 289.805108 -298.300727) (xy 289.796978 -298.352062)
			(xy 289.780917 -298.401492) (xy 289.757321 -298.447802) (xy 289.726771 -298.48985) (xy 289.69002 -298.526601)
			(xy 289.647972 -298.557151) (xy 289.601662 -298.580747) (xy 289.552232 -298.596808) (xy 289.500897 -298.604938)
			(xy 289.448923 -298.604938) (xy 289.397588 -298.596808) (xy 289.348158 -298.580747) (xy 289.301848 -298.557151)
			(xy 289.2598 -298.526601) (xy 289.223049 -298.48985) (xy 289.192499 -298.447802) (xy 289.168903 -298.401492)
			(xy 289.152842 -298.352062) (xy 289.144712 -298.300727) (xy 288.854894 -298.300727) (xy 288.846764 -298.352062)
			(xy 288.830703 -298.401492) (xy 288.807107 -298.447802) (xy 288.776557 -298.48985) (xy 288.739806 -298.526601)
			(xy 288.697758 -298.557151) (xy 288.651448 -298.580747) (xy 288.602018 -298.596808) (xy 288.550683 -298.604938)
			(xy 288.498709 -298.604938) (xy 288.447374 -298.596808) (xy 288.397944 -298.580747) (xy 288.351634 -298.557151)
			(xy 288.309586 -298.526601) (xy 288.272835 -298.48985) (xy 288.242285 -298.447802) (xy 288.218689 -298.401492)
			(xy 288.202628 -298.352062) (xy 288.194498 -298.300727) (xy 287.904934 -298.300727) (xy 287.896804 -298.352062)
			(xy 287.880743 -298.401492) (xy 287.857147 -298.447802) (xy 287.826597 -298.48985) (xy 287.789846 -298.526601)
			(xy 287.747798 -298.557151) (xy 287.701488 -298.580747) (xy 287.652058 -298.596808) (xy 287.600723 -298.604938)
			(xy 287.548749 -298.604938) (xy 287.497414 -298.596808) (xy 287.447984 -298.580747) (xy 287.401674 -298.557151)
			(xy 287.359626 -298.526601) (xy 287.322875 -298.48985) (xy 287.292325 -298.447802) (xy 287.268729 -298.401492)
			(xy 287.252668 -298.352062) (xy 287.244538 -298.300727) (xy 286.954974 -298.300727) (xy 286.946844 -298.352062)
			(xy 286.930783 -298.401492) (xy 286.907187 -298.447802) (xy 286.876637 -298.48985) (xy 286.839886 -298.526601)
			(xy 286.797838 -298.557151) (xy 286.751528 -298.580747) (xy 286.702098 -298.596808) (xy 286.650763 -298.604938)
			(xy 286.598789 -298.604938) (xy 286.547454 -298.596808) (xy 286.498024 -298.580747) (xy 286.451714 -298.557151)
			(xy 286.409666 -298.526601) (xy 286.372915 -298.48985) (xy 286.342365 -298.447802) (xy 286.318769 -298.401492)
			(xy 286.302708 -298.352062) (xy 286.294578 -298.300727) (xy 286.005014 -298.300727) (xy 285.996884 -298.352062)
			(xy 285.980823 -298.401492) (xy 285.957227 -298.447802) (xy 285.926677 -298.48985) (xy 285.889926 -298.526601)
			(xy 285.847878 -298.557151) (xy 285.801568 -298.580747) (xy 285.752138 -298.596808) (xy 285.700803 -298.604938)
			(xy 285.648829 -298.604938) (xy 285.597494 -298.596808) (xy 285.548064 -298.580747) (xy 285.501754 -298.557151)
			(xy 285.459706 -298.526601) (xy 285.422955 -298.48985) (xy 285.392405 -298.447802) (xy 285.368809 -298.401492)
			(xy 285.352748 -298.352062) (xy 285.344618 -298.300727) (xy 285.055054 -298.300727) (xy 285.046924 -298.352062)
			(xy 285.030863 -298.401492) (xy 285.007267 -298.447802) (xy 284.976717 -298.48985) (xy 284.939966 -298.526601)
			(xy 284.897918 -298.557151) (xy 284.851608 -298.580747) (xy 284.802178 -298.596808) (xy 284.750843 -298.604938)
			(xy 284.698869 -298.604938) (xy 284.647534 -298.596808) (xy 284.598104 -298.580747) (xy 284.551794 -298.557151)
			(xy 284.509746 -298.526601) (xy 284.472995 -298.48985) (xy 284.442445 -298.447802) (xy 284.418849 -298.401492)
			(xy 284.402788 -298.352062) (xy 284.394658 -298.300727) (xy 284.105094 -298.300727) (xy 284.096964 -298.352062)
			(xy 284.080903 -298.401492) (xy 284.057307 -298.447802) (xy 284.026757 -298.48985) (xy 283.990006 -298.526601)
			(xy 283.947958 -298.557151) (xy 283.901648 -298.580747) (xy 283.852218 -298.596808) (xy 283.800883 -298.604938)
			(xy 283.748909 -298.604938) (xy 283.697574 -298.596808) (xy 283.648144 -298.580747) (xy 283.601834 -298.557151)
			(xy 283.559786 -298.526601) (xy 283.523035 -298.48985) (xy 283.492485 -298.447802) (xy 283.468889 -298.401492)
			(xy 283.452828 -298.352062) (xy 283.444698 -298.300727) (xy 283.155134 -298.300727) (xy 283.147004 -298.352062)
			(xy 283.130943 -298.401492) (xy 283.107347 -298.447802) (xy 283.076797 -298.48985) (xy 283.040046 -298.526601)
			(xy 282.997998 -298.557151) (xy 282.951688 -298.580747) (xy 282.902258 -298.596808) (xy 282.850923 -298.604938)
			(xy 282.798949 -298.604938) (xy 282.747614 -298.596808) (xy 282.698184 -298.580747) (xy 282.651874 -298.557151)
			(xy 282.609826 -298.526601) (xy 282.573075 -298.48985) (xy 282.542525 -298.447802) (xy 282.518929 -298.401492)
			(xy 282.502868 -298.352062) (xy 282.494738 -298.300727) (xy 282.20492 -298.300727) (xy 282.19679 -298.352062)
			(xy 282.180729 -298.401492) (xy 282.157133 -298.447802) (xy 282.126583 -298.48985) (xy 282.089832 -298.526601)
			(xy 282.047784 -298.557151) (xy 282.001474 -298.580747) (xy 281.952044 -298.596808) (xy 281.900709 -298.604938)
			(xy 281.848735 -298.604938) (xy 281.7974 -298.596808) (xy 281.74797 -298.580747) (xy 281.70166 -298.557151)
			(xy 281.659612 -298.526601) (xy 281.622861 -298.48985) (xy 281.592311 -298.447802) (xy 281.568715 -298.401492)
			(xy 281.552654 -298.352062) (xy 281.544524 -298.300727) (xy 281.25496 -298.300727) (xy 281.24683 -298.352062)
			(xy 281.230769 -298.401492) (xy 281.207173 -298.447802) (xy 281.176623 -298.48985) (xy 281.139872 -298.526601)
			(xy 281.097824 -298.557151) (xy 281.051514 -298.580747) (xy 281.002084 -298.596808) (xy 280.950749 -298.604938)
			(xy 280.898775 -298.604938) (xy 280.84744 -298.596808) (xy 280.79801 -298.580747) (xy 280.7517 -298.557151)
			(xy 280.709652 -298.526601) (xy 280.672901 -298.48985) (xy 280.642351 -298.447802) (xy 280.618755 -298.401492)
			(xy 280.602694 -298.352062) (xy 280.594564 -298.300727) (xy 280.305 -298.300727) (xy 280.29687 -298.352062)
			(xy 280.280809 -298.401492) (xy 280.257213 -298.447802) (xy 280.226663 -298.48985) (xy 280.189912 -298.526601)
			(xy 280.147864 -298.557151) (xy 280.101554 -298.580747) (xy 280.052124 -298.596808) (xy 280.000789 -298.604938)
			(xy 279.948815 -298.604938) (xy 279.89748 -298.596808) (xy 279.84805 -298.580747) (xy 279.80174 -298.557151)
			(xy 279.759692 -298.526601) (xy 279.722941 -298.48985) (xy 279.692391 -298.447802) (xy 279.668795 -298.401492)
			(xy 279.652734 -298.352062) (xy 279.644604 -298.300727) (xy 279.35504 -298.300727) (xy 279.34691 -298.352062)
			(xy 279.330849 -298.401492) (xy 279.307253 -298.447802) (xy 279.276703 -298.48985) (xy 279.239952 -298.526601)
			(xy 279.197904 -298.557151) (xy 279.151594 -298.580747) (xy 279.102164 -298.596808) (xy 279.050829 -298.604938)
			(xy 278.998855 -298.604938) (xy 278.94752 -298.596808) (xy 278.89809 -298.580747) (xy 278.85178 -298.557151)
			(xy 278.809732 -298.526601) (xy 278.772981 -298.48985) (xy 278.742431 -298.447802) (xy 278.718835 -298.401492)
			(xy 278.702774 -298.352062) (xy 278.694644 -298.300727) (xy 278.404005 -298.300727) (xy 278.401895 -298.327184)
			(xy 278.389448 -298.378332) (xy 278.369054 -298.426863) (xy 278.341228 -298.471549) (xy 278.306673 -298.511261)
			(xy 278.266262 -298.544997) (xy 278.221016 -298.571904) (xy 278.172079 -298.591301) (xy 278.14651 -298.597574)
			(xy 278.128984 -298.601384) (xy 278.106632 -298.629324) (xy 278.106632 -298.87037) (xy 278.128984 -298.89831)
			(xy 278.14651 -298.90212) (xy 278.172102 -298.908318) (xy 278.221052 -298.92772) (xy 278.26631 -298.954634)
			(xy 278.306731 -298.988378) (xy 278.341295 -299.0281) (xy 278.369128 -299.072797) (xy 278.389527 -299.12134)
			(xy 278.401977 -299.172502) (xy 278.406164 -299.22499) (xy 278.404095 -299.250941) (xy 278.694644 -299.250941)
			(xy 278.694644 -299.198967) (xy 278.702774 -299.147632) (xy 278.718835 -299.098202) (xy 278.742431 -299.051892)
			(xy 278.772981 -299.009844) (xy 278.809732 -298.973093) (xy 278.85178 -298.942543) (xy 278.89809 -298.918947)
			(xy 278.94752 -298.902886) (xy 278.998855 -298.894756) (xy 279.050829 -298.894756) (xy 279.102164 -298.902886)
			(xy 279.151594 -298.918947) (xy 279.197904 -298.942543) (xy 279.239952 -298.973093) (xy 279.276703 -299.009844)
			(xy 279.307253 -299.051892) (xy 279.330849 -299.098202) (xy 279.34691 -299.147632) (xy 279.35504 -299.198967)
			(xy 279.35555 -299.224954) (xy 279.35504 -299.250941) (xy 279.644604 -299.250941) (xy 279.644604 -299.198967)
			(xy 279.652734 -299.147632) (xy 279.668795 -299.098202) (xy 279.692391 -299.051892) (xy 279.722941 -299.009844)
			(xy 279.759692 -298.973093) (xy 279.80174 -298.942543) (xy 279.84805 -298.918947) (xy 279.89748 -298.902886)
			(xy 279.948815 -298.894756) (xy 280.000789 -298.894756) (xy 280.052124 -298.902886) (xy 280.101554 -298.918947)
			(xy 280.147864 -298.942543) (xy 280.189912 -298.973093) (xy 280.226663 -299.009844) (xy 280.257213 -299.051892)
			(xy 280.280809 -299.098202) (xy 280.29687 -299.147632) (xy 280.305 -299.198967) (xy 280.30551 -299.224954)
			(xy 280.305 -299.250941) (xy 280.594564 -299.250941) (xy 280.594564 -299.198967) (xy 280.602694 -299.147632)
			(xy 280.618755 -299.098202) (xy 280.642351 -299.051892) (xy 280.672901 -299.009844) (xy 280.709652 -298.973093)
			(xy 280.7517 -298.942543) (xy 280.79801 -298.918947) (xy 280.84744 -298.902886) (xy 280.898775 -298.894756)
			(xy 280.950749 -298.894756) (xy 281.002084 -298.902886) (xy 281.051514 -298.918947) (xy 281.097824 -298.942543)
			(xy 281.139872 -298.973093) (xy 281.176623 -299.009844) (xy 281.207173 -299.051892) (xy 281.230769 -299.098202)
			(xy 281.24683 -299.147632) (xy 281.25496 -299.198967) (xy 281.25547 -299.224954) (xy 281.25496 -299.250941)
			(xy 281.544524 -299.250941) (xy 281.544524 -299.198967) (xy 281.552654 -299.147632) (xy 281.568715 -299.098202)
			(xy 281.592311 -299.051892) (xy 281.622861 -299.009844) (xy 281.659612 -298.973093) (xy 281.70166 -298.942543)
			(xy 281.74797 -298.918947) (xy 281.7974 -298.902886) (xy 281.848735 -298.894756) (xy 281.900709 -298.894756)
			(xy 281.952044 -298.902886) (xy 282.001474 -298.918947) (xy 282.047784 -298.942543) (xy 282.089832 -298.973093)
			(xy 282.126583 -299.009844) (xy 282.157133 -299.051892) (xy 282.180729 -299.098202) (xy 282.19679 -299.147632)
			(xy 282.20492 -299.198967) (xy 282.20543 -299.224954) (xy 282.20492 -299.250941) (xy 282.494738 -299.250941)
			(xy 282.494738 -299.198967) (xy 282.502868 -299.147632) (xy 282.518929 -299.098202) (xy 282.542525 -299.051892)
			(xy 282.573075 -299.009844) (xy 282.609826 -298.973093) (xy 282.651874 -298.942543) (xy 282.698184 -298.918947)
			(xy 282.747614 -298.902886) (xy 282.798949 -298.894756) (xy 282.850923 -298.894756) (xy 282.902258 -298.902886)
			(xy 282.951688 -298.918947) (xy 282.997998 -298.942543) (xy 283.040046 -298.973093) (xy 283.076797 -299.009844)
			(xy 283.107347 -299.051892) (xy 283.130943 -299.098202) (xy 283.147004 -299.147632) (xy 283.155134 -299.198967)
			(xy 283.155644 -299.224954) (xy 283.155134 -299.250941) (xy 283.444698 -299.250941) (xy 283.444698 -299.198967)
			(xy 283.452828 -299.147632) (xy 283.468889 -299.098202) (xy 283.492485 -299.051892) (xy 283.523035 -299.009844)
			(xy 283.559786 -298.973093) (xy 283.601834 -298.942543) (xy 283.648144 -298.918947) (xy 283.697574 -298.902886)
			(xy 283.748909 -298.894756) (xy 283.800883 -298.894756) (xy 283.852218 -298.902886) (xy 283.901648 -298.918947)
			(xy 283.947958 -298.942543) (xy 283.990006 -298.973093) (xy 284.026757 -299.009844) (xy 284.057307 -299.051892)
			(xy 284.080903 -299.098202) (xy 284.096964 -299.147632) (xy 284.105094 -299.198967) (xy 284.105604 -299.224954)
			(xy 284.105094 -299.250941) (xy 284.394658 -299.250941) (xy 284.394658 -299.198967) (xy 284.402788 -299.147632)
			(xy 284.418849 -299.098202) (xy 284.442445 -299.051892) (xy 284.472995 -299.009844) (xy 284.509746 -298.973093)
			(xy 284.551794 -298.942543) (xy 284.598104 -298.918947) (xy 284.647534 -298.902886) (xy 284.698869 -298.894756)
			(xy 284.750843 -298.894756) (xy 284.802178 -298.902886) (xy 284.851608 -298.918947) (xy 284.897918 -298.942543)
			(xy 284.939966 -298.973093) (xy 284.976717 -299.009844) (xy 285.007267 -299.051892) (xy 285.030863 -299.098202)
			(xy 285.046924 -299.147632) (xy 285.055054 -299.198967) (xy 285.055564 -299.224954) (xy 285.055054 -299.250941)
			(xy 285.344618 -299.250941) (xy 285.344618 -299.198967) (xy 285.352748 -299.147632) (xy 285.368809 -299.098202)
			(xy 285.392405 -299.051892) (xy 285.422955 -299.009844) (xy 285.459706 -298.973093) (xy 285.501754 -298.942543)
			(xy 285.548064 -298.918947) (xy 285.597494 -298.902886) (xy 285.648829 -298.894756) (xy 285.700803 -298.894756)
			(xy 285.752138 -298.902886) (xy 285.801568 -298.918947) (xy 285.847878 -298.942543) (xy 285.889926 -298.973093)
			(xy 285.926677 -299.009844) (xy 285.957227 -299.051892) (xy 285.980823 -299.098202) (xy 285.996884 -299.147632)
			(xy 286.005014 -299.198967) (xy 286.005524 -299.224954) (xy 286.005014 -299.250941) (xy 286.294578 -299.250941)
			(xy 286.294578 -299.198967) (xy 286.302708 -299.147632) (xy 286.318769 -299.098202) (xy 286.342365 -299.051892)
			(xy 286.372915 -299.009844) (xy 286.409666 -298.973093) (xy 286.451714 -298.942543) (xy 286.498024 -298.918947)
			(xy 286.547454 -298.902886) (xy 286.598789 -298.894756) (xy 286.650763 -298.894756) (xy 286.702098 -298.902886)
			(xy 286.751528 -298.918947) (xy 286.797838 -298.942543) (xy 286.839886 -298.973093) (xy 286.876637 -299.009844)
			(xy 286.907187 -299.051892) (xy 286.930783 -299.098202) (xy 286.946844 -299.147632) (xy 286.954974 -299.198967)
			(xy 286.955484 -299.224954) (xy 286.954974 -299.250941) (xy 287.244538 -299.250941) (xy 287.244538 -299.198967)
			(xy 287.252668 -299.147632) (xy 287.268729 -299.098202) (xy 287.292325 -299.051892) (xy 287.322875 -299.009844)
			(xy 287.359626 -298.973093) (xy 287.401674 -298.942543) (xy 287.447984 -298.918947) (xy 287.497414 -298.902886)
			(xy 287.548749 -298.894756) (xy 287.600723 -298.894756) (xy 287.652058 -298.902886) (xy 287.701488 -298.918947)
			(xy 287.747798 -298.942543) (xy 287.789846 -298.973093) (xy 287.826597 -299.009844) (xy 287.857147 -299.051892)
			(xy 287.880743 -299.098202) (xy 287.896804 -299.147632) (xy 287.904934 -299.198967) (xy 287.905444 -299.224954)
			(xy 287.904934 -299.250941) (xy 288.194498 -299.250941) (xy 288.194498 -299.198967) (xy 288.202628 -299.147632)
			(xy 288.218689 -299.098202) (xy 288.242285 -299.051892) (xy 288.272835 -299.009844) (xy 288.309586 -298.973093)
			(xy 288.351634 -298.942543) (xy 288.397944 -298.918947) (xy 288.447374 -298.902886) (xy 288.498709 -298.894756)
			(xy 288.550683 -298.894756) (xy 288.602018 -298.902886) (xy 288.651448 -298.918947) (xy 288.697758 -298.942543)
			(xy 288.739806 -298.973093) (xy 288.776557 -299.009844) (xy 288.807107 -299.051892) (xy 288.830703 -299.098202)
			(xy 288.846764 -299.147632) (xy 288.854894 -299.198967) (xy 288.855404 -299.224954) (xy 288.854894 -299.250941)
			(xy 289.144712 -299.250941) (xy 289.144712 -299.198967) (xy 289.152842 -299.147632) (xy 289.168903 -299.098202)
			(xy 289.192499 -299.051892) (xy 289.223049 -299.009844) (xy 289.2598 -298.973093) (xy 289.301848 -298.942543)
			(xy 289.348158 -298.918947) (xy 289.397588 -298.902886) (xy 289.448923 -298.894756) (xy 289.500897 -298.894756)
			(xy 289.552232 -298.902886) (xy 289.601662 -298.918947) (xy 289.647972 -298.942543) (xy 289.69002 -298.973093)
			(xy 289.726771 -299.009844) (xy 289.757321 -299.051892) (xy 289.780917 -299.098202) (xy 289.796978 -299.147632)
			(xy 289.805108 -299.198967) (xy 289.805618 -299.224954) (xy 289.805108 -299.250941) (xy 290.094672 -299.250941)
			(xy 290.094672 -299.198967) (xy 290.102802 -299.147632) (xy 290.118863 -299.098202) (xy 290.142459 -299.051892)
			(xy 290.173009 -299.009844) (xy 290.20976 -298.973093) (xy 290.251808 -298.942543) (xy 290.298118 -298.918947)
			(xy 290.347548 -298.902886) (xy 290.398883 -298.894756) (xy 290.450857 -298.894756) (xy 290.502192 -298.902886)
			(xy 290.551622 -298.918947) (xy 290.597932 -298.942543) (xy 290.63998 -298.973093) (xy 290.676731 -299.009844)
			(xy 290.707281 -299.051892) (xy 290.730877 -299.098202) (xy 290.746938 -299.147632) (xy 290.755068 -299.198967)
			(xy 290.755578 -299.224954) (xy 290.755068 -299.250941) (xy 291.994592 -299.250941) (xy 291.994592 -299.198967)
			(xy 292.002722 -299.147632) (xy 292.018783 -299.098202) (xy 292.042379 -299.051892) (xy 292.072929 -299.009844)
			(xy 292.10968 -298.973093) (xy 292.151728 -298.942543) (xy 292.198038 -298.918947) (xy 292.247468 -298.902886)
			(xy 292.298803 -298.894756) (xy 292.350777 -298.894756) (xy 292.402112 -298.902886) (xy 292.451542 -298.918947)
			(xy 292.497852 -298.942543) (xy 292.5399 -298.973093) (xy 292.576651 -299.009844) (xy 292.607201 -299.051892)
			(xy 292.630797 -299.098202) (xy 292.646858 -299.147632) (xy 292.654988 -299.198967) (xy 292.655498 -299.224954)
			(xy 292.654988 -299.250941) (xy 292.944552 -299.250941) (xy 292.944552 -299.198967) (xy 292.952682 -299.147632)
			(xy 292.968743 -299.098202) (xy 292.992339 -299.051892) (xy 293.022889 -299.009844) (xy 293.05964 -298.973093)
			(xy 293.101688 -298.942543) (xy 293.147998 -298.918947) (xy 293.197428 -298.902886) (xy 293.248763 -298.894756)
			(xy 293.300737 -298.894756) (xy 293.352072 -298.902886) (xy 293.401502 -298.918947) (xy 293.447812 -298.942543)
			(xy 293.48986 -298.973093) (xy 293.526611 -299.009844) (xy 293.557161 -299.051892) (xy 293.580757 -299.098202)
			(xy 293.596818 -299.147632) (xy 293.604948 -299.198967) (xy 293.605458 -299.224954) (xy 293.604948 -299.250941)
			(xy 293.894512 -299.250941) (xy 293.894512 -299.198967) (xy 293.902642 -299.147632) (xy 293.918703 -299.098202)
			(xy 293.942299 -299.051892) (xy 293.972849 -299.009844) (xy 294.0096 -298.973093) (xy 294.051648 -298.942543)
			(xy 294.097958 -298.918947) (xy 294.147388 -298.902886) (xy 294.198723 -298.894756) (xy 294.250697 -298.894756)
			(xy 294.302032 -298.902886) (xy 294.351462 -298.918947) (xy 294.397772 -298.942543) (xy 294.43982 -298.973093)
			(xy 294.476571 -299.009844) (xy 294.507121 -299.051892) (xy 294.530717 -299.098202) (xy 294.546778 -299.147632)
			(xy 294.554908 -299.198967) (xy 294.555418 -299.224954) (xy 294.554908 -299.250941) (xy 294.844726 -299.250941)
			(xy 294.844726 -299.198967) (xy 294.852856 -299.147632) (xy 294.868917 -299.098202) (xy 294.892513 -299.051892)
			(xy 294.923063 -299.009844) (xy 294.959814 -298.973093) (xy 295.001862 -298.942543) (xy 295.048172 -298.918947)
			(xy 295.097602 -298.902886) (xy 295.148937 -298.894756) (xy 295.200911 -298.894756) (xy 295.252246 -298.902886)
			(xy 295.301676 -298.918947) (xy 295.347986 -298.942543) (xy 295.390034 -298.973093) (xy 295.426785 -299.009844)
			(xy 295.457335 -299.051892) (xy 295.480931 -299.098202) (xy 295.496992 -299.147632) (xy 295.505122 -299.198967)
			(xy 295.505632 -299.224954) (xy 295.505122 -299.250941) (xy 295.794686 -299.250941) (xy 295.794686 -299.198967)
			(xy 295.802816 -299.147632) (xy 295.818877 -299.098202) (xy 295.842473 -299.051892) (xy 295.873023 -299.009844)
			(xy 295.909774 -298.973093) (xy 295.951822 -298.942543) (xy 295.998132 -298.918947) (xy 296.047562 -298.902886)
			(xy 296.098897 -298.894756) (xy 296.150871 -298.894756) (xy 296.202206 -298.902886) (xy 296.251636 -298.918947)
			(xy 296.297946 -298.942543) (xy 296.339994 -298.973093) (xy 296.376745 -299.009844) (xy 296.407295 -299.051892)
			(xy 296.430891 -299.098202) (xy 296.446952 -299.147632) (xy 296.455082 -299.198967) (xy 296.455592 -299.224954)
			(xy 296.455082 -299.250941) (xy 296.744646 -299.250941) (xy 296.744646 -299.198967) (xy 296.752776 -299.147632)
			(xy 296.768837 -299.098202) (xy 296.792433 -299.051892) (xy 296.822983 -299.009844) (xy 296.859734 -298.973093)
			(xy 296.901782 -298.942543) (xy 296.948092 -298.918947) (xy 296.997522 -298.902886) (xy 297.048857 -298.894756)
			(xy 297.100831 -298.894756) (xy 297.152166 -298.902886) (xy 297.201596 -298.918947) (xy 297.247906 -298.942543)
			(xy 297.289954 -298.973093) (xy 297.326705 -299.009844) (xy 297.357255 -299.051892) (xy 297.380851 -299.098202)
			(xy 297.396912 -299.147632) (xy 297.405042 -299.198967) (xy 297.405552 -299.224954) (xy 297.405042 -299.250941)
			(xy 297.694606 -299.250941) (xy 297.694606 -299.198967) (xy 297.702736 -299.147632) (xy 297.718797 -299.098202)
			(xy 297.742393 -299.051892) (xy 297.772943 -299.009844) (xy 297.809694 -298.973093) (xy 297.851742 -298.942543)
			(xy 297.898052 -298.918947) (xy 297.947482 -298.902886) (xy 297.998817 -298.894756) (xy 298.050791 -298.894756)
			(xy 298.102126 -298.902886) (xy 298.151556 -298.918947) (xy 298.197866 -298.942543) (xy 298.239914 -298.973093)
			(xy 298.276665 -299.009844) (xy 298.307215 -299.051892) (xy 298.330811 -299.098202) (xy 298.346872 -299.147632)
			(xy 298.355002 -299.198967) (xy 298.355512 -299.224954) (xy 298.355002 -299.250941) (xy 298.644566 -299.250941)
			(xy 298.644566 -299.198967) (xy 298.652696 -299.147632) (xy 298.668757 -299.098202) (xy 298.692353 -299.051892)
			(xy 298.722903 -299.009844) (xy 298.759654 -298.973093) (xy 298.801702 -298.942543) (xy 298.848012 -298.918947)
			(xy 298.897442 -298.902886) (xy 298.948777 -298.894756) (xy 299.000751 -298.894756) (xy 299.052086 -298.902886)
			(xy 299.101516 -298.918947) (xy 299.147826 -298.942543) (xy 299.189874 -298.973093) (xy 299.226625 -299.009844)
			(xy 299.257175 -299.051892) (xy 299.280771 -299.098202) (xy 299.296832 -299.147632) (xy 299.304962 -299.198967)
			(xy 299.305472 -299.224954) (xy 299.304962 -299.250941) (xy 299.594526 -299.250941) (xy 299.594526 -299.198967)
			(xy 299.602656 -299.147632) (xy 299.618717 -299.098202) (xy 299.642313 -299.051892) (xy 299.672863 -299.009844)
			(xy 299.709614 -298.973093) (xy 299.751662 -298.942543) (xy 299.797972 -298.918947) (xy 299.847402 -298.902886)
			(xy 299.898737 -298.894756) (xy 299.950711 -298.894756) (xy 300.002046 -298.902886) (xy 300.051476 -298.918947)
			(xy 300.097786 -298.942543) (xy 300.139834 -298.973093) (xy 300.176585 -299.009844) (xy 300.207135 -299.051892)
			(xy 300.230731 -299.098202) (xy 300.246792 -299.147632) (xy 300.254922 -299.198967) (xy 300.255432 -299.224954)
			(xy 300.254922 -299.250941) (xy 300.246792 -299.302276) (xy 300.230731 -299.351706) (xy 300.207135 -299.398016)
			(xy 300.176585 -299.440064) (xy 300.139834 -299.476815) (xy 300.097786 -299.507365) (xy 300.051476 -299.530961)
			(xy 300.002046 -299.547022) (xy 299.950711 -299.555152) (xy 299.898737 -299.555152) (xy 299.847402 -299.547022)
			(xy 299.797972 -299.530961) (xy 299.751662 -299.507365) (xy 299.709614 -299.476815) (xy 299.672863 -299.440064)
			(xy 299.642313 -299.398016) (xy 299.618717 -299.351706) (xy 299.602656 -299.302276) (xy 299.594526 -299.250941)
			(xy 299.304962 -299.250941) (xy 299.296832 -299.302276) (xy 299.280771 -299.351706) (xy 299.257175 -299.398016)
			(xy 299.226625 -299.440064) (xy 299.189874 -299.476815) (xy 299.147826 -299.507365) (xy 299.101516 -299.530961)
			(xy 299.052086 -299.547022) (xy 299.000751 -299.555152) (xy 298.948777 -299.555152) (xy 298.897442 -299.547022)
			(xy 298.848012 -299.530961) (xy 298.801702 -299.507365) (xy 298.759654 -299.476815) (xy 298.722903 -299.440064)
			(xy 298.692353 -299.398016) (xy 298.668757 -299.351706) (xy 298.652696 -299.302276) (xy 298.644566 -299.250941)
			(xy 298.355002 -299.250941) (xy 298.346872 -299.302276) (xy 298.330811 -299.351706) (xy 298.307215 -299.398016)
			(xy 298.276665 -299.440064) (xy 298.239914 -299.476815) (xy 298.197866 -299.507365) (xy 298.151556 -299.530961)
			(xy 298.102126 -299.547022) (xy 298.050791 -299.555152) (xy 297.998817 -299.555152) (xy 297.947482 -299.547022)
			(xy 297.898052 -299.530961) (xy 297.851742 -299.507365) (xy 297.809694 -299.476815) (xy 297.772943 -299.440064)
			(xy 297.742393 -299.398016) (xy 297.718797 -299.351706) (xy 297.702736 -299.302276) (xy 297.694606 -299.250941)
			(xy 297.405042 -299.250941) (xy 297.396912 -299.302276) (xy 297.380851 -299.351706) (xy 297.357255 -299.398016)
			(xy 297.326705 -299.440064) (xy 297.289954 -299.476815) (xy 297.247906 -299.507365) (xy 297.201596 -299.530961)
			(xy 297.152166 -299.547022) (xy 297.100831 -299.555152) (xy 297.048857 -299.555152) (xy 296.997522 -299.547022)
			(xy 296.948092 -299.530961) (xy 296.901782 -299.507365) (xy 296.859734 -299.476815) (xy 296.822983 -299.440064)
			(xy 296.792433 -299.398016) (xy 296.768837 -299.351706) (xy 296.752776 -299.302276) (xy 296.744646 -299.250941)
			(xy 296.455082 -299.250941) (xy 296.446952 -299.302276) (xy 296.430891 -299.351706) (xy 296.407295 -299.398016)
			(xy 296.376745 -299.440064) (xy 296.339994 -299.476815) (xy 296.297946 -299.507365) (xy 296.251636 -299.530961)
			(xy 296.202206 -299.547022) (xy 296.150871 -299.555152) (xy 296.098897 -299.555152) (xy 296.047562 -299.547022)
			(xy 295.998132 -299.530961) (xy 295.951822 -299.507365) (xy 295.909774 -299.476815) (xy 295.873023 -299.440064)
			(xy 295.842473 -299.398016) (xy 295.818877 -299.351706) (xy 295.802816 -299.302276) (xy 295.794686 -299.250941)
			(xy 295.505122 -299.250941) (xy 295.496992 -299.302276) (xy 295.480931 -299.351706) (xy 295.457335 -299.398016)
			(xy 295.426785 -299.440064) (xy 295.390034 -299.476815) (xy 295.347986 -299.507365) (xy 295.301676 -299.530961)
			(xy 295.252246 -299.547022) (xy 295.200911 -299.555152) (xy 295.148937 -299.555152) (xy 295.097602 -299.547022)
			(xy 295.048172 -299.530961) (xy 295.001862 -299.507365) (xy 294.959814 -299.476815) (xy 294.923063 -299.440064)
			(xy 294.892513 -299.398016) (xy 294.868917 -299.351706) (xy 294.852856 -299.302276) (xy 294.844726 -299.250941)
			(xy 294.554908 -299.250941) (xy 294.546778 -299.302276) (xy 294.530717 -299.351706) (xy 294.507121 -299.398016)
			(xy 294.476571 -299.440064) (xy 294.43982 -299.476815) (xy 294.397772 -299.507365) (xy 294.351462 -299.530961)
			(xy 294.302032 -299.547022) (xy 294.250697 -299.555152) (xy 294.198723 -299.555152) (xy 294.147388 -299.547022)
			(xy 294.097958 -299.530961) (xy 294.051648 -299.507365) (xy 294.0096 -299.476815) (xy 293.972849 -299.440064)
			(xy 293.942299 -299.398016) (xy 293.918703 -299.351706) (xy 293.902642 -299.302276) (xy 293.894512 -299.250941)
			(xy 293.604948 -299.250941) (xy 293.596818 -299.302276) (xy 293.580757 -299.351706) (xy 293.557161 -299.398016)
			(xy 293.526611 -299.440064) (xy 293.48986 -299.476815) (xy 293.447812 -299.507365) (xy 293.401502 -299.530961)
			(xy 293.352072 -299.547022) (xy 293.300737 -299.555152) (xy 293.248763 -299.555152) (xy 293.197428 -299.547022)
			(xy 293.147998 -299.530961) (xy 293.101688 -299.507365) (xy 293.05964 -299.476815) (xy 293.022889 -299.440064)
			(xy 292.992339 -299.398016) (xy 292.968743 -299.351706) (xy 292.952682 -299.302276) (xy 292.944552 -299.250941)
			(xy 292.654988 -299.250941) (xy 292.646858 -299.302276) (xy 292.630797 -299.351706) (xy 292.607201 -299.398016)
			(xy 292.576651 -299.440064) (xy 292.5399 -299.476815) (xy 292.497852 -299.507365) (xy 292.451542 -299.530961)
			(xy 292.402112 -299.547022) (xy 292.350777 -299.555152) (xy 292.298803 -299.555152) (xy 292.247468 -299.547022)
			(xy 292.198038 -299.530961) (xy 292.151728 -299.507365) (xy 292.10968 -299.476815) (xy 292.072929 -299.440064)
			(xy 292.042379 -299.398016) (xy 292.018783 -299.351706) (xy 292.002722 -299.302276) (xy 291.994592 -299.250941)
			(xy 290.755068 -299.250941) (xy 290.746938 -299.302276) (xy 290.730877 -299.351706) (xy 290.707281 -299.398016)
			(xy 290.676731 -299.440064) (xy 290.63998 -299.476815) (xy 290.597932 -299.507365) (xy 290.551622 -299.530961)
			(xy 290.502192 -299.547022) (xy 290.450857 -299.555152) (xy 290.398883 -299.555152) (xy 290.347548 -299.547022)
			(xy 290.298118 -299.530961) (xy 290.251808 -299.507365) (xy 290.20976 -299.476815) (xy 290.173009 -299.440064)
			(xy 290.142459 -299.398016) (xy 290.118863 -299.351706) (xy 290.102802 -299.302276) (xy 290.094672 -299.250941)
			(xy 289.805108 -299.250941) (xy 289.796978 -299.302276) (xy 289.780917 -299.351706) (xy 289.757321 -299.398016)
			(xy 289.726771 -299.440064) (xy 289.69002 -299.476815) (xy 289.647972 -299.507365) (xy 289.601662 -299.530961)
			(xy 289.552232 -299.547022) (xy 289.500897 -299.555152) (xy 289.448923 -299.555152) (xy 289.397588 -299.547022)
			(xy 289.348158 -299.530961) (xy 289.301848 -299.507365) (xy 289.2598 -299.476815) (xy 289.223049 -299.440064)
			(xy 289.192499 -299.398016) (xy 289.168903 -299.351706) (xy 289.152842 -299.302276) (xy 289.144712 -299.250941)
			(xy 288.854894 -299.250941) (xy 288.846764 -299.302276) (xy 288.830703 -299.351706) (xy 288.807107 -299.398016)
			(xy 288.776557 -299.440064) (xy 288.739806 -299.476815) (xy 288.697758 -299.507365) (xy 288.651448 -299.530961)
			(xy 288.602018 -299.547022) (xy 288.550683 -299.555152) (xy 288.498709 -299.555152) (xy 288.447374 -299.547022)
			(xy 288.397944 -299.530961) (xy 288.351634 -299.507365) (xy 288.309586 -299.476815) (xy 288.272835 -299.440064)
			(xy 288.242285 -299.398016) (xy 288.218689 -299.351706) (xy 288.202628 -299.302276) (xy 288.194498 -299.250941)
			(xy 287.904934 -299.250941) (xy 287.896804 -299.302276) (xy 287.880743 -299.351706) (xy 287.857147 -299.398016)
			(xy 287.826597 -299.440064) (xy 287.789846 -299.476815) (xy 287.747798 -299.507365) (xy 287.701488 -299.530961)
			(xy 287.652058 -299.547022) (xy 287.600723 -299.555152) (xy 287.548749 -299.555152) (xy 287.497414 -299.547022)
			(xy 287.447984 -299.530961) (xy 287.401674 -299.507365) (xy 287.359626 -299.476815) (xy 287.322875 -299.440064)
			(xy 287.292325 -299.398016) (xy 287.268729 -299.351706) (xy 287.252668 -299.302276) (xy 287.244538 -299.250941)
			(xy 286.954974 -299.250941) (xy 286.946844 -299.302276) (xy 286.930783 -299.351706) (xy 286.907187 -299.398016)
			(xy 286.876637 -299.440064) (xy 286.839886 -299.476815) (xy 286.797838 -299.507365) (xy 286.751528 -299.530961)
			(xy 286.702098 -299.547022) (xy 286.650763 -299.555152) (xy 286.598789 -299.555152) (xy 286.547454 -299.547022)
			(xy 286.498024 -299.530961) (xy 286.451714 -299.507365) (xy 286.409666 -299.476815) (xy 286.372915 -299.440064)
			(xy 286.342365 -299.398016) (xy 286.318769 -299.351706) (xy 286.302708 -299.302276) (xy 286.294578 -299.250941)
			(xy 286.005014 -299.250941) (xy 285.996884 -299.302276) (xy 285.980823 -299.351706) (xy 285.957227 -299.398016)
			(xy 285.926677 -299.440064) (xy 285.889926 -299.476815) (xy 285.847878 -299.507365) (xy 285.801568 -299.530961)
			(xy 285.752138 -299.547022) (xy 285.700803 -299.555152) (xy 285.648829 -299.555152) (xy 285.597494 -299.547022)
			(xy 285.548064 -299.530961) (xy 285.501754 -299.507365) (xy 285.459706 -299.476815) (xy 285.422955 -299.440064)
			(xy 285.392405 -299.398016) (xy 285.368809 -299.351706) (xy 285.352748 -299.302276) (xy 285.344618 -299.250941)
			(xy 285.055054 -299.250941) (xy 285.046924 -299.302276) (xy 285.030863 -299.351706) (xy 285.007267 -299.398016)
			(xy 284.976717 -299.440064) (xy 284.939966 -299.476815) (xy 284.897918 -299.507365) (xy 284.851608 -299.530961)
			(xy 284.802178 -299.547022) (xy 284.750843 -299.555152) (xy 284.698869 -299.555152) (xy 284.647534 -299.547022)
			(xy 284.598104 -299.530961) (xy 284.551794 -299.507365) (xy 284.509746 -299.476815) (xy 284.472995 -299.440064)
			(xy 284.442445 -299.398016) (xy 284.418849 -299.351706) (xy 284.402788 -299.302276) (xy 284.394658 -299.250941)
			(xy 284.105094 -299.250941) (xy 284.096964 -299.302276) (xy 284.080903 -299.351706) (xy 284.057307 -299.398016)
			(xy 284.026757 -299.440064) (xy 283.990006 -299.476815) (xy 283.947958 -299.507365) (xy 283.901648 -299.530961)
			(xy 283.852218 -299.547022) (xy 283.800883 -299.555152) (xy 283.748909 -299.555152) (xy 283.697574 -299.547022)
			(xy 283.648144 -299.530961) (xy 283.601834 -299.507365) (xy 283.559786 -299.476815) (xy 283.523035 -299.440064)
			(xy 283.492485 -299.398016) (xy 283.468889 -299.351706) (xy 283.452828 -299.302276) (xy 283.444698 -299.250941)
			(xy 283.155134 -299.250941) (xy 283.147004 -299.302276) (xy 283.130943 -299.351706) (xy 283.107347 -299.398016)
			(xy 283.076797 -299.440064) (xy 283.040046 -299.476815) (xy 282.997998 -299.507365) (xy 282.951688 -299.530961)
			(xy 282.902258 -299.547022) (xy 282.850923 -299.555152) (xy 282.798949 -299.555152) (xy 282.747614 -299.547022)
			(xy 282.698184 -299.530961) (xy 282.651874 -299.507365) (xy 282.609826 -299.476815) (xy 282.573075 -299.440064)
			(xy 282.542525 -299.398016) (xy 282.518929 -299.351706) (xy 282.502868 -299.302276) (xy 282.494738 -299.250941)
			(xy 282.20492 -299.250941) (xy 282.19679 -299.302276) (xy 282.180729 -299.351706) (xy 282.157133 -299.398016)
			(xy 282.126583 -299.440064) (xy 282.089832 -299.476815) (xy 282.047784 -299.507365) (xy 282.001474 -299.530961)
			(xy 281.952044 -299.547022) (xy 281.900709 -299.555152) (xy 281.848735 -299.555152) (xy 281.7974 -299.547022)
			(xy 281.74797 -299.530961) (xy 281.70166 -299.507365) (xy 281.659612 -299.476815) (xy 281.622861 -299.440064)
			(xy 281.592311 -299.398016) (xy 281.568715 -299.351706) (xy 281.552654 -299.302276) (xy 281.544524 -299.250941)
			(xy 281.25496 -299.250941) (xy 281.24683 -299.302276) (xy 281.230769 -299.351706) (xy 281.207173 -299.398016)
			(xy 281.176623 -299.440064) (xy 281.139872 -299.476815) (xy 281.097824 -299.507365) (xy 281.051514 -299.530961)
			(xy 281.002084 -299.547022) (xy 280.950749 -299.555152) (xy 280.898775 -299.555152) (xy 280.84744 -299.547022)
			(xy 280.79801 -299.530961) (xy 280.7517 -299.507365) (xy 280.709652 -299.476815) (xy 280.672901 -299.440064)
			(xy 280.642351 -299.398016) (xy 280.618755 -299.351706) (xy 280.602694 -299.302276) (xy 280.594564 -299.250941)
			(xy 280.305 -299.250941) (xy 280.29687 -299.302276) (xy 280.280809 -299.351706) (xy 280.257213 -299.398016)
			(xy 280.226663 -299.440064) (xy 280.189912 -299.476815) (xy 280.147864 -299.507365) (xy 280.101554 -299.530961)
			(xy 280.052124 -299.547022) (xy 280.000789 -299.555152) (xy 279.948815 -299.555152) (xy 279.89748 -299.547022)
			(xy 279.84805 -299.530961) (xy 279.80174 -299.507365) (xy 279.759692 -299.476815) (xy 279.722941 -299.440064)
			(xy 279.692391 -299.398016) (xy 279.668795 -299.351706) (xy 279.652734 -299.302276) (xy 279.644604 -299.250941)
			(xy 279.35504 -299.250941) (xy 279.34691 -299.302276) (xy 279.330849 -299.351706) (xy 279.307253 -299.398016)
			(xy 279.276703 -299.440064) (xy 279.239952 -299.476815) (xy 279.197904 -299.507365) (xy 279.151594 -299.530961)
			(xy 279.102164 -299.547022) (xy 279.050829 -299.555152) (xy 278.998855 -299.555152) (xy 278.94752 -299.547022)
			(xy 278.89809 -299.530961) (xy 278.85178 -299.507365) (xy 278.809732 -299.476815) (xy 278.772981 -299.440064)
			(xy 278.742431 -299.398016) (xy 278.718835 -299.351706) (xy 278.702774 -299.302276) (xy 278.694644 -299.250941)
			(xy 278.404095 -299.250941) (xy 278.40198 -299.277478) (xy 278.389533 -299.328641) (xy 278.369137 -299.377185)
			(xy 278.341306 -299.421884) (xy 278.306745 -299.461608) (xy 278.266326 -299.495355) (xy 278.22107 -299.522271)
			(xy 278.172122 -299.541676) (xy 278.14651 -299.547788) (xy 278.128984 -299.551598) (xy 278.106632 -299.579538)
			(xy 278.106632 -299.82033) (xy 278.128984 -299.84827) (xy 278.14651 -299.85208) (xy 278.172098 -299.858278)
			(xy 278.221038 -299.877679) (xy 278.266286 -299.904589) (xy 278.306699 -299.938329) (xy 278.341255 -299.978045)
			(xy 278.369082 -300.022736) (xy 278.389476 -300.071271) (xy 278.401922 -300.122424) (xy 278.406105 -300.174903)
			(xy 278.404032 -300.200901) (xy 278.694644 -300.200901) (xy 278.694644 -300.148927) (xy 278.702774 -300.097592)
			(xy 278.718835 -300.048162) (xy 278.742431 -300.001852) (xy 278.772981 -299.959804) (xy 278.809732 -299.923053)
			(xy 278.85178 -299.892503) (xy 278.89809 -299.868907) (xy 278.94752 -299.852846) (xy 278.998855 -299.844716)
			(xy 279.050829 -299.844716) (xy 279.102164 -299.852846) (xy 279.151594 -299.868907) (xy 279.197904 -299.892503)
			(xy 279.239952 -299.923053) (xy 279.276703 -299.959804) (xy 279.307253 -300.001852) (xy 279.330849 -300.048162)
			(xy 279.34691 -300.097592) (xy 279.35504 -300.148927) (xy 279.35555 -300.174914) (xy 279.35504 -300.200901)
			(xy 279.644604 -300.200901) (xy 279.644604 -300.148927) (xy 279.652734 -300.097592) (xy 279.668795 -300.048162)
			(xy 279.692391 -300.001852) (xy 279.722941 -299.959804) (xy 279.759692 -299.923053) (xy 279.80174 -299.892503)
			(xy 279.84805 -299.868907) (xy 279.89748 -299.852846) (xy 279.948815 -299.844716) (xy 280.000789 -299.844716)
			(xy 280.052124 -299.852846) (xy 280.101554 -299.868907) (xy 280.147864 -299.892503) (xy 280.189912 -299.923053)
			(xy 280.226663 -299.959804) (xy 280.257213 -300.001852) (xy 280.280809 -300.048162) (xy 280.29687 -300.097592)
			(xy 280.305 -300.148927) (xy 280.30551 -300.174914) (xy 280.305 -300.200901) (xy 280.594564 -300.200901)
			(xy 280.594564 -300.148927) (xy 280.602694 -300.097592) (xy 280.618755 -300.048162) (xy 280.642351 -300.001852)
			(xy 280.672901 -299.959804) (xy 280.709652 -299.923053) (xy 280.7517 -299.892503) (xy 280.79801 -299.868907)
			(xy 280.84744 -299.852846) (xy 280.898775 -299.844716) (xy 280.950749 -299.844716) (xy 281.002084 -299.852846)
			(xy 281.051514 -299.868907) (xy 281.097824 -299.892503) (xy 281.139872 -299.923053) (xy 281.176623 -299.959804)
			(xy 281.207173 -300.001852) (xy 281.230769 -300.048162) (xy 281.24683 -300.097592) (xy 281.25496 -300.148927)
			(xy 281.25547 -300.174914) (xy 281.25496 -300.200901) (xy 281.544524 -300.200901) (xy 281.544524 -300.148927)
			(xy 281.552654 -300.097592) (xy 281.568715 -300.048162) (xy 281.592311 -300.001852) (xy 281.622861 -299.959804)
			(xy 281.659612 -299.923053) (xy 281.70166 -299.892503) (xy 281.74797 -299.868907) (xy 281.7974 -299.852846)
			(xy 281.848735 -299.844716) (xy 281.900709 -299.844716) (xy 281.952044 -299.852846) (xy 282.001474 -299.868907)
			(xy 282.047784 -299.892503) (xy 282.089832 -299.923053) (xy 282.126583 -299.959804) (xy 282.157133 -300.001852)
			(xy 282.180729 -300.048162) (xy 282.19679 -300.097592) (xy 282.20492 -300.148927) (xy 282.20543 -300.174914)
			(xy 282.20492 -300.200901) (xy 282.494738 -300.200901) (xy 282.494738 -300.148927) (xy 282.502868 -300.097592)
			(xy 282.518929 -300.048162) (xy 282.542525 -300.001852) (xy 282.573075 -299.959804) (xy 282.609826 -299.923053)
			(xy 282.651874 -299.892503) (xy 282.698184 -299.868907) (xy 282.747614 -299.852846) (xy 282.798949 -299.844716)
			(xy 282.850923 -299.844716) (xy 282.902258 -299.852846) (xy 282.951688 -299.868907) (xy 282.997998 -299.892503)
			(xy 283.040046 -299.923053) (xy 283.076797 -299.959804) (xy 283.107347 -300.001852) (xy 283.130943 -300.048162)
			(xy 283.147004 -300.097592) (xy 283.155134 -300.148927) (xy 283.155644 -300.174914) (xy 283.155134 -300.200901)
			(xy 283.444698 -300.200901) (xy 283.444698 -300.148927) (xy 283.452828 -300.097592) (xy 283.468889 -300.048162)
			(xy 283.492485 -300.001852) (xy 283.523035 -299.959804) (xy 283.559786 -299.923053) (xy 283.601834 -299.892503)
			(xy 283.648144 -299.868907) (xy 283.697574 -299.852846) (xy 283.748909 -299.844716) (xy 283.800883 -299.844716)
			(xy 283.852218 -299.852846) (xy 283.901648 -299.868907) (xy 283.947958 -299.892503) (xy 283.990006 -299.923053)
			(xy 284.026757 -299.959804) (xy 284.057307 -300.001852) (xy 284.080903 -300.048162) (xy 284.096964 -300.097592)
			(xy 284.105094 -300.148927) (xy 284.105604 -300.174914) (xy 284.105094 -300.200901) (xy 284.394658 -300.200901)
			(xy 284.394658 -300.148927) (xy 284.402788 -300.097592) (xy 284.418849 -300.048162) (xy 284.442445 -300.001852)
			(xy 284.472995 -299.959804) (xy 284.509746 -299.923053) (xy 284.551794 -299.892503) (xy 284.598104 -299.868907)
			(xy 284.647534 -299.852846) (xy 284.698869 -299.844716) (xy 284.750843 -299.844716) (xy 284.802178 -299.852846)
			(xy 284.851608 -299.868907) (xy 284.897918 -299.892503) (xy 284.939966 -299.923053) (xy 284.976717 -299.959804)
			(xy 285.007267 -300.001852) (xy 285.030863 -300.048162) (xy 285.046924 -300.097592) (xy 285.055054 -300.148927)
			(xy 285.055564 -300.174914) (xy 285.055054 -300.200901) (xy 285.344618 -300.200901) (xy 285.344618 -300.148927)
			(xy 285.352748 -300.097592) (xy 285.368809 -300.048162) (xy 285.392405 -300.001852) (xy 285.422955 -299.959804)
			(xy 285.459706 -299.923053) (xy 285.501754 -299.892503) (xy 285.548064 -299.868907) (xy 285.597494 -299.852846)
			(xy 285.648829 -299.844716) (xy 285.700803 -299.844716) (xy 285.752138 -299.852846) (xy 285.801568 -299.868907)
			(xy 285.847878 -299.892503) (xy 285.889926 -299.923053) (xy 285.926677 -299.959804) (xy 285.957227 -300.001852)
			(xy 285.980823 -300.048162) (xy 285.996884 -300.097592) (xy 286.005014 -300.148927) (xy 286.005524 -300.174914)
			(xy 286.005014 -300.200901) (xy 286.294578 -300.200901) (xy 286.294578 -300.148927) (xy 286.302708 -300.097592)
			(xy 286.318769 -300.048162) (xy 286.342365 -300.001852) (xy 286.372915 -299.959804) (xy 286.409666 -299.923053)
			(xy 286.451714 -299.892503) (xy 286.498024 -299.868907) (xy 286.547454 -299.852846) (xy 286.598789 -299.844716)
			(xy 286.650763 -299.844716) (xy 286.702098 -299.852846) (xy 286.751528 -299.868907) (xy 286.797838 -299.892503)
			(xy 286.839886 -299.923053) (xy 286.876637 -299.959804) (xy 286.907187 -300.001852) (xy 286.930783 -300.048162)
			(xy 286.946844 -300.097592) (xy 286.954974 -300.148927) (xy 286.955484 -300.174914) (xy 286.954974 -300.200901)
			(xy 287.244538 -300.200901) (xy 287.244538 -300.148927) (xy 287.252668 -300.097592) (xy 287.268729 -300.048162)
			(xy 287.292325 -300.001852) (xy 287.322875 -299.959804) (xy 287.359626 -299.923053) (xy 287.401674 -299.892503)
			(xy 287.447984 -299.868907) (xy 287.497414 -299.852846) (xy 287.548749 -299.844716) (xy 287.600723 -299.844716)
			(xy 287.652058 -299.852846) (xy 287.701488 -299.868907) (xy 287.747798 -299.892503) (xy 287.789846 -299.923053)
			(xy 287.826597 -299.959804) (xy 287.857147 -300.001852) (xy 287.880743 -300.048162) (xy 287.896804 -300.097592)
			(xy 287.904934 -300.148927) (xy 287.905444 -300.174914) (xy 287.904934 -300.200901) (xy 288.194498 -300.200901)
			(xy 288.194498 -300.148927) (xy 288.202628 -300.097592) (xy 288.218689 -300.048162) (xy 288.242285 -300.001852)
			(xy 288.272835 -299.959804) (xy 288.309586 -299.923053) (xy 288.351634 -299.892503) (xy 288.397944 -299.868907)
			(xy 288.447374 -299.852846) (xy 288.498709 -299.844716) (xy 288.550683 -299.844716) (xy 288.602018 -299.852846)
			(xy 288.651448 -299.868907) (xy 288.697758 -299.892503) (xy 288.739806 -299.923053) (xy 288.776557 -299.959804)
			(xy 288.807107 -300.001852) (xy 288.830703 -300.048162) (xy 288.846764 -300.097592) (xy 288.854894 -300.148927)
			(xy 288.855404 -300.174914) (xy 288.854894 -300.200901) (xy 289.144712 -300.200901) (xy 289.144712 -300.148927)
			(xy 289.152842 -300.097592) (xy 289.168903 -300.048162) (xy 289.192499 -300.001852) (xy 289.223049 -299.959804)
			(xy 289.2598 -299.923053) (xy 289.301848 -299.892503) (xy 289.348158 -299.868907) (xy 289.397588 -299.852846)
			(xy 289.448923 -299.844716) (xy 289.500897 -299.844716) (xy 289.552232 -299.852846) (xy 289.601662 -299.868907)
			(xy 289.647972 -299.892503) (xy 289.69002 -299.923053) (xy 289.726771 -299.959804) (xy 289.757321 -300.001852)
			(xy 289.780917 -300.048162) (xy 289.796978 -300.097592) (xy 289.805108 -300.148927) (xy 289.805618 -300.174914)
			(xy 289.805108 -300.200901) (xy 290.094672 -300.200901) (xy 290.094672 -300.148927) (xy 290.102802 -300.097592)
			(xy 290.118863 -300.048162) (xy 290.142459 -300.001852) (xy 290.173009 -299.959804) (xy 290.20976 -299.923053)
			(xy 290.251808 -299.892503) (xy 290.298118 -299.868907) (xy 290.347548 -299.852846) (xy 290.398883 -299.844716)
			(xy 290.450857 -299.844716) (xy 290.502192 -299.852846) (xy 290.551622 -299.868907) (xy 290.597932 -299.892503)
			(xy 290.63998 -299.923053) (xy 290.676731 -299.959804) (xy 290.707281 -300.001852) (xy 290.730877 -300.048162)
			(xy 290.746938 -300.097592) (xy 290.755068 -300.148927) (xy 290.755578 -300.174914) (xy 290.755068 -300.200901)
			(xy 291.994592 -300.200901) (xy 291.994592 -300.148927) (xy 292.002722 -300.097592) (xy 292.018783 -300.048162)
			(xy 292.042379 -300.001852) (xy 292.072929 -299.959804) (xy 292.10968 -299.923053) (xy 292.151728 -299.892503)
			(xy 292.198038 -299.868907) (xy 292.247468 -299.852846) (xy 292.298803 -299.844716) (xy 292.350777 -299.844716)
			(xy 292.402112 -299.852846) (xy 292.451542 -299.868907) (xy 292.497852 -299.892503) (xy 292.5399 -299.923053)
			(xy 292.576651 -299.959804) (xy 292.607201 -300.001852) (xy 292.630797 -300.048162) (xy 292.646858 -300.097592)
			(xy 292.654988 -300.148927) (xy 292.655498 -300.174914) (xy 292.654988 -300.200901) (xy 292.944552 -300.200901)
			(xy 292.944552 -300.148927) (xy 292.952682 -300.097592) (xy 292.968743 -300.048162) (xy 292.992339 -300.001852)
			(xy 293.022889 -299.959804) (xy 293.05964 -299.923053) (xy 293.101688 -299.892503) (xy 293.147998 -299.868907)
			(xy 293.197428 -299.852846) (xy 293.248763 -299.844716) (xy 293.300737 -299.844716) (xy 293.352072 -299.852846)
			(xy 293.401502 -299.868907) (xy 293.447812 -299.892503) (xy 293.48986 -299.923053) (xy 293.526611 -299.959804)
			(xy 293.557161 -300.001852) (xy 293.580757 -300.048162) (xy 293.596818 -300.097592) (xy 293.604948 -300.148927)
			(xy 293.605458 -300.174914) (xy 293.604948 -300.200901) (xy 293.894512 -300.200901) (xy 293.894512 -300.148927)
			(xy 293.902642 -300.097592) (xy 293.918703 -300.048162) (xy 293.942299 -300.001852) (xy 293.972849 -299.959804)
			(xy 294.0096 -299.923053) (xy 294.051648 -299.892503) (xy 294.097958 -299.868907) (xy 294.147388 -299.852846)
			(xy 294.198723 -299.844716) (xy 294.250697 -299.844716) (xy 294.302032 -299.852846) (xy 294.351462 -299.868907)
			(xy 294.397772 -299.892503) (xy 294.43982 -299.923053) (xy 294.476571 -299.959804) (xy 294.507121 -300.001852)
			(xy 294.530717 -300.048162) (xy 294.546778 -300.097592) (xy 294.554908 -300.148927) (xy 294.555418 -300.174914)
			(xy 294.554908 -300.200901) (xy 294.844726 -300.200901) (xy 294.844726 -300.148927) (xy 294.852856 -300.097592)
			(xy 294.868917 -300.048162) (xy 294.892513 -300.001852) (xy 294.923063 -299.959804) (xy 294.959814 -299.923053)
			(xy 295.001862 -299.892503) (xy 295.048172 -299.868907) (xy 295.097602 -299.852846) (xy 295.148937 -299.844716)
			(xy 295.200911 -299.844716) (xy 295.252246 -299.852846) (xy 295.301676 -299.868907) (xy 295.347986 -299.892503)
			(xy 295.390034 -299.923053) (xy 295.426785 -299.959804) (xy 295.457335 -300.001852) (xy 295.480931 -300.048162)
			(xy 295.496992 -300.097592) (xy 295.505122 -300.148927) (xy 295.505632 -300.174914) (xy 295.505122 -300.200901)
			(xy 295.794686 -300.200901) (xy 295.794686 -300.148927) (xy 295.802816 -300.097592) (xy 295.818877 -300.048162)
			(xy 295.842473 -300.001852) (xy 295.873023 -299.959804) (xy 295.909774 -299.923053) (xy 295.951822 -299.892503)
			(xy 295.998132 -299.868907) (xy 296.047562 -299.852846) (xy 296.098897 -299.844716) (xy 296.150871 -299.844716)
			(xy 296.202206 -299.852846) (xy 296.251636 -299.868907) (xy 296.297946 -299.892503) (xy 296.339994 -299.923053)
			(xy 296.376745 -299.959804) (xy 296.407295 -300.001852) (xy 296.430891 -300.048162) (xy 296.446952 -300.097592)
			(xy 296.455082 -300.148927) (xy 296.455592 -300.174914) (xy 296.455082 -300.200901) (xy 296.744646 -300.200901)
			(xy 296.744646 -300.148927) (xy 296.752776 -300.097592) (xy 296.768837 -300.048162) (xy 296.792433 -300.001852)
			(xy 296.822983 -299.959804) (xy 296.859734 -299.923053) (xy 296.901782 -299.892503) (xy 296.948092 -299.868907)
			(xy 296.997522 -299.852846) (xy 297.048857 -299.844716) (xy 297.100831 -299.844716) (xy 297.152166 -299.852846)
			(xy 297.201596 -299.868907) (xy 297.247906 -299.892503) (xy 297.289954 -299.923053) (xy 297.326705 -299.959804)
			(xy 297.357255 -300.001852) (xy 297.380851 -300.048162) (xy 297.396912 -300.097592) (xy 297.405042 -300.148927)
			(xy 297.405552 -300.174914) (xy 297.405042 -300.200901) (xy 297.694606 -300.200901) (xy 297.694606 -300.148927)
			(xy 297.702736 -300.097592) (xy 297.718797 -300.048162) (xy 297.742393 -300.001852) (xy 297.772943 -299.959804)
			(xy 297.809694 -299.923053) (xy 297.851742 -299.892503) (xy 297.898052 -299.868907) (xy 297.947482 -299.852846)
			(xy 297.998817 -299.844716) (xy 298.050791 -299.844716) (xy 298.102126 -299.852846) (xy 298.151556 -299.868907)
			(xy 298.197866 -299.892503) (xy 298.239914 -299.923053) (xy 298.276665 -299.959804) (xy 298.307215 -300.001852)
			(xy 298.330811 -300.048162) (xy 298.346872 -300.097592) (xy 298.355002 -300.148927) (xy 298.355512 -300.174914)
			(xy 298.355002 -300.200901) (xy 298.644566 -300.200901) (xy 298.644566 -300.148927) (xy 298.652696 -300.097592)
			(xy 298.668757 -300.048162) (xy 298.692353 -300.001852) (xy 298.722903 -299.959804) (xy 298.759654 -299.923053)
			(xy 298.801702 -299.892503) (xy 298.848012 -299.868907) (xy 298.897442 -299.852846) (xy 298.948777 -299.844716)
			(xy 299.000751 -299.844716) (xy 299.052086 -299.852846) (xy 299.101516 -299.868907) (xy 299.147826 -299.892503)
			(xy 299.189874 -299.923053) (xy 299.226625 -299.959804) (xy 299.257175 -300.001852) (xy 299.280771 -300.048162)
			(xy 299.296832 -300.097592) (xy 299.304962 -300.148927) (xy 299.305472 -300.174914) (xy 299.304962 -300.200901)
			(xy 299.594526 -300.200901) (xy 299.594526 -300.148927) (xy 299.602656 -300.097592) (xy 299.618717 -300.048162)
			(xy 299.642313 -300.001852) (xy 299.672863 -299.959804) (xy 299.709614 -299.923053) (xy 299.751662 -299.892503)
			(xy 299.797972 -299.868907) (xy 299.847402 -299.852846) (xy 299.898737 -299.844716) (xy 299.950711 -299.844716)
			(xy 300.002046 -299.852846) (xy 300.051476 -299.868907) (xy 300.097786 -299.892503) (xy 300.139834 -299.923053)
			(xy 300.176585 -299.959804) (xy 300.207135 -300.001852) (xy 300.230731 -300.048162) (xy 300.246792 -300.097592)
			(xy 300.254922 -300.148927) (xy 300.255432 -300.174914) (xy 300.254922 -300.200901) (xy 300.246792 -300.252236)
			(xy 300.230731 -300.301666) (xy 300.207135 -300.347976) (xy 300.176585 -300.390024) (xy 300.139834 -300.426775)
			(xy 300.097786 -300.457325) (xy 300.051476 -300.480921) (xy 300.002046 -300.496982) (xy 299.950711 -300.505112)
			(xy 299.898737 -300.505112) (xy 299.847402 -300.496982) (xy 299.797972 -300.480921) (xy 299.751662 -300.457325)
			(xy 299.709614 -300.426775) (xy 299.672863 -300.390024) (xy 299.642313 -300.347976) (xy 299.618717 -300.301666)
			(xy 299.602656 -300.252236) (xy 299.594526 -300.200901) (xy 299.304962 -300.200901) (xy 299.296832 -300.252236)
			(xy 299.280771 -300.301666) (xy 299.257175 -300.347976) (xy 299.226625 -300.390024) (xy 299.189874 -300.426775)
			(xy 299.147826 -300.457325) (xy 299.101516 -300.480921) (xy 299.052086 -300.496982) (xy 299.000751 -300.505112)
			(xy 298.948777 -300.505112) (xy 298.897442 -300.496982) (xy 298.848012 -300.480921) (xy 298.801702 -300.457325)
			(xy 298.759654 -300.426775) (xy 298.722903 -300.390024) (xy 298.692353 -300.347976) (xy 298.668757 -300.301666)
			(xy 298.652696 -300.252236) (xy 298.644566 -300.200901) (xy 298.355002 -300.200901) (xy 298.346872 -300.252236)
			(xy 298.330811 -300.301666) (xy 298.307215 -300.347976) (xy 298.276665 -300.390024) (xy 298.239914 -300.426775)
			(xy 298.197866 -300.457325) (xy 298.151556 -300.480921) (xy 298.102126 -300.496982) (xy 298.050791 -300.505112)
			(xy 297.998817 -300.505112) (xy 297.947482 -300.496982) (xy 297.898052 -300.480921) (xy 297.851742 -300.457325)
			(xy 297.809694 -300.426775) (xy 297.772943 -300.390024) (xy 297.742393 -300.347976) (xy 297.718797 -300.301666)
			(xy 297.702736 -300.252236) (xy 297.694606 -300.200901) (xy 297.405042 -300.200901) (xy 297.396912 -300.252236)
			(xy 297.380851 -300.301666) (xy 297.357255 -300.347976) (xy 297.326705 -300.390024) (xy 297.289954 -300.426775)
			(xy 297.247906 -300.457325) (xy 297.201596 -300.480921) (xy 297.152166 -300.496982) (xy 297.100831 -300.505112)
			(xy 297.048857 -300.505112) (xy 296.997522 -300.496982) (xy 296.948092 -300.480921) (xy 296.901782 -300.457325)
			(xy 296.859734 -300.426775) (xy 296.822983 -300.390024) (xy 296.792433 -300.347976) (xy 296.768837 -300.301666)
			(xy 296.752776 -300.252236) (xy 296.744646 -300.200901) (xy 296.455082 -300.200901) (xy 296.446952 -300.252236)
			(xy 296.430891 -300.301666) (xy 296.407295 -300.347976) (xy 296.376745 -300.390024) (xy 296.339994 -300.426775)
			(xy 296.297946 -300.457325) (xy 296.251636 -300.480921) (xy 296.202206 -300.496982) (xy 296.150871 -300.505112)
			(xy 296.098897 -300.505112) (xy 296.047562 -300.496982) (xy 295.998132 -300.480921) (xy 295.951822 -300.457325)
			(xy 295.909774 -300.426775) (xy 295.873023 -300.390024) (xy 295.842473 -300.347976) (xy 295.818877 -300.301666)
			(xy 295.802816 -300.252236) (xy 295.794686 -300.200901) (xy 295.505122 -300.200901) (xy 295.496992 -300.252236)
			(xy 295.480931 -300.301666) (xy 295.457335 -300.347976) (xy 295.426785 -300.390024) (xy 295.390034 -300.426775)
			(xy 295.347986 -300.457325) (xy 295.301676 -300.480921) (xy 295.252246 -300.496982) (xy 295.200911 -300.505112)
			(xy 295.148937 -300.505112) (xy 295.097602 -300.496982) (xy 295.048172 -300.480921) (xy 295.001862 -300.457325)
			(xy 294.959814 -300.426775) (xy 294.923063 -300.390024) (xy 294.892513 -300.347976) (xy 294.868917 -300.301666)
			(xy 294.852856 -300.252236) (xy 294.844726 -300.200901) (xy 294.554908 -300.200901) (xy 294.546778 -300.252236)
			(xy 294.530717 -300.301666) (xy 294.507121 -300.347976) (xy 294.476571 -300.390024) (xy 294.43982 -300.426775)
			(xy 294.397772 -300.457325) (xy 294.351462 -300.480921) (xy 294.302032 -300.496982) (xy 294.250697 -300.505112)
			(xy 294.198723 -300.505112) (xy 294.147388 -300.496982) (xy 294.097958 -300.480921) (xy 294.051648 -300.457325)
			(xy 294.0096 -300.426775) (xy 293.972849 -300.390024) (xy 293.942299 -300.347976) (xy 293.918703 -300.301666)
			(xy 293.902642 -300.252236) (xy 293.894512 -300.200901) (xy 293.604948 -300.200901) (xy 293.596818 -300.252236)
			(xy 293.580757 -300.301666) (xy 293.557161 -300.347976) (xy 293.526611 -300.390024) (xy 293.48986 -300.426775)
			(xy 293.447812 -300.457325) (xy 293.401502 -300.480921) (xy 293.352072 -300.496982) (xy 293.300737 -300.505112)
			(xy 293.248763 -300.505112) (xy 293.197428 -300.496982) (xy 293.147998 -300.480921) (xy 293.101688 -300.457325)
			(xy 293.05964 -300.426775) (xy 293.022889 -300.390024) (xy 292.992339 -300.347976) (xy 292.968743 -300.301666)
			(xy 292.952682 -300.252236) (xy 292.944552 -300.200901) (xy 292.654988 -300.200901) (xy 292.646858 -300.252236)
			(xy 292.630797 -300.301666) (xy 292.607201 -300.347976) (xy 292.576651 -300.390024) (xy 292.5399 -300.426775)
			(xy 292.497852 -300.457325) (xy 292.451542 -300.480921) (xy 292.402112 -300.496982) (xy 292.350777 -300.505112)
			(xy 292.298803 -300.505112) (xy 292.247468 -300.496982) (xy 292.198038 -300.480921) (xy 292.151728 -300.457325)
			(xy 292.10968 -300.426775) (xy 292.072929 -300.390024) (xy 292.042379 -300.347976) (xy 292.018783 -300.301666)
			(xy 292.002722 -300.252236) (xy 291.994592 -300.200901) (xy 290.755068 -300.200901) (xy 290.746938 -300.252236)
			(xy 290.730877 -300.301666) (xy 290.707281 -300.347976) (xy 290.676731 -300.390024) (xy 290.63998 -300.426775)
			(xy 290.597932 -300.457325) (xy 290.551622 -300.480921) (xy 290.502192 -300.496982) (xy 290.450857 -300.505112)
			(xy 290.398883 -300.505112) (xy 290.347548 -300.496982) (xy 290.298118 -300.480921) (xy 290.251808 -300.457325)
			(xy 290.20976 -300.426775) (xy 290.173009 -300.390024) (xy 290.142459 -300.347976) (xy 290.118863 -300.301666)
			(xy 290.102802 -300.252236) (xy 290.094672 -300.200901) (xy 289.805108 -300.200901) (xy 289.796978 -300.252236)
			(xy 289.780917 -300.301666) (xy 289.757321 -300.347976) (xy 289.726771 -300.390024) (xy 289.69002 -300.426775)
			(xy 289.647972 -300.457325) (xy 289.601662 -300.480921) (xy 289.552232 -300.496982) (xy 289.500897 -300.505112)
			(xy 289.448923 -300.505112) (xy 289.397588 -300.496982) (xy 289.348158 -300.480921) (xy 289.301848 -300.457325)
			(xy 289.2598 -300.426775) (xy 289.223049 -300.390024) (xy 289.192499 -300.347976) (xy 289.168903 -300.301666)
			(xy 289.152842 -300.252236) (xy 289.144712 -300.200901) (xy 288.854894 -300.200901) (xy 288.846764 -300.252236)
			(xy 288.830703 -300.301666) (xy 288.807107 -300.347976) (xy 288.776557 -300.390024) (xy 288.739806 -300.426775)
			(xy 288.697758 -300.457325) (xy 288.651448 -300.480921) (xy 288.602018 -300.496982) (xy 288.550683 -300.505112)
			(xy 288.498709 -300.505112) (xy 288.447374 -300.496982) (xy 288.397944 -300.480921) (xy 288.351634 -300.457325)
			(xy 288.309586 -300.426775) (xy 288.272835 -300.390024) (xy 288.242285 -300.347976) (xy 288.218689 -300.301666)
			(xy 288.202628 -300.252236) (xy 288.194498 -300.200901) (xy 287.904934 -300.200901) (xy 287.896804 -300.252236)
			(xy 287.880743 -300.301666) (xy 287.857147 -300.347976) (xy 287.826597 -300.390024) (xy 287.789846 -300.426775)
			(xy 287.747798 -300.457325) (xy 287.701488 -300.480921) (xy 287.652058 -300.496982) (xy 287.600723 -300.505112)
			(xy 287.548749 -300.505112) (xy 287.497414 -300.496982) (xy 287.447984 -300.480921) (xy 287.401674 -300.457325)
			(xy 287.359626 -300.426775) (xy 287.322875 -300.390024) (xy 287.292325 -300.347976) (xy 287.268729 -300.301666)
			(xy 287.252668 -300.252236) (xy 287.244538 -300.200901) (xy 286.954974 -300.200901) (xy 286.946844 -300.252236)
			(xy 286.930783 -300.301666) (xy 286.907187 -300.347976) (xy 286.876637 -300.390024) (xy 286.839886 -300.426775)
			(xy 286.797838 -300.457325) (xy 286.751528 -300.480921) (xy 286.702098 -300.496982) (xy 286.650763 -300.505112)
			(xy 286.598789 -300.505112) (xy 286.547454 -300.496982) (xy 286.498024 -300.480921) (xy 286.451714 -300.457325)
			(xy 286.409666 -300.426775) (xy 286.372915 -300.390024) (xy 286.342365 -300.347976) (xy 286.318769 -300.301666)
			(xy 286.302708 -300.252236) (xy 286.294578 -300.200901) (xy 286.005014 -300.200901) (xy 285.996884 -300.252236)
			(xy 285.980823 -300.301666) (xy 285.957227 -300.347976) (xy 285.926677 -300.390024) (xy 285.889926 -300.426775)
			(xy 285.847878 -300.457325) (xy 285.801568 -300.480921) (xy 285.752138 -300.496982) (xy 285.700803 -300.505112)
			(xy 285.648829 -300.505112) (xy 285.597494 -300.496982) (xy 285.548064 -300.480921) (xy 285.501754 -300.457325)
			(xy 285.459706 -300.426775) (xy 285.422955 -300.390024) (xy 285.392405 -300.347976) (xy 285.368809 -300.301666)
			(xy 285.352748 -300.252236) (xy 285.344618 -300.200901) (xy 285.055054 -300.200901) (xy 285.046924 -300.252236)
			(xy 285.030863 -300.301666) (xy 285.007267 -300.347976) (xy 284.976717 -300.390024) (xy 284.939966 -300.426775)
			(xy 284.897918 -300.457325) (xy 284.851608 -300.480921) (xy 284.802178 -300.496982) (xy 284.750843 -300.505112)
			(xy 284.698869 -300.505112) (xy 284.647534 -300.496982) (xy 284.598104 -300.480921) (xy 284.551794 -300.457325)
			(xy 284.509746 -300.426775) (xy 284.472995 -300.390024) (xy 284.442445 -300.347976) (xy 284.418849 -300.301666)
			(xy 284.402788 -300.252236) (xy 284.394658 -300.200901) (xy 284.105094 -300.200901) (xy 284.096964 -300.252236)
			(xy 284.080903 -300.301666) (xy 284.057307 -300.347976) (xy 284.026757 -300.390024) (xy 283.990006 -300.426775)
			(xy 283.947958 -300.457325) (xy 283.901648 -300.480921) (xy 283.852218 -300.496982) (xy 283.800883 -300.505112)
			(xy 283.748909 -300.505112) (xy 283.697574 -300.496982) (xy 283.648144 -300.480921) (xy 283.601834 -300.457325)
			(xy 283.559786 -300.426775) (xy 283.523035 -300.390024) (xy 283.492485 -300.347976) (xy 283.468889 -300.301666)
			(xy 283.452828 -300.252236) (xy 283.444698 -300.200901) (xy 283.155134 -300.200901) (xy 283.147004 -300.252236)
			(xy 283.130943 -300.301666) (xy 283.107347 -300.347976) (xy 283.076797 -300.390024) (xy 283.040046 -300.426775)
			(xy 282.997998 -300.457325) (xy 282.951688 -300.480921) (xy 282.902258 -300.496982) (xy 282.850923 -300.505112)
			(xy 282.798949 -300.505112) (xy 282.747614 -300.496982) (xy 282.698184 -300.480921) (xy 282.651874 -300.457325)
			(xy 282.609826 -300.426775) (xy 282.573075 -300.390024) (xy 282.542525 -300.347976) (xy 282.518929 -300.301666)
			(xy 282.502868 -300.252236) (xy 282.494738 -300.200901) (xy 282.20492 -300.200901) (xy 282.19679 -300.252236)
			(xy 282.180729 -300.301666) (xy 282.157133 -300.347976) (xy 282.126583 -300.390024) (xy 282.089832 -300.426775)
			(xy 282.047784 -300.457325) (xy 282.001474 -300.480921) (xy 281.952044 -300.496982) (xy 281.900709 -300.505112)
			(xy 281.848735 -300.505112) (xy 281.7974 -300.496982) (xy 281.74797 -300.480921) (xy 281.70166 -300.457325)
			(xy 281.659612 -300.426775) (xy 281.622861 -300.390024) (xy 281.592311 -300.347976) (xy 281.568715 -300.301666)
			(xy 281.552654 -300.252236) (xy 281.544524 -300.200901) (xy 281.25496 -300.200901) (xy 281.24683 -300.252236)
			(xy 281.230769 -300.301666) (xy 281.207173 -300.347976) (xy 281.176623 -300.390024) (xy 281.139872 -300.426775)
			(xy 281.097824 -300.457325) (xy 281.051514 -300.480921) (xy 281.002084 -300.496982) (xy 280.950749 -300.505112)
			(xy 280.898775 -300.505112) (xy 280.84744 -300.496982) (xy 280.79801 -300.480921) (xy 280.7517 -300.457325)
			(xy 280.709652 -300.426775) (xy 280.672901 -300.390024) (xy 280.642351 -300.347976) (xy 280.618755 -300.301666)
			(xy 280.602694 -300.252236) (xy 280.594564 -300.200901) (xy 280.305 -300.200901) (xy 280.29687 -300.252236)
			(xy 280.280809 -300.301666) (xy 280.257213 -300.347976) (xy 280.226663 -300.390024) (xy 280.189912 -300.426775)
			(xy 280.147864 -300.457325) (xy 280.101554 -300.480921) (xy 280.052124 -300.496982) (xy 280.000789 -300.505112)
			(xy 279.948815 -300.505112) (xy 279.89748 -300.496982) (xy 279.84805 -300.480921) (xy 279.80174 -300.457325)
			(xy 279.759692 -300.426775) (xy 279.722941 -300.390024) (xy 279.692391 -300.347976) (xy 279.668795 -300.301666)
			(xy 279.652734 -300.252236) (xy 279.644604 -300.200901) (xy 279.35504 -300.200901) (xy 279.34691 -300.252236)
			(xy 279.330849 -300.301666) (xy 279.307253 -300.347976) (xy 279.276703 -300.390024) (xy 279.239952 -300.426775)
			(xy 279.197904 -300.457325) (xy 279.151594 -300.480921) (xy 279.102164 -300.496982) (xy 279.050829 -300.505112)
			(xy 278.998855 -300.505112) (xy 278.94752 -300.496982) (xy 278.89809 -300.480921) (xy 278.85178 -300.457325)
			(xy 278.809732 -300.426775) (xy 278.772981 -300.390024) (xy 278.742431 -300.347976) (xy 278.718835 -300.301666)
			(xy 278.702774 -300.252236) (xy 278.694644 -300.200901) (xy 278.404032 -300.200901) (xy 278.401921 -300.227382)
			(xy 278.389474 -300.278535) (xy 278.369079 -300.32707) (xy 278.341252 -300.37176) (xy 278.306695 -300.411476)
			(xy 278.266281 -300.445215) (xy 278.221033 -300.472124) (xy 278.172092 -300.491524) (xy 278.14651 -300.497748)
			(xy 278.128984 -300.501558) (xy 278.106632 -300.529498) (xy 278.106632 -300.77029) (xy 278.128984 -300.79823)
			(xy 278.14651 -300.80204) (xy 278.172101 -300.808238) (xy 278.221048 -300.82764) (xy 278.266302 -300.854552)
			(xy 278.30672 -300.888295) (xy 278.341281 -300.928015) (xy 278.369112 -300.97271) (xy 278.38951 -301.02125)
			(xy 278.401959 -301.072409) (xy 278.406144 -301.124894) (xy 278.404074 -301.150861) (xy 279.644604 -301.150861)
			(xy 279.644604 -301.098887) (xy 279.652734 -301.047552) (xy 279.668795 -300.998122) (xy 279.692391 -300.951812)
			(xy 279.722941 -300.909764) (xy 279.759692 -300.873013) (xy 279.80174 -300.842463) (xy 279.84805 -300.818867)
			(xy 279.89748 -300.802806) (xy 279.948815 -300.794676) (xy 280.000789 -300.794676) (xy 280.052124 -300.802806)
			(xy 280.101554 -300.818867) (xy 280.147864 -300.842463) (xy 280.189912 -300.873013) (xy 280.226663 -300.909764)
			(xy 280.257213 -300.951812) (xy 280.280809 -300.998122) (xy 280.29687 -301.047552) (xy 280.305 -301.098887)
			(xy 280.30551 -301.124874) (xy 280.305 -301.150861) (xy 280.594564 -301.150861) (xy 280.594564 -301.098887)
			(xy 280.602694 -301.047552) (xy 280.618755 -300.998122) (xy 280.642351 -300.951812) (xy 280.672901 -300.909764)
			(xy 280.709652 -300.873013) (xy 280.7517 -300.842463) (xy 280.79801 -300.818867) (xy 280.84744 -300.802806)
			(xy 280.898775 -300.794676) (xy 280.950749 -300.794676) (xy 281.002084 -300.802806) (xy 281.051514 -300.818867)
			(xy 281.097824 -300.842463) (xy 281.139872 -300.873013) (xy 281.176623 -300.909764) (xy 281.207173 -300.951812)
			(xy 281.230769 -300.998122) (xy 281.24683 -301.047552) (xy 281.25496 -301.098887) (xy 281.25547 -301.124874)
			(xy 281.25496 -301.150861) (xy 281.544524 -301.150861) (xy 281.544524 -301.098887) (xy 281.552654 -301.047552)
			(xy 281.568715 -300.998122) (xy 281.592311 -300.951812) (xy 281.622861 -300.909764) (xy 281.659612 -300.873013)
			(xy 281.70166 -300.842463) (xy 281.74797 -300.818867) (xy 281.7974 -300.802806) (xy 281.848735 -300.794676)
			(xy 281.900709 -300.794676) (xy 281.952044 -300.802806) (xy 282.001474 -300.818867) (xy 282.047784 -300.842463)
			(xy 282.089832 -300.873013) (xy 282.126583 -300.909764) (xy 282.157133 -300.951812) (xy 282.180729 -300.998122)
			(xy 282.19679 -301.047552) (xy 282.20492 -301.098887) (xy 282.20543 -301.124874) (xy 282.20492 -301.150861)
			(xy 282.494738 -301.150861) (xy 282.494738 -301.098887) (xy 282.502868 -301.047552) (xy 282.518929 -300.998122)
			(xy 282.542525 -300.951812) (xy 282.573075 -300.909764) (xy 282.609826 -300.873013) (xy 282.651874 -300.842463)
			(xy 282.698184 -300.818867) (xy 282.747614 -300.802806) (xy 282.798949 -300.794676) (xy 282.850923 -300.794676)
			(xy 282.902258 -300.802806) (xy 282.951688 -300.818867) (xy 282.997998 -300.842463) (xy 283.040046 -300.873013)
			(xy 283.076797 -300.909764) (xy 283.107347 -300.951812) (xy 283.130943 -300.998122) (xy 283.147004 -301.047552)
			(xy 283.155134 -301.098887) (xy 283.155644 -301.124874) (xy 283.155134 -301.150861) (xy 283.444698 -301.150861)
			(xy 283.444698 -301.098887) (xy 283.452828 -301.047552) (xy 283.468889 -300.998122) (xy 283.492485 -300.951812)
			(xy 283.523035 -300.909764) (xy 283.559786 -300.873013) (xy 283.601834 -300.842463) (xy 283.648144 -300.818867)
			(xy 283.697574 -300.802806) (xy 283.748909 -300.794676) (xy 283.800883 -300.794676) (xy 283.852218 -300.802806)
			(xy 283.901648 -300.818867) (xy 283.947958 -300.842463) (xy 283.990006 -300.873013) (xy 284.026757 -300.909764)
			(xy 284.057307 -300.951812) (xy 284.080903 -300.998122) (xy 284.096964 -301.047552) (xy 284.105094 -301.098887)
			(xy 284.105604 -301.124874) (xy 284.105094 -301.150861) (xy 284.394658 -301.150861) (xy 284.394658 -301.098887)
			(xy 284.402788 -301.047552) (xy 284.418849 -300.998122) (xy 284.442445 -300.951812) (xy 284.472995 -300.909764)
			(xy 284.509746 -300.873013) (xy 284.551794 -300.842463) (xy 284.598104 -300.818867) (xy 284.647534 -300.802806)
			(xy 284.698869 -300.794676) (xy 284.750843 -300.794676) (xy 284.802178 -300.802806) (xy 284.851608 -300.818867)
			(xy 284.897918 -300.842463) (xy 284.939966 -300.873013) (xy 284.976717 -300.909764) (xy 285.007267 -300.951812)
			(xy 285.030863 -300.998122) (xy 285.046924 -301.047552) (xy 285.055054 -301.098887) (xy 285.055564 -301.124874)
			(xy 285.055054 -301.150861) (xy 285.344618 -301.150861) (xy 285.344618 -301.098887) (xy 285.352748 -301.047552)
			(xy 285.368809 -300.998122) (xy 285.392405 -300.951812) (xy 285.422955 -300.909764) (xy 285.459706 -300.873013)
			(xy 285.501754 -300.842463) (xy 285.548064 -300.818867) (xy 285.597494 -300.802806) (xy 285.648829 -300.794676)
			(xy 285.700803 -300.794676) (xy 285.752138 -300.802806) (xy 285.801568 -300.818867) (xy 285.847878 -300.842463)
			(xy 285.889926 -300.873013) (xy 285.926677 -300.909764) (xy 285.957227 -300.951812) (xy 285.980823 -300.998122)
			(xy 285.996884 -301.047552) (xy 286.005014 -301.098887) (xy 286.005524 -301.124874) (xy 286.005014 -301.150861)
			(xy 286.294578 -301.150861) (xy 286.294578 -301.098887) (xy 286.302708 -301.047552) (xy 286.318769 -300.998122)
			(xy 286.342365 -300.951812) (xy 286.372915 -300.909764) (xy 286.409666 -300.873013) (xy 286.451714 -300.842463)
			(xy 286.498024 -300.818867) (xy 286.547454 -300.802806) (xy 286.598789 -300.794676) (xy 286.650763 -300.794676)
			(xy 286.702098 -300.802806) (xy 286.751528 -300.818867) (xy 286.797838 -300.842463) (xy 286.839886 -300.873013)
			(xy 286.876637 -300.909764) (xy 286.907187 -300.951812) (xy 286.930783 -300.998122) (xy 286.946844 -301.047552)
			(xy 286.954974 -301.098887) (xy 286.955484 -301.124874) (xy 286.954974 -301.150861) (xy 287.244538 -301.150861)
			(xy 287.244538 -301.098887) (xy 287.252668 -301.047552) (xy 287.268729 -300.998122) (xy 287.292325 -300.951812)
			(xy 287.322875 -300.909764) (xy 287.359626 -300.873013) (xy 287.401674 -300.842463) (xy 287.447984 -300.818867)
			(xy 287.497414 -300.802806) (xy 287.548749 -300.794676) (xy 287.600723 -300.794676) (xy 287.652058 -300.802806)
			(xy 287.701488 -300.818867) (xy 287.747798 -300.842463) (xy 287.789846 -300.873013) (xy 287.826597 -300.909764)
			(xy 287.857147 -300.951812) (xy 287.880743 -300.998122) (xy 287.896804 -301.047552) (xy 287.904934 -301.098887)
			(xy 287.905444 -301.124874) (xy 287.904934 -301.150861) (xy 288.194498 -301.150861) (xy 288.194498 -301.098887)
			(xy 288.202628 -301.047552) (xy 288.218689 -300.998122) (xy 288.242285 -300.951812) (xy 288.272835 -300.909764)
			(xy 288.309586 -300.873013) (xy 288.351634 -300.842463) (xy 288.397944 -300.818867) (xy 288.447374 -300.802806)
			(xy 288.498709 -300.794676) (xy 288.550683 -300.794676) (xy 288.602018 -300.802806) (xy 288.651448 -300.818867)
			(xy 288.697758 -300.842463) (xy 288.739806 -300.873013) (xy 288.776557 -300.909764) (xy 288.807107 -300.951812)
			(xy 288.830703 -300.998122) (xy 288.846764 -301.047552) (xy 288.854894 -301.098887) (xy 288.855404 -301.124874)
			(xy 288.854894 -301.150861) (xy 289.144712 -301.150861) (xy 289.144712 -301.098887) (xy 289.152842 -301.047552)
			(xy 289.168903 -300.998122) (xy 289.192499 -300.951812) (xy 289.223049 -300.909764) (xy 289.2598 -300.873013)
			(xy 289.301848 -300.842463) (xy 289.348158 -300.818867) (xy 289.397588 -300.802806) (xy 289.448923 -300.794676)
			(xy 289.500897 -300.794676) (xy 289.552232 -300.802806) (xy 289.601662 -300.818867) (xy 289.647972 -300.842463)
			(xy 289.69002 -300.873013) (xy 289.726771 -300.909764) (xy 289.757321 -300.951812) (xy 289.780917 -300.998122)
			(xy 289.796978 -301.047552) (xy 289.805108 -301.098887) (xy 289.805618 -301.124874) (xy 289.805108 -301.150861)
			(xy 290.094672 -301.150861) (xy 290.094672 -301.098887) (xy 290.102802 -301.047552) (xy 290.118863 -300.998122)
			(xy 290.142459 -300.951812) (xy 290.173009 -300.909764) (xy 290.20976 -300.873013) (xy 290.251808 -300.842463)
			(xy 290.298118 -300.818867) (xy 290.347548 -300.802806) (xy 290.398883 -300.794676) (xy 290.450857 -300.794676)
			(xy 290.502192 -300.802806) (xy 290.551622 -300.818867) (xy 290.597932 -300.842463) (xy 290.63998 -300.873013)
			(xy 290.676731 -300.909764) (xy 290.707281 -300.951812) (xy 290.730877 -300.998122) (xy 290.746938 -301.047552)
			(xy 290.755068 -301.098887) (xy 290.755578 -301.124874) (xy 290.755068 -301.150861) (xy 291.994592 -301.150861)
			(xy 291.994592 -301.098887) (xy 292.002722 -301.047552) (xy 292.018783 -300.998122) (xy 292.042379 -300.951812)
			(xy 292.072929 -300.909764) (xy 292.10968 -300.873013) (xy 292.151728 -300.842463) (xy 292.198038 -300.818867)
			(xy 292.247468 -300.802806) (xy 292.298803 -300.794676) (xy 292.350777 -300.794676) (xy 292.402112 -300.802806)
			(xy 292.451542 -300.818867) (xy 292.497852 -300.842463) (xy 292.5399 -300.873013) (xy 292.576651 -300.909764)
			(xy 292.607201 -300.951812) (xy 292.630797 -300.998122) (xy 292.646858 -301.047552) (xy 292.654988 -301.098887)
			(xy 292.655498 -301.124874) (xy 292.654988 -301.150861) (xy 292.944552 -301.150861) (xy 292.944552 -301.098887)
			(xy 292.952682 -301.047552) (xy 292.968743 -300.998122) (xy 292.992339 -300.951812) (xy 293.022889 -300.909764)
			(xy 293.05964 -300.873013) (xy 293.101688 -300.842463) (xy 293.147998 -300.818867) (xy 293.197428 -300.802806)
			(xy 293.248763 -300.794676) (xy 293.300737 -300.794676) (xy 293.352072 -300.802806) (xy 293.401502 -300.818867)
			(xy 293.447812 -300.842463) (xy 293.48986 -300.873013) (xy 293.526611 -300.909764) (xy 293.557161 -300.951812)
			(xy 293.580757 -300.998122) (xy 293.596818 -301.047552) (xy 293.604948 -301.098887) (xy 293.605458 -301.124874)
			(xy 293.604948 -301.150861) (xy 293.894512 -301.150861) (xy 293.894512 -301.098887) (xy 293.902642 -301.047552)
			(xy 293.918703 -300.998122) (xy 293.942299 -300.951812) (xy 293.972849 -300.909764) (xy 294.0096 -300.873013)
			(xy 294.051648 -300.842463) (xy 294.097958 -300.818867) (xy 294.147388 -300.802806) (xy 294.198723 -300.794676)
			(xy 294.250697 -300.794676) (xy 294.302032 -300.802806) (xy 294.351462 -300.818867) (xy 294.397772 -300.842463)
			(xy 294.43982 -300.873013) (xy 294.476571 -300.909764) (xy 294.507121 -300.951812) (xy 294.530717 -300.998122)
			(xy 294.546778 -301.047552) (xy 294.554908 -301.098887) (xy 294.555418 -301.124874) (xy 294.554908 -301.150861)
			(xy 294.844726 -301.150861) (xy 294.844726 -301.098887) (xy 294.852856 -301.047552) (xy 294.868917 -300.998122)
			(xy 294.892513 -300.951812) (xy 294.923063 -300.909764) (xy 294.959814 -300.873013) (xy 295.001862 -300.842463)
			(xy 295.048172 -300.818867) (xy 295.097602 -300.802806) (xy 295.148937 -300.794676) (xy 295.200911 -300.794676)
			(xy 295.252246 -300.802806) (xy 295.301676 -300.818867) (xy 295.347986 -300.842463) (xy 295.390034 -300.873013)
			(xy 295.426785 -300.909764) (xy 295.457335 -300.951812) (xy 295.480931 -300.998122) (xy 295.496992 -301.047552)
			(xy 295.505122 -301.098887) (xy 295.505632 -301.124874) (xy 295.505122 -301.150861) (xy 295.794686 -301.150861)
			(xy 295.794686 -301.098887) (xy 295.802816 -301.047552) (xy 295.818877 -300.998122) (xy 295.842473 -300.951812)
			(xy 295.873023 -300.909764) (xy 295.909774 -300.873013) (xy 295.951822 -300.842463) (xy 295.998132 -300.818867)
			(xy 296.047562 -300.802806) (xy 296.098897 -300.794676) (xy 296.150871 -300.794676) (xy 296.202206 -300.802806)
			(xy 296.251636 -300.818867) (xy 296.297946 -300.842463) (xy 296.339994 -300.873013) (xy 296.376745 -300.909764)
			(xy 296.407295 -300.951812) (xy 296.430891 -300.998122) (xy 296.446952 -301.047552) (xy 296.455082 -301.098887)
			(xy 296.455592 -301.124874) (xy 296.455082 -301.150861) (xy 296.744646 -301.150861) (xy 296.744646 -301.098887)
			(xy 296.752776 -301.047552) (xy 296.768837 -300.998122) (xy 296.792433 -300.951812) (xy 296.822983 -300.909764)
			(xy 296.859734 -300.873013) (xy 296.901782 -300.842463) (xy 296.948092 -300.818867) (xy 296.997522 -300.802806)
			(xy 297.048857 -300.794676) (xy 297.100831 -300.794676) (xy 297.152166 -300.802806) (xy 297.201596 -300.818867)
			(xy 297.247906 -300.842463) (xy 297.289954 -300.873013) (xy 297.326705 -300.909764) (xy 297.357255 -300.951812)
			(xy 297.380851 -300.998122) (xy 297.396912 -301.047552) (xy 297.405042 -301.098887) (xy 297.405552 -301.124874)
			(xy 297.405042 -301.150861) (xy 297.694606 -301.150861) (xy 297.694606 -301.098887) (xy 297.702736 -301.047552)
			(xy 297.718797 -300.998122) (xy 297.742393 -300.951812) (xy 297.772943 -300.909764) (xy 297.809694 -300.873013)
			(xy 297.851742 -300.842463) (xy 297.898052 -300.818867) (xy 297.947482 -300.802806) (xy 297.998817 -300.794676)
			(xy 298.050791 -300.794676) (xy 298.102126 -300.802806) (xy 298.151556 -300.818867) (xy 298.197866 -300.842463)
			(xy 298.239914 -300.873013) (xy 298.276665 -300.909764) (xy 298.307215 -300.951812) (xy 298.330811 -300.998122)
			(xy 298.346872 -301.047552) (xy 298.355002 -301.098887) (xy 298.355512 -301.124874) (xy 298.355002 -301.150861)
			(xy 298.644566 -301.150861) (xy 298.644566 -301.098887) (xy 298.652696 -301.047552) (xy 298.668757 -300.998122)
			(xy 298.692353 -300.951812) (xy 298.722903 -300.909764) (xy 298.759654 -300.873013) (xy 298.801702 -300.842463)
			(xy 298.848012 -300.818867) (xy 298.897442 -300.802806) (xy 298.948777 -300.794676) (xy 299.000751 -300.794676)
			(xy 299.052086 -300.802806) (xy 299.101516 -300.818867) (xy 299.147826 -300.842463) (xy 299.189874 -300.873013)
			(xy 299.226625 -300.909764) (xy 299.257175 -300.951812) (xy 299.280771 -300.998122) (xy 299.296832 -301.047552)
			(xy 299.304962 -301.098887) (xy 299.305472 -301.124874) (xy 299.304962 -301.150861) (xy 299.594526 -301.150861)
			(xy 299.594526 -301.098887) (xy 299.602656 -301.047552) (xy 299.618717 -300.998122) (xy 299.642313 -300.951812)
			(xy 299.672863 -300.909764) (xy 299.709614 -300.873013) (xy 299.751662 -300.842463) (xy 299.797972 -300.818867)
			(xy 299.847402 -300.802806) (xy 299.898737 -300.794676) (xy 299.950711 -300.794676) (xy 300.002046 -300.802806)
			(xy 300.051476 -300.818867) (xy 300.097786 -300.842463) (xy 300.139834 -300.873013) (xy 300.176585 -300.909764)
			(xy 300.207135 -300.951812) (xy 300.230731 -300.998122) (xy 300.246792 -301.047552) (xy 300.254922 -301.098887)
			(xy 300.255432 -301.124874) (xy 300.254922 -301.150861) (xy 300.544486 -301.150861) (xy 300.544486 -301.098887)
			(xy 300.552616 -301.047552) (xy 300.568677 -300.998122) (xy 300.592273 -300.951812) (xy 300.622823 -300.909764)
			(xy 300.659574 -300.873013) (xy 300.701622 -300.842463) (xy 300.747932 -300.818867) (xy 300.797362 -300.802806)
			(xy 300.848697 -300.794676) (xy 300.900671 -300.794676) (xy 300.952006 -300.802806) (xy 301.001436 -300.818867)
			(xy 301.047746 -300.842463) (xy 301.089794 -300.873013) (xy 301.126545 -300.909764) (xy 301.157095 -300.951812)
			(xy 301.180691 -300.998122) (xy 301.196752 -301.047552) (xy 301.204882 -301.098887) (xy 301.205392 -301.124874)
			(xy 301.204882 -301.150861) (xy 301.196752 -301.202196) (xy 301.180691 -301.251626) (xy 301.157095 -301.297936)
			(xy 301.126545 -301.339984) (xy 301.089794 -301.376735) (xy 301.047746 -301.407285) (xy 301.001436 -301.430881)
			(xy 300.952006 -301.446942) (xy 300.900671 -301.455072) (xy 300.848697 -301.455072) (xy 300.797362 -301.446942)
			(xy 300.747932 -301.430881) (xy 300.701622 -301.407285) (xy 300.659574 -301.376735) (xy 300.622823 -301.339984)
			(xy 300.592273 -301.297936) (xy 300.568677 -301.251626) (xy 300.552616 -301.202196) (xy 300.544486 -301.150861)
			(xy 300.254922 -301.150861) (xy 300.246792 -301.202196) (xy 300.230731 -301.251626) (xy 300.207135 -301.297936)
			(xy 300.176585 -301.339984) (xy 300.139834 -301.376735) (xy 300.097786 -301.407285) (xy 300.051476 -301.430881)
			(xy 300.002046 -301.446942) (xy 299.950711 -301.455072) (xy 299.898737 -301.455072) (xy 299.847402 -301.446942)
			(xy 299.797972 -301.430881) (xy 299.751662 -301.407285) (xy 299.709614 -301.376735) (xy 299.672863 -301.339984)
			(xy 299.642313 -301.297936) (xy 299.618717 -301.251626) (xy 299.602656 -301.202196) (xy 299.594526 -301.150861)
			(xy 299.304962 -301.150861) (xy 299.296832 -301.202196) (xy 299.280771 -301.251626) (xy 299.257175 -301.297936)
			(xy 299.226625 -301.339984) (xy 299.189874 -301.376735) (xy 299.147826 -301.407285) (xy 299.101516 -301.430881)
			(xy 299.052086 -301.446942) (xy 299.000751 -301.455072) (xy 298.948777 -301.455072) (xy 298.897442 -301.446942)
			(xy 298.848012 -301.430881) (xy 298.801702 -301.407285) (xy 298.759654 -301.376735) (xy 298.722903 -301.339984)
			(xy 298.692353 -301.297936) (xy 298.668757 -301.251626) (xy 298.652696 -301.202196) (xy 298.644566 -301.150861)
			(xy 298.355002 -301.150861) (xy 298.346872 -301.202196) (xy 298.330811 -301.251626) (xy 298.307215 -301.297936)
			(xy 298.276665 -301.339984) (xy 298.239914 -301.376735) (xy 298.197866 -301.407285) (xy 298.151556 -301.430881)
			(xy 298.102126 -301.446942) (xy 298.050791 -301.455072) (xy 297.998817 -301.455072) (xy 297.947482 -301.446942)
			(xy 297.898052 -301.430881) (xy 297.851742 -301.407285) (xy 297.809694 -301.376735) (xy 297.772943 -301.339984)
			(xy 297.742393 -301.297936) (xy 297.718797 -301.251626) (xy 297.702736 -301.202196) (xy 297.694606 -301.150861)
			(xy 297.405042 -301.150861) (xy 297.396912 -301.202196) (xy 297.380851 -301.251626) (xy 297.357255 -301.297936)
			(xy 297.326705 -301.339984) (xy 297.289954 -301.376735) (xy 297.247906 -301.407285) (xy 297.201596 -301.430881)
			(xy 297.152166 -301.446942) (xy 297.100831 -301.455072) (xy 297.048857 -301.455072) (xy 296.997522 -301.446942)
			(xy 296.948092 -301.430881) (xy 296.901782 -301.407285) (xy 296.859734 -301.376735) (xy 296.822983 -301.339984)
			(xy 296.792433 -301.297936) (xy 296.768837 -301.251626) (xy 296.752776 -301.202196) (xy 296.744646 -301.150861)
			(xy 296.455082 -301.150861) (xy 296.446952 -301.202196) (xy 296.430891 -301.251626) (xy 296.407295 -301.297936)
			(xy 296.376745 -301.339984) (xy 296.339994 -301.376735) (xy 296.297946 -301.407285) (xy 296.251636 -301.430881)
			(xy 296.202206 -301.446942) (xy 296.150871 -301.455072) (xy 296.098897 -301.455072) (xy 296.047562 -301.446942)
			(xy 295.998132 -301.430881) (xy 295.951822 -301.407285) (xy 295.909774 -301.376735) (xy 295.873023 -301.339984)
			(xy 295.842473 -301.297936) (xy 295.818877 -301.251626) (xy 295.802816 -301.202196) (xy 295.794686 -301.150861)
			(xy 295.505122 -301.150861) (xy 295.496992 -301.202196) (xy 295.480931 -301.251626) (xy 295.457335 -301.297936)
			(xy 295.426785 -301.339984) (xy 295.390034 -301.376735) (xy 295.347986 -301.407285) (xy 295.301676 -301.430881)
			(xy 295.252246 -301.446942) (xy 295.200911 -301.455072) (xy 295.148937 -301.455072) (xy 295.097602 -301.446942)
			(xy 295.048172 -301.430881) (xy 295.001862 -301.407285) (xy 294.959814 -301.376735) (xy 294.923063 -301.339984)
			(xy 294.892513 -301.297936) (xy 294.868917 -301.251626) (xy 294.852856 -301.202196) (xy 294.844726 -301.150861)
			(xy 294.554908 -301.150861) (xy 294.546778 -301.202196) (xy 294.530717 -301.251626) (xy 294.507121 -301.297936)
			(xy 294.476571 -301.339984) (xy 294.43982 -301.376735) (xy 294.397772 -301.407285) (xy 294.351462 -301.430881)
			(xy 294.302032 -301.446942) (xy 294.250697 -301.455072) (xy 294.198723 -301.455072) (xy 294.147388 -301.446942)
			(xy 294.097958 -301.430881) (xy 294.051648 -301.407285) (xy 294.0096 -301.376735) (xy 293.972849 -301.339984)
			(xy 293.942299 -301.297936) (xy 293.918703 -301.251626) (xy 293.902642 -301.202196) (xy 293.894512 -301.150861)
			(xy 293.604948 -301.150861) (xy 293.596818 -301.202196) (xy 293.580757 -301.251626) (xy 293.557161 -301.297936)
			(xy 293.526611 -301.339984) (xy 293.48986 -301.376735) (xy 293.447812 -301.407285) (xy 293.401502 -301.430881)
			(xy 293.352072 -301.446942) (xy 293.300737 -301.455072) (xy 293.248763 -301.455072) (xy 293.197428 -301.446942)
			(xy 293.147998 -301.430881) (xy 293.101688 -301.407285) (xy 293.05964 -301.376735) (xy 293.022889 -301.339984)
			(xy 292.992339 -301.297936) (xy 292.968743 -301.251626) (xy 292.952682 -301.202196) (xy 292.944552 -301.150861)
			(xy 292.654988 -301.150861) (xy 292.646858 -301.202196) (xy 292.630797 -301.251626) (xy 292.607201 -301.297936)
			(xy 292.576651 -301.339984) (xy 292.5399 -301.376735) (xy 292.497852 -301.407285) (xy 292.451542 -301.430881)
			(xy 292.402112 -301.446942) (xy 292.350777 -301.455072) (xy 292.298803 -301.455072) (xy 292.247468 -301.446942)
			(xy 292.198038 -301.430881) (xy 292.151728 -301.407285) (xy 292.10968 -301.376735) (xy 292.072929 -301.339984)
			(xy 292.042379 -301.297936) (xy 292.018783 -301.251626) (xy 292.002722 -301.202196) (xy 291.994592 -301.150861)
			(xy 290.755068 -301.150861) (xy 290.746938 -301.202196) (xy 290.730877 -301.251626) (xy 290.707281 -301.297936)
			(xy 290.676731 -301.339984) (xy 290.63998 -301.376735) (xy 290.597932 -301.407285) (xy 290.551622 -301.430881)
			(xy 290.502192 -301.446942) (xy 290.450857 -301.455072) (xy 290.398883 -301.455072) (xy 290.347548 -301.446942)
			(xy 290.298118 -301.430881) (xy 290.251808 -301.407285) (xy 290.20976 -301.376735) (xy 290.173009 -301.339984)
			(xy 290.142459 -301.297936) (xy 290.118863 -301.251626) (xy 290.102802 -301.202196) (xy 290.094672 -301.150861)
			(xy 289.805108 -301.150861) (xy 289.796978 -301.202196) (xy 289.780917 -301.251626) (xy 289.757321 -301.297936)
			(xy 289.726771 -301.339984) (xy 289.69002 -301.376735) (xy 289.647972 -301.407285) (xy 289.601662 -301.430881)
			(xy 289.552232 -301.446942) (xy 289.500897 -301.455072) (xy 289.448923 -301.455072) (xy 289.397588 -301.446942)
			(xy 289.348158 -301.430881) (xy 289.301848 -301.407285) (xy 289.2598 -301.376735) (xy 289.223049 -301.339984)
			(xy 289.192499 -301.297936) (xy 289.168903 -301.251626) (xy 289.152842 -301.202196) (xy 289.144712 -301.150861)
			(xy 288.854894 -301.150861) (xy 288.846764 -301.202196) (xy 288.830703 -301.251626) (xy 288.807107 -301.297936)
			(xy 288.776557 -301.339984) (xy 288.739806 -301.376735) (xy 288.697758 -301.407285) (xy 288.651448 -301.430881)
			(xy 288.602018 -301.446942) (xy 288.550683 -301.455072) (xy 288.498709 -301.455072) (xy 288.447374 -301.446942)
			(xy 288.397944 -301.430881) (xy 288.351634 -301.407285) (xy 288.309586 -301.376735) (xy 288.272835 -301.339984)
			(xy 288.242285 -301.297936) (xy 288.218689 -301.251626) (xy 288.202628 -301.202196) (xy 288.194498 -301.150861)
			(xy 287.904934 -301.150861) (xy 287.896804 -301.202196) (xy 287.880743 -301.251626) (xy 287.857147 -301.297936)
			(xy 287.826597 -301.339984) (xy 287.789846 -301.376735) (xy 287.747798 -301.407285) (xy 287.701488 -301.430881)
			(xy 287.652058 -301.446942) (xy 287.600723 -301.455072) (xy 287.548749 -301.455072) (xy 287.497414 -301.446942)
			(xy 287.447984 -301.430881) (xy 287.401674 -301.407285) (xy 287.359626 -301.376735) (xy 287.322875 -301.339984)
			(xy 287.292325 -301.297936) (xy 287.268729 -301.251626) (xy 287.252668 -301.202196) (xy 287.244538 -301.150861)
			(xy 286.954974 -301.150861) (xy 286.946844 -301.202196) (xy 286.930783 -301.251626) (xy 286.907187 -301.297936)
			(xy 286.876637 -301.339984) (xy 286.839886 -301.376735) (xy 286.797838 -301.407285) (xy 286.751528 -301.430881)
			(xy 286.702098 -301.446942) (xy 286.650763 -301.455072) (xy 286.598789 -301.455072) (xy 286.547454 -301.446942)
			(xy 286.498024 -301.430881) (xy 286.451714 -301.407285) (xy 286.409666 -301.376735) (xy 286.372915 -301.339984)
			(xy 286.342365 -301.297936) (xy 286.318769 -301.251626) (xy 286.302708 -301.202196) (xy 286.294578 -301.150861)
			(xy 286.005014 -301.150861) (xy 285.996884 -301.202196) (xy 285.980823 -301.251626) (xy 285.957227 -301.297936)
			(xy 285.926677 -301.339984) (xy 285.889926 -301.376735) (xy 285.847878 -301.407285) (xy 285.801568 -301.430881)
			(xy 285.752138 -301.446942) (xy 285.700803 -301.455072) (xy 285.648829 -301.455072) (xy 285.597494 -301.446942)
			(xy 285.548064 -301.430881) (xy 285.501754 -301.407285) (xy 285.459706 -301.376735) (xy 285.422955 -301.339984)
			(xy 285.392405 -301.297936) (xy 285.368809 -301.251626) (xy 285.352748 -301.202196) (xy 285.344618 -301.150861)
			(xy 285.055054 -301.150861) (xy 285.046924 -301.202196) (xy 285.030863 -301.251626) (xy 285.007267 -301.297936)
			(xy 284.976717 -301.339984) (xy 284.939966 -301.376735) (xy 284.897918 -301.407285) (xy 284.851608 -301.430881)
			(xy 284.802178 -301.446942) (xy 284.750843 -301.455072) (xy 284.698869 -301.455072) (xy 284.647534 -301.446942)
			(xy 284.598104 -301.430881) (xy 284.551794 -301.407285) (xy 284.509746 -301.376735) (xy 284.472995 -301.339984)
			(xy 284.442445 -301.297936) (xy 284.418849 -301.251626) (xy 284.402788 -301.202196) (xy 284.394658 -301.150861)
			(xy 284.105094 -301.150861) (xy 284.096964 -301.202196) (xy 284.080903 -301.251626) (xy 284.057307 -301.297936)
			(xy 284.026757 -301.339984) (xy 283.990006 -301.376735) (xy 283.947958 -301.407285) (xy 283.901648 -301.430881)
			(xy 283.852218 -301.446942) (xy 283.800883 -301.455072) (xy 283.748909 -301.455072) (xy 283.697574 -301.446942)
			(xy 283.648144 -301.430881) (xy 283.601834 -301.407285) (xy 283.559786 -301.376735) (xy 283.523035 -301.339984)
			(xy 283.492485 -301.297936) (xy 283.468889 -301.251626) (xy 283.452828 -301.202196) (xy 283.444698 -301.150861)
			(xy 283.155134 -301.150861) (xy 283.147004 -301.202196) (xy 283.130943 -301.251626) (xy 283.107347 -301.297936)
			(xy 283.076797 -301.339984) (xy 283.040046 -301.376735) (xy 282.997998 -301.407285) (xy 282.951688 -301.430881)
			(xy 282.902258 -301.446942) (xy 282.850923 -301.455072) (xy 282.798949 -301.455072) (xy 282.747614 -301.446942)
			(xy 282.698184 -301.430881) (xy 282.651874 -301.407285) (xy 282.609826 -301.376735) (xy 282.573075 -301.339984)
			(xy 282.542525 -301.297936) (xy 282.518929 -301.251626) (xy 282.502868 -301.202196) (xy 282.494738 -301.150861)
			(xy 282.20492 -301.150861) (xy 282.19679 -301.202196) (xy 282.180729 -301.251626) (xy 282.157133 -301.297936)
			(xy 282.126583 -301.339984) (xy 282.089832 -301.376735) (xy 282.047784 -301.407285) (xy 282.001474 -301.430881)
			(xy 281.952044 -301.446942) (xy 281.900709 -301.455072) (xy 281.848735 -301.455072) (xy 281.7974 -301.446942)
			(xy 281.74797 -301.430881) (xy 281.70166 -301.407285) (xy 281.659612 -301.376735) (xy 281.622861 -301.339984)
			(xy 281.592311 -301.297936) (xy 281.568715 -301.251626) (xy 281.552654 -301.202196) (xy 281.544524 -301.150861)
			(xy 281.25496 -301.150861) (xy 281.24683 -301.202196) (xy 281.230769 -301.251626) (xy 281.207173 -301.297936)
			(xy 281.176623 -301.339984) (xy 281.139872 -301.376735) (xy 281.097824 -301.407285) (xy 281.051514 -301.430881)
			(xy 281.002084 -301.446942) (xy 280.950749 -301.455072) (xy 280.898775 -301.455072) (xy 280.84744 -301.446942)
			(xy 280.79801 -301.430881) (xy 280.7517 -301.407285) (xy 280.709652 -301.376735) (xy 280.672901 -301.339984)
			(xy 280.642351 -301.297936) (xy 280.618755 -301.251626) (xy 280.602694 -301.202196) (xy 280.594564 -301.150861)
			(xy 280.305 -301.150861) (xy 280.29687 -301.202196) (xy 280.280809 -301.251626) (xy 280.257213 -301.297936)
			(xy 280.226663 -301.339984) (xy 280.189912 -301.376735) (xy 280.147864 -301.407285) (xy 280.101554 -301.430881)
			(xy 280.052124 -301.446942) (xy 280.000789 -301.455072) (xy 279.948815 -301.455072) (xy 279.89748 -301.446942)
			(xy 279.84805 -301.430881) (xy 279.80174 -301.407285) (xy 279.759692 -301.376735) (xy 279.722941 -301.339984)
			(xy 279.692391 -301.297936) (xy 279.668795 -301.251626) (xy 279.652734 -301.202196) (xy 279.644604 -301.150861)
			(xy 278.404074 -301.150861) (xy 278.401961 -301.17738) (xy 278.389514 -301.228539) (xy 278.369118 -301.27708)
			(xy 278.341288 -301.321776) (xy 278.306728 -301.361497) (xy 278.266311 -301.395241) (xy 278.221058 -301.422155)
			(xy 278.172112 -301.441558) (xy 278.14651 -301.447708) (xy 278.128984 -301.451518) (xy 278.106632 -301.479458)
			(xy 278.106632 -301.72025) (xy 278.128984 -301.74819) (xy 278.14651 -301.752) (xy 278.170352 -301.757749)
			(xy 278.216136 -301.775329) (xy 278.258824 -301.799475) (xy 278.297479 -301.829658) (xy 278.331255 -301.865216)
			(xy 278.359413 -301.905371) (xy 278.381335 -301.949242) (xy 278.39654 -301.995869) (xy 278.404697 -302.044229)
			(xy 278.40559 -302.068738) (xy 278.40559 -302.0695) (xy 278.406279 -302.079076) (xy 278.413846 -302.096704)
			(xy 278.417609 -302.100821) (xy 281.544524 -302.100821) (xy 281.544524 -302.048847) (xy 281.552654 -301.997512)
			(xy 281.568715 -301.948082) (xy 281.592311 -301.901772) (xy 281.622861 -301.859724) (xy 281.659612 -301.822973)
			(xy 281.70166 -301.792423) (xy 281.74797 -301.768827) (xy 281.7974 -301.752766) (xy 281.848735 -301.744636)
			(xy 281.900709 -301.744636) (xy 281.952044 -301.752766) (xy 282.001474 -301.768827) (xy 282.047784 -301.792423)
			(xy 282.089832 -301.822973) (xy 282.126583 -301.859724) (xy 282.157133 -301.901772) (xy 282.180729 -301.948082)
			(xy 282.19679 -301.997512) (xy 282.20492 -302.048847) (xy 282.20543 -302.074834) (xy 282.20492 -302.100821)
			(xy 282.494738 -302.100821) (xy 282.494738 -302.048847) (xy 282.502868 -301.997512) (xy 282.518929 -301.948082)
			(xy 282.542525 -301.901772) (xy 282.573075 -301.859724) (xy 282.609826 -301.822973) (xy 282.651874 -301.792423)
			(xy 282.698184 -301.768827) (xy 282.747614 -301.752766) (xy 282.798949 -301.744636) (xy 282.850923 -301.744636)
			(xy 282.902258 -301.752766) (xy 282.951688 -301.768827) (xy 282.997998 -301.792423) (xy 283.040046 -301.822973)
			(xy 283.076797 -301.859724) (xy 283.107347 -301.901772) (xy 283.130943 -301.948082) (xy 283.147004 -301.997512)
			(xy 283.155134 -302.048847) (xy 283.155644 -302.074834) (xy 283.155134 -302.100821) (xy 283.444698 -302.100821)
			(xy 283.444698 -302.048847) (xy 283.452828 -301.997512) (xy 283.468889 -301.948082) (xy 283.492485 -301.901772)
			(xy 283.523035 -301.859724) (xy 283.559786 -301.822973) (xy 283.601834 -301.792423) (xy 283.648144 -301.768827)
			(xy 283.697574 -301.752766) (xy 283.748909 -301.744636) (xy 283.800883 -301.744636) (xy 283.852218 -301.752766)
			(xy 283.901648 -301.768827) (xy 283.947958 -301.792423) (xy 283.990006 -301.822973) (xy 284.026757 -301.859724)
			(xy 284.057307 -301.901772) (xy 284.080903 -301.948082) (xy 284.096964 -301.997512) (xy 284.105094 -302.048847)
			(xy 284.105604 -302.074834) (xy 284.105094 -302.100821) (xy 284.394658 -302.100821) (xy 284.394658 -302.048847)
			(xy 284.402788 -301.997512) (xy 284.418849 -301.948082) (xy 284.442445 -301.901772) (xy 284.472995 -301.859724)
			(xy 284.509746 -301.822973) (xy 284.551794 -301.792423) (xy 284.598104 -301.768827) (xy 284.647534 -301.752766)
			(xy 284.698869 -301.744636) (xy 284.750843 -301.744636) (xy 284.802178 -301.752766) (xy 284.851608 -301.768827)
			(xy 284.897918 -301.792423) (xy 284.939966 -301.822973) (xy 284.976717 -301.859724) (xy 285.007267 -301.901772)
			(xy 285.030863 -301.948082) (xy 285.046924 -301.997512) (xy 285.055054 -302.048847) (xy 285.055564 -302.074834)
			(xy 285.055054 -302.100821) (xy 285.344618 -302.100821) (xy 285.344618 -302.048847) (xy 285.352748 -301.997512)
			(xy 285.368809 -301.948082) (xy 285.392405 -301.901772) (xy 285.422955 -301.859724) (xy 285.459706 -301.822973)
			(xy 285.501754 -301.792423) (xy 285.548064 -301.768827) (xy 285.597494 -301.752766) (xy 285.648829 -301.744636)
			(xy 285.700803 -301.744636) (xy 285.752138 -301.752766) (xy 285.801568 -301.768827) (xy 285.847878 -301.792423)
			(xy 285.889926 -301.822973) (xy 285.926677 -301.859724) (xy 285.957227 -301.901772) (xy 285.980823 -301.948082)
			(xy 285.996884 -301.997512) (xy 286.005014 -302.048847) (xy 286.005524 -302.074834) (xy 286.005014 -302.100821)
			(xy 286.294578 -302.100821) (xy 286.294578 -302.048847) (xy 286.302708 -301.997512) (xy 286.318769 -301.948082)
			(xy 286.342365 -301.901772) (xy 286.372915 -301.859724) (xy 286.409666 -301.822973) (xy 286.451714 -301.792423)
			(xy 286.498024 -301.768827) (xy 286.547454 -301.752766) (xy 286.598789 -301.744636) (xy 286.650763 -301.744636)
			(xy 286.702098 -301.752766) (xy 286.751528 -301.768827) (xy 286.797838 -301.792423) (xy 286.839886 -301.822973)
			(xy 286.876637 -301.859724) (xy 286.907187 -301.901772) (xy 286.930783 -301.948082) (xy 286.946844 -301.997512)
			(xy 286.954974 -302.048847) (xy 286.955484 -302.074834) (xy 286.954974 -302.100821) (xy 287.244538 -302.100821)
			(xy 287.244538 -302.048847) (xy 287.252668 -301.997512) (xy 287.268729 -301.948082) (xy 287.292325 -301.901772)
			(xy 287.322875 -301.859724) (xy 287.359626 -301.822973) (xy 287.401674 -301.792423) (xy 287.447984 -301.768827)
			(xy 287.497414 -301.752766) (xy 287.548749 -301.744636) (xy 287.600723 -301.744636) (xy 287.652058 -301.752766)
			(xy 287.701488 -301.768827) (xy 287.747798 -301.792423) (xy 287.789846 -301.822973) (xy 287.826597 -301.859724)
			(xy 287.857147 -301.901772) (xy 287.880743 -301.948082) (xy 287.896804 -301.997512) (xy 287.904934 -302.048847)
			(xy 287.905444 -302.074834) (xy 287.904934 -302.100821) (xy 288.194498 -302.100821) (xy 288.194498 -302.048847)
			(xy 288.202628 -301.997512) (xy 288.218689 -301.948082) (xy 288.242285 -301.901772) (xy 288.272835 -301.859724)
			(xy 288.309586 -301.822973) (xy 288.351634 -301.792423) (xy 288.397944 -301.768827) (xy 288.447374 -301.752766)
			(xy 288.498709 -301.744636) (xy 288.550683 -301.744636) (xy 288.602018 -301.752766) (xy 288.651448 -301.768827)
			(xy 288.697758 -301.792423) (xy 288.739806 -301.822973) (xy 288.776557 -301.859724) (xy 288.807107 -301.901772)
			(xy 288.830703 -301.948082) (xy 288.846764 -301.997512) (xy 288.854894 -302.048847) (xy 288.855404 -302.074834)
			(xy 288.854894 -302.100821) (xy 289.144712 -302.100821) (xy 289.144712 -302.048847) (xy 289.152842 -301.997512)
			(xy 289.168903 -301.948082) (xy 289.192499 -301.901772) (xy 289.223049 -301.859724) (xy 289.2598 -301.822973)
			(xy 289.301848 -301.792423) (xy 289.348158 -301.768827) (xy 289.397588 -301.752766) (xy 289.448923 -301.744636)
			(xy 289.500897 -301.744636) (xy 289.552232 -301.752766) (xy 289.601662 -301.768827) (xy 289.647972 -301.792423)
			(xy 289.69002 -301.822973) (xy 289.726771 -301.859724) (xy 289.757321 -301.901772) (xy 289.780917 -301.948082)
			(xy 289.796978 -301.997512) (xy 289.805108 -302.048847) (xy 289.805618 -302.074834) (xy 289.805108 -302.100821)
			(xy 290.094672 -302.100821) (xy 290.094672 -302.048847) (xy 290.102802 -301.997512) (xy 290.118863 -301.948082)
			(xy 290.142459 -301.901772) (xy 290.173009 -301.859724) (xy 290.20976 -301.822973) (xy 290.251808 -301.792423)
			(xy 290.298118 -301.768827) (xy 290.347548 -301.752766) (xy 290.398883 -301.744636) (xy 290.450857 -301.744636)
			(xy 290.502192 -301.752766) (xy 290.551622 -301.768827) (xy 290.597932 -301.792423) (xy 290.63998 -301.822973)
			(xy 290.676731 -301.859724) (xy 290.707281 -301.901772) (xy 290.730877 -301.948082) (xy 290.746938 -301.997512)
			(xy 290.755068 -302.048847) (xy 290.755578 -302.074834) (xy 290.755068 -302.100821) (xy 291.994592 -302.100821)
			(xy 291.994592 -302.048847) (xy 292.002722 -301.997512) (xy 292.018783 -301.948082) (xy 292.042379 -301.901772)
			(xy 292.072929 -301.859724) (xy 292.10968 -301.822973) (xy 292.151728 -301.792423) (xy 292.198038 -301.768827)
			(xy 292.247468 -301.752766) (xy 292.298803 -301.744636) (xy 292.350777 -301.744636) (xy 292.402112 -301.752766)
			(xy 292.451542 -301.768827) (xy 292.497852 -301.792423) (xy 292.5399 -301.822973) (xy 292.576651 -301.859724)
			(xy 292.607201 -301.901772) (xy 292.630797 -301.948082) (xy 292.646858 -301.997512) (xy 292.654988 -302.048847)
			(xy 292.655498 -302.074834) (xy 292.654988 -302.100821) (xy 292.944552 -302.100821) (xy 292.944552 -302.048847)
			(xy 292.952682 -301.997512) (xy 292.968743 -301.948082) (xy 292.992339 -301.901772) (xy 293.022889 -301.859724)
			(xy 293.05964 -301.822973) (xy 293.101688 -301.792423) (xy 293.147998 -301.768827) (xy 293.197428 -301.752766)
			(xy 293.248763 -301.744636) (xy 293.300737 -301.744636) (xy 293.352072 -301.752766) (xy 293.401502 -301.768827)
			(xy 293.447812 -301.792423) (xy 293.48986 -301.822973) (xy 293.526611 -301.859724) (xy 293.557161 -301.901772)
			(xy 293.580757 -301.948082) (xy 293.596818 -301.997512) (xy 293.604948 -302.048847) (xy 293.605458 -302.074834)
			(xy 293.604948 -302.100821) (xy 293.894512 -302.100821) (xy 293.894512 -302.048847) (xy 293.902642 -301.997512)
			(xy 293.918703 -301.948082) (xy 293.942299 -301.901772) (xy 293.972849 -301.859724) (xy 294.0096 -301.822973)
			(xy 294.051648 -301.792423) (xy 294.097958 -301.768827) (xy 294.147388 -301.752766) (xy 294.198723 -301.744636)
			(xy 294.250697 -301.744636) (xy 294.302032 -301.752766) (xy 294.351462 -301.768827) (xy 294.397772 -301.792423)
			(xy 294.43982 -301.822973) (xy 294.476571 -301.859724) (xy 294.507121 -301.901772) (xy 294.530717 -301.948082)
			(xy 294.546778 -301.997512) (xy 294.554908 -302.048847) (xy 294.555418 -302.074834) (xy 294.554908 -302.100821)
			(xy 294.844726 -302.100821) (xy 294.844726 -302.048847) (xy 294.852856 -301.997512) (xy 294.868917 -301.948082)
			(xy 294.892513 -301.901772) (xy 294.923063 -301.859724) (xy 294.959814 -301.822973) (xy 295.001862 -301.792423)
			(xy 295.048172 -301.768827) (xy 295.097602 -301.752766) (xy 295.148937 -301.744636) (xy 295.200911 -301.744636)
			(xy 295.252246 -301.752766) (xy 295.301676 -301.768827) (xy 295.347986 -301.792423) (xy 295.390034 -301.822973)
			(xy 295.426785 -301.859724) (xy 295.457335 -301.901772) (xy 295.480931 -301.948082) (xy 295.496992 -301.997512)
			(xy 295.505122 -302.048847) (xy 295.505632 -302.074834) (xy 295.505122 -302.100821) (xy 295.794686 -302.100821)
			(xy 295.794686 -302.048847) (xy 295.802816 -301.997512) (xy 295.818877 -301.948082) (xy 295.842473 -301.901772)
			(xy 295.873023 -301.859724) (xy 295.909774 -301.822973) (xy 295.951822 -301.792423) (xy 295.998132 -301.768827)
			(xy 296.047562 -301.752766) (xy 296.098897 -301.744636) (xy 296.150871 -301.744636) (xy 296.202206 -301.752766)
			(xy 296.251636 -301.768827) (xy 296.297946 -301.792423) (xy 296.339994 -301.822973) (xy 296.376745 -301.859724)
			(xy 296.407295 -301.901772) (xy 296.430891 -301.948082) (xy 296.446952 -301.997512) (xy 296.455082 -302.048847)
			(xy 296.455592 -302.074834) (xy 296.455082 -302.100821) (xy 296.744646 -302.100821) (xy 296.744646 -302.048847)
			(xy 296.752776 -301.997512) (xy 296.768837 -301.948082) (xy 296.792433 -301.901772) (xy 296.822983 -301.859724)
			(xy 296.859734 -301.822973) (xy 296.901782 -301.792423) (xy 296.948092 -301.768827) (xy 296.997522 -301.752766)
			(xy 297.048857 -301.744636) (xy 297.100831 -301.744636) (xy 297.152166 -301.752766) (xy 297.201596 -301.768827)
			(xy 297.247906 -301.792423) (xy 297.289954 -301.822973) (xy 297.326705 -301.859724) (xy 297.357255 -301.901772)
			(xy 297.380851 -301.948082) (xy 297.396912 -301.997512) (xy 297.405042 -302.048847) (xy 297.405552 -302.074834)
			(xy 297.405042 -302.100821) (xy 297.694606 -302.100821) (xy 297.694606 -302.048847) (xy 297.702736 -301.997512)
			(xy 297.718797 -301.948082) (xy 297.742393 -301.901772) (xy 297.772943 -301.859724) (xy 297.809694 -301.822973)
			(xy 297.851742 -301.792423) (xy 297.898052 -301.768827) (xy 297.947482 -301.752766) (xy 297.998817 -301.744636)
			(xy 298.050791 -301.744636) (xy 298.102126 -301.752766) (xy 298.151556 -301.768827) (xy 298.197866 -301.792423)
			(xy 298.239914 -301.822973) (xy 298.276665 -301.859724) (xy 298.307215 -301.901772) (xy 298.330811 -301.948082)
			(xy 298.346872 -301.997512) (xy 298.355002 -302.048847) (xy 298.355512 -302.074834) (xy 298.355002 -302.100821)
			(xy 298.644566 -302.100821) (xy 298.644566 -302.048847) (xy 298.652696 -301.997512) (xy 298.668757 -301.948082)
			(xy 298.692353 -301.901772) (xy 298.722903 -301.859724) (xy 298.759654 -301.822973) (xy 298.801702 -301.792423)
			(xy 298.848012 -301.768827) (xy 298.897442 -301.752766) (xy 298.948777 -301.744636) (xy 299.000751 -301.744636)
			(xy 299.052086 -301.752766) (xy 299.101516 -301.768827) (xy 299.147826 -301.792423) (xy 299.189874 -301.822973)
			(xy 299.226625 -301.859724) (xy 299.257175 -301.901772) (xy 299.280771 -301.948082) (xy 299.296832 -301.997512)
			(xy 299.304962 -302.048847) (xy 299.305472 -302.074834) (xy 299.304962 -302.100821) (xy 299.594526 -302.100821)
			(xy 299.594526 -302.048847) (xy 299.602656 -301.997512) (xy 299.618717 -301.948082) (xy 299.642313 -301.901772)
			(xy 299.672863 -301.859724) (xy 299.709614 -301.822973) (xy 299.751662 -301.792423) (xy 299.797972 -301.768827)
			(xy 299.847402 -301.752766) (xy 299.898737 -301.744636) (xy 299.950711 -301.744636) (xy 300.002046 -301.752766)
			(xy 300.051476 -301.768827) (xy 300.097786 -301.792423) (xy 300.139834 -301.822973) (xy 300.176585 -301.859724)
			(xy 300.207135 -301.901772) (xy 300.230731 -301.948082) (xy 300.246792 -301.997512) (xy 300.254922 -302.048847)
			(xy 300.255432 -302.074834) (xy 300.254922 -302.100821) (xy 300.544486 -302.100821) (xy 300.544486 -302.048847)
			(xy 300.552616 -301.997512) (xy 300.568677 -301.948082) (xy 300.592273 -301.901772) (xy 300.622823 -301.859724)
			(xy 300.659574 -301.822973) (xy 300.701622 -301.792423) (xy 300.747932 -301.768827) (xy 300.797362 -301.752766)
			(xy 300.848697 -301.744636) (xy 300.900671 -301.744636) (xy 300.952006 -301.752766) (xy 301.001436 -301.768827)
			(xy 301.047746 -301.792423) (xy 301.089794 -301.822973) (xy 301.126545 -301.859724) (xy 301.157095 -301.901772)
			(xy 301.180691 -301.948082) (xy 301.196752 -301.997512) (xy 301.204882 -302.048847) (xy 301.205392 -302.074834)
			(xy 301.204882 -302.100821) (xy 301.196752 -302.152156) (xy 301.180691 -302.201586) (xy 301.157095 -302.247896)
			(xy 301.126545 -302.289944) (xy 301.089794 -302.326695) (xy 301.047746 -302.357245) (xy 301.001436 -302.380841)
			(xy 300.952006 -302.396902) (xy 300.900671 -302.405032) (xy 300.848697 -302.405032) (xy 300.797362 -302.396902)
			(xy 300.747932 -302.380841) (xy 300.701622 -302.357245) (xy 300.659574 -302.326695) (xy 300.622823 -302.289944)
			(xy 300.592273 -302.247896) (xy 300.568677 -302.201586) (xy 300.552616 -302.152156) (xy 300.544486 -302.100821)
			(xy 300.254922 -302.100821) (xy 300.246792 -302.152156) (xy 300.230731 -302.201586) (xy 300.207135 -302.247896)
			(xy 300.176585 -302.289944) (xy 300.139834 -302.326695) (xy 300.097786 -302.357245) (xy 300.051476 -302.380841)
			(xy 300.002046 -302.396902) (xy 299.950711 -302.405032) (xy 299.898737 -302.405032) (xy 299.847402 -302.396902)
			(xy 299.797972 -302.380841) (xy 299.751662 -302.357245) (xy 299.709614 -302.326695) (xy 299.672863 -302.289944)
			(xy 299.642313 -302.247896) (xy 299.618717 -302.201586) (xy 299.602656 -302.152156) (xy 299.594526 -302.100821)
			(xy 299.304962 -302.100821) (xy 299.296832 -302.152156) (xy 299.280771 -302.201586) (xy 299.257175 -302.247896)
			(xy 299.226625 -302.289944) (xy 299.189874 -302.326695) (xy 299.147826 -302.357245) (xy 299.101516 -302.380841)
			(xy 299.052086 -302.396902) (xy 299.000751 -302.405032) (xy 298.948777 -302.405032) (xy 298.897442 -302.396902)
			(xy 298.848012 -302.380841) (xy 298.801702 -302.357245) (xy 298.759654 -302.326695) (xy 298.722903 -302.289944)
			(xy 298.692353 -302.247896) (xy 298.668757 -302.201586) (xy 298.652696 -302.152156) (xy 298.644566 -302.100821)
			(xy 298.355002 -302.100821) (xy 298.346872 -302.152156) (xy 298.330811 -302.201586) (xy 298.307215 -302.247896)
			(xy 298.276665 -302.289944) (xy 298.239914 -302.326695) (xy 298.197866 -302.357245) (xy 298.151556 -302.380841)
			(xy 298.102126 -302.396902) (xy 298.050791 -302.405032) (xy 297.998817 -302.405032) (xy 297.947482 -302.396902)
			(xy 297.898052 -302.380841) (xy 297.851742 -302.357245) (xy 297.809694 -302.326695) (xy 297.772943 -302.289944)
			(xy 297.742393 -302.247896) (xy 297.718797 -302.201586) (xy 297.702736 -302.152156) (xy 297.694606 -302.100821)
			(xy 297.405042 -302.100821) (xy 297.396912 -302.152156) (xy 297.380851 -302.201586) (xy 297.357255 -302.247896)
			(xy 297.326705 -302.289944) (xy 297.289954 -302.326695) (xy 297.247906 -302.357245) (xy 297.201596 -302.380841)
			(xy 297.152166 -302.396902) (xy 297.100831 -302.405032) (xy 297.048857 -302.405032) (xy 296.997522 -302.396902)
			(xy 296.948092 -302.380841) (xy 296.901782 -302.357245) (xy 296.859734 -302.326695) (xy 296.822983 -302.289944)
			(xy 296.792433 -302.247896) (xy 296.768837 -302.201586) (xy 296.752776 -302.152156) (xy 296.744646 -302.100821)
			(xy 296.455082 -302.100821) (xy 296.446952 -302.152156) (xy 296.430891 -302.201586) (xy 296.407295 -302.247896)
			(xy 296.376745 -302.289944) (xy 296.339994 -302.326695) (xy 296.297946 -302.357245) (xy 296.251636 -302.380841)
			(xy 296.202206 -302.396902) (xy 296.150871 -302.405032) (xy 296.098897 -302.405032) (xy 296.047562 -302.396902)
			(xy 295.998132 -302.380841) (xy 295.951822 -302.357245) (xy 295.909774 -302.326695) (xy 295.873023 -302.289944)
			(xy 295.842473 -302.247896) (xy 295.818877 -302.201586) (xy 295.802816 -302.152156) (xy 295.794686 -302.100821)
			(xy 295.505122 -302.100821) (xy 295.496992 -302.152156) (xy 295.480931 -302.201586) (xy 295.457335 -302.247896)
			(xy 295.426785 -302.289944) (xy 295.390034 -302.326695) (xy 295.347986 -302.357245) (xy 295.301676 -302.380841)
			(xy 295.252246 -302.396902) (xy 295.200911 -302.405032) (xy 295.148937 -302.405032) (xy 295.097602 -302.396902)
			(xy 295.048172 -302.380841) (xy 295.001862 -302.357245) (xy 294.959814 -302.326695) (xy 294.923063 -302.289944)
			(xy 294.892513 -302.247896) (xy 294.868917 -302.201586) (xy 294.852856 -302.152156) (xy 294.844726 -302.100821)
			(xy 294.554908 -302.100821) (xy 294.546778 -302.152156) (xy 294.530717 -302.201586) (xy 294.507121 -302.247896)
			(xy 294.476571 -302.289944) (xy 294.43982 -302.326695) (xy 294.397772 -302.357245) (xy 294.351462 -302.380841)
			(xy 294.302032 -302.396902) (xy 294.250697 -302.405032) (xy 294.198723 -302.405032) (xy 294.147388 -302.396902)
			(xy 294.097958 -302.380841) (xy 294.051648 -302.357245) (xy 294.0096 -302.326695) (xy 293.972849 -302.289944)
			(xy 293.942299 -302.247896) (xy 293.918703 -302.201586) (xy 293.902642 -302.152156) (xy 293.894512 -302.100821)
			(xy 293.604948 -302.100821) (xy 293.596818 -302.152156) (xy 293.580757 -302.201586) (xy 293.557161 -302.247896)
			(xy 293.526611 -302.289944) (xy 293.48986 -302.326695) (xy 293.447812 -302.357245) (xy 293.401502 -302.380841)
			(xy 293.352072 -302.396902) (xy 293.300737 -302.405032) (xy 293.248763 -302.405032) (xy 293.197428 -302.396902)
			(xy 293.147998 -302.380841) (xy 293.101688 -302.357245) (xy 293.05964 -302.326695) (xy 293.022889 -302.289944)
			(xy 292.992339 -302.247896) (xy 292.968743 -302.201586) (xy 292.952682 -302.152156) (xy 292.944552 -302.100821)
			(xy 292.654988 -302.100821) (xy 292.646858 -302.152156) (xy 292.630797 -302.201586) (xy 292.607201 -302.247896)
			(xy 292.576651 -302.289944) (xy 292.5399 -302.326695) (xy 292.497852 -302.357245) (xy 292.451542 -302.380841)
			(xy 292.402112 -302.396902) (xy 292.350777 -302.405032) (xy 292.298803 -302.405032) (xy 292.247468 -302.396902)
			(xy 292.198038 -302.380841) (xy 292.151728 -302.357245) (xy 292.10968 -302.326695) (xy 292.072929 -302.289944)
			(xy 292.042379 -302.247896) (xy 292.018783 -302.201586) (xy 292.002722 -302.152156) (xy 291.994592 -302.100821)
			(xy 290.755068 -302.100821) (xy 290.746938 -302.152156) (xy 290.730877 -302.201586) (xy 290.707281 -302.247896)
			(xy 290.676731 -302.289944) (xy 290.63998 -302.326695) (xy 290.597932 -302.357245) (xy 290.551622 -302.380841)
			(xy 290.502192 -302.396902) (xy 290.450857 -302.405032) (xy 290.398883 -302.405032) (xy 290.347548 -302.396902)
			(xy 290.298118 -302.380841) (xy 290.251808 -302.357245) (xy 290.20976 -302.326695) (xy 290.173009 -302.289944)
			(xy 290.142459 -302.247896) (xy 290.118863 -302.201586) (xy 290.102802 -302.152156) (xy 290.094672 -302.100821)
			(xy 289.805108 -302.100821) (xy 289.796978 -302.152156) (xy 289.780917 -302.201586) (xy 289.757321 -302.247896)
			(xy 289.726771 -302.289944) (xy 289.69002 -302.326695) (xy 289.647972 -302.357245) (xy 289.601662 -302.380841)
			(xy 289.552232 -302.396902) (xy 289.500897 -302.405032) (xy 289.448923 -302.405032) (xy 289.397588 -302.396902)
			(xy 289.348158 -302.380841) (xy 289.301848 -302.357245) (xy 289.2598 -302.326695) (xy 289.223049 -302.289944)
			(xy 289.192499 -302.247896) (xy 289.168903 -302.201586) (xy 289.152842 -302.152156) (xy 289.144712 -302.100821)
			(xy 288.854894 -302.100821) (xy 288.846764 -302.152156) (xy 288.830703 -302.201586) (xy 288.807107 -302.247896)
			(xy 288.776557 -302.289944) (xy 288.739806 -302.326695) (xy 288.697758 -302.357245) (xy 288.651448 -302.380841)
			(xy 288.602018 -302.396902) (xy 288.550683 -302.405032) (xy 288.498709 -302.405032) (xy 288.447374 -302.396902)
			(xy 288.397944 -302.380841) (xy 288.351634 -302.357245) (xy 288.309586 -302.326695) (xy 288.272835 -302.289944)
			(xy 288.242285 -302.247896) (xy 288.218689 -302.201586) (xy 288.202628 -302.152156) (xy 288.194498 -302.100821)
			(xy 287.904934 -302.100821) (xy 287.896804 -302.152156) (xy 287.880743 -302.201586) (xy 287.857147 -302.247896)
			(xy 287.826597 -302.289944) (xy 287.789846 -302.326695) (xy 287.747798 -302.357245) (xy 287.701488 -302.380841)
			(xy 287.652058 -302.396902) (xy 287.600723 -302.405032) (xy 287.548749 -302.405032) (xy 287.497414 -302.396902)
			(xy 287.447984 -302.380841) (xy 287.401674 -302.357245) (xy 287.359626 -302.326695) (xy 287.322875 -302.289944)
			(xy 287.292325 -302.247896) (xy 287.268729 -302.201586) (xy 287.252668 -302.152156) (xy 287.244538 -302.100821)
			(xy 286.954974 -302.100821) (xy 286.946844 -302.152156) (xy 286.930783 -302.201586) (xy 286.907187 -302.247896)
			(xy 286.876637 -302.289944) (xy 286.839886 -302.326695) (xy 286.797838 -302.357245) (xy 286.751528 -302.380841)
			(xy 286.702098 -302.396902) (xy 286.650763 -302.405032) (xy 286.598789 -302.405032) (xy 286.547454 -302.396902)
			(xy 286.498024 -302.380841) (xy 286.451714 -302.357245) (xy 286.409666 -302.326695) (xy 286.372915 -302.289944)
			(xy 286.342365 -302.247896) (xy 286.318769 -302.201586) (xy 286.302708 -302.152156) (xy 286.294578 -302.100821)
			(xy 286.005014 -302.100821) (xy 285.996884 -302.152156) (xy 285.980823 -302.201586) (xy 285.957227 -302.247896)
			(xy 285.926677 -302.289944) (xy 285.889926 -302.326695) (xy 285.847878 -302.357245) (xy 285.801568 -302.380841)
			(xy 285.752138 -302.396902) (xy 285.700803 -302.405032) (xy 285.648829 -302.405032) (xy 285.597494 -302.396902)
			(xy 285.548064 -302.380841) (xy 285.501754 -302.357245) (xy 285.459706 -302.326695) (xy 285.422955 -302.289944)
			(xy 285.392405 -302.247896) (xy 285.368809 -302.201586) (xy 285.352748 -302.152156) (xy 285.344618 -302.100821)
			(xy 285.055054 -302.100821) (xy 285.046924 -302.152156) (xy 285.030863 -302.201586) (xy 285.007267 -302.247896)
			(xy 284.976717 -302.289944) (xy 284.939966 -302.326695) (xy 284.897918 -302.357245) (xy 284.851608 -302.380841)
			(xy 284.802178 -302.396902) (xy 284.750843 -302.405032) (xy 284.698869 -302.405032) (xy 284.647534 -302.396902)
			(xy 284.598104 -302.380841) (xy 284.551794 -302.357245) (xy 284.509746 -302.326695) (xy 284.472995 -302.289944)
			(xy 284.442445 -302.247896) (xy 284.418849 -302.201586) (xy 284.402788 -302.152156) (xy 284.394658 -302.100821)
			(xy 284.105094 -302.100821) (xy 284.096964 -302.152156) (xy 284.080903 -302.201586) (xy 284.057307 -302.247896)
			(xy 284.026757 -302.289944) (xy 283.990006 -302.326695) (xy 283.947958 -302.357245) (xy 283.901648 -302.380841)
			(xy 283.852218 -302.396902) (xy 283.800883 -302.405032) (xy 283.748909 -302.405032) (xy 283.697574 -302.396902)
			(xy 283.648144 -302.380841) (xy 283.601834 -302.357245) (xy 283.559786 -302.326695) (xy 283.523035 -302.289944)
			(xy 283.492485 -302.247896) (xy 283.468889 -302.201586) (xy 283.452828 -302.152156) (xy 283.444698 -302.100821)
			(xy 283.155134 -302.100821) (xy 283.147004 -302.152156) (xy 283.130943 -302.201586) (xy 283.107347 -302.247896)
			(xy 283.076797 -302.289944) (xy 283.040046 -302.326695) (xy 282.997998 -302.357245) (xy 282.951688 -302.380841)
			(xy 282.902258 -302.396902) (xy 282.850923 -302.405032) (xy 282.798949 -302.405032) (xy 282.747614 -302.396902)
			(xy 282.698184 -302.380841) (xy 282.651874 -302.357245) (xy 282.609826 -302.326695) (xy 282.573075 -302.289944)
			(xy 282.542525 -302.247896) (xy 282.518929 -302.201586) (xy 282.502868 -302.152156) (xy 282.494738 -302.100821)
			(xy 282.20492 -302.100821) (xy 282.19679 -302.152156) (xy 282.180729 -302.201586) (xy 282.157133 -302.247896)
			(xy 282.126583 -302.289944) (xy 282.089832 -302.326695) (xy 282.047784 -302.357245) (xy 282.001474 -302.380841)
			(xy 281.952044 -302.396902) (xy 281.900709 -302.405032) (xy 281.848735 -302.405032) (xy 281.7974 -302.396902)
			(xy 281.74797 -302.380841) (xy 281.70166 -302.357245) (xy 281.659612 -302.326695) (xy 281.622861 -302.289944)
			(xy 281.592311 -302.247896) (xy 281.568715 -302.201586) (xy 281.552654 -302.152156) (xy 281.544524 -302.100821)
			(xy 278.417609 -302.100821) (xy 278.420322 -302.10379) (xy 278.65705 -302.340518) (xy 278.657558 -302.341026)
			(xy 278.664938 -302.34761) (xy 278.683238 -302.355063) (xy 278.693118 -302.355504) (xy 281.272488 -302.355504)
			(xy 281.282559 -302.355925) (xy 281.301166 -302.363637) (xy 281.308556 -302.37049) (xy 281.591258 -302.653192)
			(xy 281.59811 -302.660588) (xy 281.605854 -302.679186) (xy 281.606244 -302.68926) (xy 281.606244 -302.695102)
			(xy 281.620976 -302.719232) (xy 281.660092 -302.739552) (xy 281.667818 -302.743245) (xy 281.684744 -302.745766)
			(xy 281.701553 -302.742555) (xy 281.709114 -302.738536) (xy 281.734455 -302.724567) (xy 281.788814 -302.70475)
			(xy 281.845792 -302.69469) (xy 281.874722 -302.694086) (xy 281.900709 -302.694597) (xy 281.952041 -302.702731)
			(xy 282.00147 -302.718794) (xy 282.047777 -302.742391) (xy 282.089823 -302.772942) (xy 282.126572 -302.809694)
			(xy 282.15712 -302.851742) (xy 282.180715 -302.898051) (xy 282.196774 -302.94748) (xy 282.204905 -302.998813)
			(xy 282.204905 -303.050781) (xy 282.494738 -303.050781) (xy 282.494738 -302.998807) (xy 282.502868 -302.947472)
			(xy 282.518929 -302.898042) (xy 282.542525 -302.851732) (xy 282.573075 -302.809684) (xy 282.609826 -302.772933)
			(xy 282.651874 -302.742383) (xy 282.698184 -302.718787) (xy 282.747614 -302.702726) (xy 282.798949 -302.694596)
			(xy 282.850923 -302.694596) (xy 282.902258 -302.702726) (xy 282.951688 -302.718787) (xy 282.997998 -302.742383)
			(xy 283.040046 -302.772933) (xy 283.076797 -302.809684) (xy 283.107347 -302.851732) (xy 283.130943 -302.898042)
			(xy 283.147004 -302.947472) (xy 283.155134 -302.998807) (xy 283.155644 -303.024794) (xy 283.155134 -303.050781)
			(xy 283.444698 -303.050781) (xy 283.444698 -302.998807) (xy 283.452828 -302.947472) (xy 283.468889 -302.898042)
			(xy 283.492485 -302.851732) (xy 283.523035 -302.809684) (xy 283.559786 -302.772933) (xy 283.601834 -302.742383)
			(xy 283.648144 -302.718787) (xy 283.697574 -302.702726) (xy 283.748909 -302.694596) (xy 283.800883 -302.694596)
			(xy 283.852218 -302.702726) (xy 283.901648 -302.718787) (xy 283.947958 -302.742383) (xy 283.990006 -302.772933)
			(xy 284.026757 -302.809684) (xy 284.057307 -302.851732) (xy 284.080903 -302.898042) (xy 284.096964 -302.947472)
			(xy 284.105094 -302.998807) (xy 284.105604 -303.024794) (xy 284.105094 -303.050781) (xy 284.394658 -303.050781)
			(xy 284.394658 -302.998807) (xy 284.402788 -302.947472) (xy 284.418849 -302.898042) (xy 284.442445 -302.851732)
			(xy 284.472995 -302.809684) (xy 284.509746 -302.772933) (xy 284.551794 -302.742383) (xy 284.598104 -302.718787)
			(xy 284.647534 -302.702726) (xy 284.698869 -302.694596) (xy 284.750843 -302.694596) (xy 284.802178 -302.702726)
			(xy 284.851608 -302.718787) (xy 284.897918 -302.742383) (xy 284.939966 -302.772933) (xy 284.976717 -302.809684)
			(xy 285.007267 -302.851732) (xy 285.030863 -302.898042) (xy 285.046924 -302.947472) (xy 285.055054 -302.998807)
			(xy 285.055564 -303.024794) (xy 285.055054 -303.050781) (xy 285.344618 -303.050781) (xy 285.344618 -302.998807)
			(xy 285.352748 -302.947472) (xy 285.368809 -302.898042) (xy 285.392405 -302.851732) (xy 285.422955 -302.809684)
			(xy 285.459706 -302.772933) (xy 285.501754 -302.742383) (xy 285.548064 -302.718787) (xy 285.597494 -302.702726)
			(xy 285.648829 -302.694596) (xy 285.700803 -302.694596) (xy 285.752138 -302.702726) (xy 285.801568 -302.718787)
			(xy 285.847878 -302.742383) (xy 285.889926 -302.772933) (xy 285.926677 -302.809684) (xy 285.957227 -302.851732)
			(xy 285.980823 -302.898042) (xy 285.996884 -302.947472) (xy 286.005014 -302.998807) (xy 286.005524 -303.024794)
			(xy 286.005014 -303.050781) (xy 286.294578 -303.050781) (xy 286.294578 -302.998807) (xy 286.302708 -302.947472)
			(xy 286.318769 -302.898042) (xy 286.342365 -302.851732) (xy 286.372915 -302.809684) (xy 286.409666 -302.772933)
			(xy 286.451714 -302.742383) (xy 286.498024 -302.718787) (xy 286.547454 -302.702726) (xy 286.598789 -302.694596)
			(xy 286.650763 -302.694596) (xy 286.702098 -302.702726) (xy 286.751528 -302.718787) (xy 286.797838 -302.742383)
			(xy 286.839886 -302.772933) (xy 286.876637 -302.809684) (xy 286.907187 -302.851732) (xy 286.930783 -302.898042)
			(xy 286.946844 -302.947472) (xy 286.954974 -302.998807) (xy 286.955484 -303.024794) (xy 286.954974 -303.050781)
			(xy 287.244538 -303.050781) (xy 287.244538 -302.998807) (xy 287.252668 -302.947472) (xy 287.268729 -302.898042)
			(xy 287.292325 -302.851732) (xy 287.322875 -302.809684) (xy 287.359626 -302.772933) (xy 287.401674 -302.742383)
			(xy 287.447984 -302.718787) (xy 287.497414 -302.702726) (xy 287.548749 -302.694596) (xy 287.600723 -302.694596)
			(xy 287.652058 -302.702726) (xy 287.701488 -302.718787) (xy 287.747798 -302.742383) (xy 287.789846 -302.772933)
			(xy 287.826597 -302.809684) (xy 287.857147 -302.851732) (xy 287.880743 -302.898042) (xy 287.896804 -302.947472)
			(xy 287.904934 -302.998807) (xy 287.905444 -303.024794) (xy 287.904934 -303.050781) (xy 288.194498 -303.050781)
			(xy 288.194498 -302.998807) (xy 288.202628 -302.947472) (xy 288.218689 -302.898042) (xy 288.242285 -302.851732)
			(xy 288.272835 -302.809684) (xy 288.309586 -302.772933) (xy 288.351634 -302.742383) (xy 288.397944 -302.718787)
			(xy 288.447374 -302.702726) (xy 288.498709 -302.694596) (xy 288.550683 -302.694596) (xy 288.602018 -302.702726)
			(xy 288.651448 -302.718787) (xy 288.697758 -302.742383) (xy 288.739806 -302.772933) (xy 288.776557 -302.809684)
			(xy 288.807107 -302.851732) (xy 288.830703 -302.898042) (xy 288.846764 -302.947472) (xy 288.854894 -302.998807)
			(xy 288.855404 -303.024794) (xy 288.854894 -303.050781) (xy 289.144712 -303.050781) (xy 289.144712 -302.998807)
			(xy 289.152842 -302.947472) (xy 289.168903 -302.898042) (xy 289.192499 -302.851732) (xy 289.223049 -302.809684)
			(xy 289.2598 -302.772933) (xy 289.301848 -302.742383) (xy 289.348158 -302.718787) (xy 289.397588 -302.702726)
			(xy 289.448923 -302.694596) (xy 289.500897 -302.694596) (xy 289.552232 -302.702726) (xy 289.601662 -302.718787)
			(xy 289.647972 -302.742383) (xy 289.69002 -302.772933) (xy 289.726771 -302.809684) (xy 289.757321 -302.851732)
			(xy 289.780917 -302.898042) (xy 289.796978 -302.947472) (xy 289.805108 -302.998807) (xy 289.805618 -303.024794)
			(xy 289.805108 -303.050781) (xy 290.094672 -303.050781) (xy 290.094672 -302.998807) (xy 290.102802 -302.947472)
			(xy 290.118863 -302.898042) (xy 290.142459 -302.851732) (xy 290.173009 -302.809684) (xy 290.20976 -302.772933)
			(xy 290.251808 -302.742383) (xy 290.298118 -302.718787) (xy 290.347548 -302.702726) (xy 290.398883 -302.694596)
			(xy 290.450857 -302.694596) (xy 290.502192 -302.702726) (xy 290.551622 -302.718787) (xy 290.597932 -302.742383)
			(xy 290.63998 -302.772933) (xy 290.676731 -302.809684) (xy 290.707281 -302.851732) (xy 290.730877 -302.898042)
			(xy 290.746938 -302.947472) (xy 290.755068 -302.998807) (xy 290.755578 -303.024794) (xy 290.755068 -303.050781)
			(xy 291.994592 -303.050781) (xy 291.994592 -302.998807) (xy 292.002722 -302.947472) (xy 292.018783 -302.898042)
			(xy 292.042379 -302.851732) (xy 292.072929 -302.809684) (xy 292.10968 -302.772933) (xy 292.151728 -302.742383)
			(xy 292.198038 -302.718787) (xy 292.247468 -302.702726) (xy 292.298803 -302.694596) (xy 292.350777 -302.694596)
			(xy 292.402112 -302.702726) (xy 292.451542 -302.718787) (xy 292.497852 -302.742383) (xy 292.5399 -302.772933)
			(xy 292.576651 -302.809684) (xy 292.607201 -302.851732) (xy 292.630797 -302.898042) (xy 292.646858 -302.947472)
			(xy 292.654988 -302.998807) (xy 292.655498 -303.024794) (xy 292.654988 -303.050781) (xy 292.944552 -303.050781)
			(xy 292.944552 -302.998807) (xy 292.952682 -302.947472) (xy 292.968743 -302.898042) (xy 292.992339 -302.851732)
			(xy 293.022889 -302.809684) (xy 293.05964 -302.772933) (xy 293.101688 -302.742383) (xy 293.147998 -302.718787)
			(xy 293.197428 -302.702726) (xy 293.248763 -302.694596) (xy 293.300737 -302.694596) (xy 293.352072 -302.702726)
			(xy 293.401502 -302.718787) (xy 293.447812 -302.742383) (xy 293.48986 -302.772933) (xy 293.526611 -302.809684)
			(xy 293.557161 -302.851732) (xy 293.580757 -302.898042) (xy 293.596818 -302.947472) (xy 293.604948 -302.998807)
			(xy 293.605458 -303.024794) (xy 293.604948 -303.050781) (xy 293.894512 -303.050781) (xy 293.894512 -302.998807)
			(xy 293.902642 -302.947472) (xy 293.918703 -302.898042) (xy 293.942299 -302.851732) (xy 293.972849 -302.809684)
			(xy 294.0096 -302.772933) (xy 294.051648 -302.742383) (xy 294.097958 -302.718787) (xy 294.147388 -302.702726)
			(xy 294.198723 -302.694596) (xy 294.250697 -302.694596) (xy 294.302032 -302.702726) (xy 294.351462 -302.718787)
			(xy 294.397772 -302.742383) (xy 294.43982 -302.772933) (xy 294.476571 -302.809684) (xy 294.507121 -302.851732)
			(xy 294.530717 -302.898042) (xy 294.546778 -302.947472) (xy 294.554908 -302.998807) (xy 294.555418 -303.024794)
			(xy 294.554908 -303.050781) (xy 294.844726 -303.050781) (xy 294.844726 -302.998807) (xy 294.852856 -302.947472)
			(xy 294.868917 -302.898042) (xy 294.892513 -302.851732) (xy 294.923063 -302.809684) (xy 294.959814 -302.772933)
			(xy 295.001862 -302.742383) (xy 295.048172 -302.718787) (xy 295.097602 -302.702726) (xy 295.148937 -302.694596)
			(xy 295.200911 -302.694596) (xy 295.252246 -302.702726) (xy 295.301676 -302.718787) (xy 295.347986 -302.742383)
			(xy 295.390034 -302.772933) (xy 295.426785 -302.809684) (xy 295.457335 -302.851732) (xy 295.480931 -302.898042)
			(xy 295.496992 -302.947472) (xy 295.505122 -302.998807) (xy 295.505632 -303.024794) (xy 295.505122 -303.050781)
			(xy 295.794686 -303.050781) (xy 295.794686 -302.998807) (xy 295.802816 -302.947472) (xy 295.818877 -302.898042)
			(xy 295.842473 -302.851732) (xy 295.873023 -302.809684) (xy 295.909774 -302.772933) (xy 295.951822 -302.742383)
			(xy 295.998132 -302.718787) (xy 296.047562 -302.702726) (xy 296.098897 -302.694596) (xy 296.150871 -302.694596)
			(xy 296.202206 -302.702726) (xy 296.251636 -302.718787) (xy 296.297946 -302.742383) (xy 296.339994 -302.772933)
			(xy 296.376745 -302.809684) (xy 296.407295 -302.851732) (xy 296.430891 -302.898042) (xy 296.446952 -302.947472)
			(xy 296.455082 -302.998807) (xy 296.455592 -303.024794) (xy 296.455082 -303.050781) (xy 296.744646 -303.050781)
			(xy 296.744646 -302.998807) (xy 296.752776 -302.947472) (xy 296.768837 -302.898042) (xy 296.792433 -302.851732)
			(xy 296.822983 -302.809684) (xy 296.859734 -302.772933) (xy 296.901782 -302.742383) (xy 296.948092 -302.718787)
			(xy 296.997522 -302.702726) (xy 297.048857 -302.694596) (xy 297.100831 -302.694596) (xy 297.152166 -302.702726)
			(xy 297.201596 -302.718787) (xy 297.247906 -302.742383) (xy 297.289954 -302.772933) (xy 297.326705 -302.809684)
			(xy 297.357255 -302.851732) (xy 297.380851 -302.898042) (xy 297.396912 -302.947472) (xy 297.405042 -302.998807)
			(xy 297.405552 -303.024794) (xy 297.405042 -303.050781) (xy 297.694606 -303.050781) (xy 297.694606 -302.998807)
			(xy 297.702736 -302.947472) (xy 297.718797 -302.898042) (xy 297.742393 -302.851732) (xy 297.772943 -302.809684)
			(xy 297.809694 -302.772933) (xy 297.851742 -302.742383) (xy 297.898052 -302.718787) (xy 297.947482 -302.702726)
			(xy 297.998817 -302.694596) (xy 298.050791 -302.694596) (xy 298.102126 -302.702726) (xy 298.151556 -302.718787)
			(xy 298.197866 -302.742383) (xy 298.239914 -302.772933) (xy 298.276665 -302.809684) (xy 298.307215 -302.851732)
			(xy 298.330811 -302.898042) (xy 298.346872 -302.947472) (xy 298.355002 -302.998807) (xy 298.355512 -303.024794)
			(xy 298.355002 -303.050781) (xy 298.644566 -303.050781) (xy 298.644566 -302.998807) (xy 298.652696 -302.947472)
			(xy 298.668757 -302.898042) (xy 298.692353 -302.851732) (xy 298.722903 -302.809684) (xy 298.759654 -302.772933)
			(xy 298.801702 -302.742383) (xy 298.848012 -302.718787) (xy 298.897442 -302.702726) (xy 298.948777 -302.694596)
			(xy 299.000751 -302.694596) (xy 299.052086 -302.702726) (xy 299.101516 -302.718787) (xy 299.147826 -302.742383)
			(xy 299.189874 -302.772933) (xy 299.226625 -302.809684) (xy 299.257175 -302.851732) (xy 299.280771 -302.898042)
			(xy 299.296832 -302.947472) (xy 299.304962 -302.998807) (xy 299.305472 -303.024794) (xy 299.304962 -303.050781)
			(xy 299.594526 -303.050781) (xy 299.594526 -302.998807) (xy 299.602656 -302.947472) (xy 299.618717 -302.898042)
			(xy 299.642313 -302.851732) (xy 299.672863 -302.809684) (xy 299.709614 -302.772933) (xy 299.751662 -302.742383)
			(xy 299.797972 -302.718787) (xy 299.847402 -302.702726) (xy 299.898737 -302.694596) (xy 299.950711 -302.694596)
			(xy 300.002046 -302.702726) (xy 300.051476 -302.718787) (xy 300.097786 -302.742383) (xy 300.139834 -302.772933)
			(xy 300.176585 -302.809684) (xy 300.207135 -302.851732) (xy 300.230731 -302.898042) (xy 300.246792 -302.947472)
			(xy 300.254922 -302.998807) (xy 300.255432 -303.024794) (xy 300.254922 -303.050781) (xy 300.544486 -303.050781)
			(xy 300.544486 -302.998807) (xy 300.552616 -302.947472) (xy 300.568677 -302.898042) (xy 300.592273 -302.851732)
			(xy 300.622823 -302.809684) (xy 300.659574 -302.772933) (xy 300.701622 -302.742383) (xy 300.747932 -302.718787)
			(xy 300.797362 -302.702726) (xy 300.848697 -302.694596) (xy 300.900671 -302.694596) (xy 300.952006 -302.702726)
			(xy 301.001436 -302.718787) (xy 301.047746 -302.742383) (xy 301.089794 -302.772933) (xy 301.126545 -302.809684)
			(xy 301.157095 -302.851732) (xy 301.180691 -302.898042) (xy 301.196752 -302.947472) (xy 301.204882 -302.998807)
			(xy 301.205392 -303.024794) (xy 301.204882 -303.050781) (xy 301.196752 -303.102116) (xy 301.180691 -303.151546)
			(xy 301.157095 -303.197856) (xy 301.126545 -303.239904) (xy 301.089794 -303.276655) (xy 301.047746 -303.307205)
			(xy 301.001436 -303.330801) (xy 300.952006 -303.346862) (xy 300.900671 -303.354992) (xy 300.848697 -303.354992)
			(xy 300.797362 -303.346862) (xy 300.747932 -303.330801) (xy 300.701622 -303.307205) (xy 300.659574 -303.276655)
			(xy 300.622823 -303.239904) (xy 300.592273 -303.197856) (xy 300.568677 -303.151546) (xy 300.552616 -303.102116)
			(xy 300.544486 -303.050781) (xy 300.254922 -303.050781) (xy 300.246792 -303.102116) (xy 300.230731 -303.151546)
			(xy 300.207135 -303.197856) (xy 300.176585 -303.239904) (xy 300.139834 -303.276655) (xy 300.097786 -303.307205)
			(xy 300.051476 -303.330801) (xy 300.002046 -303.346862) (xy 299.950711 -303.354992) (xy 299.898737 -303.354992)
			(xy 299.847402 -303.346862) (xy 299.797972 -303.330801) (xy 299.751662 -303.307205) (xy 299.709614 -303.276655)
			(xy 299.672863 -303.239904) (xy 299.642313 -303.197856) (xy 299.618717 -303.151546) (xy 299.602656 -303.102116)
			(xy 299.594526 -303.050781) (xy 299.304962 -303.050781) (xy 299.296832 -303.102116) (xy 299.280771 -303.151546)
			(xy 299.257175 -303.197856) (xy 299.226625 -303.239904) (xy 299.189874 -303.276655) (xy 299.147826 -303.307205)
			(xy 299.101516 -303.330801) (xy 299.052086 -303.346862) (xy 299.000751 -303.354992) (xy 298.948777 -303.354992)
			(xy 298.897442 -303.346862) (xy 298.848012 -303.330801) (xy 298.801702 -303.307205) (xy 298.759654 -303.276655)
			(xy 298.722903 -303.239904) (xy 298.692353 -303.197856) (xy 298.668757 -303.151546) (xy 298.652696 -303.102116)
			(xy 298.644566 -303.050781) (xy 298.355002 -303.050781) (xy 298.346872 -303.102116) (xy 298.330811 -303.151546)
			(xy 298.307215 -303.197856) (xy 298.276665 -303.239904) (xy 298.239914 -303.276655) (xy 298.197866 -303.307205)
			(xy 298.151556 -303.330801) (xy 298.102126 -303.346862) (xy 298.050791 -303.354992) (xy 297.998817 -303.354992)
			(xy 297.947482 -303.346862) (xy 297.898052 -303.330801) (xy 297.851742 -303.307205) (xy 297.809694 -303.276655)
			(xy 297.772943 -303.239904) (xy 297.742393 -303.197856) (xy 297.718797 -303.151546) (xy 297.702736 -303.102116)
			(xy 297.694606 -303.050781) (xy 297.405042 -303.050781) (xy 297.396912 -303.102116) (xy 297.380851 -303.151546)
			(xy 297.357255 -303.197856) (xy 297.326705 -303.239904) (xy 297.289954 -303.276655) (xy 297.247906 -303.307205)
			(xy 297.201596 -303.330801) (xy 297.152166 -303.346862) (xy 297.100831 -303.354992) (xy 297.048857 -303.354992)
			(xy 296.997522 -303.346862) (xy 296.948092 -303.330801) (xy 296.901782 -303.307205) (xy 296.859734 -303.276655)
			(xy 296.822983 -303.239904) (xy 296.792433 -303.197856) (xy 296.768837 -303.151546) (xy 296.752776 -303.102116)
			(xy 296.744646 -303.050781) (xy 296.455082 -303.050781) (xy 296.446952 -303.102116) (xy 296.430891 -303.151546)
			(xy 296.407295 -303.197856) (xy 296.376745 -303.239904) (xy 296.339994 -303.276655) (xy 296.297946 -303.307205)
			(xy 296.251636 -303.330801) (xy 296.202206 -303.346862) (xy 296.150871 -303.354992) (xy 296.098897 -303.354992)
			(xy 296.047562 -303.346862) (xy 295.998132 -303.330801) (xy 295.951822 -303.307205) (xy 295.909774 -303.276655)
			(xy 295.873023 -303.239904) (xy 295.842473 -303.197856) (xy 295.818877 -303.151546) (xy 295.802816 -303.102116)
			(xy 295.794686 -303.050781) (xy 295.505122 -303.050781) (xy 295.496992 -303.102116) (xy 295.480931 -303.151546)
			(xy 295.457335 -303.197856) (xy 295.426785 -303.239904) (xy 295.390034 -303.276655) (xy 295.347986 -303.307205)
			(xy 295.301676 -303.330801) (xy 295.252246 -303.346862) (xy 295.200911 -303.354992) (xy 295.148937 -303.354992)
			(xy 295.097602 -303.346862) (xy 295.048172 -303.330801) (xy 295.001862 -303.307205) (xy 294.959814 -303.276655)
			(xy 294.923063 -303.239904) (xy 294.892513 -303.197856) (xy 294.868917 -303.151546) (xy 294.852856 -303.102116)
			(xy 294.844726 -303.050781) (xy 294.554908 -303.050781) (xy 294.546778 -303.102116) (xy 294.530717 -303.151546)
			(xy 294.507121 -303.197856) (xy 294.476571 -303.239904) (xy 294.43982 -303.276655) (xy 294.397772 -303.307205)
			(xy 294.351462 -303.330801) (xy 294.302032 -303.346862) (xy 294.250697 -303.354992) (xy 294.198723 -303.354992)
			(xy 294.147388 -303.346862) (xy 294.097958 -303.330801) (xy 294.051648 -303.307205) (xy 294.0096 -303.276655)
			(xy 293.972849 -303.239904) (xy 293.942299 -303.197856) (xy 293.918703 -303.151546) (xy 293.902642 -303.102116)
			(xy 293.894512 -303.050781) (xy 293.604948 -303.050781) (xy 293.596818 -303.102116) (xy 293.580757 -303.151546)
			(xy 293.557161 -303.197856) (xy 293.526611 -303.239904) (xy 293.48986 -303.276655) (xy 293.447812 -303.307205)
			(xy 293.401502 -303.330801) (xy 293.352072 -303.346862) (xy 293.300737 -303.354992) (xy 293.248763 -303.354992)
			(xy 293.197428 -303.346862) (xy 293.147998 -303.330801) (xy 293.101688 -303.307205) (xy 293.05964 -303.276655)
			(xy 293.022889 -303.239904) (xy 292.992339 -303.197856) (xy 292.968743 -303.151546) (xy 292.952682 -303.102116)
			(xy 292.944552 -303.050781) (xy 292.654988 -303.050781) (xy 292.646858 -303.102116) (xy 292.630797 -303.151546)
			(xy 292.607201 -303.197856) (xy 292.576651 -303.239904) (xy 292.5399 -303.276655) (xy 292.497852 -303.307205)
			(xy 292.451542 -303.330801) (xy 292.402112 -303.346862) (xy 292.350777 -303.354992) (xy 292.298803 -303.354992)
			(xy 292.247468 -303.346862) (xy 292.198038 -303.330801) (xy 292.151728 -303.307205) (xy 292.10968 -303.276655)
			(xy 292.072929 -303.239904) (xy 292.042379 -303.197856) (xy 292.018783 -303.151546) (xy 292.002722 -303.102116)
			(xy 291.994592 -303.050781) (xy 290.755068 -303.050781) (xy 290.746938 -303.102116) (xy 290.730877 -303.151546)
			(xy 290.707281 -303.197856) (xy 290.676731 -303.239904) (xy 290.63998 -303.276655) (xy 290.597932 -303.307205)
			(xy 290.551622 -303.330801) (xy 290.502192 -303.346862) (xy 290.450857 -303.354992) (xy 290.398883 -303.354992)
			(xy 290.347548 -303.346862) (xy 290.298118 -303.330801) (xy 290.251808 -303.307205) (xy 290.20976 -303.276655)
			(xy 290.173009 -303.239904) (xy 290.142459 -303.197856) (xy 290.118863 -303.151546) (xy 290.102802 -303.102116)
			(xy 290.094672 -303.050781) (xy 289.805108 -303.050781) (xy 289.796978 -303.102116) (xy 289.780917 -303.151546)
			(xy 289.757321 -303.197856) (xy 289.726771 -303.239904) (xy 289.69002 -303.276655) (xy 289.647972 -303.307205)
			(xy 289.601662 -303.330801) (xy 289.552232 -303.346862) (xy 289.500897 -303.354992) (xy 289.448923 -303.354992)
			(xy 289.397588 -303.346862) (xy 289.348158 -303.330801) (xy 289.301848 -303.307205) (xy 289.2598 -303.276655)
			(xy 289.223049 -303.239904) (xy 289.192499 -303.197856) (xy 289.168903 -303.151546) (xy 289.152842 -303.102116)
			(xy 289.144712 -303.050781) (xy 288.854894 -303.050781) (xy 288.846764 -303.102116) (xy 288.830703 -303.151546)
			(xy 288.807107 -303.197856) (xy 288.776557 -303.239904) (xy 288.739806 -303.276655) (xy 288.697758 -303.307205)
			(xy 288.651448 -303.330801) (xy 288.602018 -303.346862) (xy 288.550683 -303.354992) (xy 288.498709 -303.354992)
			(xy 288.447374 -303.346862) (xy 288.397944 -303.330801) (xy 288.351634 -303.307205) (xy 288.309586 -303.276655)
			(xy 288.272835 -303.239904) (xy 288.242285 -303.197856) (xy 288.218689 -303.151546) (xy 288.202628 -303.102116)
			(xy 288.194498 -303.050781) (xy 287.904934 -303.050781) (xy 287.896804 -303.102116) (xy 287.880743 -303.151546)
			(xy 287.857147 -303.197856) (xy 287.826597 -303.239904) (xy 287.789846 -303.276655) (xy 287.747798 -303.307205)
			(xy 287.701488 -303.330801) (xy 287.652058 -303.346862) (xy 287.600723 -303.354992) (xy 287.548749 -303.354992)
			(xy 287.497414 -303.346862) (xy 287.447984 -303.330801) (xy 287.401674 -303.307205) (xy 287.359626 -303.276655)
			(xy 287.322875 -303.239904) (xy 287.292325 -303.197856) (xy 287.268729 -303.151546) (xy 287.252668 -303.102116)
			(xy 287.244538 -303.050781) (xy 286.954974 -303.050781) (xy 286.946844 -303.102116) (xy 286.930783 -303.151546)
			(xy 286.907187 -303.197856) (xy 286.876637 -303.239904) (xy 286.839886 -303.276655) (xy 286.797838 -303.307205)
			(xy 286.751528 -303.330801) (xy 286.702098 -303.346862) (xy 286.650763 -303.354992) (xy 286.598789 -303.354992)
			(xy 286.547454 -303.346862) (xy 286.498024 -303.330801) (xy 286.451714 -303.307205) (xy 286.409666 -303.276655)
			(xy 286.372915 -303.239904) (xy 286.342365 -303.197856) (xy 286.318769 -303.151546) (xy 286.302708 -303.102116)
			(xy 286.294578 -303.050781) (xy 286.005014 -303.050781) (xy 285.996884 -303.102116) (xy 285.980823 -303.151546)
			(xy 285.957227 -303.197856) (xy 285.926677 -303.239904) (xy 285.889926 -303.276655) (xy 285.847878 -303.307205)
			(xy 285.801568 -303.330801) (xy 285.752138 -303.346862) (xy 285.700803 -303.354992) (xy 285.648829 -303.354992)
			(xy 285.597494 -303.346862) (xy 285.548064 -303.330801) (xy 285.501754 -303.307205) (xy 285.459706 -303.276655)
			(xy 285.422955 -303.239904) (xy 285.392405 -303.197856) (xy 285.368809 -303.151546) (xy 285.352748 -303.102116)
			(xy 285.344618 -303.050781) (xy 285.055054 -303.050781) (xy 285.046924 -303.102116) (xy 285.030863 -303.151546)
			(xy 285.007267 -303.197856) (xy 284.976717 -303.239904) (xy 284.939966 -303.276655) (xy 284.897918 -303.307205)
			(xy 284.851608 -303.330801) (xy 284.802178 -303.346862) (xy 284.750843 -303.354992) (xy 284.698869 -303.354992)
			(xy 284.647534 -303.346862) (xy 284.598104 -303.330801) (xy 284.551794 -303.307205) (xy 284.509746 -303.276655)
			(xy 284.472995 -303.239904) (xy 284.442445 -303.197856) (xy 284.418849 -303.151546) (xy 284.402788 -303.102116)
			(xy 284.394658 -303.050781) (xy 284.105094 -303.050781) (xy 284.096964 -303.102116) (xy 284.080903 -303.151546)
			(xy 284.057307 -303.197856) (xy 284.026757 -303.239904) (xy 283.990006 -303.276655) (xy 283.947958 -303.307205)
			(xy 283.901648 -303.330801) (xy 283.852218 -303.346862) (xy 283.800883 -303.354992) (xy 283.748909 -303.354992)
			(xy 283.697574 -303.346862) (xy 283.648144 -303.330801) (xy 283.601834 -303.307205) (xy 283.559786 -303.276655)
			(xy 283.523035 -303.239904) (xy 283.492485 -303.197856) (xy 283.468889 -303.151546) (xy 283.452828 -303.102116)
			(xy 283.444698 -303.050781) (xy 283.155134 -303.050781) (xy 283.147004 -303.102116) (xy 283.130943 -303.151546)
			(xy 283.107347 -303.197856) (xy 283.076797 -303.239904) (xy 283.040046 -303.276655) (xy 282.997998 -303.307205)
			(xy 282.951688 -303.330801) (xy 282.902258 -303.346862) (xy 282.850923 -303.354992) (xy 282.798949 -303.354992)
			(xy 282.747614 -303.346862) (xy 282.698184 -303.330801) (xy 282.651874 -303.307205) (xy 282.609826 -303.276655)
			(xy 282.573075 -303.239904) (xy 282.542525 -303.197856) (xy 282.518929 -303.151546) (xy 282.502868 -303.102116)
			(xy 282.494738 -303.050781) (xy 282.204905 -303.050781) (xy 282.204905 -303.050787) (xy 282.196774 -303.10212)
			(xy 282.180715 -303.151549) (xy 282.15712 -303.197858) (xy 282.126572 -303.239906) (xy 282.089823 -303.276658)
			(xy 282.047777 -303.307209) (xy 282.00147 -303.330806) (xy 281.952041 -303.346869) (xy 281.900709 -303.355003)
			(xy 281.874722 -303.355502) (xy 281.852852 -303.355151) (xy 281.809491 -303.349393) (xy 281.767268 -303.337974)
			(xy 281.74696 -303.329848) (xy 281.735022 -303.324768) (xy 281.71013 -303.327308) (xy 281.62885 -303.38141)
			(xy 281.618791 -303.388927) (xy 281.60694 -303.411035) (xy 281.606244 -303.423574) (xy 281.606244 -303.575974)
			(xy 281.606882 -303.588532) (xy 281.618735 -303.610671) (xy 281.62885 -303.618138) (xy 281.71013 -303.67224)
			(xy 281.735022 -303.67478) (xy 281.74696 -303.6697) (xy 281.767271 -303.661583) (xy 281.809493 -303.650163)
			(xy 281.852852 -303.644404) (xy 281.874722 -303.644046) (xy 281.900709 -303.644557) (xy 281.952044 -303.65269)
			(xy 282.001474 -303.668753) (xy 282.047784 -303.692349) (xy 282.089833 -303.722898) (xy 282.126586 -303.759649)
			(xy 282.157139 -303.801695) (xy 282.180738 -303.848003) (xy 282.196804 -303.897433) (xy 282.204941 -303.948767)
			(xy 282.20543 -303.974754) (xy 282.204876 -304.002372) (xy 282.195696 -304.05684) (xy 282.177585 -304.109022)
			(xy 282.16479 -304.133504) (xy 282.158186 -304.145442) (xy 282.158694 -304.172112) (xy 282.210256 -304.25898)
			(xy 282.215052 -304.266362) (xy 282.228603 -304.277578) (xy 282.245149 -304.283548) (xy 282.253944 -304.283872)
		)
		(stroke
			(width 0)
			(type solid)
		)
		(fill yes)
		(layer "In5.Cu")
		(net "P1V8_PEX")
	)
	(gr_poly
		(pts
			(xy 109.316012 -330.401168) (xy 109.326029 -330.400746) (xy 109.344537 -330.393073) (xy 109.358697 -330.3789)
			(xy 109.366354 -330.360386) (xy 109.366812 -330.350368) (xy 109.366812 -328.886566) (xy 109.367301 -328.86048)
			(xy 109.375471 -328.80895) (xy 109.391606 -328.759335) (xy 109.415308 -328.712856) (xy 109.445991 -328.670659)
			(xy 109.464094 -328.65187) (xy 109.996986 -328.118978) (xy 110.003795 -328.111632) (xy 110.011521 -328.09317)
			(xy 110.011972 -328.083164) (xy 110.011972 -326.908668) (xy 110.008924 -326.89673) (xy 110.00613 -326.891142)
			(xy 109.992299 -326.863613) (xy 109.972729 -326.805199) (xy 109.962807 -326.744398) (xy 109.962188 -326.713596)
			(xy 109.962674 -326.686345) (xy 109.97043 -326.632397) (xy 109.985785 -326.580102) (xy 110.008427 -326.530525)
			(xy 110.037893 -326.484675) (xy 110.073584 -326.443484) (xy 110.114775 -326.407793) (xy 110.160625 -326.378327)
			(xy 110.210202 -326.355685) (xy 110.262497 -326.34033) (xy 110.316445 -326.332574) (xy 110.370947 -326.332574)
			(xy 110.424895 -326.34033) (xy 110.47719 -326.355685) (xy 110.526767 -326.378327) (xy 110.572617 -326.407793)
			(xy 110.613808 -326.443484) (xy 110.649499 -326.484675) (xy 110.678965 -326.530525) (xy 110.701607 -326.580102)
			(xy 110.716962 -326.632397) (xy 110.724718 -326.686345) (xy 110.725204 -326.713596) (xy 110.724653 -326.744431)
			(xy 110.714817 -326.805311) (xy 110.695319 -326.863817) (xy 110.681516 -326.891396) (xy 110.678468 -326.896984)
			(xy 110.67542 -326.908922) (xy 110.67542 -327.456292) (xy 111.608106 -327.456292) (xy 111.612177 -327.40067)
			(xy 111.624303 -327.346233) (xy 111.644226 -327.294142) (xy 111.671522 -327.245507) (xy 111.705608 -327.201364)
			(xy 111.745757 -327.162655) (xy 111.791115 -327.130204) (xy 111.840715 -327.104703) (xy 111.893499 -327.086696)
			(xy 111.948342 -327.076566) (xy 112.004076 -327.074529) (xy 112.059513 -327.080629) (xy 112.11347 -327.094735)
			(xy 112.164799 -327.116547) (xy 112.212405 -327.145601) (xy 112.255273 -327.181276) (xy 112.29249 -327.222813)
			(xy 112.323263 -327.269326) (xy 112.346935 -327.319823) (xy 112.363003 -327.37323) (xy 112.371123 -327.428406)
			(xy 112.371632 -327.456292) (xy 112.371123 -327.484178) (xy 112.363003 -327.539354) (xy 112.346935 -327.592761)
			(xy 112.323263 -327.643258) (xy 112.29249 -327.689771) (xy 112.255273 -327.731308) (xy 112.212405 -327.766983)
			(xy 112.164799 -327.796037) (xy 112.11347 -327.817849) (xy 112.059513 -327.831955) (xy 112.004076 -327.838055)
			(xy 111.948342 -327.836018) (xy 111.893499 -327.825888) (xy 111.840715 -327.807881) (xy 111.791115 -327.78238)
			(xy 111.745757 -327.749929) (xy 111.705608 -327.71122) (xy 111.671522 -327.667077) (xy 111.644226 -327.618442)
			(xy 111.624303 -327.566351) (xy 111.612177 -327.511914) (xy 111.608106 -327.456292) (xy 110.67542 -327.456292)
			(xy 110.67542 -328.24166) (xy 110.674954 -328.267736) (xy 110.66683 -328.319252) (xy 110.650746 -328.368862)
			(xy 110.627097 -328.415344) (xy 110.596465 -328.457553) (xy 110.578392 -328.476356) (xy 110.0455 -329.009248)
			(xy 110.038808 -329.016655) (xy 110.031207 -329.035091) (xy 110.030768 -329.045062) (xy 110.030768 -329.44943)
			(xy 114.249198 -329.44943) (xy 114.253269 -329.393808) (xy 114.265395 -329.339371) (xy 114.285318 -329.28728)
			(xy 114.312614 -329.238645) (xy 114.3467 -329.194502) (xy 114.386849 -329.155793) (xy 114.432207 -329.123342)
			(xy 114.481807 -329.097841) (xy 114.534591 -329.079834) (xy 114.589434 -329.069704) (xy 114.645168 -329.067667)
			(xy 114.700605 -329.073767) (xy 114.754562 -329.087873) (xy 114.805891 -329.109685) (xy 114.853497 -329.138739)
			(xy 114.896365 -329.174414) (xy 114.933582 -329.215951) (xy 114.964355 -329.262464) (xy 114.988027 -329.312961)
			(xy 115.004095 -329.366368) (xy 115.012215 -329.421544) (xy 115.012678 -329.44689) (xy 116.278152 -329.44689)
			(xy 116.278738 -329.416912) (xy 116.28813 -329.357697) (xy 116.306666 -329.300679) (xy 116.333889 -329.24726)
			(xy 116.369131 -329.198756) (xy 116.389912 -329.177142) (xy 116.564664 -329.002644) (xy 116.571373 -328.995175)
			(xy 116.578954 -328.976606) (xy 116.579396 -328.966576) (xy 116.579396 -328.321162) (xy 116.579952 -328.291183)
			(xy 116.589349 -328.231966) (xy 116.607891 -328.174947) (xy 116.635122 -328.121529) (xy 116.670371 -328.073026)
			(xy 116.691156 -328.051414) (xy 117.801644 -326.94118) (xy 117.808335 -326.933697) (xy 117.815927 -326.915139)
			(xy 117.816376 -326.905112) (xy 117.816376 -306.849018) (xy 117.816973 -306.819041) (xy 117.826361 -306.759826)
			(xy 117.844894 -306.702807) (xy 117.872115 -306.649389) (xy 117.907356 -306.600884) (xy 117.928136 -306.57927)
			(xy 118.76786 -305.7398) (xy 118.774544 -305.732312) (xy 118.782139 -305.713758) (xy 118.782592 -305.703732)
			(xy 118.782592 -304.348388) (xy 118.782121 -304.338379) (xy 118.774456 -304.319885) (xy 118.760298 -304.305732)
			(xy 118.741802 -304.298075) (xy 118.731792 -304.297588) (xy 118.72976 -304.297588) (xy 118.719685 -304.297969)
			(xy 118.701086 -304.305718) (xy 118.693692 -304.312574) (xy 118.579138 -304.427382) (xy 118.557525 -304.448149)
			(xy 118.509004 -304.483334) (xy 118.455578 -304.5105) (xy 118.398562 -304.52898) (xy 118.339358 -304.538318)
			(xy 118.30939 -304.538888) (xy 118.282158 -304.538378) (xy 118.228249 -304.530626) (xy 118.175992 -304.515281)
			(xy 118.12645 -304.492657) (xy 118.080632 -304.463212) (xy 118.03947 -304.427547) (xy 118.003802 -304.386388)
			(xy 117.974355 -304.340571) (xy 117.951727 -304.291031) (xy 117.936379 -304.238774) (xy 117.928624 -304.184866)
			(xy 117.928136 -304.157634) (xy 117.928656 -304.127661) (xy 117.937976 -304.068446) (xy 117.956455 -304.01142)
			(xy 117.983637 -303.957992) (xy 118.01885 -303.909481) (xy 118.039642 -303.887886) (xy 118.24208 -303.685448)
			(xy 118.248819 -303.678061) (xy 118.256476 -303.659612) (xy 118.256486 -303.639636) (xy 118.248846 -303.621179)
			(xy 118.24208 -303.61382) (xy 118.039642 -303.411382) (xy 118.0189 -303.389746) (xy 117.983711 -303.341231)
			(xy 117.956539 -303.287811) (xy 117.938054 -303.230801) (xy 117.92871 -303.171601) (xy 117.928136 -303.141634)
			(xy 117.92864 -303.114401) (xy 117.936387 -303.060488) (xy 117.951728 -303.008226) (xy 117.974351 -302.958679)
			(xy 118.003795 -302.912857) (xy 118.039461 -302.871692) (xy 118.080622 -302.836021) (xy 118.126441 -302.806572)
			(xy 118.175985 -302.783944) (xy 118.228244 -302.768597) (xy 118.282157 -302.760843) (xy 118.30939 -302.76038)
			(xy 118.339363 -302.760901) (xy 118.398578 -302.770223) (xy 118.455602 -302.788703) (xy 118.50903 -302.815883)
			(xy 118.557543 -302.851095) (xy 118.579138 -302.871886) (xy 118.632914 -302.925734) (xy 120.828816 -302.925734)
			(xy 120.829298 -302.898364) (xy 120.837111 -302.844186) (xy 120.852597 -302.791683) (xy 120.875435 -302.741936)
			(xy 120.905156 -302.695968) (xy 120.922796 -302.675036) (xy 120.928892 -302.667924) (xy 120.935242 -302.650906)
			(xy 120.935242 -302.565562) (xy 120.928892 -302.548544) (xy 120.922796 -302.541432) (xy 120.905158 -302.520499)
			(xy 120.875446 -302.474527) (xy 120.85261 -302.424779) (xy 120.837119 -302.372279) (xy 120.82929 -302.318103)
			(xy 120.828816 -302.290734) (xy 120.829302 -302.263483) (xy 120.837058 -302.209535) (xy 120.852413 -302.15724)
			(xy 120.875055 -302.107663) (xy 120.904521 -302.061813) (xy 120.940212 -302.020622) (xy 120.981403 -301.984931)
			(xy 121.027253 -301.955465) (xy 121.07683 -301.932823) (xy 121.129125 -301.917468) (xy 121.183073 -301.909712)
			(xy 121.237575 -301.909712) (xy 121.291523 -301.917468) (xy 121.343818 -301.932823) (xy 121.393395 -301.955465)
			(xy 121.439245 -301.984931) (xy 121.480436 -302.020622) (xy 121.516127 -302.061813) (xy 121.545593 -302.107663)
			(xy 121.568235 -302.15724) (xy 121.58359 -302.209535) (xy 121.591346 -302.263483) (xy 121.591832 -302.290734)
			(xy 121.591402 -302.318106) (xy 121.583578 -302.372287) (xy 121.568082 -302.424791) (xy 121.545231 -302.474538)
			(xy 121.515498 -302.520502) (xy 121.497852 -302.541432) (xy 121.491756 -302.548544) (xy 121.485406 -302.565562)
			(xy 121.485406 -302.650906) (xy 121.491756 -302.667924) (xy 121.497852 -302.675036) (xy 121.515467 -302.695988)
			(xy 121.545184 -302.741954) (xy 121.568026 -302.791697) (xy 121.583522 -302.844193) (xy 121.591355 -302.898366)
			(xy 121.591832 -302.925734) (xy 124.248926 -302.925734) (xy 124.249406 -302.898364) (xy 124.257219 -302.844185)
			(xy 124.272705 -302.791682) (xy 124.295544 -302.741935) (xy 124.325266 -302.695968) (xy 124.342906 -302.675036)
			(xy 124.349002 -302.667924) (xy 124.355352 -302.650906) (xy 124.355352 -302.565562) (xy 124.349002 -302.548544)
			(xy 124.342906 -302.541432) (xy 124.325269 -302.520498) (xy 124.295557 -302.474526) (xy 124.27272 -302.424779)
			(xy 124.257229 -302.372279) (xy 124.2494 -302.318103) (xy 124.248926 -302.290734) (xy 124.249412 -302.263483)
			(xy 124.257168 -302.209535) (xy 124.272523 -302.15724) (xy 124.295165 -302.107663) (xy 124.324631 -302.061813)
			(xy 124.360322 -302.020622) (xy 124.401513 -301.984931) (xy 124.447363 -301.955465) (xy 124.49694 -301.932823)
			(xy 124.549235 -301.917468) (xy 124.603183 -301.909712) (xy 124.657685 -301.909712) (xy 124.711633 -301.917468)
			(xy 124.763928 -301.932823) (xy 124.813505 -301.955465) (xy 124.859355 -301.984931) (xy 124.900546 -302.020622)
			(xy 124.936237 -302.061813) (xy 124.965703 -302.107663) (xy 124.988345 -302.15724) (xy 125.0037 -302.209535)
			(xy 125.011456 -302.263483) (xy 125.011942 -302.290734) (xy 125.01151 -302.318106) (xy 125.003686 -302.372287)
			(xy 124.98819 -302.424791) (xy 124.96534 -302.474537) (xy 124.935607 -302.520502) (xy 124.917962 -302.541432)
			(xy 124.911866 -302.548544) (xy 124.905516 -302.565562) (xy 124.905516 -302.650906) (xy 124.911866 -302.667924)
			(xy 124.917962 -302.675036) (xy 124.935579 -302.695986) (xy 124.965295 -302.741953) (xy 124.988136 -302.791696)
			(xy 125.003632 -302.844193) (xy 125.011465 -302.898366) (xy 125.011942 -302.925734) (xy 125.637036 -302.925734)
			(xy 125.637513 -302.898364) (xy 125.645327 -302.844185) (xy 125.660813 -302.791682) (xy 125.683652 -302.741935)
			(xy 125.713375 -302.695968) (xy 125.731016 -302.675036) (xy 125.737112 -302.667924) (xy 125.743462 -302.650906)
			(xy 125.743462 -302.565562) (xy 125.737112 -302.548544) (xy 125.731016 -302.541432) (xy 125.713381 -302.520497)
			(xy 125.683668 -302.474525) (xy 125.660831 -302.424778) (xy 125.645339 -302.372278) (xy 125.63751 -302.318103)
			(xy 125.637036 -302.290734) (xy 125.637522 -302.263483) (xy 125.645278 -302.209535) (xy 125.660633 -302.15724)
			(xy 125.683275 -302.107663) (xy 125.712741 -302.061813) (xy 125.748432 -302.020622) (xy 125.789623 -301.984931)
			(xy 125.835473 -301.955465) (xy 125.88505 -301.932823) (xy 125.937345 -301.917468) (xy 125.991293 -301.909712)
			(xy 126.045795 -301.909712) (xy 126.099743 -301.917468) (xy 126.152038 -301.932823) (xy 126.201615 -301.955465)
			(xy 126.247465 -301.984931) (xy 126.288656 -302.020622) (xy 126.324347 -302.061813) (xy 126.353813 -302.107663)
			(xy 126.376455 -302.15724) (xy 126.39181 -302.209535) (xy 126.399566 -302.263483) (xy 126.400052 -302.290734)
			(xy 126.399618 -302.318106) (xy 126.391794 -302.372286) (xy 126.376298 -302.42479) (xy 126.353449 -302.474537)
			(xy 126.323717 -302.520502) (xy 126.306072 -302.541432) (xy 126.299976 -302.548544) (xy 126.293626 -302.565562)
			(xy 126.293626 -302.650906) (xy 126.299976 -302.667924) (xy 126.306072 -302.675036) (xy 126.32369 -302.695985)
			(xy 126.353406 -302.741953) (xy 126.376247 -302.791696) (xy 126.391742 -302.844193) (xy 126.399576 -302.898366)
			(xy 126.400052 -302.925734) (xy 127.669036 -302.925734) (xy 127.669513 -302.898364) (xy 127.677327 -302.844185)
			(xy 127.692813 -302.791682) (xy 127.715652 -302.741935) (xy 127.745375 -302.695968) (xy 127.763016 -302.675036)
			(xy 127.769112 -302.667924) (xy 127.775462 -302.650906) (xy 127.775462 -302.565562) (xy 127.769112 -302.548544)
			(xy 127.763016 -302.541432) (xy 127.745381 -302.520497) (xy 127.715668 -302.474525) (xy 127.692831 -302.424778)
			(xy 127.677339 -302.372278) (xy 127.66951 -302.318103) (xy 127.669036 -302.290734) (xy 127.669522 -302.263483)
			(xy 127.677278 -302.209535) (xy 127.692633 -302.15724) (xy 127.715275 -302.107663) (xy 127.744741 -302.061813)
			(xy 127.780432 -302.020622) (xy 127.821623 -301.984931) (xy 127.867473 -301.955465) (xy 127.91705 -301.932823)
			(xy 127.969345 -301.917468) (xy 128.023293 -301.909712) (xy 128.077795 -301.909712) (xy 128.131743 -301.917468)
			(xy 128.184038 -301.932823) (xy 128.233615 -301.955465) (xy 128.279465 -301.984931) (xy 128.320656 -302.020622)
			(xy 128.356347 -302.061813) (xy 128.385813 -302.107663) (xy 128.408455 -302.15724) (xy 128.42381 -302.209535)
			(xy 128.431566 -302.263483) (xy 128.432052 -302.290734) (xy 128.431618 -302.318106) (xy 128.423794 -302.372286)
			(xy 128.408298 -302.42479) (xy 128.385449 -302.474537) (xy 128.355717 -302.520502) (xy 128.338072 -302.541432)
			(xy 128.331976 -302.548544) (xy 128.325626 -302.565562) (xy 128.325626 -302.650906) (xy 128.331976 -302.667924)
			(xy 128.338072 -302.675036) (xy 128.35569 -302.695985) (xy 128.385406 -302.741953) (xy 128.408247 -302.791696)
			(xy 128.423742 -302.844193) (xy 128.431576 -302.898366) (xy 128.432052 -302.925734) (xy 132.477256 -302.925734)
			(xy 132.477728 -302.898364) (xy 132.485543 -302.844184) (xy 132.501029 -302.791681) (xy 132.52387 -302.741934)
			(xy 132.553595 -302.695967) (xy 132.571236 -302.675036) (xy 132.577332 -302.667924) (xy 132.583682 -302.650906)
			(xy 132.583682 -302.565562) (xy 132.577332 -302.548544) (xy 132.571236 -302.541432) (xy 132.553604 -302.520494)
			(xy 132.52389 -302.474523) (xy 132.501052 -302.424777) (xy 132.485559 -302.372278) (xy 132.47773 -302.318103)
			(xy 132.477256 -302.290734) (xy 132.477742 -302.263483) (xy 132.485498 -302.209535) (xy 132.500853 -302.15724)
			(xy 132.523495 -302.107663) (xy 132.552961 -302.061813) (xy 132.588652 -302.020622) (xy 132.629843 -301.984931)
			(xy 132.675693 -301.955465) (xy 132.72527 -301.932823) (xy 132.777565 -301.917468) (xy 132.831513 -301.909712)
			(xy 132.886015 -301.909712) (xy 132.939963 -301.917468) (xy 132.992258 -301.932823) (xy 133.041835 -301.955465)
			(xy 133.087685 -301.984931) (xy 133.128876 -302.020622) (xy 133.164567 -302.061813) (xy 133.194033 -302.107663)
			(xy 133.216675 -302.15724) (xy 133.23203 -302.209535) (xy 133.239786 -302.263483) (xy 133.240272 -302.290734)
			(xy 133.239833 -302.318105) (xy 133.232009 -302.372286) (xy 133.216514 -302.424789) (xy 133.193667 -302.474536)
			(xy 133.163936 -302.520501) (xy 133.146292 -302.541432) (xy 133.140196 -302.548544) (xy 133.133846 -302.565562)
			(xy 133.133846 -302.650906) (xy 133.140196 -302.667924) (xy 133.146292 -302.675036) (xy 133.163913 -302.695982)
			(xy 133.193628 -302.741951) (xy 133.216468 -302.791695) (xy 133.231963 -302.844193) (xy 133.239796 -302.898366)
			(xy 133.240272 -302.925734) (xy 133.239786 -302.952985) (xy 133.23203 -303.006933) (xy 133.216675 -303.059228)
			(xy 133.194033 -303.108805) (xy 133.164567 -303.154655) (xy 133.128876 -303.195846) (xy 133.087685 -303.231537)
			(xy 133.041835 -303.261003) (xy 132.992258 -303.283645) (xy 132.939963 -303.299) (xy 132.886015 -303.306756)
			(xy 132.831513 -303.306756) (xy 132.777565 -303.299) (xy 132.72527 -303.283645) (xy 132.675693 -303.261003)
			(xy 132.629843 -303.231537) (xy 132.588652 -303.195846) (xy 132.552961 -303.154655) (xy 132.523495 -303.108805)
			(xy 132.500853 -303.059228) (xy 132.485498 -303.006933) (xy 132.477742 -302.952985) (xy 132.477256 -302.925734)
			(xy 128.432052 -302.925734) (xy 128.431566 -302.952985) (xy 128.42381 -303.006933) (xy 128.408455 -303.059228)
			(xy 128.385813 -303.108805) (xy 128.356347 -303.154655) (xy 128.320656 -303.195846) (xy 128.279465 -303.231537)
			(xy 128.233615 -303.261003) (xy 128.184038 -303.283645) (xy 128.131743 -303.299) (xy 128.077795 -303.306756)
			(xy 128.023293 -303.306756) (xy 127.969345 -303.299) (xy 127.91705 -303.283645) (xy 127.867473 -303.261003)
			(xy 127.821623 -303.231537) (xy 127.780432 -303.195846) (xy 127.744741 -303.154655) (xy 127.715275 -303.108805)
			(xy 127.692633 -303.059228) (xy 127.677278 -303.006933) (xy 127.669522 -302.952985) (xy 127.669036 -302.925734)
			(xy 126.400052 -302.925734) (xy 126.399566 -302.952985) (xy 126.39181 -303.006933) (xy 126.376455 -303.059228)
			(xy 126.353813 -303.108805) (xy 126.324347 -303.154655) (xy 126.288656 -303.195846) (xy 126.247465 -303.231537)
			(xy 126.201615 -303.261003) (xy 126.152038 -303.283645) (xy 126.099743 -303.299) (xy 126.045795 -303.306756)
			(xy 125.991293 -303.306756) (xy 125.937345 -303.299) (xy 125.88505 -303.283645) (xy 125.835473 -303.261003)
			(xy 125.789623 -303.231537) (xy 125.748432 -303.195846) (xy 125.712741 -303.154655) (xy 125.683275 -303.108805)
			(xy 125.660633 -303.059228) (xy 125.645278 -303.006933) (xy 125.637522 -302.952985) (xy 125.637036 -302.925734)
			(xy 125.011942 -302.925734) (xy 125.011456 -302.952985) (xy 125.0037 -303.006933) (xy 124.988345 -303.059228)
			(xy 124.965703 -303.108805) (xy 124.936237 -303.154655) (xy 124.900546 -303.195846) (xy 124.859355 -303.231537)
			(xy 124.813505 -303.261003) (xy 124.763928 -303.283645) (xy 124.711633 -303.299) (xy 124.657685 -303.306756)
			(xy 124.603183 -303.306756) (xy 124.549235 -303.299) (xy 124.49694 -303.283645) (xy 124.447363 -303.261003)
			(xy 124.401513 -303.231537) (xy 124.360322 -303.195846) (xy 124.324631 -303.154655) (xy 124.295165 -303.108805)
			(xy 124.272523 -303.059228) (xy 124.257168 -303.006933) (xy 124.249412 -302.952985) (xy 124.248926 -302.925734)
			(xy 121.591832 -302.925734) (xy 121.591346 -302.952985) (xy 121.58359 -303.006933) (xy 121.568235 -303.059228)
			(xy 121.545593 -303.108805) (xy 121.516127 -303.154655) (xy 121.480436 -303.195846) (xy 121.439245 -303.231537)
			(xy 121.393395 -303.261003) (xy 121.343818 -303.283645) (xy 121.291523 -303.299) (xy 121.237575 -303.306756)
			(xy 121.183073 -303.306756) (xy 121.129125 -303.299) (xy 121.07683 -303.283645) (xy 121.027253 -303.261003)
			(xy 120.981403 -303.231537) (xy 120.940212 -303.195846) (xy 120.904521 -303.154655) (xy 120.875055 -303.108805)
			(xy 120.852413 -303.059228) (xy 120.837058 -303.006933) (xy 120.829302 -302.952985) (xy 120.828816 -302.925734)
			(xy 118.632914 -302.925734) (xy 118.769892 -303.062894) (xy 118.777301 -303.069722) (xy 118.795893 -303.077449)
			(xy 118.80596 -303.07788) (xy 119.144288 -303.07788) (xy 119.174261 -303.078402) (xy 119.233475 -303.087724)
			(xy 119.2905 -303.106203) (xy 119.343928 -303.133384) (xy 119.392441 -303.168595) (xy 119.414036 -303.189386)
			(xy 119.814848 -303.590198) (xy 119.83566 -303.611786) (xy 119.870914 -303.66029) (xy 119.898143 -303.713713)
			(xy 119.916675 -303.77074) (xy 119.926053 -303.829965) (xy 119.926608 -303.859946) (xy 119.926608 -306.04079)
			(xy 119.926021 -306.070768) (xy 119.916631 -306.129983) (xy 119.898096 -306.187002) (xy 119.870872 -306.240421)
			(xy 119.83563 -306.288925) (xy 119.814848 -306.310538) (xy 118.975124 -307.150008) (xy 118.968434 -307.157492)
			(xy 118.960843 -307.176049) (xy 118.960392 -307.186076) (xy 118.960392 -327.24217) (xy 118.959768 -327.272146)
			(xy 118.950383 -327.331359) (xy 118.931856 -327.388376) (xy 118.904641 -327.441795) (xy 118.869408 -327.490302)
			(xy 118.848632 -327.511918) (xy 117.738144 -328.622152) (xy 117.731438 -328.629623) (xy 117.723855 -328.64819)
			(xy 117.723412 -328.65822) (xy 117.723412 -328.934064) (xy 117.723771 -328.94411) (xy 117.731368 -328.962706)
			(xy 117.738144 -328.970132) (xy 117.945408 -329.177142) (xy 117.966204 -329.198745) (xy 118.001458 -329.247246)
			(xy 118.028689 -329.300666) (xy 118.047225 -329.357689) (xy 118.056609 -329.41691) (xy 118.057168 -329.44689)
			(xy 118.056681 -329.474135) (xy 118.048925 -329.528071) (xy 118.033568 -329.580353) (xy 118.010924 -329.629916)
			(xy 117.981455 -329.675751) (xy 117.945759 -329.716922) (xy 117.904566 -329.752593) (xy 117.858714 -329.782035)
			(xy 117.809137 -329.804648) (xy 117.756846 -329.819974) (xy 117.702906 -329.827698) (xy 117.67566 -329.828144)
			(xy 117.645687 -329.827613) (xy 117.586472 -329.818296) (xy 117.529447 -329.79982) (xy 117.476019 -329.772641)
			(xy 117.427507 -329.73743) (xy 117.405912 -329.716638) (xy 117.203474 -329.5142) (xy 117.196113 -329.507431)
			(xy 117.177651 -329.499784) (xy 117.157669 -329.499784) (xy 117.139207 -329.507431) (xy 117.131846 -329.5142)
			(xy 116.929408 -329.716638) (xy 116.907801 -329.737412) (xy 116.859279 -329.772598) (xy 116.805852 -329.799764)
			(xy 116.748834 -329.818241) (xy 116.689629 -329.827576) (xy 116.65966 -329.828144) (xy 116.632421 -329.82766)
			(xy 116.578497 -329.819906) (xy 116.526225 -329.80456) (xy 116.476667 -329.781936) (xy 116.430831 -329.752492)
			(xy 116.389649 -329.716828) (xy 116.353958 -329.67567) (xy 116.324484 -329.629853) (xy 116.301827 -329.580309)
			(xy 116.286447 -329.528047) (xy 116.278658 -329.474129) (xy 116.278152 -329.44689) (xy 115.012678 -329.44689)
			(xy 115.012724 -329.44943) (xy 115.012215 -329.477316) (xy 115.004095 -329.532492) (xy 114.988027 -329.585899)
			(xy 114.964355 -329.636396) (xy 114.933582 -329.682909) (xy 114.896365 -329.724446) (xy 114.853497 -329.760121)
			(xy 114.805891 -329.789175) (xy 114.754562 -329.810987) (xy 114.700605 -329.825093) (xy 114.645168 -329.831193)
			(xy 114.589434 -329.829156) (xy 114.534591 -329.819026) (xy 114.481807 -329.801019) (xy 114.432207 -329.775518)
			(xy 114.386849 -329.743067) (xy 114.3467 -329.704358) (xy 114.312614 -329.660215) (xy 114.285318 -329.61158)
			(xy 114.265395 -329.559489) (xy 114.253269 -329.505052) (xy 114.249198 -329.44943) (xy 110.030768 -329.44943)
			(xy 110.030768 -330.380594) (xy 110.038327 -330.389785) (xy 110.059527 -330.400525) (xy 110.071408 -330.401168)
			(xy 114.347498 -330.401168) (xy 114.355465 -330.400903) (xy 114.37062 -330.395991) (xy 114.377216 -330.391516)
			(xy 114.379756 -330.389738) (xy 114.399822 -330.375006) (xy 114.402832 -330.372633) (xy 114.408183 -330.367145)
			(xy 114.41049 -330.364084) (xy 114.415316 -330.35748) (xy 114.417856 -330.34986) (xy 114.426688 -330.324899)
			(xy 114.450271 -330.277495) (xy 114.480177 -330.233803) (xy 114.515831 -330.194661) (xy 114.55655 -330.160819)
			(xy 114.601554 -330.132927) (xy 114.649979 -330.111519) (xy 114.700898 -330.097005) (xy 114.753333 -330.089665)
			(xy 114.779806 -330.089256) (xy 114.806075 -330.08969) (xy 114.858115 -330.096895) (xy 114.908673 -330.111181)
			(xy 114.956788 -330.132277) (xy 115.001549 -330.159783) (xy 115.022122 -330.176124) (xy 115.030878 -330.182662)
			(xy 115.051973 -330.188277) (xy 115.073491 -330.1846) (xy 115.082828 -330.178918) (xy 115.112224 -330.159658)
			(xy 115.174707 -330.127486) (xy 115.240565 -330.102951) (xy 115.308867 -330.086398) (xy 115.37865 -330.078063)
			(xy 115.41379 -330.077572) (xy 115.446952 -330.078052) (xy 115.512855 -330.085507) (xy 115.57751 -330.100291)
			(xy 115.640105 -330.122218) (xy 115.699852 -330.151012) (xy 115.756002 -330.186312) (xy 115.807848 -330.227674)
			(xy 115.83162 -330.2508) (xy 115.93449 -330.35367) (xy 115.941887 -330.360521) (xy 115.960485 -330.368264)
			(xy 115.970558 -330.368656) (xy 116.04625 -330.368656) (xy 116.077824 -330.369034) (xy 116.140618 -330.375715)
			(xy 116.202337 -330.38907) (xy 116.232432 -330.398628) (xy 116.240052 -330.401168) (xy 119.04345 -330.401168)
			(xy 119.053515 -330.400735) (xy 119.072104 -330.393004) (xy 119.079518 -330.386182) (xy 119.231156 -330.234544)
			(xy 119.237998 -330.227145) (xy 119.245719 -330.208546) (xy 119.246142 -330.198476) (xy 119.246142 -309.687976)
			(xy 119.246571 -309.677909) (xy 119.254296 -309.659315) (xy 119.261128 -309.651908) (xy 119.362474 -309.550562)
			(xy 119.369056 -309.54318) (xy 119.376509 -309.524882) (xy 119.376952 -309.515002) (xy 119.376952 -309.50789)
			(xy 119.377378 -309.497822) (xy 119.385101 -309.479225) (xy 119.391938 -309.471822) (xy 119.462042 -309.401718)
			(xy 119.46255 -309.400956) (xy 119.466106 -309.3974) (xy 119.46636 -309.397146) (xy 120.420638 -308.442868)
			(xy 120.420892 -308.442614) (xy 120.424194 -308.439312) (xy 120.424956 -308.438804) (xy 120.495314 -308.368446)
			(xy 120.502711 -308.361597) (xy 120.52131 -308.35386) (xy 120.531382 -308.35346) (xy 120.538494 -308.35346)
			(xy 120.548366 -308.352988) (xy 120.566651 -308.345532) (xy 120.574054 -308.338982) (xy 120.686068 -308.226968)
			(xy 120.693467 -308.220125) (xy 120.712066 -308.212404) (xy 120.722136 -308.211982) (xy 133.968236 -308.211982)
			(xy 133.978303 -308.211552) (xy 133.996896 -308.203826) (xy 134.004304 -308.196996) (xy 134.681722 -307.519578)
			(xy 134.688573 -307.512182) (xy 134.696312 -307.493583) (xy 134.696708 -307.48351) (xy 134.696708 -285.481014)
			(xy 134.696214 -285.471017) (xy 134.688582 -285.452534) (xy 134.674497 -285.43834) (xy 134.665466 -285.434024)
			(xy 134.650988 -285.428182) (xy 134.621016 -285.434024) (xy 133.732778 -286.322516) (xy 133.725962 -286.329858)
			(xy 133.718223 -286.348322) (xy 133.717792 -286.35833) (xy 133.717792 -294.532304) (xy 133.718263 -294.542576)
			(xy 133.726313 -294.561476) (xy 133.741124 -294.575711) (xy 133.750558 -294.579802) (xy 133.779514 -294.590724)
			(xy 133.854698 -294.618918) (xy 133.884924 -294.611298) (xy 133.895592 -294.59936) (xy 133.913783 -294.57946)
			(xy 133.954802 -294.544472) (xy 134.000338 -294.515606) (xy 134.049484 -294.493438) (xy 134.101261 -294.47841)
			(xy 134.154639 -294.470819) (xy 134.181596 -294.470328) (xy 134.208846 -294.470791) (xy 134.262793 -294.478547)
			(xy 134.315086 -294.493901) (xy 134.364662 -294.516541) (xy 134.410511 -294.546006) (xy 134.451701 -294.581697)
			(xy 134.487391 -294.622885) (xy 134.516857 -294.668734) (xy 134.539498 -294.71831) (xy 134.554852 -294.770603)
			(xy 134.562609 -294.82455) (xy 134.562609 -294.87905) (xy 134.554852 -294.932997) (xy 134.539498 -294.98529)
			(xy 134.516857 -295.034866) (xy 134.487391 -295.080715) (xy 134.451701 -295.121903) (xy 134.410511 -295.157594)
			(xy 134.364662 -295.187059) (xy 134.315086 -295.209699) (xy 134.262793 -295.225053) (xy 134.208846 -295.232809)
			(xy 134.181596 -295.233344) (xy 134.155063 -295.232887) (xy 134.10251 -295.225535) (xy 134.051482 -295.210973)
			(xy 134.002964 -295.189483) (xy 133.95789 -295.161478) (xy 133.917132 -295.127498) (xy 133.881473 -295.088199)
			(xy 133.851603 -295.04434) (xy 133.839458 -295.020746) (xy 133.839204 -295.020492) (xy 133.836257 -295.014989)
			(xy 133.828159 -295.005491) (xy 133.823202 -295.001696) (xy 133.80339 -294.987726) (xy 133.797671 -294.983961)
			(xy 133.784797 -294.979316) (xy 133.77799 -294.978582) (xy 133.703314 -294.97274) (xy 133.694294 -294.972436)
			(xy 133.676954 -294.977404) (xy 133.662389 -294.988042) (xy 133.657086 -294.995346) (xy 133.656578 -294.995854)
			(xy 133.656324 -294.996108) (xy 133.645255 -295.012654) (xy 133.620186 -295.04358) (xy 133.606286 -295.05783)
			(xy 133.152896 -295.51122) (xy 133.146053 -295.51862) (xy 133.138327 -295.537218) (xy 133.13791 -295.547288)
			(xy 133.13791 -295.56964) (xy 133.138027 -295.574736) (xy 133.14008 -295.584719) (xy 133.141974 -295.589452)
			(xy 133.152388 -295.61409) (xy 133.158484 -295.620694) (xy 133.177218 -295.641593) (xy 133.208985 -295.68786)
			(xy 133.233645 -295.738276) (xy 133.250668 -295.791756) (xy 133.259687 -295.84715) (xy 133.260592 -295.875202)
			(xy 133.260592 -295.88079) (xy 133.260184 -295.906338) (xy 133.253369 -295.956976) (xy 133.239859 -296.006253)
			(xy 133.219895 -296.053286) (xy 133.193836 -296.097237) (xy 133.178296 -296.117518) (xy 133.178042 -296.117518)
			(xy 133.174994 -296.121582) (xy 133.172708 -296.1259) (xy 133.169886 -296.131529) (xy 133.166809 -296.143736)
			(xy 133.166612 -296.15003) (xy 133.166612 -296.182288) (xy 133.155436 -296.182288) (xy 133.155436 -296.242232)
			(xy 133.161786 -296.25925) (xy 133.167882 -296.266362) (xy 133.184965 -296.286807) (xy 133.21385 -296.331574)
			(xy 133.236219 -296.379927) (xy 133.251636 -296.430925) (xy 133.259802 -296.483572) (xy 133.260592 -296.510202)
			(xy 133.260592 -296.51579) (xy 133.260184 -296.541338) (xy 133.253369 -296.591976) (xy 133.239859 -296.641253)
			(xy 133.219895 -296.688286) (xy 133.193836 -296.732237) (xy 133.178296 -296.752518) (xy 133.178042 -296.752518)
			(xy 133.174994 -296.756582) (xy 133.172708 -296.7609) (xy 133.169886 -296.766529) (xy 133.166809 -296.778736)
			(xy 133.166612 -296.78503) (xy 133.166612 -296.817288) (xy 133.155436 -296.817288) (xy 133.155436 -296.877232)
			(xy 133.161786 -296.89425) (xy 133.167882 -296.901362) (xy 133.184965 -296.921807) (xy 133.21385 -296.966574)
			(xy 133.236219 -297.014927) (xy 133.251636 -297.065925) (xy 133.259802 -297.118572) (xy 133.260592 -297.145202)
			(xy 133.260592 -297.15079) (xy 133.260184 -297.176338) (xy 133.253369 -297.226976) (xy 133.239859 -297.276253)
			(xy 133.219895 -297.323286) (xy 133.193836 -297.367237) (xy 133.178296 -297.387518) (xy 133.178042 -297.387518)
			(xy 133.174994 -297.391582) (xy 133.172708 -297.3959) (xy 133.169886 -297.401529) (xy 133.166809 -297.413736)
			(xy 133.166612 -297.42003) (xy 133.166612 -297.452288) (xy 133.155436 -297.452288) (xy 133.155436 -297.512232)
			(xy 133.161786 -297.52925) (xy 133.167882 -297.536362) (xy 133.184965 -297.556807) (xy 133.21385 -297.601574)
			(xy 133.236219 -297.649927) (xy 133.251636 -297.700925) (xy 133.259802 -297.753572) (xy 133.260592 -297.780202)
			(xy 133.260592 -297.78579) (xy 133.260184 -297.811338) (xy 133.253369 -297.861976) (xy 133.239859 -297.911253)
			(xy 133.219895 -297.958286) (xy 133.193836 -298.002237) (xy 133.178296 -298.022518) (xy 133.178042 -298.022518)
			(xy 133.174994 -298.026582) (xy 133.172708 -298.0309) (xy 133.169886 -298.036529) (xy 133.166809 -298.048736)
			(xy 133.166612 -298.05503) (xy 133.166612 -298.087288) (xy 133.155436 -298.087288) (xy 133.155436 -298.147232)
			(xy 133.161786 -298.16425) (xy 133.167882 -298.171362) (xy 133.185277 -298.192238) (xy 133.214596 -298.237987)
			(xy 133.237124 -298.287435) (xy 133.252404 -298.339581) (xy 133.260127 -298.393367) (xy 133.260592 -298.420536)
			(xy 133.260121 -298.447546) (xy 133.252498 -298.501024) (xy 133.237409 -298.552893) (xy 133.215155 -298.602116)
			(xy 133.186183 -298.647708) (xy 133.15107 -298.688759) (xy 133.110518 -298.724447) (xy 133.065339 -298.75406)
			(xy 133.016435 -298.777006) (xy 132.964784 -298.792825) (xy 132.911418 -298.801202) (xy 132.884418 -298.802044)
			(xy 132.87883 -298.802044) (xy 132.853284 -298.801631) (xy 132.80265 -298.794806) (xy 132.753378 -298.78129)
			(xy 132.70635 -298.761321) (xy 132.662405 -298.735259) (xy 132.642102 -298.719748) (xy 132.642102 -298.719494)
			(xy 132.638038 -298.716446) (xy 132.63372 -298.71416) (xy 132.62809 -298.711338) (xy 132.615884 -298.708259)
			(xy 132.60959 -298.708064) (xy 132.577332 -298.708064) (xy 132.577332 -298.696888) (xy 132.517388 -298.696888)
			(xy 132.50037 -298.703238) (xy 132.493258 -298.709334) (xy 132.472381 -298.726728) (xy 132.426631 -298.756045)
			(xy 132.377183 -298.778573) (xy 132.325039 -298.793854) (xy 132.271253 -298.801578) (xy 132.244084 -298.802044)
			(xy 132.217075 -298.801574) (xy 132.163596 -298.793953) (xy 132.111728 -298.778865) (xy 132.062506 -298.756612)
			(xy 132.016914 -298.727639) (xy 131.975865 -298.692526) (xy 131.940179 -298.651973) (xy 131.910569 -298.606793)
			(xy 131.887627 -298.557888) (xy 131.871813 -298.506236) (xy 131.863442 -298.45287) (xy 131.862576 -298.42587)
			(xy 131.862576 -298.420282) (xy 131.862986 -298.394735) (xy 131.869804 -298.344098) (xy 131.883316 -298.294823)
			(xy 131.903281 -298.24779) (xy 131.92934 -298.203841) (xy 131.944872 -298.183554) (xy 131.945126 -298.183554)
			(xy 131.948174 -298.17949) (xy 131.95046 -298.175172) (xy 131.953292 -298.169545) (xy 131.956388 -298.157338)
			(xy 131.956556 -298.151042) (xy 131.956556 -298.118784) (xy 131.967732 -298.118784) (xy 131.967732 -298.05884)
			(xy 131.961382 -298.041822) (xy 131.955286 -298.03471) (xy 131.938206 -298.014264) (xy 131.909327 -297.969496)
			(xy 131.886963 -297.921142) (xy 131.871551 -297.870145) (xy 131.86339 -297.817499) (xy 131.862576 -297.79087)
			(xy 131.862576 -297.785282) (xy 131.862986 -297.759735) (xy 131.869804 -297.709098) (xy 131.883316 -297.659823)
			(xy 131.903281 -297.61279) (xy 131.92934 -297.568841) (xy 131.944872 -297.548554) (xy 131.945126 -297.548554)
			(xy 131.948174 -297.54449) (xy 131.95046 -297.540172) (xy 131.953292 -297.534545) (xy 131.956388 -297.522338)
			(xy 131.956556 -297.516042) (xy 131.956556 -297.483784) (xy 131.967732 -297.483784) (xy 131.967732 -297.42384)
			(xy 131.961382 -297.406822) (xy 131.955286 -297.39971) (xy 131.938206 -297.379264) (xy 131.909327 -297.334496)
			(xy 131.886963 -297.286142) (xy 131.871551 -297.235145) (xy 131.86339 -297.182499) (xy 131.862576 -297.15587)
			(xy 131.862576 -297.150282) (xy 131.862986 -297.124735) (xy 131.869804 -297.074098) (xy 131.883316 -297.024823)
			(xy 131.903281 -296.97779) (xy 131.92934 -296.933841) (xy 131.944872 -296.913554) (xy 131.945126 -296.913554)
			(xy 131.948174 -296.90949) (xy 131.95046 -296.905172) (xy 131.953292 -296.899545) (xy 131.956388 -296.887338)
			(xy 131.956556 -296.881042) (xy 131.956556 -296.848784) (xy 131.967732 -296.848784) (xy 131.967732 -296.78884)
			(xy 131.961382 -296.771822) (xy 131.955286 -296.76471) (xy 131.938206 -296.744264) (xy 131.909327 -296.699496)
			(xy 131.886963 -296.651142) (xy 131.871551 -296.600145) (xy 131.86339 -296.547499) (xy 131.862576 -296.52087)
			(xy 131.862576 -296.515282) (xy 131.862986 -296.489735) (xy 131.869804 -296.439098) (xy 131.883316 -296.389823)
			(xy 131.903281 -296.34279) (xy 131.92934 -296.298841) (xy 131.944872 -296.278554) (xy 131.945126 -296.278554)
			(xy 131.948174 -296.27449) (xy 131.95046 -296.270172) (xy 131.953292 -296.264545) (xy 131.956388 -296.252338)
			(xy 131.956556 -296.246042) (xy 131.956556 -296.213784) (xy 131.967732 -296.213784) (xy 131.967732 -296.15384)
			(xy 131.961382 -296.136822) (xy 131.955286 -296.12971) (xy 131.938206 -296.109264) (xy 131.909327 -296.064496)
			(xy 131.886963 -296.016142) (xy 131.871551 -295.965145) (xy 131.86339 -295.912499) (xy 131.862576 -295.88587)
			(xy 131.862576 -295.880282) (xy 131.862986 -295.854735) (xy 131.869804 -295.804098) (xy 131.883316 -295.754823)
			(xy 131.903281 -295.70779) (xy 131.92934 -295.663841) (xy 131.944872 -295.643554) (xy 131.945126 -295.643554)
			(xy 131.948174 -295.63949) (xy 131.95046 -295.635172) (xy 131.953292 -295.629545) (xy 131.956388 -295.617338)
			(xy 131.956556 -295.611042) (xy 131.956556 -295.578784) (xy 131.967732 -295.578784) (xy 131.967732 -295.51884)
			(xy 131.961382 -295.501822) (xy 131.955286 -295.49471) (xy 131.937894 -295.473833) (xy 131.908581 -295.428082)
			(xy 131.886058 -295.378634) (xy 131.870783 -295.326489) (xy 131.863065 -295.272704) (xy 131.862576 -295.245536)
			(xy 131.863036 -295.218281) (xy 131.870789 -295.164325) (xy 131.886142 -295.112022) (xy 131.908782 -295.062436)
			(xy 131.938249 -295.016578) (xy 131.973942 -294.975379) (xy 132.015136 -294.93968) (xy 132.060991 -294.910207)
			(xy 132.110573 -294.88756) (xy 132.162874 -294.8722) (xy 132.216829 -294.86444) (xy 132.244084 -294.864028)
			(xy 132.272715 -294.864546) (xy 132.329333 -294.873111) (xy 132.384037 -294.890035) (xy 132.4356 -294.91494)
			(xy 132.482865 -294.947266) (xy 132.50418 -294.96639) (xy 132.511038 -294.97274) (xy 132.536692 -294.983154)
			(xy 132.541264 -294.98487) (xy 132.550859 -294.986672) (xy 132.555742 -294.98671) (xy 132.598922 -294.98671)
			(xy 132.609336 -294.975788) (xy 132.93979 -294.645334) (xy 132.946627 -294.637932) (xy 132.954339 -294.619334)
			(xy 132.954776 -294.609266) (xy 132.954776 -284.432248) (xy 132.95418 -284.419627) (xy 132.942318 -284.397356)
			(xy 132.93217 -284.38983) (xy 132.916629 -284.379234) (xy 132.887494 -284.35544) (xy 132.874004 -284.342332)
			(xy 132.644134 -284.112208) (xy 132.636711 -284.105424) (xy 132.618115 -284.097817) (xy 132.608066 -284.097476)
			(xy 130.481578 -284.097476) (xy 130.471551 -284.097926) (xy 130.452991 -284.105515) (xy 130.44551 -284.112208)
			(xy 129.574036 -284.983936) (xy 129.55242 -285.004713) (xy 129.503914 -285.039948) (xy 129.450495 -285.067165)
			(xy 129.393478 -285.085695) (xy 129.334264 -285.095082) (xy 129.304288 -285.095696) (xy 128.093978 -285.095696)
			(xy 128.063996 -285.095143) (xy 128.004769 -285.08577) (xy 127.947739 -285.067241) (xy 127.894313 -285.040014)
			(xy 127.845806 -285.004761) (xy 127.82423 -284.983936) (xy 127.309372 -284.468824) (xy 127.301947 -284.462048)
			(xy 127.28335 -284.454461) (xy 127.273304 -284.454092) (xy 126.254002 -284.454092) (xy 126.226755 -284.453629)
			(xy 126.172815 -284.445871) (xy 126.120529 -284.430513) (xy 126.070963 -284.407867) (xy 126.025125 -284.378396)
			(xy 125.983949 -284.342699) (xy 125.948276 -284.301504) (xy 125.91883 -284.255649) (xy 125.896213 -284.20607)
			(xy 125.880884 -284.153776) (xy 125.873156 -284.099832) (xy 125.872748 -284.072584) (xy 125.873205 -284.045225)
			(xy 125.880993 -283.991064) (xy 125.896436 -283.938571) (xy 125.919218 -283.888821) (xy 125.948871 -283.842835)
			(xy 125.966474 -283.821886) (xy 125.972824 -283.814774) (xy 125.979174 -283.79801) (xy 125.97892 -283.712412)
			(xy 125.97257 -283.695394) (xy 125.966474 -283.688282) (xy 125.948834 -283.66735) (xy 125.919112 -283.621382)
			(xy 125.896273 -283.571635) (xy 125.880786 -283.519132) (xy 125.872971 -283.464954) (xy 125.872494 -283.437584)
			(xy 125.87351 -283.41066) (xy 125.874526 -283.394912) (xy 125.85827 -283.36748) (xy 125.757178 -283.321506)
			(xy 125.747593 -283.317722) (xy 125.727009 -283.317315) (xy 125.707902 -283.324983) (xy 125.700282 -283.33192)
			(xy 125.572012 -283.459936) (xy 125.565239 -283.467362) (xy 125.557656 -283.485959) (xy 125.55728 -283.496004)
			(xy 125.55728 -286.325056) (xy 125.557879 -286.336809) (xy 125.568349 -286.357854) (xy 125.577346 -286.365442)
			(xy 125.651514 -286.421576) (xy 125.674628 -286.425894) (xy 125.686312 -286.422592) (xy 125.711698 -286.415918)
			(xy 125.763699 -286.408776) (xy 125.789944 -286.408368) (xy 125.817195 -286.408857) (xy 125.871141 -286.416619)
			(xy 125.923434 -286.431979) (xy 125.973009 -286.454624) (xy 126.018857 -286.484093) (xy 126.060044 -286.519787)
			(xy 126.095733 -286.560979) (xy 126.125197 -286.60683) (xy 126.147837 -286.656407) (xy 126.16204 -286.704786)
			(xy 126.29464 -286.704786) (xy 126.298711 -286.649164) (xy 126.310837 -286.594727) (xy 126.33076 -286.542636)
			(xy 126.358056 -286.494001) (xy 126.392142 -286.449858) (xy 126.432291 -286.411149) (xy 126.477649 -286.378698)
			(xy 126.527249 -286.353197) (xy 126.580033 -286.33519) (xy 126.634876 -286.32506) (xy 126.69061 -286.323023)
			(xy 126.746047 -286.329123) (xy 126.800004 -286.343229) (xy 126.851333 -286.365041) (xy 126.898939 -286.394095)
			(xy 126.941807 -286.42977) (xy 126.979024 -286.471307) (xy 127.009797 -286.51782) (xy 127.033469 -286.568317)
			(xy 127.049537 -286.621724) (xy 127.057657 -286.6769) (xy 127.058166 -286.704786) (xy 127.057657 -286.732672)
			(xy 127.049537 -286.787848) (xy 127.033469 -286.841255) (xy 127.009797 -286.891752) (xy 126.979024 -286.938265)
			(xy 126.941807 -286.979802) (xy 126.898939 -287.015477) (xy 126.851333 -287.044531) (xy 126.800004 -287.066343)
			(xy 126.746047 -287.080449) (xy 126.69061 -287.086549) (xy 126.634876 -287.084512) (xy 126.580033 -287.074382)
			(xy 126.527249 -287.056375) (xy 126.477649 -287.030874) (xy 126.432291 -286.998423) (xy 126.392142 -286.959714)
			(xy 126.358056 -286.915571) (xy 126.33076 -286.866936) (xy 126.310837 -286.814845) (xy 126.298711 -286.760408)
			(xy 126.29464 -286.704786) (xy 126.16204 -286.704786) (xy 126.16319 -286.708702) (xy 126.170946 -286.762649)
			(xy 126.170946 -286.817151) (xy 126.16319 -286.871098) (xy 126.147837 -286.923393) (xy 126.125197 -286.97297)
			(xy 126.095733 -287.018821) (xy 126.060044 -287.060013) (xy 126.018857 -287.095707) (xy 125.973009 -287.125176)
			(xy 125.923434 -287.147821) (xy 125.871141 -287.163181) (xy 125.817195 -287.170943) (xy 125.789944 -287.171384)
			(xy 125.763699 -287.170981) (xy 125.711697 -287.163838) (xy 125.686312 -287.15716) (xy 125.674628 -287.153858)
			(xy 125.651514 -287.158176) (xy 125.577346 -287.21431) (xy 125.568357 -287.221903) (xy 125.557888 -287.242946)
			(xy 125.55728 -287.254696) (xy 125.55728 -294.1828) (xy 127.26873 -294.1828) (xy 127.272801 -294.127178)
			(xy 127.284927 -294.072741) (xy 127.30485 -294.02065) (xy 127.332146 -293.972015) (xy 127.366232 -293.927872)
			(xy 127.406381 -293.889163) (xy 127.451739 -293.856712) (xy 127.501339 -293.831211) (xy 127.554123 -293.813204)
			(xy 127.608966 -293.803074) (xy 127.6647 -293.801037) (xy 127.720137 -293.807137) (xy 127.774094 -293.821243)
			(xy 127.825423 -293.843055) (xy 127.873029 -293.872109) (xy 127.915897 -293.907784) (xy 127.953114 -293.949321)
			(xy 127.983887 -293.995834) (xy 128.007559 -294.046331) (xy 128.023627 -294.099738) (xy 128.031747 -294.154914)
			(xy 128.032256 -294.1828) (xy 128.031747 -294.210686) (xy 128.023627 -294.265862) (xy 128.007559 -294.319269)
			(xy 127.983887 -294.369766) (xy 127.953114 -294.416279) (xy 127.915897 -294.457816) (xy 127.873029 -294.493491)
			(xy 127.825423 -294.522545) (xy 127.774094 -294.544357) (xy 127.720137 -294.558463) (xy 127.6647 -294.564563)
			(xy 127.608966 -294.562526) (xy 127.554123 -294.552396) (xy 127.501339 -294.534389) (xy 127.451739 -294.508888)
			(xy 127.406381 -294.476437) (xy 127.366232 -294.437728) (xy 127.332146 -294.393585) (xy 127.30485 -294.34495)
			(xy 127.284927 -294.292859) (xy 127.272801 -294.238422) (xy 127.26873 -294.1828) (xy 125.55728 -294.1828)
			(xy 125.55728 -294.787066) (xy 125.557886 -294.799108) (xy 125.568772 -294.820581) (xy 125.578108 -294.828214)
			(xy 125.654816 -294.883586) (xy 125.6792 -294.887396) (xy 125.69063 -294.883332) (xy 125.71984 -294.874301)
			(xy 125.780203 -294.864607) (xy 125.810772 -294.864028) (xy 125.838025 -294.864489) (xy 125.891977 -294.872243)
			(xy 125.944276 -294.887597) (xy 125.993858 -294.910239) (xy 126.039712 -294.939707) (xy 126.080905 -294.975401)
			(xy 126.116598 -295.016595) (xy 126.146065 -295.062449) (xy 126.168705 -295.112031) (xy 126.184058 -295.164331)
			(xy 126.191811 -295.218283) (xy 126.19228 -295.245536) (xy 126.191806 -295.272905) (xy 126.183977 -295.32708)
			(xy 126.168485 -295.379581) (xy 126.145649 -295.429328) (xy 126.115937 -295.4753) (xy 126.0983 -295.496234)
			(xy 126.092204 -295.503346) (xy 126.085854 -295.520364) (xy 126.085854 -295.605708) (xy 126.092204 -295.622726)
			(xy 126.0983 -295.629838) (xy 126.115937 -295.650771) (xy 126.145655 -295.696739) (xy 126.168493 -295.746484)
			(xy 126.183984 -295.798983) (xy 126.191807 -295.853158) (xy 126.191804 -295.907896) (xy 126.183972 -295.96207)
			(xy 126.168474 -296.014567) (xy 126.145628 -296.064309) (xy 126.115904 -296.110272) (xy 126.0983 -296.131234)
			(xy 126.092204 -296.138346) (xy 126.085854 -296.155364) (xy 126.085854 -296.240708) (xy 126.092204 -296.257726)
			(xy 126.0983 -296.264838) (xy 126.115937 -296.285771) (xy 126.145655 -296.331739) (xy 126.168493 -296.381484)
			(xy 126.183984 -296.433983) (xy 126.191807 -296.488158) (xy 126.191804 -296.542896) (xy 126.183972 -296.59707)
			(xy 126.168474 -296.649567) (xy 126.145628 -296.699309) (xy 126.115904 -296.745272) (xy 126.0983 -296.766234)
			(xy 126.092204 -296.773346) (xy 126.085854 -296.790364) (xy 126.085854 -296.875708) (xy 126.092204 -296.892726)
			(xy 126.0983 -296.899838) (xy 126.115937 -296.920771) (xy 126.145655 -296.966739) (xy 126.168493 -297.016484)
			(xy 126.183984 -297.068983) (xy 126.191807 -297.123158) (xy 126.191804 -297.177896) (xy 126.183972 -297.23207)
			(xy 126.168474 -297.284567) (xy 126.145628 -297.334309) (xy 126.115904 -297.380272) (xy 126.0983 -297.401234)
			(xy 126.092204 -297.408346) (xy 126.085854 -297.425364) (xy 126.085854 -297.510708) (xy 126.092204 -297.527726)
			(xy 126.0983 -297.534838) (xy 126.115937 -297.555771) (xy 126.145655 -297.601739) (xy 126.168493 -297.651484)
			(xy 126.183984 -297.703983) (xy 126.191807 -297.758158) (xy 126.191804 -297.812896) (xy 126.183972 -297.86707)
			(xy 126.168474 -297.919567) (xy 126.145628 -297.969309) (xy 126.115904 -298.015272) (xy 126.0983 -298.036234)
			(xy 126.092204 -298.043346) (xy 126.085854 -298.060364) (xy 126.085854 -298.145708) (xy 126.092204 -298.162726)
			(xy 126.0983 -298.169838) (xy 126.11594 -298.19077) (xy 126.145661 -298.236737) (xy 126.1685 -298.286485)
			(xy 126.183985 -298.338988) (xy 126.191798 -298.393166) (xy 126.19228 -298.420536) (xy 127.221996 -298.420536)
			(xy 127.222484 -298.393167) (xy 127.230297 -298.338988) (xy 127.245781 -298.286486) (xy 127.268618 -298.236738)
			(xy 127.298337 -298.190771) (xy 127.315976 -298.169838) (xy 127.322072 -298.162726) (xy 127.328422 -298.145708)
			(xy 127.328422 -298.060364) (xy 127.322072 -298.043346) (xy 127.315976 -298.036234) (xy 127.298369 -298.015274)
			(xy 127.268639 -297.969312) (xy 127.245788 -297.91957) (xy 127.230287 -297.867072) (xy 127.222454 -297.812897)
			(xy 127.22245 -297.758158) (xy 127.230275 -297.703981) (xy 127.245769 -297.65148) (xy 127.268612 -297.601736)
			(xy 127.298336 -297.55577) (xy 127.315976 -297.534838) (xy 127.322072 -297.527726) (xy 127.328422 -297.510708)
			(xy 127.328422 -297.425364) (xy 127.322072 -297.408346) (xy 127.315976 -297.401234) (xy 127.298369 -297.380274)
			(xy 127.268639 -297.334312) (xy 127.245788 -297.28457) (xy 127.230287 -297.232072) (xy 127.222454 -297.177897)
			(xy 127.22245 -297.123158) (xy 127.230275 -297.068981) (xy 127.245769 -297.01648) (xy 127.268612 -296.966736)
			(xy 127.298336 -296.92077) (xy 127.315976 -296.899838) (xy 127.322072 -296.892726) (xy 127.328422 -296.875708)
			(xy 127.328422 -296.790364) (xy 127.322072 -296.773346) (xy 127.315976 -296.766234) (xy 127.298369 -296.745274)
			(xy 127.268639 -296.699312) (xy 127.245788 -296.64957) (xy 127.230287 -296.597072) (xy 127.222454 -296.542897)
			(xy 127.22245 -296.488158) (xy 127.230275 -296.433981) (xy 127.245769 -296.38148) (xy 127.268612 -296.331736)
			(xy 127.298336 -296.28577) (xy 127.315976 -296.264838) (xy 127.322072 -296.257726) (xy 127.328422 -296.240708)
			(xy 127.328422 -296.155364) (xy 127.322072 -296.138346) (xy 127.315976 -296.131234) (xy 127.298369 -296.110274)
			(xy 127.268639 -296.064312) (xy 127.245788 -296.01457) (xy 127.230287 -295.962072) (xy 127.222454 -295.907897)
			(xy 127.22245 -295.853158) (xy 127.230275 -295.798981) (xy 127.245769 -295.74648) (xy 127.268612 -295.696736)
			(xy 127.298336 -295.65077) (xy 127.315976 -295.629838) (xy 127.322072 -295.622726) (xy 127.328422 -295.605708)
			(xy 127.328422 -295.520364) (xy 127.322072 -295.503346) (xy 127.315976 -295.496234) (xy 127.298336 -295.475303)
			(xy 127.268625 -295.42933) (xy 127.24579 -295.379582) (xy 127.230299 -295.327081) (xy 127.22247 -295.272905)
			(xy 127.221996 -295.245536) (xy 127.222489 -295.218284) (xy 127.230241 -295.164334) (xy 127.245593 -295.112036)
			(xy 127.268231 -295.062456) (xy 127.297696 -295.016602) (xy 127.333387 -294.975409) (xy 127.374577 -294.939715)
			(xy 127.420428 -294.910247) (xy 127.470006 -294.887604) (xy 127.522302 -294.872248) (xy 127.576252 -294.864491)
			(xy 127.603504 -294.864028) (xy 127.630875 -294.864485) (xy 127.685054 -294.872304) (xy 127.737558 -294.887795)
			(xy 127.787305 -294.910639) (xy 127.833271 -294.940366) (xy 127.854202 -294.958008) (xy 127.861314 -294.964104)
			(xy 127.878332 -294.970454) (xy 127.963676 -294.970454) (xy 127.980694 -294.964104) (xy 127.987806 -294.958008)
			(xy 128.008726 -294.940354) (xy 128.054702 -294.910644) (xy 128.104453 -294.887811) (xy 128.156956 -294.872323)
			(xy 128.211134 -294.8645) (xy 128.238504 -294.864028) (xy 128.265759 -294.864452) (xy 128.319713 -294.87221)
			(xy 128.372014 -294.887569) (xy 128.421596 -294.910214) (xy 128.467451 -294.939686) (xy 128.508645 -294.975384)
			(xy 128.544338 -295.016581) (xy 128.573805 -295.062439) (xy 128.596445 -295.112024) (xy 128.611798 -295.164326)
			(xy 128.619551 -295.218281) (xy 128.620012 -295.245536) (xy 128.619564 -295.272907) (xy 128.611741 -295.327087)
			(xy 128.596248 -295.37959) (xy 128.573402 -295.429336) (xy 128.543675 -295.475303) (xy 128.526032 -295.496234)
			(xy 128.519936 -295.503346) (xy 128.513586 -295.520364) (xy 128.513586 -295.605708) (xy 128.519936 -295.622726)
			(xy 128.526032 -295.629838) (xy 128.54371 -295.650741) (xy 128.573436 -295.696713) (xy 128.596282 -295.746464)
			(xy 128.611777 -295.798971) (xy 128.619603 -295.853154) (xy 128.619599 -295.9079) (xy 128.611766 -295.962082)
			(xy 128.596263 -296.014587) (xy 128.57341 -296.064334) (xy 128.543677 -296.110302) (xy 128.526032 -296.131234)
			(xy 128.519936 -296.138346) (xy 128.513586 -296.155364) (xy 128.513586 -296.240708) (xy 128.519936 -296.257726)
			(xy 128.526032 -296.264838) (xy 128.54371 -296.285741) (xy 128.573436 -296.331713) (xy 128.596282 -296.381464)
			(xy 128.611777 -296.433971) (xy 128.619603 -296.488154) (xy 128.619599 -296.5429) (xy 128.611766 -296.597082)
			(xy 128.596263 -296.649587) (xy 128.57341 -296.699334) (xy 128.543677 -296.745302) (xy 128.526032 -296.766234)
			(xy 128.519936 -296.773346) (xy 128.513586 -296.790364) (xy 128.513586 -296.875708) (xy 128.519936 -296.892726)
			(xy 128.526032 -296.899838) (xy 128.54371 -296.920741) (xy 128.573436 -296.966713) (xy 128.596282 -297.016464)
			(xy 128.611777 -297.068971) (xy 128.619603 -297.123154) (xy 128.619599 -297.1779) (xy 128.611766 -297.232082)
			(xy 128.596263 -297.284587) (xy 128.57341 -297.334334) (xy 128.543677 -297.380302) (xy 128.526032 -297.401234)
			(xy 128.519936 -297.408346) (xy 128.513586 -297.425364) (xy 128.513586 -297.510708) (xy 128.519936 -297.527726)
			(xy 128.526032 -297.534838) (xy 128.54371 -297.555741) (xy 128.573436 -297.601713) (xy 128.596282 -297.651464)
			(xy 128.611777 -297.703971) (xy 128.619603 -297.758154) (xy 128.619599 -297.8129) (xy 128.611766 -297.867082)
			(xy 128.596263 -297.919587) (xy 128.57341 -297.969334) (xy 128.543677 -298.015302) (xy 128.526032 -298.036234)
			(xy 128.519936 -298.043346) (xy 128.513586 -298.060364) (xy 128.513586 -298.145708) (xy 128.519936 -298.162726)
			(xy 128.526032 -298.169838) (xy 128.54366 -298.190779) (xy 128.573373 -298.23675) (xy 128.59621 -298.286495)
			(xy 128.611704 -298.338994) (xy 128.619536 -298.393167) (xy 128.620012 -298.420536) (xy 128.619556 -298.447788)
			(xy 128.611794 -298.501737) (xy 128.596435 -298.554032) (xy 128.57379 -298.603609) (xy 128.54432 -298.649459)
			(xy 128.508626 -298.690648) (xy 128.467433 -298.726339) (xy 128.421581 -298.755805) (xy 128.372002 -298.778446)
			(xy 128.319705 -298.793801) (xy 128.265756 -298.801558) (xy 128.238504 -298.802044) (xy 128.211133 -298.801589)
			(xy 128.156953 -298.793771) (xy 128.104449 -298.77828) (xy 128.054703 -298.755435) (xy 128.008737 -298.725707)
			(xy 127.987806 -298.708064) (xy 127.980694 -298.701968) (xy 127.963676 -298.695618) (xy 127.878332 -298.695618)
			(xy 127.861314 -298.701968) (xy 127.854202 -298.708064) (xy 127.833275 -298.72571) (xy 127.787302 -298.755422)
			(xy 127.737553 -298.778257) (xy 127.685051 -298.793747) (xy 127.630874 -298.801572) (xy 127.603504 -298.802044)
			(xy 127.576254 -298.801519) (xy 127.52231 -298.793764) (xy 127.470018 -298.778411) (xy 127.420443 -298.755773)
			(xy 127.374595 -298.72631) (xy 127.333405 -298.690623) (xy 127.297714 -298.649437) (xy 127.268246 -298.603592)
			(xy 127.245603 -298.554019) (xy 127.230245 -298.501729) (xy 127.222484 -298.447785) (xy 127.221996 -298.420536)
			(xy 126.19228 -298.420536) (xy 126.191791 -298.447785) (xy 126.18403 -298.501727) (xy 126.168672 -298.554016)
			(xy 126.146028 -298.603587) (xy 126.116561 -298.649431) (xy 126.080869 -298.690614) (xy 126.039679 -298.726299)
			(xy 125.99383 -298.755759) (xy 125.944256 -298.778394) (xy 125.891964 -298.793744) (xy 125.838021 -298.801496)
			(xy 125.810772 -298.802044) (xy 125.783403 -298.80157) (xy 125.729228 -298.793742) (xy 125.676727 -298.77825)
			(xy 125.626981 -298.755412) (xy 125.58101 -298.725699) (xy 125.560074 -298.708064) (xy 125.552962 -298.701968)
			(xy 125.535944 -298.695618) (xy 125.4506 -298.695618) (xy 125.433582 -298.701968) (xy 125.42647 -298.708064)
			(xy 125.405539 -298.725706) (xy 125.359572 -298.755431) (xy 125.309825 -298.778272) (xy 125.257322 -298.79376)
			(xy 125.203142 -298.801575) (xy 125.175772 -298.802044) (xy 125.148521 -298.801556) (xy 125.094575 -298.793797)
			(xy 125.042281 -298.77844) (xy 124.992705 -298.755797) (xy 124.946856 -298.726331) (xy 124.905666 -298.69064)
			(xy 124.869974 -298.649451) (xy 124.840506 -298.603602) (xy 124.817863 -298.554026) (xy 124.802505 -298.501733)
			(xy 124.794744 -298.447787) (xy 124.794264 -298.420536) (xy 124.79474 -298.393168) (xy 124.802573 -298.338995)
			(xy 124.81807 -298.286498) (xy 124.840911 -298.236755) (xy 124.870627 -298.190788) (xy 124.888244 -298.169838)
			(xy 124.89434 -298.162726) (xy 124.90069 -298.145708) (xy 124.90069 -298.060364) (xy 124.89434 -298.043346)
			(xy 124.888244 -298.036234) (xy 124.8706 -298.015302) (xy 124.840869 -297.969333) (xy 124.818017 -297.919586)
			(xy 124.802516 -297.867081) (xy 124.794682 -297.8129) (xy 124.794679 -297.758155) (xy 124.802504 -297.703972)
			(xy 124.817998 -297.651465) (xy 124.840843 -297.601714) (xy 124.870567 -297.555742) (xy 124.888244 -297.534838)
			(xy 124.89434 -297.527726) (xy 124.90069 -297.510708) (xy 124.90069 -297.425364) (xy 124.89434 -297.408346)
			(xy 124.888244 -297.401234) (xy 124.8706 -297.380302) (xy 124.840869 -297.334333) (xy 124.818017 -297.284586)
			(xy 124.802516 -297.232081) (xy 124.794682 -297.1779) (xy 124.794679 -297.123155) (xy 124.802504 -297.068972)
			(xy 124.817998 -297.016465) (xy 124.840843 -296.966714) (xy 124.870567 -296.920742) (xy 124.888244 -296.899838)
			(xy 124.89434 -296.892726) (xy 124.90069 -296.875708) (xy 124.90069 -296.790364) (xy 124.89434 -296.773346)
			(xy 124.888244 -296.766234) (xy 124.8706 -296.745302) (xy 124.840869 -296.699333) (xy 124.818017 -296.649586)
			(xy 124.802516 -296.597081) (xy 124.794682 -296.5429) (xy 124.794679 -296.488155) (xy 124.802504 -296.433972)
			(xy 124.817998 -296.381465) (xy 124.840843 -296.331714) (xy 124.870567 -296.285742) (xy 124.888244 -296.264838)
			(xy 124.89434 -296.257726) (xy 124.90069 -296.240708) (xy 124.90069 -296.155364) (xy 124.89434 -296.138346)
			(xy 124.888244 -296.131234) (xy 124.8706 -296.110302) (xy 124.840869 -296.064333) (xy 124.818017 -296.014586)
			(xy 124.802516 -295.962081) (xy 124.794682 -295.9079) (xy 124.794679 -295.853155) (xy 124.802504 -295.798972)
			(xy 124.817998 -295.746465) (xy 124.840843 -295.696714) (xy 124.870567 -295.650742) (xy 124.888244 -295.629838)
			(xy 124.89434 -295.622726) (xy 124.90069 -295.605708) (xy 124.900944 -295.52011) (xy 124.894594 -295.503346)
			(xy 124.888244 -295.496234) (xy 124.870598 -295.475304) (xy 124.840865 -295.429339) (xy 124.818014 -295.379593)
			(xy 124.802518 -295.327089) (xy 124.794693 -295.272908) (xy 124.794264 -295.245536) (xy 124.794264 -283.316934)
			(xy 124.794819 -283.286953) (xy 124.804198 -283.227729) (xy 124.82273 -283.170702) (xy 124.849959 -283.117279)
			(xy 124.885213 -283.068775) (xy 124.906024 -283.047186) (xy 125.436884 -282.51658) (xy 125.443922 -282.508906)
			(xy 125.451646 -282.489592) (xy 125.451019 -282.4688) (xy 125.447044 -282.459176) (xy 125.3998 -282.35783)
			(xy 125.372368 -282.342082) (xy 125.356112 -282.343352) (xy 125.322838 -282.344876) (xy 125.295586 -282.344415)
			(xy 125.241635 -282.336663) (xy 125.189337 -282.321312) (xy 125.139756 -282.298674) (xy 125.093902 -282.269209)
			(xy 125.052709 -282.233518) (xy 125.017014 -282.192328) (xy 124.987545 -282.146477) (xy 124.964901 -282.096899)
			(xy 124.949545 -282.044602) (xy 124.941787 -281.990652) (xy 124.941787 -281.936148) (xy 124.949545 -281.882198)
			(xy 124.964901 -281.829901) (xy 124.987545 -281.780323) (xy 125.017014 -281.734472) (xy 125.052709 -281.693282)
			(xy 125.093902 -281.657591) (xy 125.139756 -281.628126) (xy 125.189337 -281.605488) (xy 125.241635 -281.590137)
			(xy 125.295586 -281.582385) (xy 125.322838 -281.58186) (xy 125.351459 -281.582373) (xy 125.408059 -281.590921)
			(xy 125.462749 -281.60782) (xy 125.514305 -281.632691) (xy 125.53823 -281.648408) (xy 125.549914 -281.656536)
			(xy 125.577854 -281.65806) (xy 125.670056 -281.609546) (xy 125.677985 -281.604857) (xy 125.690117 -281.591014)
			(xy 125.696613 -281.573791) (xy 125.69698 -281.564588) (xy 125.69698 -280.999692) (xy 125.697466 -280.972441)
			(xy 125.705222 -280.918493) (xy 125.720577 -280.866198) (xy 125.743219 -280.816621) (xy 125.772685 -280.770771)
			(xy 125.808376 -280.72958) (xy 125.849567 -280.693889) (xy 125.895417 -280.664423) (xy 125.944994 -280.641781)
			(xy 125.997289 -280.626426) (xy 126.051237 -280.61867) (xy 126.105739 -280.61867) (xy 126.159687 -280.626426)
			(xy 126.211982 -280.641781) (xy 126.261559 -280.664423) (xy 126.307409 -280.693889) (xy 126.3486 -280.72958)
			(xy 126.384291 -280.770771) (xy 126.413757 -280.816621) (xy 126.436399 -280.866198) (xy 126.451754 -280.918493)
			(xy 126.45951 -280.972441) (xy 126.459996 -280.999692) (xy 126.459996 -282.414218) (xy 126.459444 -282.4442)
			(xy 126.450071 -282.503427) (xy 126.431542 -282.560458) (xy 126.404316 -282.613885) (xy 126.369063 -282.662391)
			(xy 126.348236 -282.683966) (xy 126.148338 -282.883864) (xy 126.14134 -282.891456) (xy 126.13359 -282.910573)
			(xy 126.134037 -282.931196) (xy 126.137924 -282.94076) (xy 126.183898 -283.041852) (xy 126.21133 -283.058108)
			(xy 126.227078 -283.057092) (xy 126.254002 -283.056076) (xy 126.281254 -283.056562) (xy 126.335202 -283.064319)
			(xy 126.387497 -283.079674) (xy 126.437075 -283.102315) (xy 126.482927 -283.131781) (xy 126.524118 -283.167472)
			(xy 126.559811 -283.208662) (xy 126.589279 -283.254512) (xy 126.611921 -283.304089) (xy 126.627278 -283.356384)
			(xy 126.635037 -283.410332) (xy 126.63551 -283.437584) (xy 126.634928 -283.468153) (xy 126.625235 -283.528516)
			(xy 126.616206 -283.557726) (xy 126.612142 -283.569156) (xy 126.615952 -283.59354) (xy 126.671324 -283.670248)
			(xy 126.67898 -283.679546) (xy 126.700446 -283.690398) (xy 126.712472 -283.691076) (xy 127.452374 -283.691076)
			(xy 127.482355 -283.691632) (xy 127.541578 -283.701012) (xy 127.598603 -283.719546) (xy 127.652026 -283.746776)
			(xy 127.700528 -283.782031) (xy 127.722122 -283.802836) (xy 128.23698 -284.317948) (xy 128.244406 -284.324724)
			(xy 128.263002 -284.332317) (xy 128.273048 -284.33268) (xy 128.284478 -284.33268) (xy 128.295199 -284.332255)
			(xy 128.314792 -284.323559) (xy 128.322324 -284.315916) (xy 128.380236 -284.250892) (xy 128.386586 -284.230572)
			(xy 128.385316 -284.219396) (xy 128.384126 -284.20845) (xy 128.382856 -284.186465) (xy 128.382776 -284.175454)
			(xy 128.383341 -284.145329) (xy 128.392807 -284.085827) (xy 128.411513 -284.028554) (xy 128.438992 -283.974935)
			(xy 128.474561 -283.926305) (xy 128.495552 -283.90469) (xy 128.502918 -283.897578) (xy 128.510538 -283.878782)
			(xy 128.510538 -283.786326) (xy 128.502918 -283.76753) (xy 128.495552 -283.760418) (xy 128.474575 -283.738793)
			(xy 128.43902 -283.690158) (xy 128.411549 -283.63654) (xy 128.392843 -283.579272) (xy 128.383369 -283.519777)
			(xy 128.382776 -283.489654) (xy 128.383373 -283.459817) (xy 128.392684 -283.400873) (xy 128.401318 -283.372306)
			(xy 128.40462 -283.361892) (xy 128.402334 -283.340302) (xy 128.352296 -283.25572) (xy 128.334516 -283.243274)
			(xy 128.323848 -283.241242) (xy 128.295999 -283.235368) (xy 128.242315 -283.216466) (xy 128.192037 -283.189794)
			(xy 128.146284 -283.155944) (xy 128.10607 -283.115668) (xy 128.072291 -283.069862) (xy 128.045697 -283.019544)
			(xy 128.026878 -282.965831) (xy 128.02108 -282.937966) (xy 128.01854 -282.925774) (xy 128.002792 -282.905962)
			(xy 127.902716 -282.862528) (xy 127.87757 -282.86456) (xy 127.866902 -282.871164) (xy 127.843909 -282.885157)
			(xy 127.79483 -282.907254) (xy 127.743137 -282.922248) (xy 127.689852 -282.929845) (xy 127.66294 -282.930346)
			(xy 127.644922 -282.93011) (xy 127.609048 -282.926674) (xy 127.591312 -282.923488) (xy 127.581914 -282.92171)
			(xy 127.562864 -282.92552) (xy 127.48768 -282.973272) (xy 127.47625 -282.98902) (xy 127.473964 -282.998418)
			(xy 127.46658 -283.025468) (xy 127.444966 -283.077205) (xy 127.41601 -283.12522) (xy 127.380336 -283.168478)
			(xy 127.338713 -283.206047) (xy 127.292039 -283.237117) (xy 127.241318 -283.261019) (xy 127.187645 -283.277238)
			(xy 127.132175 -283.285424) (xy 127.10414 -283.285946) (xy 127.076884 -283.285486) (xy 127.022927 -283.277734)
			(xy 126.970622 -283.262382) (xy 126.921034 -283.239742) (xy 126.875173 -283.210275) (xy 126.833973 -283.174582)
			(xy 126.798271 -283.133389) (xy 126.768796 -283.087534) (xy 126.746146 -283.037951) (xy 126.730783 -282.985649)
			(xy 126.72302 -282.931694) (xy 126.722632 -282.904438) (xy 126.723116 -282.876862) (xy 126.731053 -282.822285)
			(xy 126.746766 -282.76942) (xy 126.769928 -282.719369) (xy 126.800057 -282.673175) (xy 126.836524 -282.631801)
			(xy 126.857252 -282.613608) (xy 126.865377 -282.606014) (xy 126.874708 -282.585855) (xy 126.875286 -282.574746)
			(xy 126.875286 -282.49753) (xy 126.874718 -282.486425) (xy 126.86536 -282.46628) (xy 126.857252 -282.458668)
			(xy 126.836541 -282.440454) (xy 126.800068 -282.399083) (xy 126.769932 -282.352892) (xy 126.746761 -282.302843)
			(xy 126.731039 -282.249978) (xy 126.723094 -282.195401) (xy 126.72309 -282.140248) (xy 126.731029 -282.08567)
			(xy 126.746744 -282.032803) (xy 126.769908 -281.982751) (xy 126.800038 -281.936556) (xy 126.836506 -281.895181)
			(xy 126.857252 -281.877008) (xy 126.865377 -281.869414) (xy 126.874708 -281.849255) (xy 126.875286 -281.838146)
			(xy 126.875286 -281.76093) (xy 126.874718 -281.749825) (xy 126.86536 -281.72968) (xy 126.857252 -281.722068)
			(xy 126.836547 -281.703852) (xy 126.800083 -281.66248) (xy 126.769956 -281.61629) (xy 126.746792 -281.566243)
			(xy 126.731074 -281.513383) (xy 126.723129 -281.458812) (xy 126.722632 -281.431238) (xy 126.723093 -281.403984)
			(xy 126.730846 -281.350032) (xy 126.746199 -281.297731) (xy 126.76884 -281.248149) (xy 126.798307 -281.202294)
			(xy 126.834001 -281.1611) (xy 126.875196 -281.125406) (xy 126.921051 -281.095939) (xy 126.970633 -281.073298)
			(xy 127.022933 -281.057945) (xy 127.076886 -281.050193) (xy 127.10414 -281.04973) (xy 127.132 -281.050232)
			(xy 127.187129 -281.058328) (xy 127.240495 -281.074356) (xy 127.290961 -281.097975) (xy 127.337456 -281.128683)
			(xy 127.37899 -281.165827) (xy 127.41468 -281.208617) (xy 127.443766 -281.256143) (xy 127.465631 -281.307394)
			(xy 127.473202 -281.33421) (xy 127.475488 -281.3431) (xy 127.486156 -281.35834) (xy 127.558038 -281.406092)
			(xy 127.576072 -281.410156) (xy 127.585216 -281.408886) (xy 127.598231 -281.407202) (xy 127.624417 -281.405422)
			(xy 127.63754 -281.40533) (xy 127.650663 -281.405436) (xy 127.676848 -281.407215) (xy 127.689864 -281.408886)
			(xy 127.699008 -281.410156) (xy 127.717042 -281.406092) (xy 127.788924 -281.35834) (xy 127.799592 -281.3431)
			(xy 127.801878 -281.33421) (xy 127.809471 -281.307405) (xy 127.831357 -281.256173) (xy 127.860455 -281.208665)
			(xy 127.896149 -281.165891) (xy 127.937679 -281.128756) (xy 127.984164 -281.098051) (xy 128.034618 -281.074427)
			(xy 128.087969 -281.058386) (xy 128.143085 -281.050267) (xy 128.17094 -281.04973) (xy 128.198188 -281.050219)
			(xy 128.25213 -281.05798) (xy 128.304417 -281.073339) (xy 128.353987 -281.095983) (xy 128.39983 -281.125451)
			(xy 128.441012 -281.161143) (xy 128.476696 -281.202333) (xy 128.506154 -281.248181) (xy 128.528788 -281.297756)
			(xy 128.544136 -281.350047) (xy 128.551887 -281.40399) (xy 128.552448 -281.431238) (xy 128.55198 -281.458536)
			(xy 128.544194 -281.512575) (xy 128.528788 -281.564954) (xy 128.506074 -281.614602) (xy 128.476518 -281.660507)
			(xy 128.458976 -281.681428) (xy 128.452626 -281.688794) (xy 128.446276 -281.706574) (xy 128.449832 -281.795982)
			(xy 128.457452 -281.813254) (xy 128.46431 -281.820112) (xy 128.485419 -281.84176) (xy 128.52121 -281.890489)
			(xy 128.548871 -281.944252) (xy 128.567708 -282.001704) (xy 128.577251 -282.061407) (xy 128.577848 -282.091638)
			(xy 128.577361 -282.119278) (xy 128.569386 -282.173979) (xy 128.553595 -282.226955) (xy 128.530318 -282.277095)
			(xy 128.500044 -282.323348) (xy 128.48209 -282.344368) (xy 128.473708 -282.35402) (xy 128.467866 -282.378404)
			(xy 128.495044 -282.484576) (xy 128.512062 -282.503118) (xy 128.524 -282.507436) (xy 128.551407 -282.517775)
			(xy 128.602923 -282.545652) (xy 128.649569 -282.581082) (xy 128.690245 -282.62323) (xy 128.723996 -282.671104)
			(xy 128.750026 -282.723578) (xy 128.767722 -282.779416) (xy 128.776668 -282.837304) (xy 128.777238 -282.866592)
			(xy 128.776689 -282.893855) (xy 129.106847 -282.893855) (xy 129.106847 -282.839345) (xy 129.114605 -282.785391)
			(xy 129.129963 -282.733089) (xy 129.152608 -282.683506) (xy 129.18208 -282.637651) (xy 129.217777 -282.596456)
			(xy 129.258975 -282.560762) (xy 129.304832 -282.531294) (xy 129.354417 -282.508653) (xy 129.40672 -282.493299)
			(xy 129.460675 -282.485545) (xy 129.48793 -282.485084) (xy 129.515302 -282.485512) (xy 129.569483 -282.493336)
			(xy 129.621988 -282.508833) (xy 129.671734 -282.531683) (xy 129.717698 -282.561418) (xy 129.738628 -282.579064)
			(xy 129.74574 -282.58516) (xy 129.762758 -282.59151) (xy 129.848102 -282.59151) (xy 129.86512 -282.58516)
			(xy 129.872232 -282.579064) (xy 129.893174 -282.561438) (xy 129.939145 -282.531725) (xy 129.98889 -282.508887)
			(xy 130.041388 -282.493393) (xy 130.095562 -282.485561) (xy 130.12293 -282.485084) (xy 130.150179 -282.485588)
			(xy 130.204123 -282.493348) (xy 130.256413 -282.508705) (xy 130.305985 -282.531347) (xy 130.351831 -282.560814)
			(xy 130.393017 -282.596505) (xy 130.428704 -282.637693) (xy 130.458167 -282.683541) (xy 130.480805 -282.733115)
			(xy 130.496159 -282.785407) (xy 130.503914 -282.839351) (xy 130.503914 -282.893849) (xy 130.496159 -282.947793)
			(xy 130.480805 -283.000085) (xy 130.458167 -283.049659) (xy 130.428704 -283.095507) (xy 130.393017 -283.136695)
			(xy 130.351831 -283.172386) (xy 130.305985 -283.201853) (xy 130.256413 -283.224495) (xy 130.204123 -283.239852)
			(xy 130.150179 -283.247612) (xy 130.12293 -283.2481) (xy 130.09556 -283.247616) (xy 130.041382 -283.239803)
			(xy 129.988879 -283.224318) (xy 129.939132 -283.20148) (xy 129.893164 -283.171759) (xy 129.872232 -283.15412)
			(xy 129.86512 -283.148024) (xy 129.848102 -283.141674) (xy 129.762758 -283.141674) (xy 129.74574 -283.148024)
			(xy 129.738628 -283.15412) (xy 129.717699 -283.171763) (xy 129.671725 -283.201473) (xy 129.621977 -283.224308)
			(xy 129.569475 -283.239798) (xy 129.515299 -283.247626) (xy 129.48793 -283.2481) (xy 129.460675 -283.247655)
			(xy 129.40672 -283.239901) (xy 129.354417 -283.224547) (xy 129.304832 -283.201906) (xy 129.258975 -283.172438)
			(xy 129.217777 -283.136744) (xy 129.18208 -283.095549) (xy 129.152608 -283.049694) (xy 129.129963 -283.000111)
			(xy 129.114605 -282.947809) (xy 129.106847 -282.893855) (xy 128.776689 -282.893855) (xy 128.776637 -282.896428)
			(xy 128.76732 -282.955371) (xy 128.758696 -282.98394) (xy 128.755394 -282.994354) (xy 128.75768 -283.015944)
			(xy 128.807718 -283.100526) (xy 128.825498 -283.112972) (xy 128.836166 -283.115004) (xy 128.861969 -283.120406)
			(xy 128.911883 -283.13737) (xy 128.958987 -283.161044) (xy 129.002382 -283.190978) (xy 129.041242 -283.226602)
			(xy 129.074828 -283.267236) (xy 129.102499 -283.312108) (xy 129.123729 -283.360362) (xy 129.138113 -283.41108)
			(xy 129.145378 -283.463295) (xy 129.145792 -283.489654) (xy 129.145226 -283.519779) (xy 129.135761 -283.579282)
			(xy 129.117057 -283.636556) (xy 129.089581 -283.690177) (xy 129.054016 -283.738811) (xy 129.033016 -283.760418)
			(xy 129.02565 -283.76753) (xy 129.01803 -283.786326) (xy 129.01803 -283.878782) (xy 129.02565 -283.897578)
			(xy 129.033016 -283.90469) (xy 129.053656 -283.925974) (xy 129.088766 -283.973744) (xy 129.116076 -284.026365)
			(xy 129.134931 -284.082572) (xy 129.140458 -284.1117) (xy 129.142744 -284.125924) (xy 129.161286 -284.14726)
			(xy 129.261108 -284.179264) (xy 129.270095 -284.181652) (xy 129.28864 -284.180521) (xy 129.305562 -284.17285)
			(xy 129.312416 -284.166564) (xy 130.03276 -283.44622) (xy 130.054374 -283.42544) (xy 130.102879 -283.3902)
			(xy 130.156298 -283.362978) (xy 130.213316 -283.344444) (xy 130.272531 -283.335055) (xy 130.302508 -283.33446)
			(xy 132.787136 -283.33446) (xy 132.802124 -283.334634) (xy 132.832004 -283.33705) (xy 132.846826 -283.339286)
			(xy 132.856732 -283.34081) (xy 132.875528 -283.336492) (xy 132.949696 -283.28493) (xy 132.960364 -283.268674)
			(xy 132.962142 -283.259022) (xy 132.96814 -283.231622) (xy 132.987102 -283.178836) (xy 133.013597 -283.1294)
			(xy 133.047052 -283.084381) (xy 133.066536 -283.064204) (xy 133.842506 -282.288234) (xy 133.849342 -282.280832)
			(xy 133.857051 -282.262234) (xy 133.857492 -282.252166) (xy 133.857492 -282.250134) (xy 133.856787 -282.237979)
			(xy 133.845637 -282.216374) (xy 133.836156 -282.208732) (xy 133.82625 -282.201874) (xy 133.80212 -282.198318)
			(xy 133.783832 -282.204668) (xy 133.773164 -282.211526) (xy 133.768592 -282.216606) (xy 133.750421 -282.236403)
			(xy 133.709475 -282.271202) (xy 133.664048 -282.299905) (xy 133.61504 -282.321944) (xy 133.563422 -282.336881)
			(xy 133.510218 -282.344421) (xy 133.48335 -282.344876) (xy 133.456096 -282.344416) (xy 133.402141 -282.336665)
			(xy 133.349839 -282.321313) (xy 133.300255 -282.298673) (xy 133.254398 -282.269205) (xy 133.213201 -282.233511)
			(xy 133.177505 -282.192317) (xy 133.148036 -282.146461) (xy 133.125394 -282.096878) (xy 133.110039 -282.044577)
			(xy 133.102285 -281.990622) (xy 133.101842 -281.963368) (xy 133.102314 -281.936336) (xy 133.10995 -281.882814)
			(xy 133.125065 -281.830906) (xy 133.147355 -281.781651) (xy 133.176375 -281.736035) (xy 133.211544 -281.694973)
			(xy 133.252156 -281.659286) (xy 133.297399 -281.62969) (xy 133.346367 -281.606776) (xy 133.39808 -281.591003)
			(xy 133.4515 -281.582689) (xy 133.478524 -281.58186) (xy 133.483604 -281.58186) (xy 133.512077 -281.582408)
			(xy 133.568385 -281.590906) (xy 133.622808 -281.607668) (xy 133.674141 -281.632322) (xy 133.69798 -281.6479)
			(xy 133.698234 -281.648154) (xy 133.69925 -281.648662) (xy 133.705303 -281.652366) (xy 133.718836 -281.656617)
			(xy 133.72592 -281.657044) (xy 133.740144 -281.657298) (xy 133.806184 -281.622246) (xy 133.807962 -281.623262)
			(xy 133.8326 -281.60853) (xy 133.839978 -281.603732) (xy 133.851186 -281.59018) (xy 133.857149 -281.573635)
			(xy 133.857492 -281.564842) (xy 133.857492 -281.01671) (xy 133.857935 -280.989966) (xy 133.865395 -280.937002)
			(xy 133.880183 -280.8856) (xy 133.902009 -280.836769) (xy 133.930446 -280.791467) (xy 133.964934 -280.750584)
			(xy 134.004797 -280.714921) (xy 134.049253 -280.68518) (xy 134.097429 -280.661943) (xy 134.148379 -280.645667)
			(xy 134.201104 -280.63667) (xy 134.227824 -280.635456) (xy 134.23773 -280.635202) (xy 134.263447 -280.635537)
			(xy 134.314434 -280.642275) (xy 134.364055 -280.655801) (xy 134.411409 -280.675868) (xy 134.455639 -280.702114)
			(xy 134.495942 -280.734064) (xy 134.514082 -280.752296) (xy 134.521194 -280.759662) (xy 134.543292 -280.769314)
			(xy 134.547723 -280.771106) (xy 134.55706 -280.773147) (xy 134.561834 -280.773378) (xy 134.572502 -280.773886)
			(xy 134.634478 -280.749502) (xy 134.66445 -280.737564) (xy 134.673749 -280.733423) (xy 134.68831 -280.719222)
			(xy 134.696233 -280.700489) (xy 134.696708 -280.69032) (xy 134.696708 -279.041352) (xy 134.6963 -279.032157)
			(xy 134.689805 -279.014948) (xy 134.677691 -279.001107) (xy 134.669784 -278.996394) (xy 134.596443 -278.957006)
			(xy 134.453298 -278.871975) (xy 134.314516 -278.779997) (xy 134.180432 -278.681295) (xy 134.051372 -278.576109)
			(xy 133.92765 -278.464694) (xy 133.809566 -278.34732) (xy 133.697406 -278.224272) (xy 133.591443 -278.09585)
			(xy 133.491934 -277.962364) (xy 133.39912 -277.824139) (xy 133.313227 -277.681511) (xy 133.234463 -277.534825)
			(xy 133.16302 -277.384437) (xy 133.099071 -277.230713) (xy 133.04277 -277.074027) (xy 132.994256 -276.914757)
			(xy 132.953645 -276.753291) (xy 132.921036 -276.59002) (xy 132.896508 -276.425342) (xy 132.880121 -276.259656)
			(xy 132.871915 -276.093363) (xy 132.871464 -276.010116) (xy 132.871968 -275.927035) (xy 132.880134 -275.761073)
			(xy 132.896448 -275.595714) (xy 132.92087 -275.431356) (xy 132.953341 -275.268397) (xy 132.993783 -275.107232)
			(xy 133.042097 -274.948249) (xy 133.098167 -274.791832) (xy 133.161858 -274.638361) (xy 133.233015 -274.488206)
			(xy 133.311466 -274.34173) (xy 133.397023 -274.199287) (xy 133.489477 -274.061221) (xy 133.588605 -273.927867)
			(xy 133.694169 -273.799546) (xy 133.805912 -273.676569) (xy 133.923565 -273.559233) (xy 134.046843 -273.447821)
			(xy 134.175448 -273.342604) (xy 134.309069 -273.243835) (xy 134.447383 -273.151753) (xy 134.590056 -273.066581)
			(xy 134.66318 -273.02714) (xy 134.670038 -273.023584) (xy 136.241536 -271.452086) (xy 136.242044 -271.451578)
			(xy 136.248632 -271.444199) (xy 136.256095 -271.4259) (xy 136.256522 -271.416018) (xy 136.256522 -264.44829)
			(xy 136.256098 -264.43822) (xy 136.248383 -264.419616) (xy 136.241536 -264.412222) (xy 135.214868 -263.385554)
			(xy 135.207756 -263.378188) (xy 135.18896 -263.370568) (xy 132.728716 -263.370568) (xy 132.718653 -263.370129)
			(xy 132.700074 -263.362389) (xy 132.692648 -263.355582) (xy 131.28117 -261.944104) (xy 131.275582 -261.939278)
			(xy 131.266921 -261.933403) (xy 131.246589 -261.928529) (xy 131.236212 -261.92988) (xy 131.141724 -261.946898)
			(xy 131.122166 -261.962138) (xy 131.117086 -261.973568) (xy 131.10529 -261.998109) (xy 131.075776 -262.043865)
			(xy 131.040061 -262.084964) (xy 130.998869 -262.120572) (xy 130.953037 -262.149967) (xy 130.903493 -262.172552)
			(xy 130.851243 -262.187869) (xy 130.797346 -262.195608) (xy 130.770122 -262.196072) (xy 130.74321 -262.195611)
			(xy 130.689919 -262.188046) (xy 130.638222 -262.173064) (xy 130.589144 -262.150961) (xy 130.543662 -262.122177)
			(xy 130.502679 -262.087285) (xy 130.467009 -262.046977) (xy 130.437361 -262.002053) (xy 130.414324 -261.953408)
			(xy 130.405886 -261.927848) (xy 130.403854 -261.922006) (xy 130.397504 -261.911338) (xy 129.860802 -261.374636)
			(xy 129.84269 -261.355855) (xy 129.812008 -261.313658) (xy 129.788311 -261.267176) (xy 129.772184 -261.217558)
			(xy 129.764024 -261.166027) (xy 129.76352 -261.13994) (xy 129.76352 -257.69316) (xy 129.763827 -257.674123)
			(xy 129.768282 -257.636309) (xy 129.77241 -257.617722) (xy 129.77368 -257.61188) (xy 129.77368 -256.215896)
			(xy 129.774175 -256.190606) (xy 129.782084 -256.140648) (xy 129.797706 -256.092541) (xy 129.820658 -256.047467)
			(xy 129.850374 -256.006537) (xy 129.867914 -255.988312) (xy 130.38455 -255.471422) (xy 130.391354 -255.464075)
			(xy 130.399066 -255.445612) (xy 130.399536 -255.435608) (xy 130.399536 -255.405636) (xy 130.396488 -255.393698)
			(xy 130.393694 -255.38811) (xy 130.379856 -255.360583) (xy 130.360272 -255.30217) (xy 130.350337 -255.241368)
			(xy 130.349752 -255.210564) (xy 130.349752 -255.200912) (xy 130.350856 -255.174548) (xy 130.359433 -255.122483)
			(xy 130.37511 -255.072098) (xy 130.397587 -255.024358) (xy 130.426434 -254.980174) (xy 130.461099 -254.940392)
			(xy 130.500921 -254.905772) (xy 130.545138 -254.876975) (xy 130.592904 -254.854553) (xy 130.617976 -254.846328)
			(xy 130.624072 -254.844296) (xy 130.634486 -254.837946) (xy 130.734816 -254.737616) (xy 130.741358 -254.730454)
			(xy 130.748984 -254.712635) (xy 130.749463 -254.693259) (xy 130.7465 -254.684022) (xy 130.71856 -254.608838)
			(xy 130.71698 -254.604786) (xy 130.712641 -254.597249) (xy 130.709924 -254.593852) (xy 130.702812 -254.58547)
			(xy 130.684524 -254.576072) (xy 130.673856 -254.57531) (xy 130.645278 -254.572825) (xy 130.589285 -254.560365)
			(xy 130.535785 -254.53967) (xy 130.485984 -254.511204) (xy 130.441001 -254.475609) (xy 130.40185 -254.433685)
			(xy 130.36941 -254.386376) (xy 130.344413 -254.334747) (xy 130.32742 -254.279959) (xy 130.318815 -254.223245)
			(xy 130.318256 -254.194564) (xy 130.318744 -254.167313) (xy 130.326505 -254.113368) (xy 130.341863 -254.061075)
			(xy 130.364505 -254.0115) (xy 130.393972 -253.965652) (xy 130.429663 -253.924463) (xy 130.470852 -253.888772)
			(xy 130.5167 -253.859305) (xy 130.566275 -253.836663) (xy 130.618568 -253.821305) (xy 130.672513 -253.813544)
			(xy 130.699764 -253.813056) (xy 130.715521 -253.813182) (xy 130.74693 -253.815726) (xy 130.762502 -253.818136)
			(xy 130.765042 -253.818644) (xy 130.76936 -253.818898) (xy 130.779183 -253.819187) (xy 130.797873 -253.813179)
			(xy 130.805682 -253.807214) (xy 130.853942 -253.766574) (xy 130.856681 -253.764361) (xy 130.862672 -253.760659)
			(xy 130.86588 -253.759208) (xy 130.866896 -253.7587) (xy 130.883152 -253.733808) (xy 130.883152 -253.659132)
			(xy 130.882684 -253.648377) (xy 130.873886 -253.628752) (xy 130.866134 -253.621286) (xy 130.809746 -253.57074)
			(xy 130.801573 -253.564134) (xy 130.781635 -253.557563) (xy 130.771138 -253.55804) (xy 130.770376 -253.55804)
			(xy 130.760625 -253.558989) (xy 130.741057 -253.560004) (xy 130.73126 -253.560072) (xy 130.728974 -253.560072)
			(xy 130.701162 -253.559405) (xy 130.64617 -253.551002) (xy 130.592982 -253.534698) (xy 130.542727 -253.51084)
			(xy 130.496472 -253.479933) (xy 130.455198 -253.442635) (xy 130.41978 -253.399735) (xy 130.390971 -253.352145)
			(xy 130.369382 -253.300875) (xy 130.361944 -253.274068) (xy 130.360166 -253.26721) (xy 130.353562 -253.25578)
			(xy 129.679446 -252.58141) (xy 129.672593 -252.574014) (xy 129.664848 -252.555416) (xy 129.66446 -252.545342)
			(xy 129.66446 -249.576844) (xy 129.664025 -249.566779) (xy 129.656292 -249.548193) (xy 129.649474 -249.540776)
			(xy 129.022602 -248.913904) (xy 128.9812 -248.91365) (xy 128.966214 -248.927874) (xy 128.944788 -248.947669)
			(xy 128.897041 -248.981176) (xy 128.844745 -249.007017) (xy 128.789123 -249.024587) (xy 128.731474 -249.033476)
			(xy 128.702308 -249.034046) (xy 128.675055 -249.033561) (xy 128.621105 -249.025805) (xy 128.568807 -249.010451)
			(xy 128.519226 -248.987811) (xy 128.473372 -248.958346) (xy 128.432178 -248.922655) (xy 128.396482 -248.881465)
			(xy 128.367011 -248.835614) (xy 128.344365 -248.786036) (xy 128.329004 -248.73374) (xy 128.321242 -248.679791)
			(xy 128.3208 -248.652538) (xy 128.32127 -248.62524) (xy 128.32906 -248.571204) (xy 128.34447 -248.518829)
			(xy 128.367188 -248.469184) (xy 128.396749 -248.423284) (xy 128.414272 -248.402348) (xy 128.420008 -248.395113)
			(xy 128.426373 -248.377795) (xy 128.426718 -248.368566) (xy 128.426464 -248.338086) (xy 128.425852 -248.32823)
			(xy 128.418139 -248.310071) (xy 128.411478 -248.30278) (xy 126.300992 -246.192294) (xy 126.293593 -246.185449)
			(xy 126.274995 -246.177719) (xy 126.264924 -246.177308) (xy 124.771404 -246.177308) (xy 124.761334 -246.177731)
			(xy 124.742729 -246.185445) (xy 124.735336 -246.192294) (xy 124.644912 -246.282718) (xy 124.638229 -246.290128)
			(xy 124.630652 -246.308564) (xy 124.63018 -246.318532) (xy 124.63018 -248.199402) (xy 124.62967 -248.227695)
			(xy 124.621337 -248.283665) (xy 124.604853 -248.337797) (xy 124.580577 -248.388912) (xy 124.549038 -248.435895)
			(xy 124.510924 -248.477721) (xy 124.467067 -248.513478) (xy 124.442982 -248.528332) (xy 124.432568 -248.534428)
			(xy 124.419868 -248.553986) (xy 124.41047 -248.631202) (xy 124.409632 -248.642731) (xy 124.417174 -248.664557)
			(xy 124.424948 -248.673112) (xy 125.025404 -249.273568) (xy 127.616964 -249.273568) (xy 127.621035 -249.217946)
			(xy 127.633161 -249.163509) (xy 127.653084 -249.111418) (xy 127.68038 -249.062783) (xy 127.714466 -249.01864)
			(xy 127.754615 -248.979931) (xy 127.799973 -248.94748) (xy 127.849573 -248.921979) (xy 127.902357 -248.903972)
			(xy 127.9572 -248.893842) (xy 128.012934 -248.891805) (xy 128.068371 -248.897905) (xy 128.122328 -248.912011)
			(xy 128.173657 -248.933823) (xy 128.221263 -248.962877) (xy 128.264131 -248.998552) (xy 128.301348 -249.040089)
			(xy 128.332121 -249.086602) (xy 128.355793 -249.137099) (xy 128.371861 -249.190506) (xy 128.379981 -249.245682)
			(xy 128.38049 -249.273568) (xy 128.379981 -249.301454) (xy 128.371861 -249.35663) (xy 128.355793 -249.410037)
			(xy 128.332121 -249.460534) (xy 128.301348 -249.507047) (xy 128.264131 -249.548584) (xy 128.221263 -249.584259)
			(xy 128.173657 -249.613313) (xy 128.122328 -249.635125) (xy 128.068371 -249.649231) (xy 128.012934 -249.655331)
			(xy 127.9572 -249.653294) (xy 127.902357 -249.643164) (xy 127.849573 -249.625157) (xy 127.799973 -249.599656)
			(xy 127.754615 -249.567205) (xy 127.714466 -249.528496) (xy 127.68038 -249.484353) (xy 127.653084 -249.435718)
			(xy 127.633161 -249.383627) (xy 127.621035 -249.32919) (xy 127.616964 -249.273568) (xy 125.025404 -249.273568)
			(xy 126.012483 -250.260647) (xy 127.657412 -250.260647) (xy 127.657412 -250.206153) (xy 127.665167 -250.152215)
			(xy 127.680518 -250.099929) (xy 127.703154 -250.050359) (xy 127.732613 -250.004515) (xy 127.768296 -249.96333)
			(xy 127.809477 -249.927641) (xy 127.855317 -249.898177) (xy 127.904884 -249.875535) (xy 127.957168 -249.860177)
			(xy 128.011105 -249.852415) (xy 128.038352 -249.851926) (xy 128.064669 -249.852356) (xy 128.116804 -249.85958)
			(xy 128.167453 -249.873897) (xy 128.215655 -249.895036) (xy 128.260497 -249.922595) (xy 128.301127 -249.956053)
			(xy 128.319276 -249.975116) (xy 128.326802 -249.982512) (xy 128.346079 -249.991039) (xy 128.356614 -249.991626)
			(xy 128.43129 -249.991626) (xy 128.44184 -249.991097) (xy 128.461134 -249.982561) (xy 128.468628 -249.975116)
			(xy 128.486752 -249.956026) (xy 128.527375 -249.922548) (xy 128.572217 -249.894979) (xy 128.620427 -249.873842)
			(xy 128.671086 -249.85954) (xy 128.723232 -249.852345) (xy 128.749552 -249.851926) (xy 128.77681 -249.852318)
			(xy 128.830771 -249.86007) (xy 128.883079 -249.875423) (xy 128.93267 -249.898065) (xy 128.978533 -249.927534)
			(xy 129.019735 -249.963231) (xy 129.055437 -250.004429) (xy 129.084912 -250.050288) (xy 129.10756 -250.099876)
			(xy 129.12292 -250.152182) (xy 129.130679 -250.206143) (xy 129.130679 -250.260657) (xy 129.12292 -250.314618)
			(xy 129.10756 -250.366924) (xy 129.084912 -250.416512) (xy 129.055437 -250.462371) (xy 129.019735 -250.503569)
			(xy 128.978533 -250.539266) (xy 128.93267 -250.568735) (xy 128.883079 -250.591377) (xy 128.830771 -250.60673)
			(xy 128.77681 -250.614482) (xy 128.749552 -250.614942) (xy 128.723236 -250.614487) (xy 128.671103 -250.607266)
			(xy 128.620455 -250.592952) (xy 128.572254 -250.571818) (xy 128.527411 -250.544263) (xy 128.486779 -250.510811)
			(xy 128.468628 -250.491752) (xy 128.461091 -250.484368) (xy 128.441823 -250.475832) (xy 128.43129 -250.475242)
			(xy 128.356614 -250.475242) (xy 128.346062 -250.475753) (xy 128.326766 -250.484299) (xy 128.319276 -250.491752)
			(xy 128.301144 -250.510834) (xy 128.260524 -250.544314) (xy 128.215683 -250.571885) (xy 128.167475 -250.593023)
			(xy 128.116817 -250.607327) (xy 128.064672 -250.614523) (xy 128.038352 -250.614942) (xy 128.011105 -250.614385)
			(xy 127.957168 -250.606623) (xy 127.904884 -250.591265) (xy 127.855317 -250.568623) (xy 127.809477 -250.539159)
			(xy 127.768296 -250.50347) (xy 127.732613 -250.462285) (xy 127.703154 -250.416441) (xy 127.680518 -250.366871)
			(xy 127.665167 -250.314585) (xy 127.657412 -250.260647) (xy 126.012483 -250.260647) (xy 126.859792 -251.107956)
			(xy 126.877878 -251.126748) (xy 126.908509 -251.168959) (xy 126.932158 -251.215444) (xy 126.948242 -251.265056)
			(xy 126.956364 -251.316574) (xy 126.95682 -251.342652) (xy 126.95682 -253.178564) (xy 128.285746 -253.178564)
			(xy 128.289817 -253.122942) (xy 128.301943 -253.068505) (xy 128.321866 -253.016414) (xy 128.349162 -252.967779)
			(xy 128.383248 -252.923636) (xy 128.423397 -252.884927) (xy 128.468755 -252.852476) (xy 128.518355 -252.826975)
			(xy 128.571139 -252.808968) (xy 128.625982 -252.798838) (xy 128.681716 -252.796801) (xy 128.737153 -252.802901)
			(xy 128.79111 -252.817007) (xy 128.842439 -252.838819) (xy 128.890045 -252.867873) (xy 128.932913 -252.903548)
			(xy 128.97013 -252.945085) (xy 129.000903 -252.991598) (xy 129.024575 -253.042095) (xy 129.040643 -253.095502)
			(xy 129.048763 -253.150678) (xy 129.049272 -253.178564) (xy 129.048763 -253.20645) (xy 129.040643 -253.261626)
			(xy 129.024575 -253.315033) (xy 129.000903 -253.36553) (xy 128.97013 -253.412043) (xy 128.932913 -253.45358)
			(xy 128.890045 -253.489255) (xy 128.842439 -253.518309) (xy 128.79111 -253.540121) (xy 128.737153 -253.554227)
			(xy 128.681716 -253.560327) (xy 128.625982 -253.55829) (xy 128.571139 -253.54816) (xy 128.518355 -253.530153)
			(xy 128.468755 -253.504652) (xy 128.423397 -253.472201) (xy 128.383248 -253.433492) (xy 128.349162 -253.389349)
			(xy 128.321866 -253.340714) (xy 128.301943 -253.288623) (xy 128.289817 -253.234186) (xy 128.285746 -253.178564)
			(xy 126.95682 -253.178564) (xy 126.95682 -253.192788) (xy 126.959868 -253.204726) (xy 126.962662 -253.210314)
			(xy 126.976497 -253.237842) (xy 126.996074 -253.296256) (xy 127.006003 -253.357057) (xy 127.006604 -253.38786)
			(xy 127.006118 -253.415111) (xy 126.998362 -253.469059) (xy 126.983007 -253.521354) (xy 126.960365 -253.570931)
			(xy 126.930899 -253.616781) (xy 126.895208 -253.657972) (xy 126.854017 -253.693663) (xy 126.808167 -253.723129)
			(xy 126.75859 -253.745771) (xy 126.706295 -253.761126) (xy 126.652347 -253.768882) (xy 126.597845 -253.768882)
			(xy 126.543897 -253.761126) (xy 126.491602 -253.745771) (xy 126.442025 -253.723129) (xy 126.396175 -253.693663)
			(xy 126.354984 -253.657972) (xy 126.319293 -253.616781) (xy 126.289827 -253.570931) (xy 126.267185 -253.521354)
			(xy 126.25183 -253.469059) (xy 126.244074 -253.415111) (xy 126.243588 -253.38786) (xy 126.244203 -253.357059)
			(xy 126.254147 -253.296264) (xy 126.273723 -253.237854) (xy 126.28753 -253.210314) (xy 126.290324 -253.204726)
			(xy 126.293372 -253.192788) (xy 126.293372 -251.501148) (xy 126.292843 -251.491157) (xy 126.285138 -251.472715)
			(xy 126.278386 -251.465334) (xy 123.470162 -248.65711) (xy 123.462762 -248.650268) (xy 123.444164 -248.642546)
			(xy 123.434094 -248.642124) (xy 123.391422 -248.642124) (xy 123.381371 -248.641619) (xy 123.36281 -248.633898)
			(xy 123.355354 -248.627138) (xy 122.971052 -248.242836) (xy 122.96421 -248.235437) (xy 122.956491 -248.216838)
			(xy 122.956066 -248.206768) (xy 122.956066 -242.868704) (xy 122.955643 -242.858634) (xy 122.947926 -242.840032)
			(xy 122.94108 -242.832636) (xy 122.42927 -242.320572) (xy 122.422158 -242.313206) (xy 122.403362 -242.305586)
			(xy 122.206512 -242.305586) (xy 122.190764 -242.311174) (xy 122.183906 -242.316508) (xy 122.158056 -242.336298)
			(xy 122.102752 -242.370651) (xy 122.043978 -242.398656) (xy 121.98246 -242.419969) (xy 121.918958 -242.434325)
			(xy 121.854255 -242.441548) (xy 121.821702 -242.441984) (xy 121.789151 -242.441526) (xy 121.724454 -242.434284)
			(xy 121.660956 -242.419921) (xy 121.59944 -242.398614) (xy 121.540661 -242.370625) (xy 121.485344 -242.3363)
			(xy 121.459498 -242.316508) (xy 121.452616 -242.311479) (xy 121.43652 -242.3059) (xy 121.428002 -242.305586)
			(xy 120.523508 -242.305586) (xy 120.515634 -242.308126) (xy 120.48609 -242.317475) (xy 120.42495 -242.327557)
			(xy 120.393968 -242.328192) (xy 120.362988 -242.327541) (xy 120.301853 -242.31745) (xy 120.272302 -242.308126)
			(xy 120.264428 -242.305586) (xy 120.072658 -242.305586) (xy 120.062591 -242.305155) (xy 120.043999 -242.297428)
			(xy 120.03659 -242.2906) (xy 119.369332 -241.623342) (xy 119.362491 -241.615942) (xy 119.354773 -241.597343)
			(xy 119.354346 -241.587274) (xy 119.354346 -237.36681) (xy 119.353923 -237.35674) (xy 119.346205 -237.338138)
			(xy 119.33936 -237.330742) (xy 119.266462 -237.257844) (xy 119.259618 -237.250446) (xy 119.251894 -237.231847)
			(xy 119.251476 -237.221776) (xy 119.251476 -236.351572) (xy 119.251279 -236.344905) (xy 119.247802 -236.332033)
			(xy 119.244618 -236.326172) (xy 119.230795 -236.30083) (xy 119.211177 -236.246544) (xy 119.201269 -236.18968)
			(xy 119.200676 -236.160818) (xy 119.200676 -235.010198) (xy 119.200138 -235.000211) (xy 119.192421 -234.981782)
			(xy 119.18569 -234.974384) (xy 118.723156 -234.51185) (xy 118.716311 -234.504451) (xy 118.708586 -234.485853)
			(xy 118.70817 -234.475782) (xy 118.70817 -233.730292) (xy 118.708576 -233.721522) (xy 118.71454 -233.705021)
			(xy 118.719854 -233.698034) (xy 118.725442 -233.690922) (xy 118.731284 -233.674666) (xy 118.731284 -228.25583)
			(xy 118.730848 -228.245766) (xy 118.723114 -228.227181) (xy 118.716298 -228.219762) (xy 113.48593 -222.989394)
			(xy 113.479081 -222.981997) (xy 113.471344 -222.963398) (xy 113.470944 -222.953326) (xy 113.470944 -213.879938)
			(xy 113.470508 -213.869874) (xy 113.462772 -213.851291) (xy 113.455958 -213.84387) (xy 108.575348 -208.96326)
			(xy 108.568236 -208.955894) (xy 108.54944 -208.948274) (xy 99.501706 -208.948274) (xy 99.491635 -208.948695)
			(xy 99.473026 -208.956405) (xy 99.465638 -208.96326) (xy 97.920556 -210.508342) (xy 97.91319 -210.515454)
			(xy 97.90557 -210.53425) (xy 97.90557 -211.250022) (xy 104.08031 -211.250022) (xy 104.080787 -211.222652)
			(xy 104.088601 -211.168473) (xy 104.104088 -211.11597) (xy 104.126927 -211.066223) (xy 104.15665 -211.020256)
			(xy 104.17429 -210.999324) (xy 104.180386 -210.992212) (xy 104.186736 -210.975194) (xy 104.186736 -210.88985)
			(xy 104.180386 -210.872832) (xy 104.17429 -210.86572) (xy 104.156645 -210.844793) (xy 104.126935 -210.798818)
			(xy 104.1041 -210.74907) (xy 104.08861 -210.696568) (xy 104.080783 -210.642391) (xy 104.08031 -210.615022)
			(xy 104.080776 -210.587769) (xy 104.08853 -210.533817) (xy 104.103884 -210.481518) (xy 104.126526 -210.431937)
			(xy 104.155993 -210.386083) (xy 104.191687 -210.344889) (xy 104.23288 -210.309195) (xy 104.278733 -210.279728)
			(xy 104.328314 -210.257086) (xy 104.380613 -210.241731) (xy 104.434565 -210.233976) (xy 104.461818 -210.233514)
			(xy 104.489189 -210.233966) (xy 104.543369 -210.241787) (xy 104.595872 -210.257279) (xy 104.645619 -210.280124)
			(xy 104.691585 -210.309851) (xy 104.712516 -210.327494) (xy 104.719628 -210.33359) (xy 104.736646 -210.33994)
			(xy 104.82199 -210.33994) (xy 104.839008 -210.33359) (xy 104.84612 -210.327494) (xy 104.867053 -210.309853)
			(xy 104.913021 -210.280129) (xy 104.962767 -210.257283) (xy 105.015269 -210.241787) (xy 105.069447 -210.233958)
			(xy 105.124189 -210.233958) (xy 105.178367 -210.241787) (xy 105.230869 -210.257283) (xy 105.280615 -210.280129)
			(xy 105.326583 -210.309853) (xy 105.347516 -210.327494) (xy 105.354628 -210.33359) (xy 105.371646 -210.33994)
			(xy 105.45699 -210.33994) (xy 105.474008 -210.33359) (xy 105.48112 -210.327494) (xy 105.502071 -210.309878)
			(xy 105.548038 -210.280163) (xy 105.597781 -210.257323) (xy 105.650278 -210.241826) (xy 105.70445 -210.233992)
			(xy 105.731818 -210.233514) (xy 105.759072 -210.233938) (xy 105.813026 -210.241698) (xy 105.865326 -210.257058)
			(xy 105.914908 -210.279704) (xy 105.960762 -210.309176) (xy 106.001955 -210.344874) (xy 106.037648 -210.38607)
			(xy 106.067115 -210.431928) (xy 106.089756 -210.481512) (xy 106.10511 -210.533813) (xy 106.112865 -210.587768)
			(xy 106.113326 -210.615022) (xy 106.112891 -210.642394) (xy 106.105068 -210.696575) (xy 106.089573 -210.749079)
			(xy 106.066724 -210.798825) (xy 106.036991 -210.84479) (xy 106.019346 -210.86572) (xy 106.01325 -210.872832)
			(xy 106.0069 -210.88985) (xy 106.0069 -210.975194) (xy 106.01325 -210.992212) (xy 106.019346 -210.999324)
			(xy 106.036955 -211.020281) (xy 106.066673 -211.066246) (xy 106.089516 -211.115987) (xy 106.105014 -211.168483)
			(xy 106.112849 -211.222654) (xy 106.113326 -211.250022) (xy 106.112843 -211.277273) (xy 106.105084 -211.33122)
			(xy 106.089727 -211.383514) (xy 106.067084 -211.43309) (xy 106.037617 -211.478939) (xy 106.001926 -211.520129)
			(xy 105.960736 -211.55582) (xy 105.914886 -211.585286) (xy 105.86531 -211.607928) (xy 105.813016 -211.623285)
			(xy 105.759069 -211.631043) (xy 105.731818 -211.63153) (xy 105.704447 -211.63107) (xy 105.650267 -211.623254)
			(xy 105.597763 -211.607764) (xy 105.548017 -211.58492) (xy 105.502051 -211.555193) (xy 105.48112 -211.53755)
			(xy 105.474008 -211.531454) (xy 105.45699 -211.525104) (xy 105.371646 -211.525104) (xy 105.354628 -211.531454)
			(xy 105.347516 -211.53755) (xy 105.326583 -211.555191) (xy 105.280615 -211.584915) (xy 105.230869 -211.607761)
			(xy 105.178367 -211.623257) (xy 105.124189 -211.631086) (xy 105.069447 -211.631086) (xy 105.015269 -211.623257)
			(xy 104.962767 -211.607761) (xy 104.913021 -211.584915) (xy 104.867053 -211.555191) (xy 104.84612 -211.53755)
			(xy 104.839008 -211.531454) (xy 104.82199 -211.525104) (xy 104.736646 -211.525104) (xy 104.719628 -211.531454)
			(xy 104.712516 -211.53755) (xy 104.691582 -211.555187) (xy 104.645611 -211.584901) (xy 104.595864 -211.607738)
			(xy 104.543363 -211.623229) (xy 104.489187 -211.631057) (xy 104.461818 -211.63153) (xy 104.434568 -211.631005)
			(xy 104.380623 -211.623252) (xy 104.32833 -211.6079) (xy 104.278755 -211.585262) (xy 104.232905 -211.5558)
			(xy 104.191716 -211.520113) (xy 104.156024 -211.478927) (xy 104.126557 -211.43308) (xy 104.103914 -211.383507)
			(xy 104.088557 -211.331216) (xy 104.080798 -211.277272) (xy 104.08031 -211.250022) (xy 97.90557 -211.250022)
			(xy 97.90557 -218.19235) (xy 97.905137 -218.202416) (xy 97.897407 -218.221004) (xy 97.890584 -218.228418)
			(xy 97.745804 -218.373198) (xy 97.740216 -218.403932) (xy 97.74682 -218.418664) (xy 97.757543 -218.443475)
			(xy 97.772677 -218.495362) (xy 97.780342 -218.548866) (xy 97.780856 -218.57589) (xy 97.780394 -218.602802)
			(xy 97.772828 -218.65609) (xy 97.757844 -218.707786) (xy 97.73574 -218.756861) (xy 97.706955 -218.802341)
			(xy 97.672062 -218.843321) (xy 97.631753 -218.878988) (xy 97.58683 -218.908633) (xy 97.538185 -218.931668)
			(xy 97.512632 -218.940126) (xy 97.50679 -218.942158) (xy 97.496122 -218.948508) (xy 96.884998 -219.559632)
			(xy 97.811588 -219.559632) (xy 97.815659 -219.50401) (xy 97.827785 -219.449573) (xy 97.847708 -219.397482)
			(xy 97.875004 -219.348847) (xy 97.90909 -219.304704) (xy 97.949239 -219.265995) (xy 97.994597 -219.233544)
			(xy 98.044197 -219.208043) (xy 98.096981 -219.190036) (xy 98.151824 -219.179906) (xy 98.207558 -219.177869)
			(xy 98.262995 -219.183969) (xy 98.316952 -219.198075) (xy 98.368281 -219.219887) (xy 98.415887 -219.248941)
			(xy 98.458755 -219.284616) (xy 98.495972 -219.326153) (xy 98.526745 -219.372666) (xy 98.550417 -219.423163)
			(xy 98.566485 -219.47657) (xy 98.574605 -219.531746) (xy 98.575114 -219.559632) (xy 98.575109 -219.559886)
			(xy 100.178616 -219.559886) (xy 100.179128 -219.528261) (xy 100.187388 -219.465552) (xy 100.203764 -219.404459)
			(xy 100.227977 -219.346026) (xy 100.259612 -219.291255) (xy 100.298127 -219.241084) (xy 100.342863 -219.19637)
			(xy 100.393054 -219.15788) (xy 100.44784 -219.126272) (xy 100.506284 -219.102088) (xy 100.567386 -219.085741)
			(xy 100.630099 -219.077512) (xy 100.661724 -219.077032) (xy 100.693349 -219.077518) (xy 100.756063 -219.085725)
			(xy 100.817169 -219.102049) (xy 100.875621 -219.126209) (xy 100.93042 -219.157793) (xy 100.980626 -219.19626)
			(xy 101.003354 -219.218256) (xy 101.500432 -219.715588) (xy 101.507853 -219.722254) (xy 101.526282 -219.729837)
			(xy 101.536246 -219.73032) (xy 102.256844 -219.73032) (xy 102.267766 -219.729762) (xy 102.287641 -219.720697)
			(xy 102.295198 -219.712794) (xy 102.352856 -219.646246) (xy 102.358952 -219.625418) (xy 102.357428 -219.614242)
			(xy 102.355553 -219.600603) (xy 102.353517 -219.573145) (xy 102.353364 -219.559378) (xy 102.35385 -219.532127)
			(xy 102.361606 -219.478179) (xy 102.376961 -219.425884) (xy 102.399603 -219.376307) (xy 102.429069 -219.330457)
			(xy 102.46476 -219.289266) (xy 102.505951 -219.253575) (xy 102.551801 -219.224109) (xy 102.601378 -219.201467)
			(xy 102.653673 -219.186112) (xy 102.707621 -219.178356) (xy 102.762123 -219.178356) (xy 102.816071 -219.186112)
			(xy 102.868366 -219.201467) (xy 102.917943 -219.224109) (xy 102.963793 -219.253575) (xy 103.004984 -219.289266)
			(xy 103.040675 -219.330457) (xy 103.070141 -219.376307) (xy 103.092783 -219.425884) (xy 103.108138 -219.478179)
			(xy 103.115894 -219.532127) (xy 103.11638 -219.559378) (xy 103.116234 -219.573145) (xy 103.114203 -219.600604)
			(xy 103.112316 -219.614242) (xy 103.110792 -219.625418) (xy 103.116888 -219.646246) (xy 103.174546 -219.712794)
			(xy 103.18211 -219.720696) (xy 103.201975 -219.729794) (xy 103.2129 -219.73032) (xy 104.281478 -219.73032)
			(xy 104.313111 -219.730826) (xy 104.375838 -219.739071) (xy 104.436951 -219.755436) (xy 104.495404 -219.779639)
			(xy 104.550196 -219.811268) (xy 104.60039 -219.84978) (xy 104.623108 -219.871798) (xy 108.307378 -223.556068)
			(xy 108.329383 -223.578796) (xy 108.367887 -223.628993) (xy 108.39951 -223.683785) (xy 108.423714 -223.742235)
			(xy 108.440084 -223.803344) (xy 108.448339 -223.866066) (xy 108.448856 -223.897698) (xy 108.448856 -224.531174)
			(xy 108.448339 -224.562805) (xy 108.440082 -224.625525) (xy 108.423709 -224.686631) (xy 108.399499 -224.745077)
			(xy 108.367869 -224.799862) (xy 108.329358 -224.850051) (xy 108.284625 -224.894784) (xy 108.234436 -224.933295)
			(xy 108.179651 -224.964925) (xy 108.121205 -224.989135) (xy 108.060099 -225.005508) (xy 107.997379 -225.013765)
			(xy 107.934117 -225.013765) (xy 107.871397 -225.005508) (xy 107.810291 -224.989135) (xy 107.751845 -224.964925)
			(xy 107.69706 -224.933295) (xy 107.646871 -224.894784) (xy 107.602138 -224.850051) (xy 107.563627 -224.799862)
			(xy 107.531997 -224.745077) (xy 107.507787 -224.686631) (xy 107.491414 -224.625525) (xy 107.483157 -224.562805)
			(xy 107.48264 -224.531174) (xy 107.48264 -224.118678) (xy 107.482191 -224.108708) (xy 107.474597 -224.090272)
			(xy 107.467908 -224.082864) (xy 104.096312 -220.711268) (xy 104.088904 -220.704585) (xy 104.070465 -220.697011)
			(xy 104.060498 -220.696536) (xy 103.786686 -220.696536) (xy 103.775053 -220.697069) (xy 103.754143 -220.707261)
			(xy 103.746554 -220.716094) (xy 103.690166 -220.7895) (xy 103.685594 -220.812106) (xy 103.688642 -220.82379)
			(xy 103.694461 -220.847624) (xy 103.700705 -220.896287) (xy 103.701088 -220.920818) (xy 103.700602 -220.948069)
			(xy 103.692846 -221.002017) (xy 103.677491 -221.054312) (xy 103.654849 -221.103889) (xy 103.625383 -221.149739)
			(xy 103.589692 -221.19093) (xy 103.548501 -221.226621) (xy 103.502651 -221.256087) (xy 103.453074 -221.278729)
			(xy 103.400779 -221.294084) (xy 103.346831 -221.30184) (xy 103.292329 -221.30184) (xy 103.238381 -221.294084)
			(xy 103.186086 -221.278729) (xy 103.136509 -221.256087) (xy 103.090659 -221.226621) (xy 103.049468 -221.19093)
			(xy 103.013777 -221.149739) (xy 102.984311 -221.103889) (xy 102.961669 -221.054312) (xy 102.946314 -221.002017)
			(xy 102.938558 -220.948069) (xy 102.938072 -220.920818) (xy 102.938421 -220.896284) (xy 102.944662 -220.847617)
			(xy 102.950518 -220.82379) (xy 102.953566 -220.812106) (xy 102.948994 -220.7895) (xy 102.892606 -220.716094)
			(xy 102.884987 -220.707299) (xy 102.864095 -220.697109) (xy 102.852474 -220.696536) (xy 101.315266 -220.696536)
			(xy 101.283631 -220.696078) (xy 101.220902 -220.687825) (xy 101.159788 -220.671453) (xy 101.101334 -220.64724)
			(xy 101.046543 -220.615602) (xy 100.996352 -220.57708) (xy 100.973636 -220.555058) (xy 100.320094 -219.901516)
			(xy 100.298124 -219.878755) (xy 100.259618 -219.828564) (xy 100.22799 -219.773779) (xy 100.20378 -219.715336)
			(xy 100.187403 -219.654233) (xy 100.179138 -219.591516) (xy 100.178616 -219.559886) (xy 98.575109 -219.559886)
			(xy 98.574605 -219.587518) (xy 98.566485 -219.642694) (xy 98.550417 -219.696101) (xy 98.526745 -219.746598)
			(xy 98.495972 -219.793111) (xy 98.458755 -219.834648) (xy 98.415887 -219.870323) (xy 98.368281 -219.899377)
			(xy 98.316952 -219.921189) (xy 98.262995 -219.935295) (xy 98.207558 -219.941395) (xy 98.151824 -219.939358)
			(xy 98.096981 -219.929228) (xy 98.044197 -219.911221) (xy 97.994597 -219.88572) (xy 97.949239 -219.853269)
			(xy 97.90909 -219.81456) (xy 97.875004 -219.770417) (xy 97.847708 -219.721782) (xy 97.827785 -219.669691)
			(xy 97.815659 -219.615254) (xy 97.811588 -219.559632) (xy 96.884998 -219.559632) (xy 96.56191 -219.88272)
			(xy 96.555102 -219.890066) (xy 96.547375 -219.908528) (xy 96.546924 -219.918534) (xy 96.546924 -221.018354)
			(xy 96.817432 -221.018354) (xy 96.821503 -220.962732) (xy 96.833629 -220.908295) (xy 96.853552 -220.856204)
			(xy 96.880848 -220.807569) (xy 96.914934 -220.763426) (xy 96.955083 -220.724717) (xy 97.000441 -220.692266)
			(xy 97.050041 -220.666765) (xy 97.102825 -220.648758) (xy 97.157668 -220.638628) (xy 97.213402 -220.636591)
			(xy 97.268839 -220.642691) (xy 97.322796 -220.656797) (xy 97.374125 -220.678609) (xy 97.421731 -220.707663)
			(xy 97.464599 -220.743338) (xy 97.501816 -220.784875) (xy 97.532589 -220.831388) (xy 97.556261 -220.881885)
			(xy 97.572329 -220.935292) (xy 97.580449 -220.990468) (xy 97.580958 -221.018354) (xy 97.580449 -221.04624)
			(xy 97.572329 -221.101416) (xy 97.558881 -221.146116) (xy 100.565456 -221.146116) (xy 100.569527 -221.090494)
			(xy 100.581653 -221.036057) (xy 100.601576 -220.983966) (xy 100.628872 -220.935331) (xy 100.662958 -220.891188)
			(xy 100.703107 -220.852479) (xy 100.748465 -220.820028) (xy 100.798065 -220.794527) (xy 100.850849 -220.77652)
			(xy 100.905692 -220.76639) (xy 100.961426 -220.764353) (xy 101.016863 -220.770453) (xy 101.07082 -220.784559)
			(xy 101.122149 -220.806371) (xy 101.169755 -220.835425) (xy 101.212623 -220.8711) (xy 101.24984 -220.912637)
			(xy 101.280613 -220.95915) (xy 101.304285 -221.009647) (xy 101.320353 -221.063054) (xy 101.328473 -221.11823)
			(xy 101.328982 -221.146116) (xy 101.328473 -221.174002) (xy 101.320353 -221.229178) (xy 101.304285 -221.282585)
			(xy 101.280613 -221.333082) (xy 101.24984 -221.379595) (xy 101.212623 -221.421132) (xy 101.169755 -221.456807)
			(xy 101.122149 -221.485861) (xy 101.07082 -221.507673) (xy 101.016863 -221.521779) (xy 100.961426 -221.527879)
			(xy 100.905692 -221.525842) (xy 100.850849 -221.515712) (xy 100.798065 -221.497705) (xy 100.748465 -221.472204)
			(xy 100.703107 -221.439753) (xy 100.662958 -221.401044) (xy 100.628872 -221.356901) (xy 100.601576 -221.308266)
			(xy 100.581653 -221.256175) (xy 100.569527 -221.201738) (xy 100.565456 -221.146116) (xy 97.558881 -221.146116)
			(xy 97.556261 -221.154823) (xy 97.532589 -221.20532) (xy 97.501816 -221.251833) (xy 97.464599 -221.29337)
			(xy 97.421731 -221.329045) (xy 97.374125 -221.358099) (xy 97.322796 -221.379911) (xy 97.268839 -221.394017)
			(xy 97.213402 -221.400117) (xy 97.157668 -221.39808) (xy 97.102825 -221.38795) (xy 97.050041 -221.369943)
			(xy 97.000441 -221.344442) (xy 96.955083 -221.311991) (xy 96.914934 -221.273282) (xy 96.880848 -221.229139)
			(xy 96.853552 -221.180504) (xy 96.833629 -221.128413) (xy 96.821503 -221.073976) (xy 96.817432 -221.018354)
			(xy 96.546924 -221.018354) (xy 96.546924 -222.46463) (xy 99.334318 -222.46463) (xy 99.338389 -222.409008)
			(xy 99.350515 -222.354571) (xy 99.370438 -222.30248) (xy 99.397734 -222.253845) (xy 99.43182 -222.209702)
			(xy 99.471969 -222.170993) (xy 99.517327 -222.138542) (xy 99.566927 -222.113041) (xy 99.619711 -222.095034)
			(xy 99.674554 -222.084904) (xy 99.730288 -222.082867) (xy 99.785725 -222.088967) (xy 99.839682 -222.103073)
			(xy 99.891011 -222.124885) (xy 99.938617 -222.153939) (xy 99.981485 -222.189614) (xy 100.018702 -222.231151)
			(xy 100.049475 -222.277664) (xy 100.073147 -222.328161) (xy 100.089215 -222.381568) (xy 100.097335 -222.436744)
			(xy 100.097844 -222.46463) (xy 100.097335 -222.492516) (xy 100.089215 -222.547692) (xy 100.073147 -222.601099)
			(xy 100.049475 -222.651596) (xy 100.018702 -222.698109) (xy 99.981485 -222.739646) (xy 99.938617 -222.775321)
			(xy 99.891011 -222.804375) (xy 99.839682 -222.826187) (xy 99.785725 -222.840293) (xy 99.730288 -222.846393)
			(xy 99.674554 -222.844356) (xy 99.619711 -222.834226) (xy 99.566927 -222.816219) (xy 99.517327 -222.790718)
			(xy 99.471969 -222.758267) (xy 99.43182 -222.719558) (xy 99.397734 -222.675415) (xy 99.370438 -222.62678)
			(xy 99.350515 -222.574689) (xy 99.338389 -222.520252) (xy 99.334318 -222.46463) (xy 96.546924 -222.46463)
			(xy 96.546924 -223.135698) (xy 101.499414 -223.135698) (xy 101.503485 -223.080076) (xy 101.515611 -223.025639)
			(xy 101.535534 -222.973548) (xy 101.56283 -222.924913) (xy 101.596916 -222.88077) (xy 101.637065 -222.842061)
			(xy 101.682423 -222.80961) (xy 101.732023 -222.784109) (xy 101.784807 -222.766102) (xy 101.83965 -222.755972)
			(xy 101.895384 -222.753935) (xy 101.950821 -222.760035) (xy 102.004778 -222.774141) (xy 102.056107 -222.795953)
			(xy 102.103713 -222.825007) (xy 102.146581 -222.860682) (xy 102.183798 -222.902219) (xy 102.214571 -222.948732)
			(xy 102.238243 -222.999229) (xy 102.254311 -223.052636) (xy 102.262431 -223.107812) (xy 102.26294 -223.135698)
			(xy 102.262431 -223.163584) (xy 102.254311 -223.21876) (xy 102.238243 -223.272167) (xy 102.214571 -223.322664)
			(xy 102.183798 -223.369177) (xy 102.146581 -223.410714) (xy 102.103713 -223.446389) (xy 102.056107 -223.475443)
			(xy 102.004778 -223.497255) (xy 101.950821 -223.511361) (xy 101.895384 -223.517461) (xy 101.83965 -223.515424)
			(xy 101.784807 -223.505294) (xy 101.732023 -223.487287) (xy 101.682423 -223.461786) (xy 101.637065 -223.429335)
			(xy 101.596916 -223.390626) (xy 101.56283 -223.346483) (xy 101.535534 -223.297848) (xy 101.515611 -223.245757)
			(xy 101.503485 -223.19132) (xy 101.499414 -223.135698) (xy 96.546924 -223.135698) (xy 96.546924 -223.849946)
			(xy 102.606346 -223.849946) (xy 102.610417 -223.794324) (xy 102.622543 -223.739887) (xy 102.642466 -223.687796)
			(xy 102.669762 -223.639161) (xy 102.703848 -223.595018) (xy 102.743997 -223.556309) (xy 102.789355 -223.523858)
			(xy 102.838955 -223.498357) (xy 102.891739 -223.48035) (xy 102.946582 -223.47022) (xy 103.002316 -223.468183)
			(xy 103.057753 -223.474283) (xy 103.11171 -223.488389) (xy 103.163039 -223.510201) (xy 103.210645 -223.539255)
			(xy 103.253513 -223.57493) (xy 103.29073 -223.616467) (xy 103.321503 -223.66298) (xy 103.345175 -223.713477)
			(xy 103.361243 -223.766884) (xy 103.369363 -223.82206) (xy 103.369872 -223.849946) (xy 103.369363 -223.877832)
			(xy 103.361243 -223.933008) (xy 103.345175 -223.986415) (xy 103.321503 -224.036912) (xy 103.29073 -224.083425)
			(xy 103.253513 -224.124962) (xy 103.210645 -224.160637) (xy 103.163039 -224.189691) (xy 103.11171 -224.211503)
			(xy 103.057753 -224.225609) (xy 103.002316 -224.231709) (xy 102.946582 -224.229672) (xy 102.891739 -224.219542)
			(xy 102.838955 -224.201535) (xy 102.789355 -224.176034) (xy 102.743997 -224.143583) (xy 102.703848 -224.104874)
			(xy 102.669762 -224.060731) (xy 102.642466 -224.012096) (xy 102.622543 -223.960005) (xy 102.610417 -223.905568)
			(xy 102.606346 -223.849946) (xy 96.546924 -223.849946) (xy 96.546924 -236.391704) (xy 99.087938 -236.391704)
			(xy 99.092009 -236.336082) (xy 99.104135 -236.281645) (xy 99.124058 -236.229554) (xy 99.151354 -236.180919)
			(xy 99.18544 -236.136776) (xy 99.225589 -236.098067) (xy 99.270947 -236.065616) (xy 99.320547 -236.040115)
			(xy 99.373331 -236.022108) (xy 99.428174 -236.011978) (xy 99.483908 -236.009941) (xy 99.539345 -236.016041)
			(xy 99.593302 -236.030147) (xy 99.644631 -236.051959) (xy 99.692237 -236.081013) (xy 99.735105 -236.116688)
			(xy 99.772322 -236.158225) (xy 99.803095 -236.204738) (xy 99.826767 -236.255235) (xy 99.842835 -236.308642)
			(xy 99.850955 -236.363818) (xy 99.851464 -236.391704) (xy 99.850955 -236.41959) (xy 99.842835 -236.474766)
			(xy 99.826767 -236.528173) (xy 99.803095 -236.57867) (xy 99.772322 -236.625183) (xy 99.735105 -236.66672)
			(xy 99.692237 -236.702395) (xy 99.644631 -236.731449) (xy 99.593302 -236.753261) (xy 99.539345 -236.767367)
			(xy 99.483908 -236.773467) (xy 99.428174 -236.77143) (xy 99.373331 -236.7613) (xy 99.320547 -236.743293)
			(xy 99.270947 -236.717792) (xy 99.225589 -236.685341) (xy 99.18544 -236.646632) (xy 99.151354 -236.602489)
			(xy 99.124058 -236.553854) (xy 99.104135 -236.501763) (xy 99.092009 -236.447326) (xy 99.087938 -236.391704)
			(xy 96.546924 -236.391704) (xy 96.546924 -236.775244) (xy 101.503226 -236.775244) (xy 101.503712 -236.747874)
			(xy 101.511524 -236.693696) (xy 101.527008 -236.641193) (xy 101.549845 -236.591446) (xy 101.579566 -236.545478)
			(xy 101.597206 -236.524546) (xy 101.603302 -236.517434) (xy 101.609652 -236.500416) (xy 101.609652 -236.415072)
			(xy 101.603302 -236.398054) (xy 101.597206 -236.390942) (xy 101.579574 -236.370004) (xy 101.549861 -236.324033)
			(xy 101.527024 -236.274287) (xy 101.511531 -236.221788) (xy 101.503701 -236.167613) (xy 101.503226 -236.140244)
			(xy 101.503712 -236.112993) (xy 101.511468 -236.059045) (xy 101.526823 -236.00675) (xy 101.549465 -235.957173)
			(xy 101.578931 -235.911323) (xy 101.614622 -235.870132) (xy 101.655813 -235.834441) (xy 101.701663 -235.804975)
			(xy 101.75124 -235.782333) (xy 101.803535 -235.766978) (xy 101.857483 -235.759222) (xy 101.911985 -235.759222)
			(xy 101.965933 -235.766978) (xy 102.018228 -235.782333) (xy 102.067805 -235.804975) (xy 102.113655 -235.834441)
			(xy 102.154846 -235.870132) (xy 102.190537 -235.911323) (xy 102.220003 -235.957173) (xy 102.242645 -236.00675)
			(xy 102.258 -236.059045) (xy 102.265756 -236.112993) (xy 102.266242 -236.140244) (xy 102.265757 -236.167614)
			(xy 102.257946 -236.221793) (xy 102.242462 -236.274296) (xy 102.219624 -236.324043) (xy 102.189902 -236.37001)
			(xy 102.172262 -236.390942) (xy 102.166166 -236.398054) (xy 102.159816 -236.415072) (xy 102.159816 -236.500416)
			(xy 102.166166 -236.517434) (xy 102.172262 -236.524546) (xy 102.189883 -236.545492) (xy 102.219599 -236.591461)
			(xy 102.242439 -236.641205) (xy 102.257934 -236.693702) (xy 102.265766 -236.747876) (xy 102.266242 -236.775244)
			(xy 103.535226 -236.775244) (xy 103.535712 -236.747874) (xy 103.543524 -236.693696) (xy 103.559008 -236.641193)
			(xy 103.581845 -236.591446) (xy 103.611566 -236.545478) (xy 103.629206 -236.524546) (xy 103.635302 -236.517434)
			(xy 103.641652 -236.500416) (xy 103.641652 -236.415072) (xy 103.635302 -236.398054) (xy 103.629206 -236.390942)
			(xy 103.611574 -236.370004) (xy 103.581861 -236.324033) (xy 103.559024 -236.274287) (xy 103.543531 -236.221788)
			(xy 103.535701 -236.167613) (xy 103.535226 -236.140244) (xy 103.535712 -236.112993) (xy 103.543468 -236.059045)
			(xy 103.558823 -236.00675) (xy 103.581465 -235.957173) (xy 103.610931 -235.911323) (xy 103.646622 -235.870132)
			(xy 103.687813 -235.834441) (xy 103.733663 -235.804975) (xy 103.78324 -235.782333) (xy 103.835535 -235.766978)
			(xy 103.889483 -235.759222) (xy 103.943985 -235.759222) (xy 103.997933 -235.766978) (xy 104.050228 -235.782333)
			(xy 104.099805 -235.804975) (xy 104.145655 -235.834441) (xy 104.186846 -235.870132) (xy 104.222537 -235.911323)
			(xy 104.252003 -235.957173) (xy 104.274645 -236.00675) (xy 104.29 -236.059045) (xy 104.297756 -236.112993)
			(xy 104.298242 -236.140244) (xy 104.297757 -236.167614) (xy 104.289946 -236.221793) (xy 104.274462 -236.274296)
			(xy 104.251624 -236.324043) (xy 104.221902 -236.37001) (xy 104.204262 -236.390942) (xy 104.198166 -236.398054)
			(xy 104.191816 -236.415072) (xy 104.191816 -236.500416) (xy 104.198166 -236.517434) (xy 104.204262 -236.524546)
			(xy 104.221883 -236.545492) (xy 104.251599 -236.591461) (xy 104.274439 -236.641205) (xy 104.289934 -236.693702)
			(xy 104.297766 -236.747876) (xy 104.298242 -236.775244) (xy 105.567226 -236.775244) (xy 105.567712 -236.747874)
			(xy 105.575524 -236.693696) (xy 105.591008 -236.641193) (xy 105.613845 -236.591446) (xy 105.643566 -236.545478)
			(xy 105.661206 -236.524546) (xy 105.667302 -236.517434) (xy 105.673652 -236.500416) (xy 105.673652 -236.415072)
			(xy 105.667302 -236.398054) (xy 105.661206 -236.390942) (xy 105.643574 -236.370004) (xy 105.613861 -236.324033)
			(xy 105.591024 -236.274287) (xy 105.575531 -236.221788) (xy 105.567701 -236.167613) (xy 105.567226 -236.140244)
			(xy 105.567712 -236.112993) (xy 105.575468 -236.059045) (xy 105.590823 -236.00675) (xy 105.613465 -235.957173)
			(xy 105.642931 -235.911323) (xy 105.678622 -235.870132) (xy 105.719813 -235.834441) (xy 105.765663 -235.804975)
			(xy 105.81524 -235.782333) (xy 105.867535 -235.766978) (xy 105.921483 -235.759222) (xy 105.975985 -235.759222)
			(xy 106.029933 -235.766978) (xy 106.082228 -235.782333) (xy 106.131805 -235.804975) (xy 106.177655 -235.834441)
			(xy 106.218846 -235.870132) (xy 106.254537 -235.911323) (xy 106.284003 -235.957173) (xy 106.306645 -236.00675)
			(xy 106.322 -236.059045) (xy 106.329756 -236.112993) (xy 106.330242 -236.140244) (xy 106.329757 -236.167614)
			(xy 106.321946 -236.221793) (xy 106.306462 -236.274296) (xy 106.283624 -236.324043) (xy 106.253902 -236.37001)
			(xy 106.236262 -236.390942) (xy 106.230166 -236.398054) (xy 106.223816 -236.415072) (xy 106.223816 -236.500416)
			(xy 106.230166 -236.517434) (xy 106.236262 -236.524546) (xy 106.253883 -236.545492) (xy 106.283599 -236.591461)
			(xy 106.306439 -236.641205) (xy 106.321934 -236.693702) (xy 106.329766 -236.747876) (xy 106.330242 -236.775244)
			(xy 107.599226 -236.775244) (xy 107.599712 -236.747874) (xy 107.607524 -236.693696) (xy 107.623008 -236.641193)
			(xy 107.645845 -236.591446) (xy 107.675566 -236.545478) (xy 107.693206 -236.524546) (xy 107.699302 -236.517434)
			(xy 107.705652 -236.500416) (xy 107.705652 -236.415072) (xy 107.699302 -236.398054) (xy 107.693206 -236.390942)
			(xy 107.675574 -236.370004) (xy 107.645861 -236.324033) (xy 107.623024 -236.274287) (xy 107.607531 -236.221788)
			(xy 107.599701 -236.167613) (xy 107.599226 -236.140244) (xy 107.599712 -236.112993) (xy 107.607468 -236.059045)
			(xy 107.622823 -236.00675) (xy 107.645465 -235.957173) (xy 107.674931 -235.911323) (xy 107.710622 -235.870132)
			(xy 107.751813 -235.834441) (xy 107.797663 -235.804975) (xy 107.84724 -235.782333) (xy 107.899535 -235.766978)
			(xy 107.953483 -235.759222) (xy 108.007985 -235.759222) (xy 108.061933 -235.766978) (xy 108.114228 -235.782333)
			(xy 108.163805 -235.804975) (xy 108.209655 -235.834441) (xy 108.250846 -235.870132) (xy 108.286537 -235.911323)
			(xy 108.316003 -235.957173) (xy 108.338645 -236.00675) (xy 108.354 -236.059045) (xy 108.361756 -236.112993)
			(xy 108.362242 -236.140244) (xy 108.361757 -236.167614) (xy 108.353946 -236.221793) (xy 108.338462 -236.274296)
			(xy 108.315624 -236.324043) (xy 108.285902 -236.37001) (xy 108.268262 -236.390942) (xy 108.262166 -236.398054)
			(xy 108.255816 -236.415072) (xy 108.255816 -236.500416) (xy 108.262166 -236.517434) (xy 108.268262 -236.524546)
			(xy 108.285883 -236.545492) (xy 108.315599 -236.591461) (xy 108.338439 -236.641205) (xy 108.353934 -236.693702)
			(xy 108.361766 -236.747876) (xy 108.362242 -236.775244) (xy 108.361756 -236.802495) (xy 108.354 -236.856443)
			(xy 108.338645 -236.908738) (xy 108.316003 -236.958315) (xy 108.286537 -237.004165) (xy 108.250846 -237.045356)
			(xy 108.209655 -237.081047) (xy 108.163805 -237.110513) (xy 108.114228 -237.133155) (xy 108.061933 -237.14851)
			(xy 108.007985 -237.156266) (xy 107.953483 -237.156266) (xy 107.899535 -237.14851) (xy 107.84724 -237.133155)
			(xy 107.797663 -237.110513) (xy 107.751813 -237.081047) (xy 107.710622 -237.045356) (xy 107.674931 -237.004165)
			(xy 107.645465 -236.958315) (xy 107.622823 -236.908738) (xy 107.607468 -236.856443) (xy 107.599712 -236.802495)
			(xy 107.599226 -236.775244) (xy 106.330242 -236.775244) (xy 106.329756 -236.802495) (xy 106.322 -236.856443)
			(xy 106.306645 -236.908738) (xy 106.284003 -236.958315) (xy 106.254537 -237.004165) (xy 106.218846 -237.045356)
			(xy 106.177655 -237.081047) (xy 106.131805 -237.110513) (xy 106.082228 -237.133155) (xy 106.029933 -237.14851)
			(xy 105.975985 -237.156266) (xy 105.921483 -237.156266) (xy 105.867535 -237.14851) (xy 105.81524 -237.133155)
			(xy 105.765663 -237.110513) (xy 105.719813 -237.081047) (xy 105.678622 -237.045356) (xy 105.642931 -237.004165)
			(xy 105.613465 -236.958315) (xy 105.590823 -236.908738) (xy 105.575468 -236.856443) (xy 105.567712 -236.802495)
			(xy 105.567226 -236.775244) (xy 104.298242 -236.775244) (xy 104.297756 -236.802495) (xy 104.29 -236.856443)
			(xy 104.274645 -236.908738) (xy 104.252003 -236.958315) (xy 104.222537 -237.004165) (xy 104.186846 -237.045356)
			(xy 104.145655 -237.081047) (xy 104.099805 -237.110513) (xy 104.050228 -237.133155) (xy 103.997933 -237.14851)
			(xy 103.943985 -237.156266) (xy 103.889483 -237.156266) (xy 103.835535 -237.14851) (xy 103.78324 -237.133155)
			(xy 103.733663 -237.110513) (xy 103.687813 -237.081047) (xy 103.646622 -237.045356) (xy 103.610931 -237.004165)
			(xy 103.581465 -236.958315) (xy 103.558823 -236.908738) (xy 103.543468 -236.856443) (xy 103.535712 -236.802495)
			(xy 103.535226 -236.775244) (xy 102.266242 -236.775244) (xy 102.265756 -236.802495) (xy 102.258 -236.856443)
			(xy 102.242645 -236.908738) (xy 102.220003 -236.958315) (xy 102.190537 -237.004165) (xy 102.154846 -237.045356)
			(xy 102.113655 -237.081047) (xy 102.067805 -237.110513) (xy 102.018228 -237.133155) (xy 101.965933 -237.14851)
			(xy 101.911985 -237.156266) (xy 101.857483 -237.156266) (xy 101.803535 -237.14851) (xy 101.75124 -237.133155)
			(xy 101.701663 -237.110513) (xy 101.655813 -237.081047) (xy 101.614622 -237.045356) (xy 101.578931 -237.004165)
			(xy 101.549465 -236.958315) (xy 101.526823 -236.908738) (xy 101.511468 -236.856443) (xy 101.503712 -236.802495)
			(xy 101.503226 -236.775244) (xy 96.546924 -236.775244) (xy 96.546924 -240.788698) (xy 97.371406 -240.788698)
			(xy 97.375477 -240.733076) (xy 97.387603 -240.678639) (xy 97.407526 -240.626548) (xy 97.434822 -240.577913)
			(xy 97.468908 -240.53377) (xy 97.509057 -240.495061) (xy 97.554415 -240.46261) (xy 97.604015 -240.437109)
			(xy 97.656799 -240.419102) (xy 97.711642 -240.408972) (xy 97.767376 -240.406935) (xy 97.822813 -240.413035)
			(xy 97.87677 -240.427141) (xy 97.928099 -240.448953) (xy 97.975705 -240.478007) (xy 98.018573 -240.513682)
			(xy 98.05579 -240.555219) (xy 98.086563 -240.601732) (xy 98.110235 -240.652229) (xy 98.126303 -240.705636)
			(xy 98.134423 -240.760812) (xy 98.134932 -240.788698) (xy 98.134423 -240.816584) (xy 98.126303 -240.87176)
			(xy 98.110235 -240.925167) (xy 98.108839 -240.928144) (xy 99.417122 -240.928144) (xy 99.421193 -240.872522)
			(xy 99.433319 -240.818085) (xy 99.453242 -240.765994) (xy 99.480538 -240.717359) (xy 99.514624 -240.673216)
			(xy 99.554773 -240.634507) (xy 99.600131 -240.602056) (xy 99.649731 -240.576555) (xy 99.702515 -240.558548)
			(xy 99.757358 -240.548418) (xy 99.813092 -240.546381) (xy 99.868529 -240.552481) (xy 99.922486 -240.566587)
			(xy 99.973815 -240.588399) (xy 100.021421 -240.617453) (xy 100.064289 -240.653128) (xy 100.101506 -240.694665)
			(xy 100.132279 -240.741178) (xy 100.155951 -240.791675) (xy 100.172019 -240.845082) (xy 100.180139 -240.900258)
			(xy 100.180648 -240.928144) (xy 100.180139 -240.95603) (xy 100.172019 -241.011206) (xy 100.155951 -241.064613)
			(xy 100.132279 -241.11511) (xy 100.101506 -241.161623) (xy 100.064289 -241.20316) (xy 100.021421 -241.238835)
			(xy 99.973815 -241.267889) (xy 99.922486 -241.289701) (xy 99.868529 -241.303807) (xy 99.813092 -241.309907)
			(xy 99.757358 -241.30787) (xy 99.702515 -241.29774) (xy 99.649731 -241.279733) (xy 99.600131 -241.254232)
			(xy 99.554773 -241.221781) (xy 99.514624 -241.183072) (xy 99.480538 -241.138929) (xy 99.453242 -241.090294)
			(xy 99.433319 -241.038203) (xy 99.421193 -240.983766) (xy 99.417122 -240.928144) (xy 98.108839 -240.928144)
			(xy 98.086563 -240.975664) (xy 98.05579 -241.022177) (xy 98.018573 -241.063714) (xy 97.975705 -241.099389)
			(xy 97.928099 -241.128443) (xy 97.87677 -241.150255) (xy 97.822813 -241.164361) (xy 97.767376 -241.170461)
			(xy 97.711642 -241.168424) (xy 97.656799 -241.158294) (xy 97.604015 -241.140287) (xy 97.554415 -241.114786)
			(xy 97.509057 -241.082335) (xy 97.468908 -241.043626) (xy 97.434822 -240.999483) (xy 97.407526 -240.950848)
			(xy 97.387603 -240.898757) (xy 97.375477 -240.84432) (xy 97.371406 -240.788698) (xy 96.546924 -240.788698)
			(xy 96.546924 -240.83899) (xy 96.569022 -240.866676) (xy 96.586548 -240.870486) (xy 96.614268 -240.877373)
			(xy 96.667427 -240.898262) (xy 96.716882 -240.926836) (xy 96.761528 -240.962458) (xy 96.800371 -241.004332)
			(xy 96.832542 -241.051526) (xy 96.857325 -241.102985) (xy 96.874166 -241.157562) (xy 96.882689 -241.214038)
			(xy 96.88322 -241.242596) (xy 96.882753 -241.269585) (xy 96.875148 -241.323025) (xy 96.860088 -241.374859)
			(xy 96.837874 -241.424055) (xy 96.80895 -241.469629) (xy 96.773892 -241.510673) (xy 96.733401 -241.546367)
			(xy 96.688284 -241.576) (xy 96.639441 -241.598979) (xy 96.587848 -241.614846) (xy 96.534534 -241.623286)
			(xy 96.507554 -241.624104) (xy 96.501458 -241.624104) (xy 96.468927 -241.623403) (xy 96.404818 -241.612298)
			(xy 96.37395 -241.602006) (xy 96.373442 -241.602006) (xy 96.367731 -241.600152) (xy 96.355795 -241.598868)
			(xy 96.34982 -241.599466) (xy 96.337374 -241.601244) (xy 96.259396 -241.656108) (xy 96.249764 -241.663728)
			(xy 96.238484 -241.6855) (xy 96.237806 -241.697764) (xy 96.237806 -241.870992) (xy 96.237978 -241.877145)
			(xy 96.240935 -241.889089) (xy 96.243648 -241.894614) (xy 96.256856 -241.919506) (xy 96.264222 -241.928142)
			(xy 96.268794 -241.931698) (xy 96.291937 -241.949479) (xy 96.333059 -241.990889) (xy 96.367405 -242.038072)
			(xy 96.394175 -242.089929) (xy 96.412748 -242.145254) (xy 96.42269 -242.202761) (xy 96.423734 -242.231926)
			(xy 96.423734 -242.237514) (xy 96.423734 -242.238784) (xy 96.423172 -242.268021) (xy 96.414256 -242.325812)
			(xy 96.396643 -242.381571) (xy 96.370745 -242.433998) (xy 96.354392 -242.45824) (xy 96.354138 -242.458494)
			(xy 96.347481 -242.469075) (xy 96.344413 -242.493855) (xy 96.348296 -242.505738) (xy 96.383094 -242.596416)
			(xy 96.40189 -242.612672) (xy 96.414336 -242.61572) (xy 96.441959 -242.622663) (xy 96.494914 -242.643626)
			(xy 96.544165 -242.672229) (xy 96.588617 -242.707835) (xy 96.627282 -242.749653) (xy 96.659301 -242.796754)
			(xy 96.683963 -242.848092) (xy 96.700719 -242.902526) (xy 96.709197 -242.958845) (xy 96.709738 -242.987322)
			(xy 96.709659 -243.00006) (xy 96.708004 -243.025481) (xy 96.706436 -243.038122) (xy 96.702376 -243.064823)
			(xy 96.68771 -243.1168) (xy 96.665862 -243.166191) (xy 96.63727 -243.212008) (xy 96.602503 -243.253336)
			(xy 96.562258 -243.289351) (xy 96.517336 -243.319332) (xy 96.468637 -243.34268) (xy 96.417133 -243.35893)
			(xy 96.363852 -243.367756) (xy 96.336866 -243.36883) (xy 96.326706 -243.369084) (xy 96.308672 -243.376958)
			(xy 96.252284 -243.43487) (xy 96.2457 -243.44225) (xy 96.238251 -243.46055) (xy 96.237806 -243.47043)
			(xy 96.237806 -243.732157) (xy 101.008827 -243.732157) (xy 101.008827 -243.677643) (xy 101.016586 -243.623685)
			(xy 101.031945 -243.571379) (xy 101.054592 -243.521793) (xy 101.084066 -243.475934) (xy 101.119767 -243.434737)
			(xy 101.160968 -243.399041) (xy 101.20683 -243.369572) (xy 101.256419 -243.34693) (xy 101.308726 -243.331577)
			(xy 101.362685 -243.323824) (xy 101.389942 -243.323364) (xy 101.416936 -243.323799) (xy 101.470386 -243.331411)
			(xy 101.522229 -243.346477) (xy 101.571434 -243.368697) (xy 101.617017 -243.397627) (xy 101.637846 -243.414804)
			(xy 101.645974 -243.421916) (xy 101.666548 -243.428012) (xy 101.76256 -243.41582) (xy 101.780848 -243.404644)
			(xy 101.787198 -243.395754) (xy 101.804809 -243.371452) (xy 101.846406 -243.328193) (xy 101.870002 -243.309648)
			(xy 101.87813 -243.303552) (xy 101.88829 -243.286534) (xy 101.901498 -243.195602) (xy 101.896672 -243.176552)
			(xy 101.89083 -243.168424) (xy 101.873309 -243.143692) (xy 101.84551 -243.089835) (xy 101.826579 -243.032259)
			(xy 101.816992 -242.972414) (xy 101.816408 -242.94211) (xy 101.816865 -242.914857) (xy 101.824621 -242.860905)
			(xy 101.839976 -242.808606) (xy 101.862619 -242.759025) (xy 101.892087 -242.713171) (xy 101.927782 -242.671977)
			(xy 101.968975 -242.636284) (xy 102.01483 -242.606816) (xy 102.064411 -242.584174) (xy 102.116711 -242.568819)
			(xy 102.170663 -242.561064) (xy 102.197916 -242.560602) (xy 102.223949 -242.561056) (xy 102.275531 -242.568144)
			(xy 102.325672 -242.582173) (xy 102.373443 -242.602882) (xy 102.417959 -242.629887) (xy 102.438454 -242.645946)
			(xy 102.446074 -242.652296) (xy 102.464616 -242.657884) (xy 102.554278 -242.650772) (xy 102.57155 -242.642136)
			(xy 102.578154 -242.63477) (xy 102.596347 -242.615136) (xy 102.637251 -242.58061) (xy 102.682577 -242.552138)
			(xy 102.731436 -242.530278) (xy 102.78287 -242.515459) (xy 102.835871 -242.507971) (xy 102.862634 -242.507516)
			(xy 102.889887 -242.507946) (xy 102.943838 -242.515708) (xy 102.996135 -242.531069) (xy 103.045714 -242.553716)
			(xy 103.091566 -242.583188) (xy 103.132756 -242.618885) (xy 103.168447 -242.660081) (xy 103.197912 -242.705937)
			(xy 103.220552 -242.755519) (xy 103.235904 -242.807819) (xy 103.243658 -242.861771) (xy 103.244142 -242.889024)
			(xy 103.243581 -242.917797) (xy 103.234937 -242.974689) (xy 103.217849 -243.029638) (xy 103.192704 -243.081399)
			(xy 103.160072 -243.128797) (xy 103.140764 -243.150136) (xy 103.133144 -243.158264) (xy 103.126286 -243.177822)
			(xy 103.133398 -243.274342) (xy 103.143304 -243.29263) (xy 103.15194 -243.299488) (xy 103.174144 -243.31769)
			(xy 103.213355 -243.359629) (xy 103.245839 -243.406969) (xy 103.270865 -243.458642) (xy 103.287866 -243.51348)
			(xy 103.29646 -243.570247) (xy 103.296974 -243.598954) (xy 103.296502 -243.626207) (xy 103.28875 -243.68016)
			(xy 103.273398 -243.732459) (xy 103.250759 -243.782042) (xy 103.221292 -243.827897) (xy 103.185599 -243.869091)
			(xy 103.144406 -243.904785) (xy 103.098552 -243.934253) (xy 103.048971 -243.956894) (xy 102.996671 -243.972248)
			(xy 102.942719 -243.980001) (xy 102.915466 -243.980462) (xy 102.888564 -243.98) (xy 102.835295 -243.972425)
			(xy 102.783618 -243.957443) (xy 102.734557 -243.935353) (xy 102.689085 -243.906591) (xy 102.648103 -243.871728)
			(xy 102.612423 -243.831455) (xy 102.597204 -243.809266) (xy 102.590092 -243.798344) (xy 102.567232 -243.786406)
			(xy 102.454964 -243.788438) (xy 102.432612 -243.801392) (xy 102.425754 -243.812568) (xy 102.410835 -243.836172)
			(xy 102.375158 -243.879126) (xy 102.3336 -243.91642) (xy 102.287049 -243.947258) (xy 102.236501 -243.970981)
			(xy 102.183034 -243.987082) (xy 102.127791 -243.995218) (xy 102.099872 -243.995702) (xy 102.072879 -243.995243)
			(xy 102.019431 -243.987635) (xy 101.967588 -243.972573) (xy 101.918384 -243.950359) (xy 101.872799 -243.921435)
			(xy 101.851968 -243.904262) (xy 101.84384 -243.89715) (xy 101.823266 -243.891054) (xy 101.727254 -243.903246)
			(xy 101.708966 -243.914422) (xy 101.702616 -243.923312) (xy 101.687264 -243.944543) (xy 101.651674 -243.982993)
			(xy 101.611156 -244.01621) (xy 101.566473 -244.043567) (xy 101.518466 -244.064551) (xy 101.468038 -244.078765)
			(xy 101.416138 -244.085943) (xy 101.389942 -244.08638) (xy 101.362685 -244.085976) (xy 101.308726 -244.078223)
			(xy 101.256419 -244.06287) (xy 101.20683 -244.040228) (xy 101.160968 -244.010759) (xy 101.119767 -243.975063)
			(xy 101.084066 -243.933866) (xy 101.054592 -243.888007) (xy 101.031945 -243.838421) (xy 101.016586 -243.786115)
			(xy 101.008827 -243.732157) (xy 96.237806 -243.732157) (xy 96.237806 -243.9035) (xy 96.262952 -243.931948)
			(xy 96.282256 -243.934488) (xy 96.309543 -243.938436) (xy 96.362672 -243.95317) (xy 96.413126 -243.9754)
			(xy 96.459854 -244.004663) (xy 96.501882 -244.040348) (xy 96.538335 -244.081712) (xy 96.568452 -244.127894)
			(xy 96.591606 -244.17793) (xy 96.607316 -244.230779) (xy 96.615253 -244.285339) (xy 96.615252 -244.340473)
			(xy 96.607313 -244.395033) (xy 96.591602 -244.447881) (xy 96.568446 -244.497917) (xy 96.538327 -244.544097)
			(xy 96.518412 -244.566694) (xy 100.51999 -244.566694) (xy 100.524061 -244.511072) (xy 100.536187 -244.456635)
			(xy 100.55611 -244.404544) (xy 100.583406 -244.355909) (xy 100.617492 -244.311766) (xy 100.657641 -244.273057)
			(xy 100.702999 -244.240606) (xy 100.752599 -244.215105) (xy 100.805383 -244.197098) (xy 100.860226 -244.186968)
			(xy 100.91596 -244.184931) (xy 100.971397 -244.191031) (xy 101.025354 -244.205137) (xy 101.076683 -244.226949)
			(xy 101.124289 -244.256003) (xy 101.167157 -244.291678) (xy 101.204374 -244.333215) (xy 101.235147 -244.379728)
			(xy 101.258819 -244.430225) (xy 101.262228 -244.441555) (xy 104.256749 -244.441555) (xy 104.256749 -244.387045)
			(xy 104.264508 -244.33309) (xy 104.279866 -244.280788) (xy 104.302512 -244.231204) (xy 104.331984 -244.185348)
			(xy 104.367682 -244.144154) (xy 104.40888 -244.10846) (xy 104.454739 -244.078992) (xy 104.504325 -244.056352)
			(xy 104.556629 -244.040999) (xy 104.610585 -244.033247) (xy 104.63784 -244.032786) (xy 104.66658 -244.033289)
			(xy 104.723408 -244.041917) (xy 104.778299 -244.058972) (xy 104.83001 -244.084068) (xy 104.877372 -244.116638)
			(xy 104.898698 -244.13591) (xy 104.90581 -244.142514) (xy 104.923336 -244.149626) (xy 105.012744 -244.149626)
			(xy 105.03027 -244.142514) (xy 105.037382 -244.13591) (xy 105.058709 -244.11664) (xy 105.106072 -244.084075)
			(xy 105.157783 -244.058984) (xy 105.212674 -244.041934) (xy 105.269501 -244.033312) (xy 105.326979 -244.033312)
			(xy 105.383806 -244.041934) (xy 105.438697 -244.058984) (xy 105.490408 -244.084075) (xy 105.537771 -244.11664)
			(xy 105.559098 -244.13591) (xy 105.56621 -244.142514) (xy 105.583736 -244.149626) (xy 105.673144 -244.149626)
			(xy 105.69067 -244.142514) (xy 105.697782 -244.13591) (xy 105.719089 -244.116616) (xy 105.766457 -244.084054)
			(xy 105.818174 -244.058966) (xy 105.873069 -244.041921) (xy 105.9299 -244.033304) (xy 105.95864 -244.032786)
			(xy 105.985889 -244.033286) (xy 106.039832 -244.041048) (xy 106.092121 -244.056406) (xy 106.141692 -244.079049)
			(xy 106.187537 -244.108516) (xy 106.228722 -244.144207) (xy 106.264408 -244.185395) (xy 106.29387 -244.231243)
			(xy 106.316508 -244.280817) (xy 106.331861 -244.333108) (xy 106.339616 -244.387051) (xy 106.339616 -244.441549)
			(xy 106.331861 -244.495492) (xy 106.316508 -244.547783) (xy 106.29387 -244.597357) (xy 106.264408 -244.643205)
			(xy 106.228722 -244.684393) (xy 106.187537 -244.720084) (xy 106.141692 -244.749551) (xy 106.092121 -244.772194)
			(xy 106.039832 -244.787552) (xy 105.985889 -244.795314) (xy 105.95864 -244.795802) (xy 105.9299 -244.795314)
			(xy 105.873071 -244.786683) (xy 105.81818 -244.769624) (xy 105.766469 -244.744525) (xy 105.719108 -244.711952)
			(xy 105.697782 -244.692678) (xy 105.69067 -244.686074) (xy 105.673144 -244.678962) (xy 105.583736 -244.678962)
			(xy 105.56621 -244.686074) (xy 105.559098 -244.692678) (xy 105.537771 -244.711948) (xy 105.490408 -244.744513)
			(xy 105.438697 -244.769604) (xy 105.383806 -244.786654) (xy 105.326979 -244.795276) (xy 105.269501 -244.795276)
			(xy 105.212674 -244.786654) (xy 105.157783 -244.769604) (xy 105.106072 -244.744513) (xy 105.058709 -244.711948)
			(xy 105.037382 -244.692678) (xy 105.03027 -244.686074) (xy 105.012744 -244.678962) (xy 104.923336 -244.678962)
			(xy 104.90581 -244.686074) (xy 104.898698 -244.692678) (xy 104.877357 -244.711932) (xy 104.829998 -244.7445)
			(xy 104.77829 -244.769596) (xy 104.723403 -244.78665) (xy 104.666578 -244.795278) (xy 104.63784 -244.795802)
			(xy 104.610585 -244.795353) (xy 104.556629 -244.787601) (xy 104.504325 -244.772248) (xy 104.454739 -244.749608)
			(xy 104.40888 -244.72014) (xy 104.367682 -244.684446) (xy 104.331984 -244.643252) (xy 104.302512 -244.597396)
			(xy 104.279866 -244.547812) (xy 104.264508 -244.49551) (xy 104.256749 -244.441555) (xy 101.262228 -244.441555)
			(xy 101.274887 -244.483632) (xy 101.283007 -244.538808) (xy 101.283516 -244.566694) (xy 101.283007 -244.59458)
			(xy 101.274887 -244.649756) (xy 101.258819 -244.703163) (xy 101.235147 -244.75366) (xy 101.204374 -244.800173)
			(xy 101.167157 -244.84171) (xy 101.124289 -244.877385) (xy 101.076683 -244.906439) (xy 101.025354 -244.928251)
			(xy 100.971397 -244.942357) (xy 100.91596 -244.948457) (xy 100.860226 -244.94642) (xy 100.805383 -244.93629)
			(xy 100.752599 -244.918283) (xy 100.702999 -244.892782) (xy 100.657641 -244.860331) (xy 100.617492 -244.821622)
			(xy 100.583406 -244.777479) (xy 100.55611 -244.728844) (xy 100.536187 -244.676753) (xy 100.524061 -244.622316)
			(xy 100.51999 -244.566694) (xy 96.518412 -244.566694) (xy 96.501873 -244.58546) (xy 96.459844 -244.621144)
			(xy 96.413116 -244.650405) (xy 96.362661 -244.672634) (xy 96.309531 -244.687366) (xy 96.282256 -244.691408)
			(xy 96.262952 -244.693948) (xy 96.237806 -244.722396) (xy 96.237806 -245.37416) (xy 96.238253 -245.383578)
			(xy 96.245041 -245.401152) (xy 96.251014 -245.40845) (xy 96.264984 -245.423944) (xy 96.268054 -245.427124)
			(xy 96.275075 -245.432493) (xy 96.278954 -245.434612) (xy 96.301306 -245.44655) (xy 96.309434 -245.44782)
			(xy 96.337261 -245.452905) (xy 96.391117 -245.470205) (xy 96.441827 -245.495269) (xy 96.488279 -245.527547)
			(xy 96.529454 -245.566333) (xy 96.56445 -245.610774) (xy 96.592498 -245.659897) (xy 96.612983 -245.712623)
			(xy 96.625456 -245.767797) (xy 96.629644 -245.824208) (xy 96.625454 -245.880618) (xy 96.612978 -245.935792)
			(xy 96.60944 -245.944898) (xy 100.372416 -245.944898) (xy 100.376487 -245.889276) (xy 100.388613 -245.834839)
			(xy 100.408536 -245.782748) (xy 100.435832 -245.734113) (xy 100.469918 -245.68997) (xy 100.510067 -245.651261)
			(xy 100.555425 -245.61881) (xy 100.605025 -245.593309) (xy 100.657809 -245.575302) (xy 100.712652 -245.565172)
			(xy 100.768386 -245.563135) (xy 100.823823 -245.569235) (xy 100.87778 -245.583341) (xy 100.929109 -245.605153)
			(xy 100.976715 -245.634207) (xy 101.019583 -245.669882) (xy 101.0568 -245.711419) (xy 101.087573 -245.757932)
			(xy 101.111245 -245.808429) (xy 101.127313 -245.861836) (xy 101.135433 -245.917012) (xy 101.135942 -245.944898)
			(xy 101.135433 -245.972784) (xy 101.127313 -246.02796) (xy 101.111245 -246.081367) (xy 101.087573 -246.131864)
			(xy 101.0568 -246.178377) (xy 101.019583 -246.219914) (xy 100.976715 -246.255589) (xy 100.929109 -246.284643)
			(xy 100.87778 -246.306455) (xy 100.823823 -246.320561) (xy 100.768386 -246.326661) (xy 100.712652 -246.324624)
			(xy 100.657809 -246.314494) (xy 100.605025 -246.296487) (xy 100.555425 -246.270986) (xy 100.510067 -246.238535)
			(xy 100.469918 -246.199826) (xy 100.435832 -246.155683) (xy 100.408536 -246.107048) (xy 100.388613 -246.054957)
			(xy 100.376487 -246.00052) (xy 100.372416 -245.944898) (xy 96.60944 -245.944898) (xy 96.592491 -245.988517)
			(xy 96.564441 -246.037639) (xy 96.529444 -246.082079) (xy 96.488267 -246.120862) (xy 96.441813 -246.153139)
			(xy 96.391102 -246.178201) (xy 96.337246 -246.195498) (xy 96.309434 -246.200676) (xy 96.301306 -246.201946)
			(xy 96.278954 -246.213884) (xy 96.275068 -246.215993) (xy 96.268043 -246.221359) (xy 96.264984 -246.224552)
			(xy 96.251014 -246.240046) (xy 96.244929 -246.247274) (xy 96.238149 -246.264894) (xy 96.237806 -246.274336)
			(xy 96.237806 -246.83212) (xy 99.693474 -246.83212) (xy 99.697545 -246.776498) (xy 99.709671 -246.722061)
			(xy 99.729594 -246.66997) (xy 99.75689 -246.621335) (xy 99.790976 -246.577192) (xy 99.831125 -246.538483)
			(xy 99.876483 -246.506032) (xy 99.926083 -246.480531) (xy 99.978867 -246.462524) (xy 100.03371 -246.452394)
			(xy 100.089444 -246.450357) (xy 100.144881 -246.456457) (xy 100.198838 -246.470563) (xy 100.250167 -246.492375)
			(xy 100.297773 -246.521429) (xy 100.340641 -246.557104) (xy 100.377858 -246.598641) (xy 100.408631 -246.645154)
			(xy 100.432303 -246.695651) (xy 100.448371 -246.749058) (xy 100.456491 -246.804234) (xy 100.457 -246.83212)
			(xy 100.456491 -246.860006) (xy 100.448371 -246.915182) (xy 100.432303 -246.968589) (xy 100.408631 -247.019086)
			(xy 100.377858 -247.065599) (xy 100.340641 -247.107136) (xy 100.297773 -247.142811) (xy 100.250167 -247.171865)
			(xy 100.198838 -247.193677) (xy 100.144881 -247.207783) (xy 100.089444 -247.213883) (xy 100.03371 -247.211846)
			(xy 99.978867 -247.201716) (xy 99.926083 -247.183709) (xy 99.876483 -247.158208) (xy 99.831125 -247.125757)
			(xy 99.790976 -247.087048) (xy 99.75689 -247.042905) (xy 99.729594 -246.99427) (xy 99.709671 -246.942179)
			(xy 99.697545 -246.887742) (xy 99.693474 -246.83212) (xy 96.237806 -246.83212) (xy 96.237806 -248.331736)
			(xy 102.279196 -248.331736) (xy 102.279682 -248.302996) (xy 102.288314 -248.246167) (xy 102.305373 -248.191276)
			(xy 102.330473 -248.139564) (xy 102.363046 -248.092204) (xy 102.38232 -248.070878) (xy 102.388924 -248.063766)
			(xy 102.396036 -248.04624) (xy 102.396036 -247.956832) (xy 102.388924 -247.939306) (xy 102.38232 -247.932194)
			(xy 102.363085 -247.910836) (xy 102.330519 -247.863479) (xy 102.305426 -247.811772) (xy 102.288373 -247.756886)
			(xy 102.279747 -247.700063) (xy 102.279743 -247.642589) (xy 102.288361 -247.585765) (xy 102.305406 -247.530877)
			(xy 102.330493 -247.479167) (xy 102.363052 -247.431805) (xy 102.38232 -247.410478) (xy 102.388924 -247.403366)
			(xy 102.396036 -247.38584) (xy 102.396036 -247.296432) (xy 102.388924 -247.278906) (xy 102.38232 -247.271794)
			(xy 102.363063 -247.250455) (xy 102.330496 -247.203096) (xy 102.305401 -247.151387) (xy 102.288347 -247.096499)
			(xy 102.27972 -247.039674) (xy 102.279196 -247.010936) (xy 102.279684 -246.983567) (xy 102.287497 -246.929388)
			(xy 102.302981 -246.876886) (xy 102.325818 -246.827138) (xy 102.355537 -246.781171) (xy 102.373176 -246.760238)
			(xy 102.379272 -246.753126) (xy 102.385622 -246.736108) (xy 102.385622 -246.650764) (xy 102.379272 -246.633746)
			(xy 102.373176 -246.626634) (xy 102.355536 -246.605703) (xy 102.325825 -246.55973) (xy 102.30299 -246.509982)
			(xy 102.287499 -246.457481) (xy 102.27967 -246.403305) (xy 102.279196 -246.375936) (xy 102.279682 -246.348685)
			(xy 102.287438 -246.294737) (xy 102.302793 -246.242442) (xy 102.325435 -246.192865) (xy 102.354901 -246.147015)
			(xy 102.390592 -246.105824) (xy 102.431783 -246.070133) (xy 102.477633 -246.040667) (xy 102.52721 -246.018025)
			(xy 102.579505 -246.00267) (xy 102.633453 -245.994914) (xy 102.687955 -245.994914) (xy 102.741903 -246.00267)
			(xy 102.794198 -246.018025) (xy 102.843775 -246.040667) (xy 102.889625 -246.070133) (xy 102.930816 -246.105824)
			(xy 102.966507 -246.147015) (xy 102.995973 -246.192865) (xy 103.018615 -246.242442) (xy 103.03397 -246.294737)
			(xy 103.041726 -246.348685) (xy 103.042212 -246.375936) (xy 103.041764 -246.403307) (xy 103.033941 -246.457487)
			(xy 103.018448 -246.50999) (xy 102.995602 -246.559736) (xy 102.965875 -246.605703) (xy 102.948232 -246.626634)
			(xy 102.942136 -246.633746) (xy 102.935786 -246.650764) (xy 102.935786 -246.736108) (xy 102.942136 -246.753126)
			(xy 102.948232 -246.760238) (xy 102.96586 -246.781179) (xy 102.995573 -246.82715) (xy 103.01841 -246.876895)
			(xy 103.033904 -246.929394) (xy 103.041736 -246.983567) (xy 103.042212 -247.010936) (xy 103.041707 -247.039676)
			(xy 103.033079 -247.096504) (xy 103.016025 -247.151394) (xy 102.990929 -247.203106) (xy 102.95836 -247.250468)
			(xy 102.939088 -247.271794) (xy 102.932484 -247.278906) (xy 102.925372 -247.296432) (xy 102.925372 -247.38584)
			(xy 102.932484 -247.403366) (xy 102.939088 -247.410478) (xy 102.958394 -247.431774) (xy 102.990957 -247.479142)
			(xy 103.016046 -247.530859) (xy 103.028986 -247.57253) (xy 114.288822 -247.57253) (xy 114.292893 -247.516908)
			(xy 114.305019 -247.462471) (xy 114.324942 -247.41038) (xy 114.352238 -247.361745) (xy 114.386324 -247.317602)
			(xy 114.426473 -247.278893) (xy 114.471831 -247.246442) (xy 114.521431 -247.220941) (xy 114.574215 -247.202934)
			(xy 114.629058 -247.192804) (xy 114.684792 -247.190767) (xy 114.740229 -247.196867) (xy 114.794186 -247.210973)
			(xy 114.845515 -247.232785) (xy 114.893121 -247.261839) (xy 114.935989 -247.297514) (xy 114.973206 -247.339051)
			(xy 115.003979 -247.385564) (xy 115.027651 -247.436061) (xy 115.043719 -247.489468) (xy 115.051839 -247.544644)
			(xy 115.052348 -247.57253) (xy 115.05232 -247.574054) (xy 115.980462 -247.574054) (xy 115.984533 -247.518432)
			(xy 115.996659 -247.463995) (xy 116.016582 -247.411904) (xy 116.043878 -247.363269) (xy 116.077964 -247.319126)
			(xy 116.118113 -247.280417) (xy 116.163471 -247.247966) (xy 116.213071 -247.222465) (xy 116.265855 -247.204458)
			(xy 116.320698 -247.194328) (xy 116.376432 -247.192291) (xy 116.431869 -247.198391) (xy 116.485826 -247.212497)
			(xy 116.537155 -247.234309) (xy 116.584761 -247.263363) (xy 116.627629 -247.299038) (xy 116.664846 -247.340575)
			(xy 116.695619 -247.387088) (xy 116.719291 -247.437585) (xy 116.735359 -247.490992) (xy 116.743479 -247.546168)
			(xy 116.743988 -247.574054) (xy 116.743479 -247.60194) (xy 116.735359 -247.657116) (xy 116.719291 -247.710523)
			(xy 116.695619 -247.76102) (xy 116.664846 -247.807533) (xy 116.627629 -247.84907) (xy 116.584761 -247.884745)
			(xy 116.537155 -247.913799) (xy 116.485826 -247.935611) (xy 116.431869 -247.949717) (xy 116.376432 -247.955817)
			(xy 116.320698 -247.95378) (xy 116.265855 -247.94365) (xy 116.213071 -247.925643) (xy 116.163471 -247.900142)
			(xy 116.118113 -247.867691) (xy 116.077964 -247.828982) (xy 116.043878 -247.784839) (xy 116.016582 -247.736204)
			(xy 115.996659 -247.684113) (xy 115.984533 -247.629676) (xy 115.980462 -247.574054) (xy 115.05232 -247.574054)
			(xy 115.051839 -247.600416) (xy 115.043719 -247.655592) (xy 115.027651 -247.708999) (xy 115.003979 -247.759496)
			(xy 114.973206 -247.806009) (xy 114.935989 -247.847546) (xy 114.893121 -247.883221) (xy 114.845515 -247.912275)
			(xy 114.794186 -247.934087) (xy 114.740229 -247.948193) (xy 114.684792 -247.954293) (xy 114.629058 -247.952256)
			(xy 114.574215 -247.942126) (xy 114.521431 -247.924119) (xy 114.471831 -247.898618) (xy 114.426473 -247.866167)
			(xy 114.386324 -247.827458) (xy 114.352238 -247.783315) (xy 114.324942 -247.73468) (xy 114.305019 -247.682589)
			(xy 114.292893 -247.628152) (xy 114.288822 -247.57253) (xy 103.028986 -247.57253) (xy 103.033093 -247.585754)
			(xy 103.041712 -247.642586) (xy 103.041708 -247.700067) (xy 103.033081 -247.756897) (xy 103.016026 -247.81179)
			(xy 102.990931 -247.863503) (xy 102.958361 -247.910867) (xy 102.939088 -247.932194) (xy 102.932484 -247.939306)
			(xy 102.925372 -247.956832) (xy 102.925372 -248.04624) (xy 102.932484 -248.063766) (xy 102.939088 -248.070878)
			(xy 102.95838 -248.092186) (xy 102.990942 -248.139554) (xy 103.01603 -248.19127) (xy 103.033076 -248.246165)
			(xy 103.041694 -248.302996) (xy 103.042212 -248.331736) (xy 103.041726 -248.358987) (xy 103.03397 -248.412935)
			(xy 103.018615 -248.46523) (xy 103.017828 -248.466954) (xy 104.083041 -248.466954) (xy 104.083041 -248.412446)
			(xy 104.090798 -248.358493) (xy 104.106155 -248.306192) (xy 104.128799 -248.25661) (xy 104.158268 -248.210755)
			(xy 104.193964 -248.169561) (xy 104.235158 -248.133866) (xy 104.281014 -248.104397) (xy 104.330596 -248.081754)
			(xy 104.382897 -248.066397) (xy 104.43685 -248.058641) (xy 104.464104 -248.058178) (xy 104.492843 -248.058705)
			(xy 104.54967 -248.067328) (xy 104.60456 -248.084377) (xy 104.656272 -248.109468) (xy 104.703635 -248.142032)
			(xy 104.724962 -248.161302) (xy 104.732074 -248.167906) (xy 104.7496 -248.175018) (xy 104.839008 -248.175018)
			(xy 104.856534 -248.167906) (xy 104.863646 -248.161302) (xy 104.884973 -248.142032) (xy 104.932336 -248.109467)
			(xy 104.984047 -248.084376) (xy 105.038938 -248.067326) (xy 105.095765 -248.058704) (xy 105.153243 -248.058704)
			(xy 105.21007 -248.067326) (xy 105.264961 -248.084376) (xy 105.316672 -248.109467) (xy 105.364035 -248.142032)
			(xy 105.385362 -248.161302) (xy 105.392474 -248.167906) (xy 105.41 -248.175018) (xy 105.499408 -248.175018)
			(xy 105.516934 -248.167906) (xy 105.524046 -248.161302) (xy 105.545381 -248.14204) (xy 105.59274 -248.109471)
			(xy 105.644449 -248.084375) (xy 105.699339 -248.067323) (xy 105.756165 -248.058699) (xy 105.784904 -248.058178)
			(xy 105.812154 -248.058693) (xy 105.866099 -248.066449) (xy 105.918392 -248.081804) (xy 105.967966 -248.104445)
			(xy 106.013815 -248.13391) (xy 106.055003 -248.1696) (xy 106.090693 -248.210789) (xy 106.120157 -248.256637)
			(xy 106.142797 -248.306212) (xy 106.158152 -248.358505) (xy 106.165908 -248.41245) (xy 106.165908 -248.46695)
			(xy 106.158152 -248.520895) (xy 106.142797 -248.573188) (xy 106.120157 -248.622763) (xy 106.090693 -248.668611)
			(xy 106.055003 -248.7098) (xy 106.013815 -248.74549) (xy 105.967966 -248.774955) (xy 105.918392 -248.797596)
			(xy 105.866099 -248.812951) (xy 105.812154 -248.820707) (xy 105.784904 -248.821194) (xy 105.756165 -248.820669)
			(xy 105.699338 -248.812047) (xy 105.644447 -248.794998) (xy 105.592735 -248.769906) (xy 105.545373 -248.737341)
			(xy 105.524046 -248.71807) (xy 105.516934 -248.711466) (xy 105.499408 -248.704354) (xy 105.41 -248.704354)
			(xy 105.392474 -248.711466) (xy 105.385362 -248.71807) (xy 105.364035 -248.73734) (xy 105.316672 -248.769905)
			(xy 105.264961 -248.794996) (xy 105.21007 -248.812046) (xy 105.153243 -248.820668) (xy 105.095765 -248.820668)
			(xy 105.038938 -248.812046) (xy 104.984047 -248.794996) (xy 104.932336 -248.769905) (xy 104.884973 -248.73734)
			(xy 104.863646 -248.71807) (xy 104.856534 -248.711466) (xy 104.839008 -248.704354) (xy 104.7496 -248.704354)
			(xy 104.732074 -248.711466) (xy 104.724962 -248.71807) (xy 104.703634 -248.73734) (xy 104.656272 -248.769906)
			(xy 104.604561 -248.794999) (xy 104.54967 -248.812049) (xy 104.492843 -248.820673) (xy 104.464104 -248.821194)
			(xy 104.43685 -248.820759) (xy 104.382897 -248.813003) (xy 104.330596 -248.797646) (xy 104.281014 -248.775003)
			(xy 104.235158 -248.745534) (xy 104.193964 -248.709839) (xy 104.158268 -248.668645) (xy 104.128799 -248.62279)
			(xy 104.106155 -248.573208) (xy 104.090798 -248.520907) (xy 104.083041 -248.466954) (xy 103.017828 -248.466954)
			(xy 102.995973 -248.514807) (xy 102.966507 -248.560657) (xy 102.930816 -248.601848) (xy 102.889625 -248.637539)
			(xy 102.843775 -248.667005) (xy 102.794198 -248.689647) (xy 102.741903 -248.705002) (xy 102.687955 -248.712758)
			(xy 102.633453 -248.712758) (xy 102.579505 -248.705002) (xy 102.52721 -248.689647) (xy 102.477633 -248.667005)
			(xy 102.431783 -248.637539) (xy 102.390592 -248.601848) (xy 102.354901 -248.560657) (xy 102.325435 -248.514807)
			(xy 102.302793 -248.46523) (xy 102.287438 -248.412935) (xy 102.279682 -248.358987) (xy 102.279196 -248.331736)
			(xy 96.237806 -248.331736) (xy 96.237806 -249.701655) (xy 102.324835 -249.701655) (xy 102.324835 -249.647145)
			(xy 102.332593 -249.59319) (xy 102.34795 -249.540888) (xy 102.370595 -249.491304) (xy 102.400066 -249.445448)
			(xy 102.435764 -249.404252) (xy 102.47696 -249.368557) (xy 102.522818 -249.339088) (xy 102.572403 -249.316445)
			(xy 102.624705 -249.301089) (xy 102.678661 -249.293334) (xy 102.705916 -249.292872) (xy 102.734655 -249.293393)
			(xy 102.791482 -249.302018) (xy 102.846372 -249.319069) (xy 102.898084 -249.344161) (xy 102.945447 -249.376726)
			(xy 102.966774 -249.395996) (xy 102.973886 -249.4026) (xy 102.991412 -249.409712) (xy 103.08082 -249.409712)
			(xy 103.098346 -249.4026) (xy 103.105458 -249.395996) (xy 103.126785 -249.376726) (xy 103.174148 -249.344161)
			(xy 103.225859 -249.31907) (xy 103.28075 -249.30202) (xy 103.337577 -249.293398) (xy 103.395055 -249.293398)
			(xy 103.451882 -249.30202) (xy 103.506773 -249.31907) (xy 103.558484 -249.344161) (xy 103.605847 -249.376726)
			(xy 103.627174 -249.395996) (xy 103.634286 -249.4026) (xy 103.651812 -249.409712) (xy 103.74122 -249.409712)
			(xy 103.758746 -249.4026) (xy 103.765858 -249.395996) (xy 103.787187 -249.376728) (xy 103.834548 -249.344159)
			(xy 103.886259 -249.319065) (xy 103.941149 -249.302014) (xy 103.997977 -249.293392) (xy 104.026716 -249.292872)
			(xy 104.053965 -249.293399) (xy 104.107908 -249.301157) (xy 104.160198 -249.316513) (xy 104.209771 -249.339154)
			(xy 104.255617 -249.368619) (xy 104.296803 -249.404309) (xy 104.332491 -249.445496) (xy 104.361954 -249.491343)
			(xy 104.384593 -249.540917) (xy 104.399946 -249.593208) (xy 104.407702 -249.647151) (xy 104.407702 -249.701649)
			(xy 104.399946 -249.755592) (xy 104.384593 -249.807883) (xy 104.361954 -249.857457) (xy 104.332491 -249.903304)
			(xy 104.296803 -249.944491) (xy 104.255617 -249.980181) (xy 104.209771 -250.009646) (xy 104.160198 -250.032287)
			(xy 104.107908 -250.047643) (xy 104.053965 -250.055401) (xy 104.026716 -250.055888) (xy 103.997977 -250.055358)
			(xy 103.94115 -250.046737) (xy 103.886259 -250.029689) (xy 103.834547 -250.004599) (xy 103.787185 -249.972034)
			(xy 103.765858 -249.952764) (xy 103.758746 -249.94616) (xy 103.74122 -249.939048) (xy 103.651812 -249.939048)
			(xy 103.634286 -249.94616) (xy 103.627174 -249.952764) (xy 103.605847 -249.972034) (xy 103.558484 -250.004599)
			(xy 103.506773 -250.02969) (xy 103.451882 -250.04674) (xy 103.395055 -250.055362) (xy 103.337577 -250.055362)
			(xy 103.28075 -250.04674) (xy 103.225859 -250.02969) (xy 103.174148 -250.004599) (xy 103.126785 -249.972034)
			(xy 103.105458 -249.952764) (xy 103.098346 -249.94616) (xy 103.08082 -249.939048) (xy 102.991412 -249.939048)
			(xy 102.973886 -249.94616) (xy 102.966774 -249.952764) (xy 102.945441 -249.972027) (xy 102.89808 -250.004595)
			(xy 102.84637 -250.029688) (xy 102.791481 -250.046741) (xy 102.734655 -250.055366) (xy 102.705916 -250.055888)
			(xy 102.678661 -250.055466) (xy 102.624705 -250.047711) (xy 102.572403 -250.032355) (xy 102.522818 -250.009712)
			(xy 102.47696 -249.980243) (xy 102.435764 -249.944548) (xy 102.400066 -249.903352) (xy 102.370595 -249.857496)
			(xy 102.34795 -249.807912) (xy 102.332593 -249.75561) (xy 102.324835 -249.701655) (xy 96.237806 -249.701655)
			(xy 96.237806 -250.7107) (xy 96.237925 -250.715654) (xy 96.239844 -250.725376) (xy 96.241616 -250.730004)
			(xy 96.496634 -251.3457) (xy 123.339096 -251.3457) (xy 123.343167 -251.290078) (xy 123.355293 -251.235641)
			(xy 123.375216 -251.18355) (xy 123.402512 -251.134915) (xy 123.436598 -251.090772) (xy 123.476747 -251.052063)
			(xy 123.522105 -251.019612) (xy 123.571705 -250.994111) (xy 123.624489 -250.976104) (xy 123.679332 -250.965974)
			(xy 123.735066 -250.963937) (xy 123.790503 -250.970037) (xy 123.84446 -250.984143) (xy 123.895789 -251.005955)
			(xy 123.943395 -251.035009) (xy 123.986263 -251.070684) (xy 124.02348 -251.112221) (xy 124.054253 -251.158734)
			(xy 124.077925 -251.209231) (xy 124.093993 -251.262638) (xy 124.102113 -251.317814) (xy 124.102622 -251.3457)
			(xy 124.863096 -251.3457) (xy 124.867167 -251.290078) (xy 124.879293 -251.235641) (xy 124.899216 -251.18355)
			(xy 124.926512 -251.134915) (xy 124.960598 -251.090772) (xy 125.000747 -251.052063) (xy 125.046105 -251.019612)
			(xy 125.095705 -250.994111) (xy 125.148489 -250.976104) (xy 125.203332 -250.965974) (xy 125.259066 -250.963937)
			(xy 125.314503 -250.970037) (xy 125.36846 -250.984143) (xy 125.419789 -251.005955) (xy 125.467395 -251.035009)
			(xy 125.510263 -251.070684) (xy 125.54748 -251.112221) (xy 125.578253 -251.158734) (xy 125.601925 -251.209231)
			(xy 125.617993 -251.262638) (xy 125.626113 -251.317814) (xy 125.626622 -251.3457) (xy 125.626113 -251.373586)
			(xy 125.617993 -251.428762) (xy 125.601925 -251.482169) (xy 125.578253 -251.532666) (xy 125.54748 -251.579179)
			(xy 125.510263 -251.620716) (xy 125.467395 -251.656391) (xy 125.419789 -251.685445) (xy 125.36846 -251.707257)
			(xy 125.314503 -251.721363) (xy 125.259066 -251.727463) (xy 125.203332 -251.725426) (xy 125.148489 -251.715296)
			(xy 125.095705 -251.697289) (xy 125.046105 -251.671788) (xy 125.000747 -251.639337) (xy 124.960598 -251.600628)
			(xy 124.926512 -251.556485) (xy 124.899216 -251.50785) (xy 124.879293 -251.455759) (xy 124.867167 -251.401322)
			(xy 124.863096 -251.3457) (xy 124.102622 -251.3457) (xy 124.102113 -251.373586) (xy 124.093993 -251.428762)
			(xy 124.077925 -251.482169) (xy 124.054253 -251.532666) (xy 124.02348 -251.579179) (xy 123.986263 -251.620716)
			(xy 123.943395 -251.656391) (xy 123.895789 -251.685445) (xy 123.84446 -251.707257) (xy 123.790503 -251.721363)
			(xy 123.735066 -251.727463) (xy 123.679332 -251.725426) (xy 123.624489 -251.715296) (xy 123.571705 -251.697289)
			(xy 123.522105 -251.671788) (xy 123.476747 -251.639337) (xy 123.436598 -251.600628) (xy 123.402512 -251.556485)
			(xy 123.375216 -251.50785) (xy 123.355293 -251.455759) (xy 123.343167 -251.401322) (xy 123.339096 -251.3457)
			(xy 96.496634 -251.3457) (xy 96.825443 -252.139552) (xy 120.27355 -252.139552) (xy 120.27355 -252.085048)
			(xy 120.281306 -252.031099) (xy 120.296661 -251.978802) (xy 120.319302 -251.929223) (xy 120.348768 -251.883371)
			(xy 120.384459 -251.842179) (xy 120.425649 -251.806484) (xy 120.471499 -251.777015) (xy 120.521076 -251.754371)
			(xy 120.573371 -251.739012) (xy 120.62732 -251.731252) (xy 120.654572 -251.730764) (xy 120.687504 -251.731503)
			(xy 120.752384 -251.742864) (xy 120.783604 -251.75337) (xy 120.791986 -251.756164) (xy 123.222258 -251.756164)
			(xy 123.250239 -251.7567) (xy 123.305509 -251.765468) (xy 123.358725 -251.78278) (xy 123.408575 -251.808209)
			(xy 123.453831 -251.841128) (xy 123.473972 -251.860558) (xy 124.957078 -253.343664) (xy 124.976479 -253.363828)
			(xy 125.009373 -253.409091) (xy 125.03479 -253.458938) (xy 125.052108 -253.512144) (xy 125.0609 -253.567402)
			(xy 125.061472 -253.595378) (xy 125.061472 -256.226564) (xy 126.220472 -256.226564) (xy 126.224543 -256.170942)
			(xy 126.236669 -256.116505) (xy 126.256592 -256.064414) (xy 126.283888 -256.015779) (xy 126.317974 -255.971636)
			(xy 126.358123 -255.932927) (xy 126.403481 -255.900476) (xy 126.453081 -255.874975) (xy 126.505865 -255.856968)
			(xy 126.560708 -255.846838) (xy 126.616442 -255.844801) (xy 126.671879 -255.850901) (xy 126.725836 -255.865007)
			(xy 126.777165 -255.886819) (xy 126.824771 -255.915873) (xy 126.867639 -255.951548) (xy 126.904856 -255.993085)
			(xy 126.935629 -256.039598) (xy 126.959301 -256.090095) (xy 126.975369 -256.143502) (xy 126.983489 -256.198678)
			(xy 126.983998 -256.226564) (xy 128.285746 -256.226564) (xy 128.289817 -256.170942) (xy 128.301943 -256.116505)
			(xy 128.321866 -256.064414) (xy 128.349162 -256.015779) (xy 128.383248 -255.971636) (xy 128.423397 -255.932927)
			(xy 128.468755 -255.900476) (xy 128.518355 -255.874975) (xy 128.571139 -255.856968) (xy 128.625982 -255.846838)
			(xy 128.681716 -255.844801) (xy 128.737153 -255.850901) (xy 128.79111 -255.865007) (xy 128.842439 -255.886819)
			(xy 128.890045 -255.915873) (xy 128.932913 -255.951548) (xy 128.97013 -255.993085) (xy 129.000903 -256.039598)
			(xy 129.024575 -256.090095) (xy 129.040643 -256.143502) (xy 129.048763 -256.198678) (xy 129.049272 -256.226564)
			(xy 129.048763 -256.25445) (xy 129.040643 -256.309626) (xy 129.024575 -256.363033) (xy 129.000903 -256.41353)
			(xy 128.97013 -256.460043) (xy 128.932913 -256.50158) (xy 128.890045 -256.537255) (xy 128.842439 -256.566309)
			(xy 128.79111 -256.588121) (xy 128.737153 -256.602227) (xy 128.681716 -256.608327) (xy 128.625982 -256.60629)
			(xy 128.571139 -256.59616) (xy 128.518355 -256.578153) (xy 128.468755 -256.552652) (xy 128.423397 -256.520201)
			(xy 128.383248 -256.481492) (xy 128.349162 -256.437349) (xy 128.321866 -256.388714) (xy 128.301943 -256.336623)
			(xy 128.289817 -256.282186) (xy 128.285746 -256.226564) (xy 126.983998 -256.226564) (xy 126.983489 -256.25445)
			(xy 126.975369 -256.309626) (xy 126.959301 -256.363033) (xy 126.935629 -256.41353) (xy 126.904856 -256.460043)
			(xy 126.867639 -256.50158) (xy 126.824771 -256.537255) (xy 126.777165 -256.566309) (xy 126.725836 -256.588121)
			(xy 126.671879 -256.602227) (xy 126.616442 -256.608327) (xy 126.560708 -256.60629) (xy 126.505865 -256.59616)
			(xy 126.453081 -256.578153) (xy 126.403481 -256.552652) (xy 126.358123 -256.520201) (xy 126.317974 -256.481492)
			(xy 126.283888 -256.437349) (xy 126.256592 -256.388714) (xy 126.236669 -256.336623) (xy 126.224543 -256.282186)
			(xy 126.220472 -256.226564) (xy 125.061472 -256.226564) (xy 125.061472 -256.542794) (xy 125.061932 -256.552763)
			(xy 125.069518 -256.571199) (xy 125.076204 -256.578608) (xy 125.61316 -257.115564) (xy 128.285746 -257.115564)
			(xy 128.289817 -257.059942) (xy 128.301943 -257.005505) (xy 128.321866 -256.953414) (xy 128.349162 -256.904779)
			(xy 128.383248 -256.860636) (xy 128.423397 -256.821927) (xy 128.468755 -256.789476) (xy 128.518355 -256.763975)
			(xy 128.571139 -256.745968) (xy 128.625982 -256.735838) (xy 128.681716 -256.733801) (xy 128.737153 -256.739901)
			(xy 128.79111 -256.754007) (xy 128.842439 -256.775819) (xy 128.890045 -256.804873) (xy 128.932913 -256.840548)
			(xy 128.97013 -256.882085) (xy 129.000903 -256.928598) (xy 129.024575 -256.979095) (xy 129.040643 -257.032502)
			(xy 129.048763 -257.087678) (xy 129.049272 -257.115564) (xy 129.048763 -257.14345) (xy 129.040643 -257.198626)
			(xy 129.024575 -257.252033) (xy 129.000903 -257.30253) (xy 128.97013 -257.349043) (xy 128.932913 -257.39058)
			(xy 128.890045 -257.426255) (xy 128.842439 -257.455309) (xy 128.79111 -257.477121) (xy 128.737153 -257.491227)
			(xy 128.681716 -257.497327) (xy 128.625982 -257.49529) (xy 128.571139 -257.48516) (xy 128.518355 -257.467153)
			(xy 128.468755 -257.441652) (xy 128.423397 -257.409201) (xy 128.383248 -257.370492) (xy 128.349162 -257.326349)
			(xy 128.321866 -257.277714) (xy 128.301943 -257.225623) (xy 128.289817 -257.171186) (xy 128.285746 -257.115564)
			(xy 125.61316 -257.115564) (xy 125.972062 -257.474466) (xy 125.991461 -257.494632) (xy 126.024356 -257.539894)
			(xy 126.049774 -257.58974) (xy 126.067092 -257.642946) (xy 126.075884 -257.698204) (xy 126.076456 -257.72618)
			(xy 126.076456 -258.131564) (xy 126.258572 -258.131564) (xy 126.262643 -258.075942) (xy 126.274769 -258.021505)
			(xy 126.294692 -257.969414) (xy 126.321988 -257.920779) (xy 126.356074 -257.876636) (xy 126.396223 -257.837927)
			(xy 126.441581 -257.805476) (xy 126.491181 -257.779975) (xy 126.543965 -257.761968) (xy 126.598808 -257.751838)
			(xy 126.654542 -257.749801) (xy 126.709979 -257.755901) (xy 126.763936 -257.770007) (xy 126.815265 -257.791819)
			(xy 126.862871 -257.820873) (xy 126.905739 -257.856548) (xy 126.942956 -257.898085) (xy 126.973729 -257.944598)
			(xy 126.997401 -257.995095) (xy 127.013469 -258.048502) (xy 127.021589 -258.103678) (xy 127.022098 -258.131564)
			(xy 127.021589 -258.15945) (xy 127.013469 -258.214626) (xy 126.997401 -258.268033) (xy 126.973729 -258.31853)
			(xy 126.942956 -258.365043) (xy 126.905739 -258.40658) (xy 126.862871 -258.442255) (xy 126.815265 -258.471309)
			(xy 126.763936 -258.493121) (xy 126.709979 -258.507227) (xy 126.654542 -258.513327) (xy 126.598808 -258.51129)
			(xy 126.543965 -258.50116) (xy 126.491181 -258.483153) (xy 126.441581 -258.457652) (xy 126.396223 -258.425201)
			(xy 126.356074 -258.386492) (xy 126.321988 -258.342349) (xy 126.294692 -258.293714) (xy 126.274769 -258.241623)
			(xy 126.262643 -258.187186) (xy 126.258572 -258.131564) (xy 126.076456 -258.131564) (xy 126.076456 -260.67766)
			(xy 126.076938 -260.687626) (xy 126.084509 -260.706063) (xy 126.091188 -260.713474) (xy 131.95681 -266.579096)
			(xy 131.976214 -266.599257) (xy 132.00911 -266.64452) (xy 132.034529 -266.694367) (xy 132.051845 -266.747574)
			(xy 132.060634 -266.802833) (xy 132.061204 -266.83081) (xy 132.061204 -277.827232) (xy 132.060661 -277.855212)
			(xy 132.051895 -277.910483) (xy 132.034585 -277.963699) (xy 132.009158 -278.01355) (xy 131.97624 -278.058805)
			(xy 131.95681 -278.078946) (xy 131.105402 -278.930354) (xy 131.098683 -278.937761) (xy 131.09096 -278.956183)
			(xy 131.090416 -278.966168) (xy 131.090416 -280.479754) (xy 131.093464 -280.488136) (xy 131.104001 -280.519348)
			(xy 131.11536 -280.584233) (xy 131.11607 -280.617168) (xy 131.116012 -280.627794) (xy 131.114869 -280.649015)
			(xy 131.113784 -280.659586) (xy 131.112514 -280.669238) (xy 131.11734 -280.687526) (xy 131.168902 -280.758392)
			(xy 131.184904 -280.768552) (xy 131.194302 -280.770584) (xy 131.209796 -280.77414) (xy 131.219448 -280.776426)
			(xy 131.238498 -280.773886) (xy 131.317238 -280.728674) (xy 131.329176 -280.713434) (xy 131.33197 -280.703782)
			(xy 131.340048 -280.677689) (xy 131.362592 -280.627938) (xy 131.392005 -280.581913) (xy 131.427684 -280.540556)
			(xy 131.468899 -280.504713) (xy 131.514807 -280.475118) (xy 131.564468 -280.452377) (xy 131.616865 -280.436954)
			(xy 131.670928 -280.429165) (xy 131.698238 -280.4287) (xy 131.72341 -280.429086) (xy 131.773317 -280.435709)
			(xy 131.821921 -280.448835) (xy 131.845304 -280.458164) (xy 131.855464 -280.462482) (xy 131.8768 -280.461974)
			(xy 131.964938 -280.420064) (xy 131.978908 -280.403808) (xy 131.981956 -280.39314) (xy 131.990713 -280.365225)
			(xy 132.01565 -280.312303) (xy 132.048377 -280.263809) (xy 132.088125 -280.220881) (xy 132.133963 -280.184528)
			(xy 132.184814 -280.155601) (xy 132.239487 -280.134778) (xy 132.296699 -280.12255) (xy 132.325872 -280.120344)
			(xy 132.337556 -280.119582) (xy 132.357622 -280.108406) (xy 132.417058 -280.02484) (xy 132.421122 -280.002234)
			(xy 132.41782 -279.991058) (xy 132.411057 -279.965556) (xy 132.403789 -279.913298) (xy 132.403342 -279.886918)
			(xy 132.403828 -279.859667) (xy 132.411584 -279.805719) (xy 132.426939 -279.753424) (xy 132.449581 -279.703847)
			(xy 132.479047 -279.657997) (xy 132.514738 -279.616806) (xy 132.555929 -279.581115) (xy 132.601779 -279.551649)
			(xy 132.651356 -279.529007) (xy 132.703651 -279.513652) (xy 132.757599 -279.505896) (xy 132.812101 -279.505896)
			(xy 132.866049 -279.513652) (xy 132.918344 -279.529007) (xy 132.967921 -279.551649) (xy 133.013771 -279.581115)
			(xy 133.054962 -279.616806) (xy 133.090653 -279.657997) (xy 133.120119 -279.703847) (xy 133.142761 -279.753424)
			(xy 133.158116 -279.805719) (xy 133.165872 -279.859667) (xy 133.166358 -279.886918) (xy 133.165866 -279.915792)
			(xy 133.157183 -279.972884) (xy 133.139987 -280.028013) (xy 133.114672 -280.079917) (xy 133.081817 -280.127408)
			(xy 133.042175 -280.169401) (xy 132.996652 -280.204933) (xy 132.94629 -280.233192) (xy 132.892242 -280.253531)
			(xy 132.835745 -280.265485) (xy 132.806948 -280.267664) (xy 132.795264 -280.268426) (xy 132.775198 -280.279602)
			(xy 132.715762 -280.363168) (xy 132.711698 -280.385774) (xy 132.715 -280.39695) (xy 132.721765 -280.422452)
			(xy 132.729032 -280.47471) (xy 132.729478 -280.50109) (xy 132.72871 -280.535173) (xy 132.716578 -280.602251)
			(xy 132.705348 -280.63444) (xy 132.701284 -280.645616) (xy 132.703824 -280.669492) (xy 132.761228 -280.758138)
			(xy 132.781802 -280.77033) (xy 132.79374 -280.771092) (xy 132.822349 -280.773546) (xy 132.878415 -280.785926)
			(xy 132.931995 -280.806566) (xy 132.981878 -280.835) (xy 133.026939 -280.870584) (xy 133.06616 -280.912518)
			(xy 133.098658 -280.959854) (xy 133.123698 -281.011523) (xy 133.140715 -281.066361) (xy 133.149325 -281.123129)
			(xy 133.149848 -281.151838) (xy 133.149362 -281.179089) (xy 133.141606 -281.233037) (xy 133.126251 -281.285332)
			(xy 133.103609 -281.334909) (xy 133.074143 -281.380759) (xy 133.038452 -281.42195) (xy 132.997261 -281.457641)
			(xy 132.951411 -281.487107) (xy 132.901834 -281.509749) (xy 132.849539 -281.525104) (xy 132.795591 -281.53286)
			(xy 132.741089 -281.53286) (xy 132.687141 -281.525104) (xy 132.634846 -281.509749) (xy 132.585269 -281.487107)
			(xy 132.539419 -281.457641) (xy 132.498228 -281.42195) (xy 132.462537 -281.380759) (xy 132.433071 -281.334909)
			(xy 132.410429 -281.285332) (xy 132.395074 -281.233037) (xy 132.387318 -281.179089) (xy 132.386832 -281.151838)
			(xy 132.387581 -281.117754) (xy 132.399725 -281.050676) (xy 132.410962 -281.018488) (xy 132.415026 -281.007312)
			(xy 132.412486 -280.983436) (xy 132.355082 -280.89479) (xy 132.334508 -280.882598) (xy 132.32257 -280.881836)
			(xy 132.291272 -280.87909) (xy 132.230127 -280.86467) (xy 132.200904 -280.853134) (xy 132.190744 -280.848816)
			(xy 132.169408 -280.849324) (xy 132.08127 -280.891234) (xy 132.0673 -280.90749) (xy 132.064252 -280.918158)
			(xy 132.056057 -280.944129) (xy 132.033378 -280.993638) (xy 132.003889 -281.03942) (xy 131.968191 -281.080544)
			(xy 131.927007 -281.116173) (xy 131.881176 -281.145585) (xy 131.831628 -281.168181) (xy 131.779371 -281.183502)
			(xy 131.725466 -281.191236) (xy 131.698238 -281.191716) (xy 131.674882 -281.191348) (xy 131.628524 -281.185619)
			(xy 131.605782 -281.180286) (xy 131.59613 -281.178) (xy 131.57708 -281.18054) (xy 131.49834 -281.225752)
			(xy 131.486402 -281.240992) (xy 131.483608 -281.250644) (xy 131.475566 -281.276749) (xy 131.453016 -281.3265)
			(xy 131.423599 -281.372525) (xy 131.387915 -281.413882) (xy 131.346695 -281.449723) (xy 131.300783 -281.479317)
			(xy 131.251118 -281.502056) (xy 131.198717 -281.517477) (xy 131.144652 -281.525262) (xy 131.11734 -281.525726)
			(xy 131.090089 -281.525208) (xy 131.036141 -281.517456) (xy 130.983845 -281.502106) (xy 130.934266 -281.47947)
			(xy 130.888414 -281.450008) (xy 130.847221 -281.41432) (xy 130.811527 -281.373133) (xy 130.782058 -281.327285)
			(xy 130.759414 -281.277709) (xy 130.744056 -281.225416) (xy 130.736297 -281.171469) (xy 130.735832 -281.144218)
			(xy 130.735889 -281.133592) (xy 130.737032 -281.112371) (xy 130.738118 -281.1018) (xy 130.739388 -281.092148)
			(xy 130.734562 -281.07386) (xy 130.683 -281.002994) (xy 130.666998 -280.992834) (xy 130.6576 -280.990802)
			(xy 130.6293 -280.984437) (xy 130.574912 -280.964276) (xy 130.524204 -280.936113) (xy 130.478344 -280.900597)
			(xy 130.43839 -280.858547) (xy 130.405263 -280.810934) (xy 130.379727 -280.758853) (xy 130.36237 -280.703506)
			(xy 130.353593 -280.64617) (xy 130.353054 -280.617168) (xy 130.353779 -280.584235) (xy 130.36515 -280.519356)
			(xy 130.37566 -280.488136) (xy 130.378708 -280.479754) (xy 130.378708 -278.797766) (xy 130.379272 -278.7698)
			(xy 130.388005 -278.714554) (xy 130.405266 -278.661352) (xy 130.430631 -278.611502) (xy 130.463476 -278.56623)
			(xy 130.482848 -278.546052) (xy 131.334256 -277.694644) (xy 131.340928 -277.687228) (xy 131.348508 -277.668795)
			(xy 131.348988 -277.65883) (xy 131.348988 -266.999212) (xy 131.348509 -266.989246) (xy 131.340935 -266.97081)
			(xy 131.334256 -266.963398) (xy 125.468634 -261.097776) (xy 125.449254 -261.077593) (xy 125.416357 -261.032335)
			(xy 125.390935 -260.982493) (xy 125.373613 -260.929291) (xy 125.364815 -260.874037) (xy 125.36424 -260.846062)
			(xy 125.36424 -257.894582) (xy 125.363789 -257.884612) (xy 125.356196 -257.866176) (xy 125.349508 -257.858768)
			(xy 124.45365 -256.96291) (xy 124.434241 -256.942753) (xy 124.401348 -256.897488) (xy 124.375931 -256.84764)
			(xy 124.358615 -256.794432) (xy 124.349826 -256.739173) (xy 124.349256 -256.711196) (xy 124.349256 -253.76378)
			(xy 124.348802 -253.753811) (xy 124.341211 -253.735375) (xy 124.334524 -253.727966) (xy 123.08967 -252.483112)
			(xy 123.082248 -252.476447) (xy 123.063819 -252.468864) (xy 123.053856 -252.46838) (xy 120.791986 -252.46838)
			(xy 120.783604 -252.471174) (xy 120.752388 -252.481698) (xy 120.687507 -252.493066) (xy 120.654572 -252.49378)
			(xy 120.62732 -252.493348) (xy 120.573371 -252.485588) (xy 120.521076 -252.470229) (xy 120.471499 -252.447585)
			(xy 120.425649 -252.418116) (xy 120.384459 -252.382421) (xy 120.348768 -252.341229) (xy 120.319302 -252.295377)
			(xy 120.296661 -252.245798) (xy 120.281306 -252.193501) (xy 120.27355 -252.139552) (xy 96.825443 -252.139552)
			(xy 97.664098 -254.164338) (xy 117.675912 -254.164338) (xy 117.679983 -254.108716) (xy 117.692109 -254.054279)
			(xy 117.712032 -254.002188) (xy 117.739328 -253.953553) (xy 117.773414 -253.90941) (xy 117.813563 -253.870701)
			(xy 117.858921 -253.83825) (xy 117.908521 -253.812749) (xy 117.961305 -253.794742) (xy 118.016148 -253.784612)
			(xy 118.071882 -253.782575) (xy 118.127319 -253.788675) (xy 118.181276 -253.802781) (xy 118.232605 -253.824593)
			(xy 118.280211 -253.853647) (xy 118.323079 -253.889322) (xy 118.360296 -253.930859) (xy 118.391069 -253.977372)
			(xy 118.414741 -254.027869) (xy 118.430809 -254.081276) (xy 118.438929 -254.136452) (xy 118.439438 -254.164338)
			(xy 118.438929 -254.192224) (xy 118.430809 -254.2474) (xy 118.414741 -254.300807) (xy 118.391069 -254.351304)
			(xy 118.360296 -254.397817) (xy 118.323079 -254.439354) (xy 118.280211 -254.475029) (xy 118.232605 -254.504083)
			(xy 118.181276 -254.525895) (xy 118.127319 -254.540001) (xy 118.071882 -254.546101) (xy 118.016148 -254.544064)
			(xy 117.961305 -254.533934) (xy 117.908521 -254.515927) (xy 117.858921 -254.490426) (xy 117.813563 -254.457975)
			(xy 117.773414 -254.419266) (xy 117.739328 -254.375123) (xy 117.712032 -254.326488) (xy 117.692109 -254.274397)
			(xy 117.679983 -254.21996) (xy 117.675912 -254.164338) (xy 97.664098 -254.164338) (xy 98.66376 -256.577846)
			(xy 98.669783 -256.592973) (xy 98.679196 -256.624144) (xy 98.682556 -256.640076) (xy 98.68535 -256.653284)
			(xy 98.688144 -256.662936) (xy 98.803206 -256.940558) (xy 98.809076 -256.955248) (xy 98.818232 -256.98553)
			(xy 98.821494 -257.00101) (xy 99.203879 -258.923536) (xy 108.0897 -258.923536) (xy 108.090164 -258.896092)
			(xy 108.098019 -258.841769) (xy 108.113586 -258.789134) (xy 108.136543 -258.739277) (xy 108.166414 -258.693229)
			(xy 108.202583 -258.651943) (xy 108.2443 -258.616273) (xy 108.267246 -258.60121) (xy 108.278168 -258.594098)
			(xy 108.290868 -258.571492) (xy 108.29163 -258.46024) (xy 108.279438 -258.43738) (xy 108.26877 -258.430268)
			(xy 108.24645 -258.415055) (xy 108.205883 -258.379395) (xy 108.170755 -258.338366) (xy 108.141768 -258.292791)
			(xy 108.119503 -258.243581) (xy 108.104405 -258.191721) (xy 108.096776 -258.13825) (xy 108.096304 -258.111244)
			(xy 108.096796 -258.083992) (xy 108.104548 -258.030041) (xy 108.119899 -257.977743) (xy 108.142537 -257.928162)
			(xy 108.172001 -257.882308) (xy 108.207692 -257.841115) (xy 108.248883 -257.805421) (xy 108.294734 -257.775952)
			(xy 108.344313 -257.75331) (xy 108.39661 -257.737954) (xy 108.45056 -257.730199) (xy 108.477812 -257.729736)
			(xy 108.504128 -257.73019) (xy 108.556263 -257.737408) (xy 108.606911 -257.75172) (xy 108.655113 -257.772855)
			(xy 108.699955 -257.80041) (xy 108.740587 -257.833865) (xy 108.758736 -257.852926) (xy 108.766252 -257.860335)
			(xy 108.785536 -257.868858) (xy 108.796074 -257.869436) (xy 108.87075 -257.869436) (xy 108.881297 -257.868883)
			(xy 108.900591 -257.860363) (xy 108.908088 -257.852926) (xy 108.926234 -257.833857) (xy 108.966851 -257.800377)
			(xy 109.011689 -257.772805) (xy 109.059895 -257.751664) (xy 109.11055 -257.737358) (xy 109.162693 -257.730158)
			(xy 109.189012 -257.729736) (xy 109.215328 -257.73019) (xy 109.267463 -257.737408) (xy 109.318111 -257.75172)
			(xy 109.366313 -257.772855) (xy 109.411155 -257.80041) (xy 109.451787 -257.833865) (xy 109.469936 -257.852926)
			(xy 109.477452 -257.860335) (xy 109.496736 -257.868858) (xy 109.507274 -257.869436) (xy 109.58195 -257.869436)
			(xy 109.592497 -257.868883) (xy 109.611791 -257.860363) (xy 109.619288 -257.852926) (xy 109.637434 -257.833857)
			(xy 109.678051 -257.800377) (xy 109.722889 -257.772805) (xy 109.771095 -257.751664) (xy 109.82175 -257.737358)
			(xy 109.873893 -257.730158) (xy 109.900212 -257.729736) (xy 109.927467 -257.730144) (xy 109.981422 -257.737904)
			(xy 110.033724 -257.753263) (xy 110.083307 -257.775911) (xy 110.129162 -257.805384) (xy 110.170356 -257.841083)
			(xy 110.20605 -257.882282) (xy 110.235516 -257.928142) (xy 110.258156 -257.977728) (xy 110.273508 -258.030032)
			(xy 110.28126 -258.083989) (xy 110.28172 -258.111244) (xy 110.281231 -258.138687) (xy 110.273379 -258.193009)
			(xy 110.257816 -258.245642) (xy 110.234863 -258.295499) (xy 110.204996 -258.341547) (xy 110.168831 -258.382834)
			(xy 110.127118 -258.418506) (xy 110.104174 -258.43357) (xy 110.093252 -258.440682) (xy 110.080552 -258.463288)
			(xy 110.07979 -258.57454) (xy 110.091982 -258.5974) (xy 110.10265 -258.604512) (xy 110.124965 -258.619731)
			(xy 110.165531 -258.655391) (xy 110.200659 -258.696419) (xy 110.229646 -258.741994) (xy 110.251912 -258.791202)
			(xy 110.267012 -258.84306) (xy 110.274642 -258.89653) (xy 110.275116 -258.923536) (xy 110.274656 -258.950788)
			(xy 110.266894 -259.004736) (xy 110.251535 -259.057031) (xy 110.22889 -259.106608) (xy 110.199421 -259.152457)
			(xy 110.163727 -259.193647) (xy 110.122535 -259.229338) (xy 110.076683 -259.258804) (xy 110.027104 -259.281445)
			(xy 109.974809 -259.2968) (xy 109.92086 -259.304558) (xy 109.893608 -259.305044) (xy 109.867291 -259.304618)
			(xy 109.815157 -259.29739) (xy 109.764508 -259.283071) (xy 109.716307 -259.261931) (xy 109.671466 -259.234372)
			(xy 109.630834 -259.200915) (xy 109.612684 -259.181854) (xy 109.605163 -259.174451) (xy 109.585883 -259.165926)
			(xy 109.575346 -259.165344) (xy 109.50067 -259.165344) (xy 109.490121 -259.165884) (xy 109.470825 -259.17441)
			(xy 109.463332 -259.181854) (xy 109.445173 -259.200909) (xy 109.404559 -259.234391) (xy 109.359724 -259.261966)
			(xy 109.311521 -259.283109) (xy 109.260867 -259.297418) (xy 109.208726 -259.304621) (xy 109.182408 -259.305044)
			(xy 109.156091 -259.304618) (xy 109.103957 -259.29739) (xy 109.053308 -259.283071) (xy 109.005107 -259.261931)
			(xy 108.960266 -259.234372) (xy 108.919634 -259.200915) (xy 108.901484 -259.181854) (xy 108.893963 -259.174451)
			(xy 108.874683 -259.165926) (xy 108.864146 -259.165344) (xy 108.78947 -259.165344) (xy 108.778921 -259.165884)
			(xy 108.759625 -259.17441) (xy 108.752132 -259.181854) (xy 108.733973 -259.200909) (xy 108.693359 -259.234391)
			(xy 108.648524 -259.261966) (xy 108.600321 -259.283109) (xy 108.549667 -259.297418) (xy 108.497526 -259.304621)
			(xy 108.471208 -259.305044) (xy 108.443959 -259.304515) (xy 108.390014 -259.29676) (xy 108.337723 -259.281408)
			(xy 108.288148 -259.258771) (xy 108.242299 -259.229308) (xy 108.20111 -259.193622) (xy 108.165418 -259.152436)
			(xy 108.135951 -259.106591) (xy 108.113307 -259.057019) (xy 108.097949 -259.004729) (xy 108.090188 -258.950785)
			(xy 108.0897 -258.923536) (xy 99.203879 -258.923536) (xy 99.86478 -262.246364) (xy 110.69828 -262.246364)
			(xy 110.69828 -258.66471) (xy 110.698774 -258.633085) (xy 110.706978 -258.570371) (xy 110.723299 -258.509265)
			(xy 110.747458 -258.450812) (xy 110.779041 -258.396013) (xy 110.817508 -258.345807) (xy 110.839504 -258.32308)
			(xy 111.296704 -257.86588) (xy 111.319435 -257.84389) (xy 111.369649 -257.805437) (xy 111.424449 -257.773862)
			(xy 111.482899 -257.749704) (xy 111.544001 -257.733376) (xy 111.606711 -257.725157) (xy 111.638334 -257.724656)
			(xy 112.130332 -257.724656) (xy 112.140336 -257.724193) (xy 112.158799 -257.716475) (xy 112.166146 -257.70967)
			(xy 114.217958 -255.657858) (xy 114.225186 -255.649954) (xy 114.232814 -255.62996) (xy 114.23269 -255.61925)
			(xy 114.228118 -255.53289) (xy 114.218466 -255.51384) (xy 114.210084 -255.506982) (xy 114.188374 -255.488803)
			(xy 114.150106 -255.447067) (xy 114.118432 -255.400131) (xy 114.094047 -255.349027) (xy 114.077489 -255.294878)
			(xy 114.06912 -255.238876) (xy 114.068606 -255.210564) (xy 114.069044 -255.183311) (xy 114.076806 -255.129361)
			(xy 114.092167 -255.077065) (xy 114.114813 -255.027486) (xy 114.144284 -254.981635) (xy 114.179981 -254.940445)
			(xy 114.221175 -254.904754) (xy 114.26703 -254.875289) (xy 114.316612 -254.852649) (xy 114.36891 -254.837295)
			(xy 114.422861 -254.829541) (xy 114.450114 -254.829056) (xy 114.477086 -254.829471) (xy 114.530501 -254.836998)
			(xy 114.55654 -254.844042) (xy 114.565684 -254.846836) (xy 114.58448 -254.845058) (xy 114.663474 -254.805942)
			(xy 114.676174 -254.791972) (xy 114.679476 -254.782828) (xy 114.69153 -254.752814) (xy 114.722549 -254.696056)
			(xy 114.760869 -254.643949) (xy 114.805803 -254.597425) (xy 114.856548 -254.557317) (xy 114.912193 -254.524345)
			(xy 114.971743 -254.499097) (xy 115.034131 -254.482028) (xy 115.098239 -254.473442) (xy 115.13058 -254.472948)
			(xy 115.162198 -254.473527) (xy 115.224893 -254.481775) (xy 115.285976 -254.498133) (xy 115.344403 -254.522322)
			(xy 115.399174 -254.553927) (xy 115.449353 -254.592408) (xy 115.494082 -254.637108) (xy 115.532596 -254.687261)
			(xy 115.564237 -254.742012) (xy 115.588464 -254.800422) (xy 115.604863 -254.861495) (xy 115.613152 -254.924185)
			(xy 115.613688 -254.955802) (xy 115.613688 -255.18872) (xy 116.295422 -255.18872) (xy 116.299493 -255.133098)
			(xy 116.311619 -255.078661) (xy 116.331542 -255.02657) (xy 116.358838 -254.977935) (xy 116.392924 -254.933792)
			(xy 116.433073 -254.895083) (xy 116.478431 -254.862632) (xy 116.528031 -254.837131) (xy 116.580815 -254.819124)
			(xy 116.635658 -254.808994) (xy 116.691392 -254.806957) (xy 116.746829 -254.813057) (xy 116.800786 -254.827163)
			(xy 116.852115 -254.848975) (xy 116.899721 -254.878029) (xy 116.942589 -254.913704) (xy 116.979806 -254.955241)
			(xy 117.010579 -255.001754) (xy 117.034251 -255.052251) (xy 117.050319 -255.105658) (xy 117.058439 -255.160834)
			(xy 117.058948 -255.18872) (xy 117.058439 -255.216606) (xy 117.050319 -255.271782) (xy 117.034251 -255.325189)
			(xy 117.010579 -255.375686) (xy 116.979806 -255.422199) (xy 116.942589 -255.463736) (xy 116.899721 -255.499411)
			(xy 116.852115 -255.528465) (xy 116.800786 -255.550277) (xy 116.746829 -255.564383) (xy 116.691392 -255.570483)
			(xy 116.635658 -255.568446) (xy 116.580815 -255.558316) (xy 116.528031 -255.540309) (xy 116.478431 -255.514808)
			(xy 116.433073 -255.482357) (xy 116.392924 -255.443648) (xy 116.358838 -255.399505) (xy 116.331542 -255.35087)
			(xy 116.311619 -255.298779) (xy 116.299493 -255.244342) (xy 116.295422 -255.18872) (xy 115.613688 -255.18872)
			(xy 115.613688 -255.428242) (xy 115.613156 -255.459874) (xy 115.604916 -255.5226) (xy 115.588557 -255.583712)
			(xy 115.564358 -255.642165) (xy 115.532734 -255.696958) (xy 115.494226 -255.747153) (xy 115.47221 -255.769872)
			(xy 114.111532 -257.13055) (xy 116.295422 -257.13055) (xy 116.299493 -257.074928) (xy 116.311619 -257.020491)
			(xy 116.331542 -256.9684) (xy 116.358838 -256.919765) (xy 116.392924 -256.875622) (xy 116.433073 -256.836913)
			(xy 116.478431 -256.804462) (xy 116.528031 -256.778961) (xy 116.580815 -256.760954) (xy 116.635658 -256.750824)
			(xy 116.691392 -256.748787) (xy 116.746829 -256.754887) (xy 116.800786 -256.768993) (xy 116.852115 -256.790805)
			(xy 116.899721 -256.819859) (xy 116.942589 -256.855534) (xy 116.979806 -256.897071) (xy 117.010579 -256.943584)
			(xy 117.034251 -256.994081) (xy 117.050319 -257.047488) (xy 117.058439 -257.102664) (xy 117.058948 -257.13055)
			(xy 117.058439 -257.158436) (xy 117.050319 -257.213612) (xy 117.034251 -257.267019) (xy 117.010579 -257.317516)
			(xy 116.979806 -257.364029) (xy 116.942589 -257.405566) (xy 116.899721 -257.441241) (xy 116.852115 -257.470295)
			(xy 116.800786 -257.492107) (xy 116.746829 -257.506213) (xy 116.691392 -257.512313) (xy 116.635658 -257.510276)
			(xy 116.580815 -257.500146) (xy 116.528031 -257.482139) (xy 116.478431 -257.456638) (xy 116.433073 -257.424187)
			(xy 116.392924 -257.385478) (xy 116.358838 -257.341335) (xy 116.331542 -257.2927) (xy 116.311619 -257.240609)
			(xy 116.299493 -257.186172) (xy 116.295422 -257.13055) (xy 114.111532 -257.13055) (xy 113.222532 -258.01955)
			(xy 116.422932 -258.01955) (xy 116.423402 -257.992297) (xy 116.431153 -257.938344) (xy 116.446505 -257.886044)
			(xy 116.469144 -257.836461) (xy 116.498611 -257.790606) (xy 116.534304 -257.749411) (xy 116.575498 -257.713717)
			(xy 116.621352 -257.684249) (xy 116.670934 -257.661608) (xy 116.723234 -257.646255) (xy 116.777187 -257.638503)
			(xy 116.80444 -257.638042) (xy 116.831497 -257.638464) (xy 116.885066 -257.646128) (xy 116.937014 -257.661283)
			(xy 116.986301 -257.683624) (xy 117.031938 -257.712704) (xy 117.073009 -257.747939) (xy 117.108691 -257.788623)
			(xy 117.138267 -257.833939) (xy 117.150134 -257.85826) (xy 117.154198 -257.866642) (xy 117.167406 -257.879596)
			(xy 117.246908 -257.913886) (xy 117.26545 -257.914648) (xy 117.27434 -257.9116) (xy 117.30367 -257.902497)
			(xy 117.364286 -257.892662) (xy 117.39499 -257.892042) (xy 117.422247 -257.892404) (xy 117.476206 -257.900161)
			(xy 117.528512 -257.915518) (xy 117.5781 -257.938163) (xy 117.62396 -257.967635) (xy 117.66516 -258.003333)
			(xy 117.700859 -258.044532) (xy 117.730332 -258.090391) (xy 117.752978 -258.139979) (xy 117.768337 -258.192284)
			(xy 117.776095 -258.246243) (xy 117.776095 -258.300757) (xy 117.768337 -258.354716) (xy 117.752978 -258.407021)
			(xy 117.730332 -258.456609) (xy 117.700859 -258.502468) (xy 117.66516 -258.543667) (xy 117.62396 -258.579365)
			(xy 117.5781 -258.608837) (xy 117.528512 -258.631482) (xy 117.476206 -258.646839) (xy 117.422247 -258.654596)
			(xy 117.39499 -258.655058) (xy 117.374442 -258.654758) (xy 117.333586 -258.650305) (xy 117.313456 -258.646168)
			(xy 117.301518 -258.643628) (xy 117.27815 -258.649724) (xy 117.198394 -258.720336) (xy 117.189504 -258.742688)
			(xy 117.19052 -258.75488) (xy 117.192298 -258.79044) (xy 117.191812 -258.817691) (xy 117.184056 -258.871639)
			(xy 117.168701 -258.923934) (xy 117.146059 -258.973511) (xy 117.116593 -259.019361) (xy 117.080902 -259.060552)
			(xy 117.039711 -259.096243) (xy 116.993861 -259.125709) (xy 116.944284 -259.148351) (xy 116.891989 -259.163706)
			(xy 116.838041 -259.171462) (xy 116.783539 -259.171462) (xy 116.729591 -259.163706) (xy 116.677296 -259.148351)
			(xy 116.627719 -259.125709) (xy 116.581869 -259.096243) (xy 116.540678 -259.060552) (xy 116.504987 -259.019361)
			(xy 116.475521 -258.973511) (xy 116.452879 -258.923934) (xy 116.437524 -258.871639) (xy 116.429768 -258.817691)
			(xy 116.429282 -258.79044) (xy 116.429857 -258.761315) (xy 116.438719 -258.703744) (xy 116.456227 -258.648188)
			(xy 116.481976 -258.595939) (xy 116.515366 -258.548209) (xy 116.555622 -258.506109) (xy 116.57838 -258.487926)
			(xy 116.587778 -258.48056) (xy 116.598192 -258.459224) (xy 116.59743 -258.354068) (xy 116.586762 -258.332986)
			(xy 116.576856 -258.325874) (xy 116.553429 -258.307703) (xy 116.511899 -258.265397) (xy 116.477407 -258.21718)
			(xy 116.450783 -258.16421) (xy 116.432668 -258.107762) (xy 116.423496 -258.049192) (xy 116.422932 -258.01955)
			(xy 113.222532 -258.01955) (xy 112.692942 -258.54914) (xy 112.6871 -258.554728) (xy 112.680459 -258.561659)
			(xy 112.672525 -258.579125) (xy 112.671574 -258.598285) (xy 112.677739 -258.616451) (xy 112.690155 -258.631075)
			(xy 112.70708 -258.640105) (xy 112.716564 -258.641596) (xy 112.744067 -258.645325) (xy 112.797667 -258.659722)
			(xy 112.848616 -258.681731) (xy 112.89584 -258.710889) (xy 112.938342 -258.74658) (xy 112.975226 -258.788051)
			(xy 113.005714 -258.834427) (xy 113.029162 -258.884731) (xy 113.045076 -258.9379) (xy 113.053121 -258.992814)
			(xy 113.053622 -259.020564) (xy 113.179096 -259.020564) (xy 113.183167 -258.964942) (xy 113.195293 -258.910505)
			(xy 113.215216 -258.858414) (xy 113.242512 -258.809779) (xy 113.276598 -258.765636) (xy 113.316747 -258.726927)
			(xy 113.362105 -258.694476) (xy 113.411705 -258.668975) (xy 113.464489 -258.650968) (xy 113.519332 -258.640838)
			(xy 113.575066 -258.638801) (xy 113.630503 -258.644901) (xy 113.68446 -258.659007) (xy 113.735789 -258.680819)
			(xy 113.783395 -258.709873) (xy 113.826263 -258.745548) (xy 113.86348 -258.787085) (xy 113.894253 -258.833598)
			(xy 113.917925 -258.884095) (xy 113.933993 -258.937502) (xy 113.942113 -258.992678) (xy 113.942622 -259.020564)
			(xy 113.942113 -259.04845) (xy 113.933993 -259.103626) (xy 113.917925 -259.157033) (xy 113.894253 -259.20753)
			(xy 113.86348 -259.254043) (xy 113.826263 -259.29558) (xy 113.783395 -259.331255) (xy 113.735789 -259.360309)
			(xy 113.68446 -259.382121) (xy 113.630503 -259.396227) (xy 113.575066 -259.402327) (xy 113.519332 -259.40029)
			(xy 113.464489 -259.39016) (xy 113.411705 -259.372153) (xy 113.362105 -259.346652) (xy 113.316747 -259.314201)
			(xy 113.276598 -259.275492) (xy 113.242512 -259.231349) (xy 113.215216 -259.182714) (xy 113.195293 -259.130623)
			(xy 113.183167 -259.076186) (xy 113.179096 -259.020564) (xy 113.053622 -259.020564) (xy 113.053136 -259.047815)
			(xy 113.04538 -259.101763) (xy 113.030025 -259.154058) (xy 113.007383 -259.203635) (xy 112.977917 -259.249485)
			(xy 112.942226 -259.290676) (xy 112.901035 -259.326367) (xy 112.855185 -259.355833) (xy 112.805608 -259.378475)
			(xy 112.753313 -259.39383) (xy 112.699365 -259.401586) (xy 112.644863 -259.401586) (xy 112.590915 -259.39383)
			(xy 112.53862 -259.378475) (xy 112.489043 -259.355833) (xy 112.443193 -259.326367) (xy 112.402002 -259.290676)
			(xy 112.366311 -259.249485) (xy 112.336845 -259.203635) (xy 112.314203 -259.154058) (xy 112.298848 -259.101763)
			(xy 112.291092 -259.047815) (xy 112.290606 -259.020564) (xy 112.291262 -258.989234) (xy 112.301551 -258.927422)
			(xy 112.321798 -258.868122) (xy 112.336072 -258.840224) (xy 112.342422 -258.828286) (xy 112.34166 -258.801616)
			(xy 112.290098 -258.715256) (xy 112.285278 -258.707896) (xy 112.271736 -258.696691) (xy 112.255198 -258.690735)
			(xy 112.24641 -258.690364) (xy 111.859314 -258.690364) (xy 111.849306 -258.690794) (xy 111.830843 -258.698534)
			(xy 111.8235 -258.70535) (xy 111.678974 -258.849876) (xy 111.672242 -258.857273) (xy 111.664527 -258.875703)
			(xy 111.663988 -258.88569) (xy 111.663988 -259.535422) (xy 114.207542 -259.535422) (xy 114.211613 -259.4798)
			(xy 114.223739 -259.425363) (xy 114.243662 -259.373272) (xy 114.270958 -259.324637) (xy 114.305044 -259.280494)
			(xy 114.345193 -259.241785) (xy 114.390551 -259.209334) (xy 114.440151 -259.183833) (xy 114.492935 -259.165826)
			(xy 114.547778 -259.155696) (xy 114.603512 -259.153659) (xy 114.658949 -259.159759) (xy 114.712906 -259.173865)
			(xy 114.764235 -259.195677) (xy 114.811841 -259.224731) (xy 114.854709 -259.260406) (xy 114.891926 -259.301943)
			(xy 114.922699 -259.348456) (xy 114.946371 -259.398953) (xy 114.962439 -259.45236) (xy 114.970559 -259.507536)
			(xy 114.971068 -259.535422) (xy 114.970559 -259.563308) (xy 114.962439 -259.618484) (xy 114.946371 -259.671891)
			(xy 114.922699 -259.722388) (xy 114.891926 -259.768901) (xy 114.854709 -259.810438) (xy 114.811841 -259.846113)
			(xy 114.764235 -259.875167) (xy 114.712906 -259.896979) (xy 114.658949 -259.911085) (xy 114.603512 -259.917185)
			(xy 114.547778 -259.915148) (xy 114.492935 -259.905018) (xy 114.440151 -259.887011) (xy 114.390551 -259.86151)
			(xy 114.345193 -259.829059) (xy 114.305044 -259.79035) (xy 114.270958 -259.746207) (xy 114.243662 -259.697572)
			(xy 114.223739 -259.645481) (xy 114.211613 -259.591044) (xy 114.207542 -259.535422) (xy 111.663988 -259.535422)
			(xy 111.663988 -260.671564) (xy 112.163096 -260.671564) (xy 112.167167 -260.615942) (xy 112.179293 -260.561505)
			(xy 112.199216 -260.509414) (xy 112.226512 -260.460779) (xy 112.260598 -260.416636) (xy 112.300747 -260.377927)
			(xy 112.346105 -260.345476) (xy 112.395705 -260.319975) (xy 112.448489 -260.301968) (xy 112.503332 -260.291838)
			(xy 112.559066 -260.289801) (xy 112.614503 -260.295901) (xy 112.66846 -260.310007) (xy 112.719789 -260.331819)
			(xy 112.767395 -260.360873) (xy 112.810263 -260.396548) (xy 112.84748 -260.438085) (xy 112.878253 -260.484598)
			(xy 112.901925 -260.535095) (xy 112.917993 -260.588502) (xy 112.926113 -260.643678) (xy 112.926622 -260.671564)
			(xy 112.926113 -260.69945) (xy 112.917993 -260.754626) (xy 112.901925 -260.808033) (xy 112.878253 -260.85853)
			(xy 112.84748 -260.905043) (xy 112.810263 -260.94658) (xy 112.767395 -260.982255) (xy 112.719789 -261.011309)
			(xy 112.66846 -261.033121) (xy 112.614503 -261.047227) (xy 112.559066 -261.053327) (xy 112.503332 -261.05129)
			(xy 112.448489 -261.04116) (xy 112.395705 -261.023153) (xy 112.346105 -260.997652) (xy 112.300747 -260.965201)
			(xy 112.260598 -260.926492) (xy 112.226512 -260.882349) (xy 112.199216 -260.833714) (xy 112.179293 -260.781623)
			(xy 112.167167 -260.727186) (xy 112.163096 -260.671564) (xy 111.663988 -260.671564) (xy 111.663988 -261.217664)
			(xy 114.140232 -261.217664) (xy 114.144303 -261.162042) (xy 114.156429 -261.107605) (xy 114.176352 -261.055514)
			(xy 114.203648 -261.006879) (xy 114.237734 -260.962736) (xy 114.277883 -260.924027) (xy 114.323241 -260.891576)
			(xy 114.372841 -260.866075) (xy 114.425625 -260.848068) (xy 114.480468 -260.837938) (xy 114.536202 -260.835901)
			(xy 114.591639 -260.842001) (xy 114.645596 -260.856107) (xy 114.696925 -260.877919) (xy 114.744531 -260.906973)
			(xy 114.787399 -260.942648) (xy 114.824616 -260.984185) (xy 114.855389 -261.030698) (xy 114.879061 -261.081195)
			(xy 114.895129 -261.134602) (xy 114.903249 -261.189778) (xy 114.903758 -261.217664) (xy 114.903249 -261.24555)
			(xy 114.895129 -261.300726) (xy 114.879061 -261.354133) (xy 114.855389 -261.40463) (xy 114.824616 -261.451143)
			(xy 114.787399 -261.49268) (xy 114.744531 -261.528355) (xy 114.696925 -261.557409) (xy 114.645596 -261.579221)
			(xy 114.591639 -261.593327) (xy 114.536202 -261.599427) (xy 114.480468 -261.59739) (xy 114.425625 -261.58726)
			(xy 114.372841 -261.569253) (xy 114.323241 -261.543752) (xy 114.277883 -261.511301) (xy 114.237734 -261.472592)
			(xy 114.203648 -261.428449) (xy 114.176352 -261.379814) (xy 114.156429 -261.327723) (xy 114.144303 -261.273286)
			(xy 114.140232 -261.217664) (xy 111.663988 -261.217664) (xy 111.663988 -262.025384) (xy 111.664413 -262.035393)
			(xy 111.672156 -262.053856) (xy 111.678974 -262.061198) (xy 111.8235 -262.205724) (xy 111.830939 -262.212367)
			(xy 111.849354 -262.219965) (xy 111.859314 -262.220456) (xy 112.545114 -262.220456) (xy 112.576742 -262.221046)
			(xy 112.639456 -262.229304) (xy 112.700556 -262.245677) (xy 112.758996 -262.269885) (xy 112.813776 -262.301514)
			(xy 112.863959 -262.340022) (xy 112.908687 -262.384751) (xy 112.947194 -262.434936) (xy 112.978821 -262.489717)
			(xy 113.003027 -262.548158) (xy 113.019399 -262.609258) (xy 113.027655 -262.671972) (xy 113.027655 -262.735228)
			(xy 113.019399 -262.797942) (xy 113.003027 -262.859042) (xy 112.978821 -262.917483) (xy 112.947194 -262.972264)
			(xy 112.908687 -263.022449) (xy 112.863959 -263.067178) (xy 112.813776 -263.105686) (xy 112.758996 -263.137315)
			(xy 112.700556 -263.161523) (xy 112.639456 -263.177896) (xy 112.576742 -263.186154) (xy 112.545114 -263.186672)
			(xy 111.638334 -263.186672) (xy 111.606701 -263.18616) (xy 111.543975 -263.177917) (xy 111.482862 -263.161554)
			(xy 111.424408 -263.137351) (xy 111.369616 -263.105723) (xy 111.319422 -263.067212) (xy 111.296704 -263.045194)
			(xy 110.839504 -262.587994) (xy 110.817518 -262.565259) (xy 110.779063 -262.515047) (xy 110.747487 -262.460248)
			(xy 110.723328 -262.401798) (xy 110.707 -262.340697) (xy 110.698781 -262.277987) (xy 110.69828 -262.246364)
			(xy 99.86478 -262.246364) (xy 101.291007 -269.417038) (xy 102.50043 -269.417038) (xy 102.500935 -269.388299)
			(xy 102.509565 -269.331471) (xy 102.52662 -269.276581) (xy 102.551716 -269.22487) (xy 102.584283 -269.177507)
			(xy 102.603554 -269.15618) (xy 102.610158 -269.149068) (xy 102.61727 -269.131542) (xy 102.61727 -269.042134)
			(xy 102.610158 -269.024608) (xy 102.603554 -269.017496) (xy 102.584304 -268.996151) (xy 102.551734 -268.948794)
			(xy 102.526638 -268.897087) (xy 102.509582 -268.8422) (xy 102.500954 -268.785376) (xy 102.50043 -268.756638)
			(xy 102.500891 -268.729384) (xy 102.508644 -268.675431) (xy 102.523997 -268.623131) (xy 102.546638 -268.573549)
			(xy 102.576105 -268.527693) (xy 102.611799 -268.486499) (xy 102.652993 -268.450805) (xy 102.698849 -268.421338)
			(xy 102.748431 -268.398697) (xy 102.800731 -268.383344) (xy 102.854684 -268.375591) (xy 102.881938 -268.37513)
			(xy 102.909307 -268.375625) (xy 102.963485 -268.383435) (xy 103.015988 -268.398917) (xy 103.065736 -268.421752)
			(xy 103.111704 -268.451471) (xy 103.132636 -268.46911) (xy 103.139748 -268.475206) (xy 103.156766 -268.481556)
			(xy 103.24211 -268.481556) (xy 103.259128 -268.475206) (xy 103.26624 -268.46911) (xy 103.287173 -268.451469)
			(xy 103.333141 -268.421745) (xy 103.382887 -268.398899) (xy 103.435389 -268.383403) (xy 103.489567 -268.375574)
			(xy 103.544309 -268.375574) (xy 103.598487 -268.383403) (xy 103.650989 -268.398899) (xy 103.700735 -268.421745)
			(xy 103.746703 -268.451469) (xy 103.767636 -268.46911) (xy 103.774748 -268.475206) (xy 103.791766 -268.481556)
			(xy 103.87711 -268.481556) (xy 103.894128 -268.475206) (xy 103.90124 -268.46911) (xy 103.922173 -268.451469)
			(xy 103.968141 -268.421745) (xy 104.017887 -268.398899) (xy 104.070389 -268.383403) (xy 104.124567 -268.375574)
			(xy 104.179309 -268.375574) (xy 104.233487 -268.383403) (xy 104.285989 -268.398899) (xy 104.335735 -268.421745)
			(xy 104.381703 -268.451469) (xy 104.402636 -268.46911) (xy 104.409748 -268.475206) (xy 104.426766 -268.481556)
			(xy 104.51211 -268.481556) (xy 104.529128 -268.475206) (xy 104.53624 -268.46911) (xy 104.557173 -268.451469)
			(xy 104.603141 -268.421745) (xy 104.652887 -268.398899) (xy 104.705389 -268.383403) (xy 104.759567 -268.375574)
			(xy 104.814309 -268.375574) (xy 104.868487 -268.383403) (xy 104.920989 -268.398899) (xy 104.970735 -268.421745)
			(xy 105.016703 -268.451469) (xy 105.037636 -268.46911) (xy 105.044748 -268.475206) (xy 105.061766 -268.481556)
			(xy 105.14711 -268.481556) (xy 105.164128 -268.475206) (xy 105.17124 -268.46911) (xy 105.192185 -268.451487)
			(xy 105.238154 -268.421773) (xy 105.287898 -268.398933) (xy 105.340396 -268.383438) (xy 105.39457 -268.375606)
			(xy 105.421938 -268.37513) (xy 105.449192 -268.375543) (xy 105.503144 -268.383305) (xy 105.555443 -268.398667)
			(xy 105.605023 -268.421315) (xy 105.650875 -268.450789) (xy 105.692065 -268.486488) (xy 105.727756 -268.527686)
			(xy 105.757221 -268.573544) (xy 105.779859 -268.623129) (xy 105.795211 -268.67543) (xy 105.802963 -268.729384)
			(xy 105.803446 -268.756638) (xy 105.802933 -268.785377) (xy 105.794306 -268.842204) (xy 105.777253 -268.897095)
			(xy 105.752159 -268.948806) (xy 105.719593 -268.996169) (xy 105.700322 -269.017496) (xy 105.693718 -269.024608)
			(xy 105.686606 -269.042134) (xy 105.686606 -269.131542) (xy 105.693718 -269.149068) (xy 105.700322 -269.15618)
			(xy 105.719604 -269.177497) (xy 105.75217 -269.224861) (xy 105.777261 -269.276575) (xy 105.794309 -269.331468)
			(xy 105.802928 -269.388298) (xy 105.803446 -269.417038) (xy 105.802958 -269.444288) (xy 105.795197 -269.498234)
			(xy 105.779839 -269.550526) (xy 105.757196 -269.600101) (xy 105.727729 -269.64595) (xy 105.692038 -269.687138)
			(xy 105.65085 -269.722829) (xy 105.605001 -269.752296) (xy 105.555426 -269.774939) (xy 105.503134 -269.790297)
			(xy 105.449188 -269.798058) (xy 105.421938 -269.798546) (xy 105.394568 -269.798071) (xy 105.340389 -269.790257)
			(xy 105.287885 -269.774771) (xy 105.238138 -269.751931) (xy 105.192171 -269.722207) (xy 105.17124 -269.704566)
			(xy 105.164128 -269.69847) (xy 105.14711 -269.69212) (xy 105.061766 -269.69212) (xy 105.044748 -269.69847)
			(xy 105.037636 -269.704566) (xy 105.016703 -269.722207) (xy 104.970735 -269.751931) (xy 104.920989 -269.774777)
			(xy 104.868487 -269.790273) (xy 104.814309 -269.798102) (xy 104.759567 -269.798102) (xy 104.705389 -269.790273)
			(xy 104.652887 -269.774777) (xy 104.603141 -269.751931) (xy 104.557173 -269.722207) (xy 104.53624 -269.704566)
			(xy 104.529128 -269.69847) (xy 104.51211 -269.69212) (xy 104.426766 -269.69212) (xy 104.409748 -269.69847)
			(xy 104.402636 -269.704566) (xy 104.381703 -269.722207) (xy 104.335735 -269.751931) (xy 104.285989 -269.774777)
			(xy 104.233487 -269.790273) (xy 104.179309 -269.798102) (xy 104.124567 -269.798102) (xy 104.070389 -269.790273)
			(xy 104.017887 -269.774777) (xy 103.968141 -269.751931) (xy 103.922173 -269.722207) (xy 103.90124 -269.704566)
			(xy 103.894128 -269.69847) (xy 103.87711 -269.69212) (xy 103.791766 -269.69212) (xy 103.774748 -269.69847)
			(xy 103.767636 -269.704566) (xy 103.746703 -269.722207) (xy 103.700735 -269.751931) (xy 103.650989 -269.774777)
			(xy 103.598487 -269.790273) (xy 103.544309 -269.798102) (xy 103.489567 -269.798102) (xy 103.435389 -269.790273)
			(xy 103.382887 -269.774777) (xy 103.333141 -269.751931) (xy 103.287173 -269.722207) (xy 103.26624 -269.704566)
			(xy 103.259128 -269.69847) (xy 103.24211 -269.69212) (xy 103.156766 -269.69212) (xy 103.139748 -269.69847)
			(xy 103.132636 -269.704566) (xy 103.111697 -269.722196) (xy 103.065727 -269.751911) (xy 103.015981 -269.774749)
			(xy 102.963482 -269.790242) (xy 102.909307 -269.798071) (xy 102.881938 -269.798546) (xy 102.854689 -269.797987)
			(xy 102.800746 -269.790236) (xy 102.748455 -269.774888) (xy 102.698881 -269.752254) (xy 102.653032 -269.722795)
			(xy 102.611843 -269.687111) (xy 102.57615 -269.645929) (xy 102.546683 -269.600086) (xy 102.524039 -269.550516)
			(xy 102.50868 -269.498228) (xy 102.500919 -269.444286) (xy 102.50043 -269.417038) (xy 101.291007 -269.417038)
			(xy 101.441758 -270.174974) (xy 101.444682 -270.190495) (xy 101.447859 -270.22192) (xy 101.448108 -270.237712)
			(xy 101.448108 -273.569938) (xy 101.447355 -273.601578) (xy 101.434938 -273.663629) (xy 101.42347 -273.693128)
			(xy 100.20427 -276.63648) (xy 100.20427 -276.636734) (xy 99.947984 -277.25497) (xy 99.883976 -277.40991)
			(xy 99.883976 -277.410164) (xy 99.882198 -277.414228) (xy 99.79152 -277.632414) (xy 99.789722 -277.637101)
			(xy 99.787806 -277.646953) (xy 99.78771 -277.651972) (xy 99.78771 -277.864824) (xy 103.46563 -277.864824)
			(xy 103.466154 -277.835907) (xy 103.47488 -277.778736) (xy 103.492136 -277.723537) (xy 103.517527 -277.671575)
			(xy 103.55047 -277.624041) (xy 103.590211 -277.582024) (xy 103.612696 -277.563834) (xy 103.621438 -277.556252)
			(xy 103.631632 -277.535509) (xy 103.632254 -277.523956) (xy 103.632254 -277.443692) (xy 103.631704 -277.432121)
			(xy 103.621497 -277.411349) (xy 103.612696 -277.403814) (xy 103.590218 -277.385616) (xy 103.550483 -277.343598)
			(xy 103.517543 -277.296064) (xy 103.492154 -277.244104) (xy 103.474896 -277.188908) (xy 103.466166 -277.13174)
			(xy 103.46563 -277.102824) (xy 103.466211 -277.073416) (xy 103.475241 -277.015298) (xy 103.493076 -276.959253)
			(xy 103.519295 -276.906604) (xy 103.553276 -276.858599) (xy 103.594217 -276.816372) (xy 103.641148 -276.780922)
			(xy 103.666798 -276.766528) (xy 103.678736 -276.760178) (xy 103.69296 -276.737826) (xy 103.698802 -276.624288)
			(xy 103.686864 -276.600412) (xy 103.675942 -276.593046) (xy 103.654185 -276.577733) (xy 103.614705 -276.54207)
			(xy 103.580561 -276.50127) (xy 103.552414 -276.456123) (xy 103.530809 -276.407504) (xy 103.516166 -276.356357)
			(xy 103.508768 -276.303671) (xy 103.508302 -276.27707) (xy 103.50875 -276.249699) (xy 103.516572 -276.195519)
			(xy 103.532065 -276.143016) (xy 103.554911 -276.093269) (xy 103.584639 -276.047303) (xy 103.602282 -276.026372)
			(xy 103.608378 -276.01926) (xy 103.614728 -276.002242) (xy 103.614728 -275.916898) (xy 103.608378 -275.89988)
			(xy 103.602282 -275.892768) (xy 103.584659 -275.871823) (xy 103.554945 -275.825854) (xy 103.532106 -275.776109)
			(xy 103.516611 -275.723612) (xy 103.508779 -275.669438) (xy 103.508302 -275.64207) (xy 103.508854 -275.612246)
			(xy 103.518108 -275.55332) (xy 103.536418 -275.496551) (xy 103.563338 -275.443323) (xy 103.598212 -275.394931)
			(xy 103.618792 -275.373338) (xy 103.626158 -275.366226) (xy 103.633778 -275.34743) (xy 103.632762 -275.25472)
			(xy 103.624888 -275.236178) (xy 103.617522 -275.229066) (xy 103.599566 -275.211014) (xy 103.568068 -275.171012)
			(xy 103.542169 -275.127176) (xy 103.522329 -275.080286) (xy 103.508902 -275.031173) (xy 103.502124 -274.980711)
			(xy 103.501698 -274.955254) (xy 103.502135 -274.928001) (xy 103.509898 -274.874052) (xy 103.525259 -274.821756)
			(xy 103.547906 -274.772178) (xy 103.577378 -274.726327) (xy 103.613074 -274.685137) (xy 103.654269 -274.649447)
			(xy 103.700123 -274.619981) (xy 103.749704 -274.597341) (xy 103.802002 -274.581987) (xy 103.855953 -274.574231)
			(xy 103.883206 -274.573746) (xy 103.912124 -274.574243) (xy 103.969297 -274.582974) (xy 104.024497 -274.600235)
			(xy 104.076459 -274.62563) (xy 104.123992 -274.658579) (xy 104.166007 -274.698324) (xy 104.184196 -274.720812)
			(xy 104.191762 -274.72957) (xy 104.212518 -274.739755) (xy 104.224074 -274.74037) (xy 104.304338 -274.74037)
			(xy 104.315903 -274.739775) (xy 104.336675 -274.729599) (xy 104.344216 -274.720812) (xy 104.360969 -274.700029)
			(xy 104.399323 -274.662899) (xy 104.442477 -274.631477) (xy 104.489591 -274.606378) (xy 104.539743 -274.588092)
			(xy 104.591954 -274.576975) (xy 104.645206 -274.573245) (xy 104.698458 -274.576975) (xy 104.750669 -274.588092)
			(xy 104.800821 -274.606378) (xy 104.847935 -274.631477) (xy 104.891089 -274.662899) (xy 104.929443 -274.700029)
			(xy 104.946196 -274.720812) (xy 104.953762 -274.72957) (xy 104.974518 -274.739755) (xy 104.986074 -274.74037)
			(xy 105.066338 -274.74037) (xy 105.077903 -274.739775) (xy 105.098675 -274.729599) (xy 105.106216 -274.720812)
			(xy 105.124401 -274.698323) (xy 105.166422 -274.658588) (xy 105.213958 -274.625649) (xy 105.26592 -274.600262)
			(xy 105.321119 -274.583007) (xy 105.37829 -274.57428) (xy 105.407206 -274.573746) (xy 105.434455 -274.574272)
			(xy 105.488399 -274.582028) (xy 105.54069 -274.597382) (xy 105.590265 -274.62002) (xy 105.636113 -274.649483)
			(xy 105.677302 -274.68517) (xy 105.712993 -274.726355) (xy 105.742461 -274.7722) (xy 105.765104 -274.821772)
			(xy 105.780463 -274.874062) (xy 105.788225 -274.928005) (xy 105.788714 -274.955254) (xy 105.788173 -274.985079)
			(xy 105.778915 -275.044005) (xy 105.760602 -275.100774) (xy 105.73368 -275.154002) (xy 105.698805 -275.202393)
			(xy 105.678224 -275.223986) (xy 105.670858 -275.231098) (xy 105.663238 -275.249894) (xy 105.664254 -275.342604)
			(xy 105.672128 -275.361146) (xy 105.679494 -275.368258) (xy 105.697465 -275.386296) (xy 105.728961 -275.426301)
			(xy 105.754857 -275.47014) (xy 105.774694 -275.517034) (xy 105.788119 -275.566148) (xy 105.794894 -275.616612)
			(xy 105.795318 -275.64207) (xy 105.794809 -275.670988) (xy 105.786083 -275.728161) (xy 105.768825 -275.783361)
			(xy 105.743432 -275.835324) (xy 105.710485 -275.882857) (xy 105.67074 -275.924872) (xy 105.648252 -275.94306)
			(xy 105.639504 -275.950635) (xy 105.629315 -275.971384) (xy 105.628694 -275.982938) (xy 105.628694 -276.063202)
			(xy 105.629265 -276.07477) (xy 105.63946 -276.09554) (xy 105.648252 -276.10308) (xy 105.670737 -276.121269)
			(xy 105.710469 -276.163291) (xy 105.743407 -276.210827) (xy 105.768794 -276.262788) (xy 105.786051 -276.317985)
			(xy 105.794782 -276.375154) (xy 105.795318 -276.40407) (xy 105.794817 -276.431322) (xy 105.787064 -276.485271)
			(xy 105.771712 -276.537567) (xy 105.749074 -276.587147) (xy 105.71961 -276.632999) (xy 105.68392 -276.674192)
			(xy 105.642731 -276.709886) (xy 105.596882 -276.739355) (xy 105.547305 -276.761998) (xy 105.49501 -276.777356)
			(xy 105.441062 -276.785114) (xy 105.41381 -276.785578) (xy 105.384893 -276.785061) (xy 105.327721 -276.776333)
			(xy 105.272522 -276.759075) (xy 105.22056 -276.733683) (xy 105.173026 -276.700739) (xy 105.13101 -276.660998)
			(xy 105.11282 -276.638512) (xy 105.105243 -276.629765) (xy 105.084496 -276.619573) (xy 105.072942 -276.618954)
			(xy 104.992678 -276.618954) (xy 104.981113 -276.61955) (xy 104.96034 -276.629725) (xy 104.9528 -276.638512)
			(xy 104.942769 -276.651117) (xy 104.920893 -276.674769) (xy 104.909112 -276.685756) (xy 104.900222 -276.693884)
			(xy 104.891586 -276.715982) (xy 104.901492 -276.82063) (xy 104.913938 -276.84095) (xy 104.924098 -276.8473)
			(xy 104.947407 -276.862306) (xy 104.989845 -276.897971) (xy 105.026673 -276.939405) (xy 105.057113 -276.985734)
			(xy 105.080524 -277.035983) (xy 105.096413 -277.089091) (xy 105.104446 -277.143941) (xy 105.104946 -277.171658)
			(xy 105.10446 -277.198909) (xy 105.096704 -277.252857) (xy 105.081349 -277.305152) (xy 105.058707 -277.354729)
			(xy 105.029241 -277.400579) (xy 104.99355 -277.44177) (xy 104.952359 -277.477461) (xy 104.906509 -277.506927)
			(xy 104.856932 -277.529569) (xy 104.804637 -277.544924) (xy 104.750689 -277.55268) (xy 104.696187 -277.55268)
			(xy 104.642239 -277.544924) (xy 104.589944 -277.529569) (xy 104.540367 -277.506927) (xy 104.494517 -277.477461)
			(xy 104.453326 -277.44177) (xy 104.417635 -277.400579) (xy 104.388169 -277.354729) (xy 104.365527 -277.305152)
			(xy 104.350172 -277.252857) (xy 104.342416 -277.198909) (xy 104.34193 -277.171658) (xy 104.342402 -277.14524)
			(xy 104.349686 -277.09291) (xy 104.364122 -277.042085) (xy 104.385435 -276.99374) (xy 104.413216 -276.948798)
			(xy 104.446934 -276.908121) (xy 104.466136 -276.889972) (xy 104.475026 -276.881844) (xy 104.483662 -276.859746)
			(xy 104.473756 -276.755098) (xy 104.46131 -276.734778) (xy 104.45115 -276.728428) (xy 104.429535 -276.714589)
			(xy 104.389877 -276.68201) (xy 104.354959 -276.644394) (xy 104.325417 -276.602424) (xy 104.313228 -276.579838)
			(xy 104.30764 -276.56917) (xy 104.28859 -276.5552) (xy 104.18445 -276.537928) (xy 104.161844 -276.544786)
			(xy 104.152954 -276.553168) (xy 104.1341 -276.57061) (xy 104.09256 -276.600817) (xy 104.07015 -276.613366)
			(xy 104.058212 -276.619716) (xy 104.043988 -276.642068) (xy 104.038146 -276.755606) (xy 104.050084 -276.779482)
			(xy 104.061006 -276.786848) (xy 104.082749 -276.802181) (xy 104.122231 -276.837839) (xy 104.156378 -276.878635)
			(xy 104.184528 -276.923778) (xy 104.206135 -276.972394) (xy 104.22078 -277.02354) (xy 104.22818 -277.076224)
			(xy 104.228646 -277.102824) (xy 104.228093 -277.13174) (xy 104.219374 -277.18891) (xy 104.202124 -277.244109)
			(xy 104.176739 -277.296072) (xy 104.143801 -277.343606) (xy 104.104064 -277.385623) (xy 104.08158 -277.403814)
			(xy 104.072813 -277.411371) (xy 104.062633 -277.432133) (xy 104.062022 -277.443692) (xy 104.062022 -277.523956)
			(xy 104.06261 -277.535522) (xy 104.072792 -277.556293) (xy 104.08158 -277.563834) (xy 104.104076 -277.582011)
			(xy 104.143811 -277.624033) (xy 104.176749 -277.671571) (xy 104.202136 -277.723535) (xy 104.219389 -277.778735)
			(xy 104.228114 -277.835907) (xy 104.228646 -277.864824) (xy 104.22816 -277.892075) (xy 104.220404 -277.946023)
			(xy 104.205049 -277.998318) (xy 104.182407 -278.047895) (xy 104.152941 -278.093745) (xy 104.11725 -278.134936)
			(xy 104.076059 -278.170627) (xy 104.030209 -278.200093) (xy 103.980632 -278.222735) (xy 103.928337 -278.23809)
			(xy 103.874389 -278.245846) (xy 103.819887 -278.245846) (xy 103.765939 -278.23809) (xy 103.713644 -278.222735)
			(xy 103.664067 -278.200093) (xy 103.618217 -278.170627) (xy 103.577026 -278.134936) (xy 103.541335 -278.093745)
			(xy 103.511869 -278.047895) (xy 103.489227 -277.998318) (xy 103.473872 -277.946023) (xy 103.466116 -277.892075)
			(xy 103.46563 -277.864824) (xy 99.78771 -277.864824) (xy 99.78771 -280.061416) (xy 105.003092 -280.061416)
			(xy 105.003092 -278.931624) (xy 105.003608 -278.903642) (xy 105.01238 -278.848371) (xy 105.029697 -278.795154)
			(xy 105.05513 -278.745304) (xy 105.088053 -278.70005) (xy 105.107486 -278.67991) (xy 106.641138 -277.146258)
			(xy 106.647901 -277.138886) (xy 106.655597 -277.120437) (xy 106.656124 -277.110444) (xy 106.656124 -268.78915)
			(xy 106.656674 -268.761183) (xy 106.665409 -268.705936) (xy 106.682673 -268.652734) (xy 106.708042 -268.602884)
			(xy 106.740891 -268.557613) (xy 106.760264 -268.537436) (xy 108.787692 -266.510008) (xy 108.80784 -266.490598)
			(xy 108.853104 -266.457722) (xy 108.902959 -266.43234) (xy 108.956173 -266.41508) (xy 109.011434 -266.406366)
			(xy 109.039406 -266.405868) (xy 110.36554 -266.405868) (xy 110.375544 -266.405406) (xy 110.394007 -266.397687)
			(xy 110.401354 -266.390882) (xy 117.930676 -258.86156) (xy 117.937344 -258.85414) (xy 117.944925 -258.83571)
			(xy 117.945408 -258.825746) (xy 117.945408 -256.717546) (xy 117.945934 -256.689565) (xy 117.954703 -256.634294)
			(xy 117.972017 -256.581077) (xy 117.997448 -256.531227) (xy 118.03037 -256.485972) (xy 118.049802 -256.465832)
			(xy 120.782334 -253.7333) (xy 120.802479 -253.713886) (xy 120.847742 -253.681007) (xy 120.897597 -253.655624)
			(xy 120.950813 -253.638365) (xy 121.006075 -253.629655) (xy 121.034048 -253.62916) (xy 121.96318 -253.62916)
			(xy 121.971562 -253.626112) (xy 122.002781 -253.615596) (xy 122.06766 -253.604223) (xy 122.100594 -253.603506)
			(xy 122.127848 -253.60394) (xy 122.181802 -253.611697) (xy 122.234102 -253.627053) (xy 122.283685 -253.649696)
			(xy 122.329541 -253.679165) (xy 122.370736 -253.71486) (xy 122.406431 -253.756054) (xy 122.435901 -253.80191)
			(xy 122.458545 -253.851492) (xy 122.473902 -253.903792) (xy 122.481659 -253.957746) (xy 122.481659 -254.012254)
			(xy 122.473902 -254.066208) (xy 122.458545 -254.118508) (xy 122.435901 -254.16809) (xy 122.406431 -254.213946)
			(xy 122.370736 -254.25514) (xy 122.329541 -254.290835) (xy 122.283685 -254.320304) (xy 122.234102 -254.342947)
			(xy 122.181802 -254.358303) (xy 122.127848 -254.36606) (xy 122.100594 -254.366522) (xy 122.067661 -254.365786)
			(xy 122.002782 -254.354422) (xy 121.971562 -254.343916) (xy 121.96318 -254.340868) (xy 121.20245 -254.340868)
			(xy 121.192444 -254.341315) (xy 121.173981 -254.349043) (xy 121.166636 -254.355854) (xy 118.672356 -256.850134)
			(xy 118.665695 -256.857559) (xy 118.658108 -256.875985) (xy 118.657624 -256.885948) (xy 118.657624 -258.994148)
			(xy 118.657086 -259.022129) (xy 118.648318 -259.077399) (xy 118.631007 -259.130615) (xy 118.605578 -259.180466)
			(xy 118.57266 -259.225721) (xy 118.55323 -259.245862) (xy 115.603528 -262.195564) (xy 116.381782 -262.195564)
			(xy 116.385853 -262.139942) (xy 116.397979 -262.085505) (xy 116.417902 -262.033414) (xy 116.445198 -261.984779)
			(xy 116.479284 -261.940636) (xy 116.519433 -261.901927) (xy 116.564791 -261.869476) (xy 116.614391 -261.843975)
			(xy 116.667175 -261.825968) (xy 116.722018 -261.815838) (xy 116.777752 -261.813801) (xy 116.833189 -261.819901)
			(xy 116.887146 -261.834007) (xy 116.938475 -261.855819) (xy 116.986081 -261.884873) (xy 117.028949 -261.920548)
			(xy 117.066166 -261.962085) (xy 117.096939 -262.008598) (xy 117.120611 -262.059095) (xy 117.136679 -262.112502)
			(xy 117.144799 -262.167678) (xy 117.145308 -262.195564) (xy 117.144799 -262.22345) (xy 117.136679 -262.278626)
			(xy 117.120611 -262.332033) (xy 117.096939 -262.38253) (xy 117.066166 -262.429043) (xy 117.028949 -262.47058)
			(xy 116.986081 -262.506255) (xy 116.938475 -262.535309) (xy 116.887146 -262.557121) (xy 116.833189 -262.571227)
			(xy 116.777752 -262.577327) (xy 116.722018 -262.57529) (xy 116.667175 -262.56516) (xy 116.614391 -262.547153)
			(xy 116.564791 -262.521652) (xy 116.519433 -262.489201) (xy 116.479284 -262.450492) (xy 116.445198 -262.406349)
			(xy 116.417902 -262.357714) (xy 116.397979 -262.305623) (xy 116.385853 -262.251186) (xy 116.381782 -262.195564)
			(xy 115.603528 -262.195564) (xy 114.727228 -263.071864) (xy 116.381782 -263.071864) (xy 116.385853 -263.016242)
			(xy 116.397979 -262.961805) (xy 116.417902 -262.909714) (xy 116.445198 -262.861079) (xy 116.479284 -262.816936)
			(xy 116.519433 -262.778227) (xy 116.564791 -262.745776) (xy 116.614391 -262.720275) (xy 116.667175 -262.702268)
			(xy 116.722018 -262.692138) (xy 116.777752 -262.690101) (xy 116.833189 -262.696201) (xy 116.887146 -262.710307)
			(xy 116.938475 -262.732119) (xy 116.986081 -262.761173) (xy 117.028949 -262.796848) (xy 117.066166 -262.838385)
			(xy 117.096939 -262.884898) (xy 117.120611 -262.935395) (xy 117.136679 -262.988802) (xy 117.144799 -263.043978)
			(xy 117.145308 -263.071864) (xy 117.144799 -263.09975) (xy 117.136679 -263.154926) (xy 117.120611 -263.208333)
			(xy 117.096939 -263.25883) (xy 117.066166 -263.305343) (xy 117.028949 -263.34688) (xy 116.986081 -263.382555)
			(xy 116.938475 -263.411609) (xy 116.887146 -263.433421) (xy 116.833189 -263.447527) (xy 116.777752 -263.453627)
			(xy 116.722018 -263.45159) (xy 116.667175 -263.44146) (xy 116.614391 -263.423453) (xy 116.564791 -263.397952)
			(xy 116.519433 -263.365501) (xy 116.479284 -263.326792) (xy 116.445198 -263.282649) (xy 116.417902 -263.234014)
			(xy 116.397979 -263.181923) (xy 116.385853 -263.127486) (xy 116.381782 -263.071864) (xy 114.727228 -263.071864)
			(xy 113.669572 -264.12952) (xy 114.449096 -264.12952) (xy 114.453167 -264.073898) (xy 114.465293 -264.019461)
			(xy 114.485216 -263.96737) (xy 114.512512 -263.918735) (xy 114.546598 -263.874592) (xy 114.586747 -263.835883)
			(xy 114.632105 -263.803432) (xy 114.681705 -263.777931) (xy 114.734489 -263.759924) (xy 114.789332 -263.749794)
			(xy 114.845066 -263.747757) (xy 114.900503 -263.753857) (xy 114.95446 -263.767963) (xy 115.000755 -263.787636)
			(xy 117.571772 -263.787636) (xy 117.575843 -263.732014) (xy 117.587969 -263.677577) (xy 117.607892 -263.625486)
			(xy 117.635188 -263.576851) (xy 117.669274 -263.532708) (xy 117.709423 -263.493999) (xy 117.754781 -263.461548)
			(xy 117.804381 -263.436047) (xy 117.857165 -263.41804) (xy 117.912008 -263.40791) (xy 117.967742 -263.405873)
			(xy 118.023179 -263.411973) (xy 118.077136 -263.426079) (xy 118.128465 -263.447891) (xy 118.176071 -263.476945)
			(xy 118.218939 -263.51262) (xy 118.256156 -263.554157) (xy 118.286929 -263.60067) (xy 118.310601 -263.651167)
			(xy 118.326669 -263.704574) (xy 118.334789 -263.75975) (xy 118.335298 -263.787636) (xy 118.334789 -263.815522)
			(xy 118.326669 -263.870698) (xy 118.310601 -263.924105) (xy 118.286929 -263.974602) (xy 118.256156 -264.021115)
			(xy 118.218939 -264.062652) (xy 118.176071 -264.098327) (xy 118.128465 -264.127381) (xy 118.077136 -264.149193)
			(xy 118.023179 -264.163299) (xy 117.967742 -264.169399) (xy 117.912008 -264.167362) (xy 117.857165 -264.157232)
			(xy 117.804381 -264.139225) (xy 117.754781 -264.113724) (xy 117.709423 -264.081273) (xy 117.669274 -264.042564)
			(xy 117.635188 -263.998421) (xy 117.607892 -263.949786) (xy 117.587969 -263.897695) (xy 117.575843 -263.843258)
			(xy 117.571772 -263.787636) (xy 115.000755 -263.787636) (xy 115.005789 -263.789775) (xy 115.053395 -263.818829)
			(xy 115.096263 -263.854504) (xy 115.13348 -263.896041) (xy 115.164253 -263.942554) (xy 115.187925 -263.993051)
			(xy 115.203993 -264.046458) (xy 115.212113 -264.101634) (xy 115.212622 -264.12952) (xy 115.212113 -264.157406)
			(xy 115.203993 -264.212582) (xy 115.187925 -264.265989) (xy 115.164253 -264.316486) (xy 115.13348 -264.362999)
			(xy 115.096263 -264.404536) (xy 115.053395 -264.440211) (xy 115.005789 -264.469265) (xy 114.95446 -264.491077)
			(xy 114.900503 -264.505183) (xy 114.845066 -264.511283) (xy 114.789332 -264.509246) (xy 114.734489 -264.499116)
			(xy 114.681705 -264.481109) (xy 114.632105 -264.455608) (xy 114.586747 -264.423157) (xy 114.546598 -264.384448)
			(xy 114.512512 -264.340305) (xy 114.485216 -264.29167) (xy 114.465293 -264.239579) (xy 114.453167 -264.185142)
			(xy 114.449096 -264.12952) (xy 113.669572 -264.12952) (xy 110.785656 -267.013436) (xy 110.765521 -267.032861)
			(xy 110.720255 -267.065737) (xy 110.670397 -267.091117) (xy 110.617179 -267.108374) (xy 110.561915 -267.117082)
			(xy 110.533942 -267.117576) (xy 109.207808 -267.117576) (xy 109.197799 -267.117999) (xy 109.179336 -267.125744)
			(xy 109.171994 -267.132562) (xy 107.382818 -268.921738) (xy 107.376065 -268.929118) (xy 107.368361 -268.947561)
			(xy 107.367832 -268.957552) (xy 107.367832 -276.051264) (xy 109.061504 -276.051264) (xy 109.061948 -276.023893)
			(xy 109.069771 -275.969713) (xy 109.085265 -275.917209) (xy 109.108112 -275.867463) (xy 109.137841 -275.821497)
			(xy 109.155484 -275.800566) (xy 109.16158 -275.793454) (xy 109.16793 -275.776436) (xy 109.16793 -275.691092)
			(xy 109.16158 -275.674074) (xy 109.155484 -275.666962) (xy 109.13781 -275.646057) (xy 109.10809 -275.600083)
			(xy 109.085249 -275.550332) (xy 109.069757 -275.497826) (xy 109.061933 -275.443645) (xy 109.061937 -275.388901)
			(xy 109.069769 -275.334721) (xy 109.085268 -275.282217) (xy 109.108116 -275.232469) (xy 109.137843 -275.1865)
			(xy 109.155484 -275.165566) (xy 109.16158 -275.158454) (xy 109.16793 -275.141436) (xy 109.16793 -275.056092)
			(xy 109.16158 -275.039074) (xy 109.155484 -275.031962) (xy 109.137858 -275.011019) (xy 109.108145 -274.965049)
			(xy 109.085307 -274.915304) (xy 109.069812 -274.862806) (xy 109.06198 -274.808632) (xy 109.061504 -274.781264)
			(xy 109.061944 -274.754011) (xy 109.069706 -274.700061) (xy 109.085066 -274.647765) (xy 109.107713 -274.598187)
			(xy 109.137184 -274.552336) (xy 109.17288 -274.511146) (xy 109.214075 -274.475455) (xy 109.259929 -274.44599)
			(xy 109.30951 -274.42335) (xy 109.361808 -274.407996) (xy 109.415759 -274.400241) (xy 109.443012 -274.399756)
			(xy 109.470383 -274.400201) (xy 109.524564 -274.408022) (xy 109.577068 -274.423515) (xy 109.626814 -274.446362)
			(xy 109.67278 -274.476092) (xy 109.69371 -274.493736) (xy 109.700822 -274.499832) (xy 109.71784 -274.506182)
			(xy 109.803184 -274.506182) (xy 109.820202 -274.499832) (xy 109.827314 -274.493736) (xy 109.848272 -274.476129)
			(xy 109.894237 -274.446411) (xy 109.943978 -274.423569) (xy 109.996473 -274.40807) (xy 110.050645 -274.400234)
			(xy 110.078012 -274.399756) (xy 110.105262 -274.400267) (xy 110.159207 -274.408024) (xy 110.211499 -274.423379)
			(xy 110.261074 -274.446018) (xy 110.306922 -274.475483) (xy 110.348112 -274.511171) (xy 110.383803 -274.552358)
			(xy 110.41327 -274.598205) (xy 110.435913 -274.647779) (xy 110.451271 -274.70007) (xy 110.459032 -274.754014)
			(xy 110.45952 -274.781264) (xy 110.459052 -274.808634) (xy 110.451238 -274.862814) (xy 110.43575 -274.915318)
			(xy 110.412908 -274.965065) (xy 110.383182 -275.011031) (xy 110.36554 -275.031962) (xy 110.359444 -275.039074)
			(xy 110.353094 -275.056092) (xy 110.353094 -275.141436) (xy 110.359444 -275.158454) (xy 110.36554 -275.165566)
			(xy 110.383147 -275.186527) (xy 110.412876 -275.232489) (xy 110.435725 -275.28223) (xy 110.451226 -275.334728)
			(xy 110.459058 -275.388904) (xy 110.459062 -275.443642) (xy 110.451237 -275.497819) (xy 110.435744 -275.550319)
			(xy 110.412902 -275.600064) (xy 110.38318 -275.64603) (xy 110.36554 -275.666962) (xy 110.359444 -275.674074)
			(xy 110.353094 -275.691092) (xy 110.353094 -275.776436) (xy 110.359444 -275.793454) (xy 110.36554 -275.800566)
			(xy 110.383147 -275.821527) (xy 110.412876 -275.867489) (xy 110.435725 -275.91723) (xy 110.451226 -275.969728)
			(xy 110.459058 -276.023904) (xy 110.459062 -276.078642) (xy 110.451237 -276.132819) (xy 110.435744 -276.185319)
			(xy 110.412902 -276.235064) (xy 110.38318 -276.28103) (xy 110.36554 -276.301962) (xy 110.359444 -276.309074)
			(xy 110.353094 -276.326092) (xy 110.353094 -276.411436) (xy 110.359444 -276.428454) (xy 110.36554 -276.435566)
			(xy 110.381698 -276.454665) (xy 110.409391 -276.496327) (xy 110.431379 -276.541263) (xy 110.439708 -276.564852)
			(xy 110.443518 -276.576282) (xy 110.460282 -276.593046) (xy 110.559342 -276.626574) (xy 110.582964 -276.623526)
			(xy 110.59287 -276.616668) (xy 110.616626 -276.601325) (xy 110.667684 -276.577015) (xy 110.721771 -276.560506)
			(xy 110.777701 -276.552158) (xy 110.805976 -276.551644) (xy 110.833224 -276.5522) (xy 110.887167 -276.559952)
			(xy 110.939458 -276.575302) (xy 110.989031 -276.597937) (xy 111.03488 -276.627396) (xy 111.076069 -276.66308)
			(xy 111.111761 -276.704263) (xy 111.141229 -276.750105) (xy 111.163873 -276.799675) (xy 111.179232 -276.851962)
			(xy 111.186994 -276.905904) (xy 111.187484 -276.933152) (xy 111.18705 -276.959469) (xy 111.179827 -277.011604)
			(xy 111.165511 -277.062253) (xy 111.144372 -277.110455) (xy 111.116813 -277.155296) (xy 111.083356 -277.195927)
			(xy 111.064294 -277.214076) (xy 111.0569 -277.221604) (xy 111.048372 -277.240879) (xy 111.047784 -277.251414)
			(xy 111.047784 -277.32609) (xy 111.04831 -277.33664) (xy 111.056848 -277.355935) (xy 111.064294 -277.363428)
			(xy 111.083386 -277.38155) (xy 111.116863 -277.422173) (xy 111.144432 -277.467016) (xy 111.163271 -277.509986)
			(xy 112.634776 -277.509986) (xy 112.634776 -270.45539) (xy 112.635275 -270.427408) (xy 112.644052 -270.372136)
			(xy 112.661373 -270.318919) (xy 112.68681 -270.269069) (xy 112.719736 -270.223816) (xy 112.73917 -270.203676)
			(xy 118.4529 -264.489946) (xy 118.459577 -264.482534) (xy 118.467153 -264.464098) (xy 118.467632 -264.454132)
			(xy 118.467632 -263.466072) (xy 118.467188 -263.456101) (xy 118.459591 -263.437666) (xy 118.4529 -263.430258)
			(xy 118.112286 -263.089644) (xy 118.0929 -263.069466) (xy 118.060002 -263.024208) (xy 118.03458 -262.974365)
			(xy 118.017259 -262.921162) (xy 118.008465 -262.865905) (xy 118.007892 -262.83793) (xy 118.007892 -261.58317)
			(xy 118.008438 -261.55519) (xy 118.017203 -261.49992) (xy 118.034512 -261.446703) (xy 118.059939 -261.396853)
			(xy 118.092857 -261.351597) (xy 118.112286 -261.331456) (xy 119.581422 -259.86232) (xy 119.588155 -259.854924)
			(xy 119.595869 -259.836493) (xy 119.596408 -259.826506) (xy 119.596408 -256.534666) (xy 119.596972 -256.5067)
			(xy 119.605705 -256.451454) (xy 119.622966 -256.398252) (xy 119.648331 -256.348402) (xy 119.681176 -256.30313)
			(xy 119.700548 -256.282952) (xy 121.026682 -254.956818) (xy 121.030492 -254.94869) (xy 121.04239 -254.924479)
			(xy 121.072033 -254.879406) (xy 121.107727 -254.838956) (xy 121.148761 -254.803936) (xy 121.194318 -254.775043)
			(xy 121.24349 -254.752853) (xy 121.295296 -254.737809) (xy 121.348705 -254.730209) (xy 121.375678 -254.729742)
			(xy 121.402933 -254.730176) (xy 121.456887 -254.737931) (xy 121.509189 -254.753287) (xy 121.558772 -254.775931)
			(xy 121.604628 -254.805401) (xy 121.645822 -254.841098) (xy 121.681516 -254.882295) (xy 121.710983 -254.928153)
			(xy 121.733623 -254.977738) (xy 121.748975 -255.03004) (xy 121.756726 -255.083995) (xy 121.757186 -255.11125)
			(xy 121.756704 -255.138224) (xy 121.749123 -255.191636) (xy 121.734089 -255.243447) (xy 121.711905 -255.292622)
			(xy 121.683011 -255.33818) (xy 121.647986 -255.379211) (xy 121.607527 -255.414896) (xy 121.562444 -255.444524)
			(xy 121.538238 -255.456436) (xy 121.53011 -255.460246) (xy 120.323102 -256.667254) (xy 120.316383 -256.674661)
			(xy 120.30866 -256.693083) (xy 120.308116 -256.703068) (xy 120.308116 -259.994908) (xy 120.307528 -260.022873)
			(xy 120.2988 -260.078118) (xy 120.281544 -260.131319) (xy 120.256185 -260.18117) (xy 120.223345 -260.226443)
			(xy 120.203976 -260.246622) (xy 118.934946 -261.515652) (xy 119.394683 -261.515652) (xy 119.394683 -261.461148)
			(xy 119.402441 -261.407198) (xy 119.417797 -261.354901) (xy 119.44044 -261.305323) (xy 119.469909 -261.259471)
			(xy 119.505604 -261.218281) (xy 119.546797 -261.18259) (xy 119.592651 -261.153125) (xy 119.642231 -261.130486)
			(xy 119.694529 -261.115134) (xy 119.74848 -261.107381) (xy 119.775732 -261.10692) (xy 119.804331 -261.107398)
			(xy 119.860888 -261.115942) (xy 119.915535 -261.132832) (xy 119.967049 -261.157692) (xy 120.014274 -261.189963)
			(xy 120.056152 -261.228922) (xy 120.091745 -261.273697) (xy 120.120256 -261.323283) (xy 120.141044 -261.37657)
			(xy 120.147842 -261.404354) (xy 120.150128 -261.413752) (xy 120.160288 -261.429246) (xy 120.231662 -261.479538)
			(xy 120.249442 -261.48411) (xy 120.259094 -261.483094) (xy 120.270352 -261.481798) (xy 120.292974 -261.480402)
			(xy 120.304306 -261.4803) (xy 120.331558 -261.48077) (xy 120.385506 -261.488528) (xy 120.437801 -261.503884)
			(xy 120.487378 -261.526526) (xy 120.533229 -261.555993) (xy 120.574419 -261.591685) (xy 120.610111 -261.632876)
			(xy 120.639577 -261.678727) (xy 120.662219 -261.728305) (xy 120.677574 -261.7806) (xy 120.68533 -261.834548)
			(xy 120.68533 -261.889052) (xy 120.677574 -261.943) (xy 120.662219 -261.995295) (xy 120.639577 -262.044873)
			(xy 120.610111 -262.090724) (xy 120.574419 -262.131915) (xy 120.533229 -262.167607) (xy 120.487378 -262.197074)
			(xy 120.437801 -262.219716) (xy 120.385506 -262.235072) (xy 120.331558 -262.24283) (xy 120.304306 -262.243316)
			(xy 120.275709 -262.242776) (xy 120.219157 -262.234239) (xy 120.164512 -262.217355) (xy 120.113001 -262.192503)
			(xy 120.065776 -262.16024) (xy 120.023897 -262.121288) (xy 119.988302 -262.076522) (xy 119.959789 -262.026943)
			(xy 119.938997 -261.973663) (xy 119.932196 -261.945882) (xy 119.92991 -261.936484) (xy 119.91975 -261.92099)
			(xy 119.848376 -261.870698) (xy 119.830596 -261.866126) (xy 119.820944 -261.867142) (xy 119.809685 -261.868435)
			(xy 119.787064 -261.869833) (xy 119.775732 -261.869936) (xy 119.74848 -261.869419) (xy 119.694529 -261.861666)
			(xy 119.642231 -261.846314) (xy 119.592651 -261.823675) (xy 119.546797 -261.79421) (xy 119.505604 -261.758519)
			(xy 119.469909 -261.717329) (xy 119.44044 -261.671477) (xy 119.417797 -261.621899) (xy 119.402441 -261.569602)
			(xy 119.394683 -261.515652) (xy 118.934946 -261.515652) (xy 118.73484 -261.715758) (xy 118.728166 -261.723173)
			(xy 118.720587 -261.741607) (xy 118.720108 -261.751572) (xy 118.720108 -262.580882) (xy 119.152922 -262.580882)
			(xy 119.156993 -262.52526) (xy 119.169119 -262.470823) (xy 119.189042 -262.418732) (xy 119.216338 -262.370097)
			(xy 119.250424 -262.325954) (xy 119.290573 -262.287245) (xy 119.335931 -262.254794) (xy 119.385531 -262.229293)
			(xy 119.438315 -262.211286) (xy 119.493158 -262.201156) (xy 119.548892 -262.199119) (xy 119.604329 -262.205219)
			(xy 119.658286 -262.219325) (xy 119.709615 -262.241137) (xy 119.757221 -262.270191) (xy 119.800089 -262.305866)
			(xy 119.837306 -262.347403) (xy 119.868079 -262.393916) (xy 119.891751 -262.444413) (xy 119.907819 -262.49782)
			(xy 119.915939 -262.552996) (xy 119.916448 -262.580882) (xy 119.915939 -262.608768) (xy 119.907819 -262.663944)
			(xy 119.891751 -262.717351) (xy 119.868079 -262.767848) (xy 119.837306 -262.814361) (xy 119.800089 -262.855898)
			(xy 119.757221 -262.891573) (xy 119.709615 -262.920627) (xy 119.658286 -262.942439) (xy 119.604329 -262.956545)
			(xy 119.548892 -262.962645) (xy 119.493158 -262.960608) (xy 119.438315 -262.950478) (xy 119.385531 -262.932471)
			(xy 119.335931 -262.90697) (xy 119.290573 -262.874519) (xy 119.250424 -262.83581) (xy 119.216338 -262.791667)
			(xy 119.189042 -262.743032) (xy 119.169119 -262.690941) (xy 119.156993 -262.636504) (xy 119.152922 -262.580882)
			(xy 118.720108 -262.580882) (xy 118.720108 -262.669528) (xy 118.720541 -262.6795) (xy 118.728145 -262.697937)
			(xy 118.73484 -262.705342) (xy 119.075454 -263.045956) (xy 119.094847 -263.066127) (xy 119.127743 -263.111388)
			(xy 119.153162 -263.161233) (xy 119.160368 -263.18337) (xy 122.968764 -263.18337) (xy 122.972835 -263.127748)
			(xy 122.984961 -263.073311) (xy 123.004884 -263.02122) (xy 123.03218 -262.972585) (xy 123.066266 -262.928442)
			(xy 123.106415 -262.889733) (xy 123.151773 -262.857282) (xy 123.201373 -262.831781) (xy 123.254157 -262.813774)
			(xy 123.309 -262.803644) (xy 123.364734 -262.801607) (xy 123.420171 -262.807707) (xy 123.474128 -262.821813)
			(xy 123.525457 -262.843625) (xy 123.573063 -262.872679) (xy 123.615931 -262.908354) (xy 123.653148 -262.949891)
			(xy 123.683921 -262.996404) (xy 123.707593 -263.046901) (xy 123.723661 -263.100308) (xy 123.731781 -263.155484)
			(xy 123.73229 -263.18337) (xy 123.731781 -263.211256) (xy 123.723661 -263.266432) (xy 123.707593 -263.319839)
			(xy 123.683921 -263.370336) (xy 123.653148 -263.416849) (xy 123.615931 -263.458386) (xy 123.573063 -263.494061)
			(xy 123.525457 -263.523115) (xy 123.474128 -263.544927) (xy 123.420171 -263.559033) (xy 123.364734 -263.565133)
			(xy 123.309 -263.563096) (xy 123.254157 -263.552966) (xy 123.201373 -263.534959) (xy 123.151773 -263.509458)
			(xy 123.106415 -263.477007) (xy 123.066266 -263.438298) (xy 123.03218 -263.394155) (xy 123.004884 -263.34552)
			(xy 122.984961 -263.293429) (xy 122.972835 -263.238992) (xy 122.968764 -263.18337) (xy 119.160368 -263.18337)
			(xy 119.170482 -263.214437) (xy 119.179275 -263.269694) (xy 119.179848 -263.29767) (xy 119.179848 -263.82091)
			(xy 119.443752 -263.82091) (xy 119.447823 -263.765288) (xy 119.459949 -263.710851) (xy 119.479872 -263.65876)
			(xy 119.507168 -263.610125) (xy 119.541254 -263.565982) (xy 119.581403 -263.527273) (xy 119.626761 -263.494822)
			(xy 119.676361 -263.469321) (xy 119.729145 -263.451314) (xy 119.783988 -263.441184) (xy 119.839722 -263.439147)
			(xy 119.895159 -263.445247) (xy 119.949116 -263.459353) (xy 120.000445 -263.481165) (xy 120.048051 -263.510219)
			(xy 120.090919 -263.545894) (xy 120.128136 -263.587431) (xy 120.158909 -263.633944) (xy 120.182581 -263.684441)
			(xy 120.198649 -263.737848) (xy 120.206769 -263.793024) (xy 120.207278 -263.82091) (xy 120.206769 -263.848796)
			(xy 120.198649 -263.903972) (xy 120.182581 -263.957379) (xy 120.158909 -264.007876) (xy 120.128136 -264.054389)
			(xy 120.090919 -264.095926) (xy 120.050552 -264.12952) (xy 122.980194 -264.12952) (xy 122.984265 -264.073898)
			(xy 122.996391 -264.019461) (xy 123.016314 -263.96737) (xy 123.04361 -263.918735) (xy 123.077696 -263.874592)
			(xy 123.117845 -263.835883) (xy 123.163203 -263.803432) (xy 123.212803 -263.777931) (xy 123.265587 -263.759924)
			(xy 123.32043 -263.749794) (xy 123.376164 -263.747757) (xy 123.431601 -263.753857) (xy 123.485558 -263.767963)
			(xy 123.536887 -263.789775) (xy 123.584493 -263.818829) (xy 123.627361 -263.854504) (xy 123.664578 -263.896041)
			(xy 123.695351 -263.942554) (xy 123.719023 -263.993051) (xy 123.735091 -264.046458) (xy 123.743211 -264.101634)
			(xy 123.74372 -264.12952) (xy 123.743211 -264.157406) (xy 123.735091 -264.212582) (xy 123.719023 -264.265989)
			(xy 123.695351 -264.316486) (xy 123.664578 -264.362999) (xy 123.627361 -264.404536) (xy 123.584493 -264.440211)
			(xy 123.536887 -264.469265) (xy 123.485558 -264.491077) (xy 123.431601 -264.505183) (xy 123.376164 -264.511283)
			(xy 123.32043 -264.509246) (xy 123.265587 -264.499116) (xy 123.212803 -264.481109) (xy 123.163203 -264.455608)
			(xy 123.117845 -264.423157) (xy 123.077696 -264.384448) (xy 123.04361 -264.340305) (xy 123.016314 -264.29167)
			(xy 122.996391 -264.239579) (xy 122.984265 -264.185142) (xy 122.980194 -264.12952) (xy 120.050552 -264.12952)
			(xy 120.048051 -264.131601) (xy 120.000445 -264.160655) (xy 119.949116 -264.182467) (xy 119.895159 -264.196573)
			(xy 119.839722 -264.202673) (xy 119.783988 -264.200636) (xy 119.729145 -264.190506) (xy 119.676361 -264.172499)
			(xy 119.626761 -264.146998) (xy 119.581403 -264.114547) (xy 119.541254 -264.075838) (xy 119.507168 -264.031695)
			(xy 119.479872 -263.98306) (xy 119.459949 -263.930969) (xy 119.447823 -263.876532) (xy 119.443752 -263.82091)
			(xy 119.179848 -263.82091) (xy 119.179848 -264.622534) (xy 119.179294 -264.650514) (xy 119.170529 -264.705783)
			(xy 119.153221 -264.758999) (xy 119.127797 -264.80885) (xy 119.094882 -264.854106) (xy 119.075454 -264.874248)
			(xy 119.013732 -264.93597) (xy 120.417334 -264.93597) (xy 120.421405 -264.880348) (xy 120.433531 -264.825911)
			(xy 120.453454 -264.77382) (xy 120.48075 -264.725185) (xy 120.514836 -264.681042) (xy 120.554985 -264.642333)
			(xy 120.600343 -264.609882) (xy 120.649943 -264.584381) (xy 120.702727 -264.566374) (xy 120.75757 -264.556244)
			(xy 120.813304 -264.554207) (xy 120.868741 -264.560307) (xy 120.922698 -264.574413) (xy 120.974027 -264.596225)
			(xy 121.021633 -264.625279) (xy 121.064501 -264.660954) (xy 121.101718 -264.702491) (xy 121.132491 -264.749004)
			(xy 121.156163 -264.799501) (xy 121.172231 -264.852908) (xy 121.180351 -264.908084) (xy 121.18086 -264.93597)
			(xy 121.180351 -264.963856) (xy 121.172231 -265.019032) (xy 121.156163 -265.072439) (xy 121.132491 -265.122936)
			(xy 121.101718 -265.169449) (xy 121.064501 -265.210986) (xy 121.021633 -265.246661) (xy 120.974027 -265.275715)
			(xy 120.922698 -265.297527) (xy 120.868741 -265.311633) (xy 120.813304 -265.317733) (xy 120.75757 -265.315696)
			(xy 120.702727 -265.305566) (xy 120.649943 -265.287559) (xy 120.600343 -265.262058) (xy 120.554985 -265.229607)
			(xy 120.514836 -265.190898) (xy 120.48075 -265.146755) (xy 120.453454 -265.09812) (xy 120.433531 -265.046029)
			(xy 120.421405 -264.991592) (xy 120.417334 -264.93597) (xy 119.013732 -264.93597) (xy 118.115588 -265.834114)
			(xy 119.246394 -265.834114) (xy 119.250465 -265.778492) (xy 119.262591 -265.724055) (xy 119.282514 -265.671964)
			(xy 119.30981 -265.623329) (xy 119.343896 -265.579186) (xy 119.384045 -265.540477) (xy 119.429403 -265.508026)
			(xy 119.479003 -265.482525) (xy 119.531787 -265.464518) (xy 119.58663 -265.454388) (xy 119.642364 -265.452351)
			(xy 119.697801 -265.458451) (xy 119.751758 -265.472557) (xy 119.803087 -265.494369) (xy 119.850693 -265.523423)
			(xy 119.893561 -265.559098) (xy 119.930778 -265.600635) (xy 119.961551 -265.647148) (xy 119.985223 -265.697645)
			(xy 120.001291 -265.751052) (xy 120.009411 -265.806228) (xy 120.00992 -265.834114) (xy 120.009411 -265.862)
			(xy 120.001291 -265.917176) (xy 119.985223 -265.970583) (xy 119.961551 -266.02108) (xy 119.930778 -266.067593)
			(xy 119.893561 -266.10913) (xy 119.850693 -266.144805) (xy 119.803087 -266.173859) (xy 119.751758 -266.195671)
			(xy 119.697801 -266.209777) (xy 119.642364 -266.215877) (xy 119.58663 -266.21384) (xy 119.531787 -266.20371)
			(xy 119.479003 -266.185703) (xy 119.429403 -266.160202) (xy 119.384045 -266.127751) (xy 119.343896 -266.089042)
			(xy 119.30981 -266.044899) (xy 119.282514 -265.996264) (xy 119.262591 -265.944173) (xy 119.250465 -265.889736)
			(xy 119.246394 -265.834114) (xy 118.115588 -265.834114) (xy 113.361724 -270.587978) (xy 113.35504 -270.595385)
			(xy 113.347468 -270.613825) (xy 113.346992 -270.623792) (xy 113.346992 -277.341584) (xy 113.347452 -277.351553)
			(xy 113.355037 -277.36999) (xy 113.361724 -277.377398) (xy 114.327178 -278.342852) (xy 114.346573 -278.363021)
			(xy 114.364035 -278.387048) (xy 117.885972 -278.387048) (xy 117.885972 -269.555214) (xy 117.886488 -269.527233)
			(xy 117.895261 -269.471961) (xy 117.912578 -269.418745) (xy 117.938011 -269.368895) (xy 117.970934 -269.32364)
			(xy 117.990366 -269.3035) (xy 120.396254 -266.897612) (xy 120.416376 -266.878173) (xy 120.461647 -266.8453)
			(xy 120.511508 -266.819924) (xy 120.564728 -266.80267) (xy 120.619994 -266.793965) (xy 120.647968 -266.793472)
			(xy 121.40311 -266.793472) (xy 121.413112 -266.792993) (xy 121.431575 -266.785286) (xy 121.438924 -266.778486)
			(xy 124.09551 -264.1219) (xy 124.102251 -264.11451) (xy 124.109961 -264.096075) (xy 124.110496 -264.086086)
			(xy 124.110496 -262.098536) (xy 124.110039 -262.088531) (xy 124.102316 -262.070069) (xy 124.09551 -262.062722)
			(xy 123.151392 -261.118604) (xy 123.131995 -261.098443) (xy 123.099114 -261.053184) (xy 123.073728 -261.003333)
			(xy 123.056465 -260.950121) (xy 123.04775 -260.894862) (xy 123.047252 -260.86689) (xy 123.047252 -253.998222)
			(xy 123.046814 -253.988215) (xy 123.039079 -253.969752) (xy 123.032266 -253.962408) (xy 122.495818 -253.42596)
			(xy 122.488409 -253.419278) (xy 122.469971 -253.411703) (xy 122.460004 -253.411228) (xy 118.950994 -253.411228)
			(xy 118.943284 -253.411448) (xy 118.928548 -253.415981) (xy 118.922038 -253.420118) (xy 118.898031 -253.435995)
			(xy 118.846266 -253.461154) (xy 118.791309 -253.478252) (xy 118.734408 -253.486902) (xy 118.70563 -253.487428)
			(xy 118.678379 -253.486917) (xy 118.624431 -253.479164) (xy 118.572135 -253.463813) (xy 118.522556 -253.441176)
			(xy 118.476704 -253.411713) (xy 118.435511 -253.376024) (xy 118.399817 -253.334836) (xy 118.370348 -253.288988)
			(xy 118.347704 -253.239412) (xy 118.332346 -253.187118) (xy 118.324587 -253.133171) (xy 118.324122 -253.10592)
			(xy 118.324676 -253.076631) (xy 118.33362 -253.01874) (xy 118.351316 -252.9629) (xy 118.377347 -252.910424)
			(xy 118.4111 -252.862549) (xy 118.45178 -252.820401) (xy 118.49843 -252.784973) (xy 118.54995 -252.7571)
			(xy 118.57736 -252.746764) (xy 118.584726 -252.743208) (xy 118.611187 -252.729304) (xy 118.667615 -252.709599)
			(xy 118.726545 -252.699616) (xy 118.75643 -252.699012) (xy 122.628406 -252.699012) (xy 122.656389 -252.699503)
			(xy 122.711661 -252.708281) (xy 122.764879 -252.725603) (xy 122.814728 -252.751042) (xy 122.859981 -252.783971)
			(xy 122.88012 -252.803406) (xy 123.65482 -253.578106) (xy 123.674224 -253.59826) (xy 123.707103 -253.643521)
			(xy 123.732488 -253.693374) (xy 123.749749 -253.746587) (xy 123.758463 -253.801848) (xy 123.75896 -253.82982)
			(xy 123.75896 -258.719574) (xy 123.759638 -258.730924) (xy 123.769535 -258.751363) (xy 123.77801 -258.758944)
			(xy 123.848368 -258.81584) (xy 123.87072 -258.821174) (xy 123.88215 -258.818888) (xy 123.901974 -258.814875)
			(xy 123.94219 -258.810546) (xy 123.962414 -258.810252) (xy 123.989662 -258.810819) (xy 124.043602 -258.818576)
			(xy 124.09589 -258.833931) (xy 124.14546 -258.856571) (xy 124.191304 -258.886034) (xy 124.232488 -258.921722)
			(xy 124.268174 -258.962907) (xy 124.297636 -259.008752) (xy 124.320274 -259.058323) (xy 124.335627 -259.110611)
			(xy 124.343382 -259.164552) (xy 124.343382 -259.219048) (xy 124.335627 -259.272989) (xy 124.320274 -259.325277)
			(xy 124.297636 -259.374848) (xy 124.268174 -259.420693) (xy 124.232488 -259.461878) (xy 124.191304 -259.497566)
			(xy 124.14546 -259.527029) (xy 124.09589 -259.549669) (xy 124.043602 -259.565024) (xy 123.989662 -259.572781)
			(xy 123.962414 -259.573268) (xy 123.942189 -259.57299) (xy 123.901972 -259.568658) (xy 123.88215 -259.564632)
			(xy 123.87072 -259.562346) (xy 123.848368 -259.56768) (xy 123.77801 -259.624576) (xy 123.769542 -259.632166)
			(xy 123.759638 -259.652597) (xy 123.75896 -259.663946) (xy 123.75896 -260.698488) (xy 123.75939 -260.708496)
			(xy 123.76713 -260.726959) (xy 123.773946 -260.734302) (xy 124.718064 -261.67842) (xy 124.737482 -261.69856)
			(xy 124.770359 -261.743826) (xy 124.795739 -261.793682) (xy 124.812998 -261.846899) (xy 124.821708 -261.902161)
			(xy 124.822204 -261.930134) (xy 124.822204 -264.254488) (xy 124.82167 -264.282455) (xy 124.812929 -264.337703)
			(xy 124.795661 -264.390905) (xy 124.770289 -264.440754) (xy 124.737438 -264.486025) (xy 124.718064 -264.506202)
			(xy 121.823226 -267.40104) (xy 121.803061 -267.420432) (xy 121.757802 -267.453312) (xy 121.707952 -267.478698)
			(xy 121.654742 -267.495963) (xy 121.599483 -267.50468) (xy 121.571512 -267.50518) (xy 120.81637 -267.50518)
			(xy 120.806364 -267.505634) (xy 120.787901 -267.513357) (xy 120.780556 -267.520166) (xy 118.883684 -269.417038)
			(xy 124.88545 -269.417038) (xy 124.885949 -269.388298) (xy 124.89458 -269.33147) (xy 124.911636 -269.27658)
			(xy 124.936733 -269.224869) (xy 124.969302 -269.177507) (xy 124.988574 -269.15618) (xy 124.995178 -269.149068)
			(xy 125.00229 -269.131542) (xy 125.00229 -269.042134) (xy 124.995178 -269.024608) (xy 124.988574 -269.017496)
			(xy 124.969327 -268.996148) (xy 124.936756 -268.948792) (xy 124.911659 -268.897086) (xy 124.894602 -268.8422)
			(xy 124.885974 -268.785376) (xy 124.88545 -268.756638) (xy 124.886013 -268.72939) (xy 124.893764 -268.675447)
			(xy 124.909112 -268.623156) (xy 124.931746 -268.573582) (xy 124.961204 -268.527733) (xy 124.996887 -268.486544)
			(xy 125.038069 -268.450852) (xy 125.083912 -268.421384) (xy 125.133481 -268.39874) (xy 125.185769 -268.383381)
			(xy 125.23971 -268.375619) (xy 125.266958 -268.37513) (xy 125.294328 -268.375613) (xy 125.348506 -268.383426)
			(xy 125.40101 -268.398911) (xy 125.450757 -268.421749) (xy 125.496724 -268.45147) (xy 125.517656 -268.46911)
			(xy 125.524768 -268.475206) (xy 125.541786 -268.481556) (xy 125.62713 -268.481556) (xy 125.644148 -268.475206)
			(xy 125.65126 -268.46911) (xy 125.672193 -268.451469) (xy 125.718161 -268.421745) (xy 125.767907 -268.398899)
			(xy 125.820409 -268.383403) (xy 125.874587 -268.375574) (xy 125.929329 -268.375574) (xy 125.983507 -268.383403)
			(xy 126.036009 -268.398899) (xy 126.085755 -268.421745) (xy 126.131723 -268.451469) (xy 126.152656 -268.46911)
			(xy 126.159768 -268.475206) (xy 126.176786 -268.481556) (xy 126.26213 -268.481556) (xy 126.279148 -268.475206)
			(xy 126.28626 -268.46911) (xy 126.307193 -268.451469) (xy 126.353161 -268.421745) (xy 126.402907 -268.398899)
			(xy 126.455409 -268.383403) (xy 126.509587 -268.375574) (xy 126.564329 -268.375574) (xy 126.618507 -268.383403)
			(xy 126.671009 -268.398899) (xy 126.720755 -268.421745) (xy 126.766723 -268.451469) (xy 126.787656 -268.46911)
			(xy 126.794768 -268.475206) (xy 126.811786 -268.481556) (xy 126.89713 -268.481556) (xy 126.914148 -268.475206)
			(xy 126.92126 -268.46911) (xy 126.942193 -268.451469) (xy 126.988161 -268.421745) (xy 127.037907 -268.398899)
			(xy 127.090409 -268.383403) (xy 127.144587 -268.375574) (xy 127.199329 -268.375574) (xy 127.253507 -268.383403)
			(xy 127.306009 -268.398899) (xy 127.355755 -268.421745) (xy 127.401723 -268.451469) (xy 127.422656 -268.46911)
			(xy 127.429768 -268.475206) (xy 127.446786 -268.481556) (xy 127.53213 -268.481556) (xy 127.549148 -268.475206)
			(xy 127.55626 -268.46911) (xy 127.577198 -268.451478) (xy 127.623169 -268.421765) (xy 127.672915 -268.398927)
			(xy 127.725414 -268.383434) (xy 127.779589 -268.375605) (xy 127.806958 -268.37513) (xy 127.834212 -268.375594)
			(xy 127.888164 -268.383347) (xy 127.940465 -268.398699) (xy 127.990047 -268.42134) (xy 128.035902 -268.450807)
			(xy 128.077096 -268.486501) (xy 128.112791 -268.527695) (xy 128.142258 -268.573549) (xy 128.164899 -268.623132)
			(xy 128.180252 -268.675432) (xy 128.188005 -268.729384) (xy 128.188466 -268.756638) (xy 128.187948 -268.785377)
			(xy 128.179321 -268.842204) (xy 128.162269 -268.897094) (xy 128.137177 -268.948805) (xy 128.104612 -268.996168)
			(xy 128.085342 -269.017496) (xy 128.078738 -269.024608) (xy 128.071626 -269.042134) (xy 128.071626 -269.131542)
			(xy 128.078738 -269.149068) (xy 128.085342 -269.15618) (xy 128.104627 -269.177494) (xy 128.137192 -269.224859)
			(xy 128.162282 -269.276574) (xy 128.17933 -269.331468) (xy 128.187948 -269.388298) (xy 128.188466 -269.417038)
			(xy 128.18808 -269.444294) (xy 128.180317 -269.49825) (xy 128.164954 -269.550552) (xy 128.142304 -269.600135)
			(xy 128.112828 -269.64599) (xy 128.077126 -269.687183) (xy 128.035926 -269.722876) (xy 127.990064 -269.752343)
			(xy 127.940477 -269.774982) (xy 127.888171 -269.790334) (xy 127.834214 -269.798086) (xy 127.806958 -269.798546)
			(xy 127.779588 -269.798059) (xy 127.72541 -269.790248) (xy 127.672906 -269.774765) (xy 127.623159 -269.751927)
			(xy 127.577192 -269.722206) (xy 127.55626 -269.704566) (xy 127.549148 -269.69847) (xy 127.53213 -269.69212)
			(xy 127.446786 -269.69212) (xy 127.429768 -269.69847) (xy 127.422656 -269.704566) (xy 127.401723 -269.722207)
			(xy 127.355755 -269.751931) (xy 127.306009 -269.774777) (xy 127.253507 -269.790273) (xy 127.199329 -269.798102)
			(xy 127.144587 -269.798102) (xy 127.090409 -269.790273) (xy 127.037907 -269.774777) (xy 126.988161 -269.751931)
			(xy 126.942193 -269.722207) (xy 126.92126 -269.704566) (xy 126.914148 -269.69847) (xy 126.89713 -269.69212)
			(xy 126.811786 -269.69212) (xy 126.794768 -269.69847) (xy 126.787656 -269.704566) (xy 126.766723 -269.722207)
			(xy 126.720755 -269.751931) (xy 126.671009 -269.774777) (xy 126.618507 -269.790273) (xy 126.564329 -269.798102)
			(xy 126.509587 -269.798102) (xy 126.455409 -269.790273) (xy 126.402907 -269.774777) (xy 126.353161 -269.751931)
			(xy 126.307193 -269.722207) (xy 126.28626 -269.704566) (xy 126.279148 -269.69847) (xy 126.26213 -269.69212)
			(xy 126.176786 -269.69212) (xy 126.159768 -269.69847) (xy 126.152656 -269.704566) (xy 126.131723 -269.722207)
			(xy 126.085755 -269.751931) (xy 126.036009 -269.774777) (xy 125.983507 -269.790273) (xy 125.929329 -269.798102)
			(xy 125.874587 -269.798102) (xy 125.820409 -269.790273) (xy 125.767907 -269.774777) (xy 125.718161 -269.751931)
			(xy 125.672193 -269.722207) (xy 125.65126 -269.704566) (xy 125.644148 -269.69847) (xy 125.62713 -269.69212)
			(xy 125.541786 -269.69212) (xy 125.524768 -269.69847) (xy 125.517656 -269.704566) (xy 125.496709 -269.722187)
			(xy 125.450741 -269.751903) (xy 125.400997 -269.774743) (xy 125.3485 -269.790238) (xy 125.294326 -269.79807)
			(xy 125.266958 -269.798546) (xy 125.239707 -269.798061) (xy 125.185762 -269.7903) (xy 125.133469 -269.774942)
			(xy 125.083894 -269.752298) (xy 125.038046 -269.722831) (xy 124.996857 -269.68714) (xy 124.961166 -269.645951)
			(xy 124.9317 -269.600102) (xy 124.909057 -269.550527) (xy 124.893699 -269.498234) (xy 124.885938 -269.444289)
			(xy 124.88545 -269.417038) (xy 118.883684 -269.417038) (xy 118.61292 -269.687802) (xy 118.606268 -269.695234)
			(xy 118.598677 -269.713655) (xy 118.598188 -269.723616) (xy 118.598188 -277.634192) (xy 120.08485 -277.634192)
			(xy 120.085348 -277.606122) (xy 120.093588 -277.550589) (xy 120.109875 -277.496862) (xy 120.133856 -277.446101)
			(xy 120.165015 -277.3994) (xy 120.202679 -277.357769) (xy 120.224042 -277.339552) (xy 120.232678 -277.33244)
			(xy 120.24233 -277.312882) (xy 120.24487 -277.213314) (xy 120.236234 -277.193502) (xy 120.227852 -277.185882)
			(xy 120.208519 -277.167737) (xy 120.174597 -277.126988) (xy 120.146643 -277.081936) (xy 120.125194 -277.033447)
			(xy 120.110665 -276.982456) (xy 120.103334 -276.929944) (xy 120.102884 -276.903434) (xy 120.103387 -276.876182)
			(xy 120.111139 -276.822233) (xy 120.12649 -276.769937) (xy 120.149128 -276.720357) (xy 120.178592 -276.674504)
			(xy 120.214282 -276.633311) (xy 120.255471 -276.597617) (xy 120.30132 -276.568148) (xy 120.350897 -276.545505)
			(xy 120.403192 -276.530148) (xy 120.45714 -276.52239) (xy 120.484392 -276.521926) (xy 120.510644 -276.52235)
			(xy 120.562654 -276.529537) (xy 120.613186 -276.543791) (xy 120.661285 -276.564842) (xy 120.706042 -276.592292)
			(xy 120.74661 -276.625622) (xy 120.782223 -276.664202) (xy 120.797574 -276.685502) (xy 120.805448 -276.696678)
			(xy 120.829324 -276.708108) (xy 120.94337 -276.700234) (xy 120.965468 -276.685502) (xy 120.971564 -276.67331)
			(xy 120.983825 -276.650017) (xy 121.013792 -276.606742) (xy 121.049423 -276.567996) (xy 121.09004 -276.534514)
			(xy 121.134873 -276.506933) (xy 121.183072 -276.485774) (xy 121.233721 -276.47144) (xy 121.285859 -276.464203)
			(xy 121.312178 -276.46376) (xy 121.345706 -276.465284) (xy 121.355779 -276.465774) (xy 121.374985 -276.459662)
			(xy 121.390363 -276.446633) (xy 121.399547 -276.428692) (xy 121.401125 -276.408599) (xy 121.394855 -276.389444)
			(xy 121.381699 -276.374175) (xy 121.372884 -276.369272) (xy 121.351374 -276.358095) (xy 121.311121 -276.331087)
			(xy 121.29262 -276.315424) (xy 121.285508 -276.309328) (xy 121.26849 -276.302978) (xy 121.183146 -276.302978)
			(xy 121.166128 -276.309328) (xy 121.159016 -276.315424) (xy 121.138092 -276.333073) (xy 121.092116 -276.362782)
			(xy 121.042367 -276.385616) (xy 120.989865 -276.401105) (xy 120.935688 -276.408931) (xy 120.908318 -276.409404)
			(xy 120.881065 -276.408928) (xy 120.827115 -276.401173) (xy 120.774817 -276.385819) (xy 120.725237 -276.363179)
			(xy 120.679383 -276.333712) (xy 120.63819 -276.29802) (xy 120.602496 -276.256828) (xy 120.573028 -276.210976)
			(xy 120.550386 -276.161396) (xy 120.53503 -276.109099) (xy 120.527273 -276.055149) (xy 120.52681 -276.027896)
			(xy 120.527271 -276.000526) (xy 120.53509 -275.946346) (xy 120.55058 -275.893843) (xy 120.573423 -275.844096)
			(xy 120.603148 -275.79813) (xy 120.62079 -275.777198) (xy 120.626886 -275.770086) (xy 120.633236 -275.753068)
			(xy 120.633236 -275.667724) (xy 120.626886 -275.650706) (xy 120.62079 -275.643594) (xy 120.603147 -275.622664)
			(xy 120.573425 -275.576695) (xy 120.550582 -275.526948) (xy 120.535088 -275.474446) (xy 120.52726 -275.420267)
			(xy 120.527261 -275.365527) (xy 120.535089 -275.311349) (xy 120.550584 -275.258847) (xy 120.573428 -275.2091)
			(xy 120.603151 -275.163131) (xy 120.62079 -275.142198) (xy 120.626886 -275.135086) (xy 120.633236 -275.118068)
			(xy 120.633236 -275.032724) (xy 120.626886 -275.015706) (xy 120.62079 -275.008594) (xy 120.603133 -274.987676)
			(xy 120.573424 -274.941699) (xy 120.550592 -274.891948) (xy 120.535105 -274.839444) (xy 120.527282 -274.785266)
			(xy 120.52681 -274.757896) (xy 120.527252 -274.730642) (xy 120.53501 -274.67669) (xy 120.550367 -274.62439)
			(xy 120.573011 -274.574809) (xy 120.602481 -274.528955) (xy 120.638177 -274.487762) (xy 120.679373 -274.452068)
			(xy 120.725228 -274.422601) (xy 120.774811 -274.399959) (xy 120.827111 -274.384605) (xy 120.881064 -274.37685)
			(xy 120.908318 -274.376388) (xy 120.935688 -274.376846) (xy 120.989868 -274.384667) (xy 121.042371 -274.400158)
			(xy 121.092118 -274.423001) (xy 121.138084 -274.452726) (xy 121.159016 -274.470368) (xy 121.166128 -274.476464)
			(xy 121.183146 -274.482814) (xy 121.26849 -274.482814) (xy 121.285508 -274.476464) (xy 121.29262 -274.470368)
			(xy 121.313567 -274.452748) (xy 121.359536 -274.423034) (xy 121.40928 -274.400195) (xy 121.461777 -274.3847)
			(xy 121.51595 -274.376865) (xy 121.543318 -274.376388) (xy 121.57057 -274.376861) (xy 121.624517 -274.38462)
			(xy 121.676812 -274.399977) (xy 121.726389 -274.42262) (xy 121.772239 -274.452088) (xy 121.813429 -274.487781)
			(xy 121.849121 -274.528972) (xy 121.878587 -274.574823) (xy 121.901228 -274.624401) (xy 121.916583 -274.676696)
			(xy 121.92434 -274.730644) (xy 121.924826 -274.757896) (xy 121.924376 -274.785267) (xy 121.916557 -274.839447)
			(xy 121.901065 -274.891951) (xy 121.878219 -274.941698) (xy 121.84849 -274.987664) (xy 121.830846 -275.008594)
			(xy 121.82475 -275.015706) (xy 121.8184 -275.032724) (xy 121.8184 -275.118068) (xy 121.82475 -275.135086)
			(xy 121.830846 -275.142198) (xy 121.848484 -275.163133) (xy 121.878211 -275.2091) (xy 121.901058 -275.258846)
			(xy 121.916556 -275.311348) (xy 121.924385 -275.365526) (xy 121.924386 -275.420268) (xy 121.916557 -275.474447)
			(xy 121.90106 -275.526949) (xy 121.878214 -275.576695) (xy 121.848488 -275.622662) (xy 121.830846 -275.643594)
			(xy 121.82475 -275.650706) (xy 121.8184 -275.667724) (xy 121.8184 -275.753068) (xy 121.82475 -275.770086)
			(xy 121.830846 -275.777198) (xy 121.848489 -275.798127) (xy 121.878202 -275.8441) (xy 121.901038 -275.893848)
			(xy 121.916528 -275.94635) (xy 121.924354 -276.000526) (xy 121.924826 -276.027896) (xy 121.924546 -276.046184)
			(xy 124.460254 -276.046184) (xy 124.460698 -276.018813) (xy 124.468519 -275.964632) (xy 124.484012 -275.912128)
			(xy 124.506859 -275.862382) (xy 124.53659 -275.816416) (xy 124.554234 -275.795486) (xy 124.56033 -275.788374)
			(xy 124.56668 -275.771356) (xy 124.56668 -275.686012) (xy 124.56033 -275.668994) (xy 124.554234 -275.661882)
			(xy 124.536625 -275.640925) (xy 124.506908 -275.59496) (xy 124.484065 -275.545219) (xy 124.468567 -275.492723)
			(xy 124.460732 -275.438552) (xy 124.460254 -275.411184) (xy 124.460763 -275.383934) (xy 124.46852 -275.329989)
			(xy 124.483876 -275.277697) (xy 124.506516 -275.228122) (xy 124.53598 -275.182274) (xy 124.571669 -275.141085)
			(xy 124.612856 -275.105394) (xy 124.658703 -275.075927) (xy 124.708277 -275.053283) (xy 124.760568 -275.037925)
			(xy 124.814512 -275.030164) (xy 124.841762 -275.029676) (xy 124.869132 -275.030146) (xy 124.923312 -275.03796)
			(xy 124.975816 -275.053447) (xy 125.025563 -275.076288) (xy 125.071529 -275.106014) (xy 125.09246 -275.123656)
			(xy 125.099572 -275.129752) (xy 125.11659 -275.136102) (xy 125.201934 -275.136102) (xy 125.218952 -275.129752)
			(xy 125.226064 -275.123656) (xy 125.246997 -275.106015) (xy 125.292965 -275.076291) (xy 125.342711 -275.053445)
			(xy 125.395213 -275.037949) (xy 125.449391 -275.03012) (xy 125.504133 -275.03012) (xy 125.558311 -275.037949)
			(xy 125.610813 -275.053445) (xy 125.660559 -275.076291) (xy 125.706527 -275.106015) (xy 125.72746 -275.123656)
			(xy 125.734572 -275.129752) (xy 125.75159 -275.136102) (xy 125.836934 -275.136102) (xy 125.853952 -275.129752)
			(xy 125.861064 -275.123656) (xy 125.881997 -275.106015) (xy 125.927965 -275.076291) (xy 125.977711 -275.053445)
			(xy 126.030213 -275.037949) (xy 126.084391 -275.03012) (xy 126.139133 -275.03012) (xy 126.193311 -275.037949)
			(xy 126.245813 -275.053445) (xy 126.295559 -275.076291) (xy 126.341527 -275.106015) (xy 126.36246 -275.123656)
			(xy 126.369572 -275.129752) (xy 126.38659 -275.136102) (xy 126.471934 -275.136102) (xy 126.488952 -275.129752)
			(xy 126.496064 -275.123656) (xy 126.516997 -275.106015) (xy 126.562965 -275.076291) (xy 126.612711 -275.053445)
			(xy 126.665213 -275.037949) (xy 126.719391 -275.03012) (xy 126.774133 -275.03012) (xy 126.828311 -275.037949)
			(xy 126.880813 -275.053445) (xy 126.930559 -275.076291) (xy 126.976527 -275.106015) (xy 126.99746 -275.123656)
			(xy 127.004572 -275.129752) (xy 127.02159 -275.136102) (xy 127.106934 -275.136102) (xy 127.123952 -275.129752)
			(xy 127.131064 -275.123656) (xy 127.151993 -275.106013) (xy 127.197967 -275.076303) (xy 127.247716 -275.053469)
			(xy 127.300217 -275.037978) (xy 127.354393 -275.03015) (xy 127.381762 -275.029676) (xy 127.409013 -275.030191)
			(xy 127.462961 -275.037942) (xy 127.515257 -275.053292) (xy 127.564836 -275.075929) (xy 127.610689 -275.105392)
			(xy 127.651882 -275.14108) (xy 127.687576 -275.182268) (xy 127.717045 -275.228116) (xy 127.739689 -275.277692)
			(xy 127.755047 -275.329986) (xy 127.762806 -275.383933) (xy 127.76327 -275.411184) (xy 127.762802 -275.438554)
			(xy 127.754986 -275.492734) (xy 127.739497 -275.545237) (xy 127.716656 -275.594984) (xy 127.686931 -275.640951)
			(xy 127.66929 -275.661882) (xy 127.663194 -275.668994) (xy 127.656844 -275.686012) (xy 127.656844 -275.771356)
			(xy 127.663194 -275.788374) (xy 127.66929 -275.795486) (xy 127.686934 -275.816414) (xy 127.716646 -275.862388)
			(xy 127.739481 -275.912136) (xy 127.754971 -275.964638) (xy 127.762797 -276.018815) (xy 127.76327 -276.046184)
			(xy 127.76283 -276.073438) (xy 127.755074 -276.127392) (xy 127.739718 -276.179693) (xy 127.717075 -276.229275)
			(xy 127.687605 -276.27513) (xy 127.651908 -276.316324) (xy 127.610713 -276.352018) (xy 127.564856 -276.381485)
			(xy 127.515272 -276.404126) (xy 127.46297 -276.419479) (xy 127.409016 -276.427231) (xy 127.381762 -276.427692)
			(xy 127.354393 -276.427192) (xy 127.300215 -276.419382) (xy 127.247712 -276.403901) (xy 127.197965 -276.381067)
			(xy 127.151997 -276.35135) (xy 127.131064 -276.333712) (xy 127.123952 -276.327616) (xy 127.106934 -276.321266)
			(xy 127.02159 -276.321266) (xy 127.004572 -276.327616) (xy 126.99746 -276.333712) (xy 126.976527 -276.351353)
			(xy 126.930559 -276.381077) (xy 126.880813 -276.403923) (xy 126.828311 -276.419419) (xy 126.774133 -276.427248)
			(xy 126.719391 -276.427248) (xy 126.665213 -276.419419) (xy 126.612711 -276.403923) (xy 126.562965 -276.381077)
			(xy 126.516997 -276.351353) (xy 126.496064 -276.333712) (xy 126.488952 -276.327616) (xy 126.471934 -276.321266)
			(xy 126.38659 -276.321266) (xy 126.369572 -276.327616) (xy 126.36246 -276.333712) (xy 126.341527 -276.351353)
			(xy 126.295559 -276.381077) (xy 126.245813 -276.403923) (xy 126.193311 -276.419419) (xy 126.139133 -276.427248)
			(xy 126.084391 -276.427248) (xy 126.030213 -276.419419) (xy 125.977711 -276.403923) (xy 125.927965 -276.381077)
			(xy 125.881997 -276.351353) (xy 125.861064 -276.333712) (xy 125.853952 -276.327616) (xy 125.836934 -276.321266)
			(xy 125.75159 -276.321266) (xy 125.734572 -276.327616) (xy 125.72746 -276.333712) (xy 125.706527 -276.351353)
			(xy 125.660559 -276.381077) (xy 125.610813 -276.403923) (xy 125.558311 -276.419419) (xy 125.504133 -276.427248)
			(xy 125.449391 -276.427248) (xy 125.395213 -276.419419) (xy 125.342711 -276.403923) (xy 125.292965 -276.381077)
			(xy 125.246997 -276.351353) (xy 125.226064 -276.333712) (xy 125.218952 -276.327616) (xy 125.201934 -276.321266)
			(xy 125.11659 -276.321266) (xy 125.099572 -276.327616) (xy 125.09246 -276.333712) (xy 125.071518 -276.351338)
			(xy 125.025547 -276.381052) (xy 124.975803 -276.40389) (xy 124.923304 -276.419384) (xy 124.86913 -276.427216)
			(xy 124.841762 -276.427692) (xy 124.814509 -276.427257) (xy 124.760559 -276.419495) (xy 124.708262 -276.404135)
			(xy 124.658684 -276.381488) (xy 124.612833 -276.352016) (xy 124.571642 -276.316319) (xy 124.535951 -276.275124)
			(xy 124.506486 -276.229269) (xy 124.483846 -276.179687) (xy 124.468493 -276.127388) (xy 124.460739 -276.073437)
			(xy 124.460254 -276.046184) (xy 121.924546 -276.046184) (xy 121.924387 -276.056524) (xy 121.915839 -276.113137)
			(xy 121.898921 -276.167835) (xy 121.874013 -276.219388) (xy 121.841674 -276.266636) (xy 121.802633 -276.308517)
			(xy 121.757768 -276.344087) (xy 121.708088 -276.372547) (xy 121.654709 -276.393257) (xy 121.626884 -276.400006)
			(xy 121.613422 -276.403054) (xy 121.593102 -276.422358) (xy 121.561098 -276.535134) (xy 121.568464 -276.562312)
			(xy 121.57837 -276.571964) (xy 121.596267 -276.58999) (xy 121.627628 -276.629949) (xy 121.653411 -276.673716)
			(xy 121.673158 -276.720517) (xy 121.686522 -276.769523) (xy 121.693266 -276.81987) (xy 121.693686 -276.845268)
			(xy 121.693215 -276.872521) (xy 121.685462 -276.926473) (xy 121.670109 -276.978772) (xy 121.647468 -277.028353)
			(xy 121.618001 -277.074208) (xy 121.582308 -277.115401) (xy 121.541116 -277.151095) (xy 121.495262 -277.180563)
			(xy 121.445681 -277.203205) (xy 121.393383 -277.21856) (xy 121.339431 -277.226314) (xy 121.312178 -277.226776)
			(xy 121.285925 -277.226374) (xy 121.233915 -277.219182) (xy 121.183382 -277.204925) (xy 121.135283 -277.18387)
			(xy 121.090527 -277.156417) (xy 121.049959 -277.123084) (xy 121.014347 -277.084501) (xy 120.998996 -277.0632)
			(xy 120.991122 -277.052024) (xy 120.967246 -277.040594) (xy 120.8532 -277.048468) (xy 120.831102 -277.0632)
			(xy 120.825006 -277.075392) (xy 120.812694 -277.098751) (xy 120.782606 -277.142141) (xy 120.746822 -277.180968)
			(xy 120.726708 -277.198074) (xy 120.718072 -277.205186) (xy 120.70842 -277.224744) (xy 120.70588 -277.324312)
			(xy 120.714516 -277.344124) (xy 120.722898 -277.351744) (xy 120.742185 -277.369935) (xy 120.776113 -277.410673)
			(xy 120.804075 -277.455716) (xy 120.825531 -277.504195) (xy 120.84007 -277.555179) (xy 120.847411 -277.607684)
			(xy 120.847866 -277.634192) (xy 120.84738 -277.661443) (xy 120.839624 -277.715391) (xy 120.834827 -277.731728)
			(xy 120.970292 -277.731728) (xy 120.974363 -277.676106) (xy 120.986489 -277.621669) (xy 121.006412 -277.569578)
			(xy 121.033708 -277.520943) (xy 121.067794 -277.4768) (xy 121.107943 -277.438091) (xy 121.153301 -277.40564)
			(xy 121.202901 -277.380139) (xy 121.255685 -277.362132) (xy 121.310528 -277.352002) (xy 121.366262 -277.349965)
			(xy 121.421699 -277.356065) (xy 121.475656 -277.370171) (xy 121.526985 -277.391983) (xy 121.574591 -277.421037)
			(xy 121.617459 -277.456712) (xy 121.654676 -277.498249) (xy 121.685449 -277.544762) (xy 121.709121 -277.595259)
			(xy 121.723891 -277.644352) (xy 127.083566 -277.644352) (xy 127.084018 -277.618036) (xy 127.09124 -277.565902)
			(xy 127.105554 -277.515255) (xy 127.126689 -277.467053) (xy 127.154244 -277.422211) (xy 127.187696 -277.381579)
			(xy 127.206756 -277.363428) (xy 127.214141 -277.355892) (xy 127.222676 -277.336623) (xy 127.223266 -277.32609)
			(xy 127.223266 -277.251414) (xy 127.222753 -277.240862) (xy 127.214208 -277.221566) (xy 127.206756 -277.214076)
			(xy 127.187676 -277.195942) (xy 127.154196 -277.155323) (xy 127.126624 -277.110482) (xy 127.105485 -277.062275)
			(xy 127.091181 -277.011616) (xy 127.083985 -276.959472) (xy 127.083566 -276.933152) (xy 127.084052 -276.905901)
			(xy 127.091808 -276.851953) (xy 127.107163 -276.799658) (xy 127.129805 -276.750081) (xy 127.159271 -276.704231)
			(xy 127.194962 -276.66304) (xy 127.236153 -276.627349) (xy 127.282003 -276.597883) (xy 127.33158 -276.575241)
			(xy 127.383875 -276.559886) (xy 127.437823 -276.55213) (xy 127.492325 -276.55213) (xy 127.546273 -276.559886)
			(xy 127.598568 -276.575241) (xy 127.648145 -276.597883) (xy 127.693995 -276.627349) (xy 127.735186 -276.66304)
			(xy 127.770877 -276.704231) (xy 127.800343 -276.750081) (xy 127.822985 -276.799658) (xy 127.83834 -276.851953)
			(xy 127.846096 -276.905901) (xy 127.846582 -276.933152) (xy 127.846149 -276.959469) (xy 127.838926 -277.011604)
			(xy 127.824609 -277.062253) (xy 127.803471 -277.110455) (xy 127.775912 -277.155296) (xy 127.742454 -277.195927)
			(xy 127.723392 -277.214076) (xy 127.715998 -277.221604) (xy 127.70747 -277.240879) (xy 127.706882 -277.251414)
			(xy 127.706882 -277.32609) (xy 127.707408 -277.33664) (xy 127.715946 -277.355935) (xy 127.723392 -277.363428)
			(xy 127.742483 -277.381551) (xy 127.775961 -277.422173) (xy 127.80353 -277.467016) (xy 127.824666 -277.515226)
			(xy 127.838968 -277.565886) (xy 127.846163 -277.618032) (xy 127.846582 -277.644352) (xy 127.846096 -277.671603)
			(xy 127.83834 -277.725551) (xy 127.822985 -277.777846) (xy 127.800343 -277.827423) (xy 127.770877 -277.873273)
			(xy 127.735186 -277.914464) (xy 127.693995 -277.950155) (xy 127.648145 -277.979621) (xy 127.598568 -278.002263)
			(xy 127.546273 -278.017618) (xy 127.492325 -278.025374) (xy 127.437823 -278.025374) (xy 127.383875 -278.017618)
			(xy 127.33158 -278.002263) (xy 127.282003 -277.979621) (xy 127.236153 -277.950155) (xy 127.194962 -277.914464)
			(xy 127.159271 -277.873273) (xy 127.129805 -277.827423) (xy 127.107163 -277.777846) (xy 127.091808 -277.725551)
			(xy 127.084052 -277.671603) (xy 127.083566 -277.644352) (xy 121.723891 -277.644352) (xy 121.725189 -277.648666)
			(xy 121.733309 -277.703842) (xy 121.733818 -277.731728) (xy 121.733309 -277.759614) (xy 121.725189 -277.81479)
			(xy 121.709121 -277.868197) (xy 121.685449 -277.918694) (xy 121.654676 -277.965207) (xy 121.617459 -278.006744)
			(xy 121.574591 -278.042419) (xy 121.526985 -278.071473) (xy 121.475656 -278.093285) (xy 121.421699 -278.107391)
			(xy 121.366262 -278.113491) (xy 121.310528 -278.111454) (xy 121.255685 -278.101324) (xy 121.202901 -278.083317)
			(xy 121.153301 -278.057816) (xy 121.107943 -278.025365) (xy 121.067794 -277.986656) (xy 121.033708 -277.942513)
			(xy 121.006412 -277.893878) (xy 120.986489 -277.841787) (xy 120.974363 -277.78735) (xy 120.970292 -277.731728)
			(xy 120.834827 -277.731728) (xy 120.824269 -277.767686) (xy 120.801627 -277.817263) (xy 120.772161 -277.863113)
			(xy 120.73647 -277.904304) (xy 120.695279 -277.939995) (xy 120.649429 -277.969461) (xy 120.599852 -277.992103)
			(xy 120.547557 -278.007458) (xy 120.493609 -278.015214) (xy 120.439107 -278.015214) (xy 120.385159 -278.007458)
			(xy 120.332864 -277.992103) (xy 120.283287 -277.969461) (xy 120.237437 -277.939995) (xy 120.196246 -277.904304)
			(xy 120.160555 -277.863113) (xy 120.131089 -277.817263) (xy 120.108447 -277.767686) (xy 120.093092 -277.715391)
			(xy 120.085336 -277.661443) (xy 120.08485 -277.634192) (xy 118.598188 -277.634192) (xy 118.598188 -278.218646)
			(xy 118.598669 -278.228613) (xy 118.60624 -278.247049) (xy 118.61292 -278.25446) (xy 119.848376 -279.489916)
			(xy 119.85579 -279.496592) (xy 119.874224 -279.504171) (xy 119.88419 -279.504648) (xy 121.817638 -279.504648)
			(xy 121.845618 -279.505201) (xy 121.900887 -279.513966) (xy 121.954103 -279.531274) (xy 122.003954 -279.556699)
			(xy 122.04921 -279.589614) (xy 122.069352 -279.609042) (xy 122.728482 -280.268172) (xy 122.73661 -280.271982)
			(xy 122.760817 -280.283888) (xy 122.80589 -280.313529) (xy 122.846339 -280.349222) (xy 122.88136 -280.390256)
			(xy 122.910253 -280.435812) (xy 122.932444 -280.484982) (xy 122.947489 -280.536787) (xy 122.95509 -280.590195)
			(xy 122.955558 -280.617168) (xy 122.9555 -280.627794) (xy 122.954357 -280.649015) (xy 122.953272 -280.659586)
			(xy 122.952002 -280.669238) (xy 122.956828 -280.687526) (xy 123.00839 -280.758392) (xy 123.024392 -280.768552)
			(xy 123.03379 -280.770584) (xy 123.049284 -280.77414) (xy 123.058936 -280.776426) (xy 123.077986 -280.773886)
			(xy 123.156726 -280.728674) (xy 123.168664 -280.713434) (xy 123.171458 -280.703782) (xy 123.179458 -280.677663)
			(xy 123.202009 -280.627907) (xy 123.23143 -280.58188) (xy 123.267119 -280.540521) (xy 123.308344 -280.50468)
			(xy 123.354262 -280.475088) (xy 123.403934 -280.452352) (xy 123.456341 -280.436937) (xy 123.510412 -280.429159)
			(xy 123.537726 -280.4287) (xy 123.562898 -280.42909) (xy 123.612805 -280.435711) (xy 123.661409 -280.448836)
			(xy 123.684792 -280.458164) (xy 123.694952 -280.462482) (xy 123.716288 -280.461974) (xy 123.804426 -280.420064)
			(xy 123.818396 -280.403808) (xy 123.821444 -280.39314) (xy 123.830211 -280.365229) (xy 123.855147 -280.312307)
			(xy 123.887872 -280.263813) (xy 123.927619 -280.220886) (xy 123.973456 -280.184532) (xy 124.024306 -280.155604)
			(xy 124.078977 -280.134781) (xy 124.136187 -280.12255) (xy 124.16536 -280.120344) (xy 124.177044 -280.119582)
			(xy 124.19711 -280.108406) (xy 124.256546 -280.02484) (xy 124.26061 -280.002234) (xy 124.257308 -279.991058)
			(xy 124.250544 -279.965556) (xy 124.243277 -279.913298) (xy 124.24283 -279.886918) (xy 124.243316 -279.859667)
			(xy 124.251072 -279.805719) (xy 124.266427 -279.753424) (xy 124.289069 -279.703847) (xy 124.318535 -279.657997)
			(xy 124.354226 -279.616806) (xy 124.395417 -279.581115) (xy 124.441267 -279.551649) (xy 124.490844 -279.529007)
			(xy 124.543139 -279.513652) (xy 124.597087 -279.505896) (xy 124.651589 -279.505896) (xy 124.705537 -279.513652)
			(xy 124.757832 -279.529007) (xy 124.807409 -279.551649) (xy 124.853259 -279.581115) (xy 124.89445 -279.616806)
			(xy 124.930141 -279.657997) (xy 124.959607 -279.703847) (xy 124.982249 -279.753424) (xy 124.997604 -279.805719)
			(xy 125.00536 -279.859667) (xy 125.005846 -279.886918) (xy 125.005365 -279.915793) (xy 124.996681 -279.972886)
			(xy 124.979485 -280.028015) (xy 124.954169 -280.07992) (xy 124.921313 -280.127412) (xy 124.88167 -280.169405)
			(xy 124.836145 -280.204937) (xy 124.785782 -280.233195) (xy 124.731732 -280.253533) (xy 124.675233 -280.265486)
			(xy 124.646436 -280.267664) (xy 124.634752 -280.268426) (xy 124.614686 -280.279602) (xy 124.55525 -280.363168)
			(xy 124.551186 -280.385774) (xy 124.554488 -280.39695) (xy 124.561253 -280.422452) (xy 124.56852 -280.47471)
			(xy 124.568966 -280.50109) (xy 124.568199 -280.535173) (xy 124.556067 -280.602251) (xy 124.544836 -280.63444)
			(xy 124.540772 -280.645616) (xy 124.543312 -280.669492) (xy 124.600716 -280.758138) (xy 124.62129 -280.77033)
			(xy 124.633228 -280.771092) (xy 124.661836 -280.773556) (xy 124.717902 -280.785935) (xy 124.771482 -280.806573)
			(xy 124.821365 -280.835005) (xy 124.866426 -280.870589) (xy 124.905648 -280.912521) (xy 124.938145 -280.959856)
			(xy 124.963185 -281.011525) (xy 124.980203 -281.066362) (xy 124.988813 -281.12313) (xy 124.989336 -281.151838)
			(xy 124.98885 -281.179089) (xy 124.981094 -281.233037) (xy 124.965739 -281.285332) (xy 124.943097 -281.334909)
			(xy 124.913631 -281.380759) (xy 124.87794 -281.42195) (xy 124.836749 -281.457641) (xy 124.790899 -281.487107)
			(xy 124.741322 -281.509749) (xy 124.689027 -281.525104) (xy 124.635079 -281.53286) (xy 124.580577 -281.53286)
			(xy 124.526629 -281.525104) (xy 124.474334 -281.509749) (xy 124.424757 -281.487107) (xy 124.378907 -281.457641)
			(xy 124.337716 -281.42195) (xy 124.302025 -281.380759) (xy 124.272559 -281.334909) (xy 124.249917 -281.285332)
			(xy 124.234562 -281.233037) (xy 124.226806 -281.179089) (xy 124.22632 -281.151838) (xy 124.22707 -281.117754)
			(xy 124.239214 -281.050676) (xy 124.25045 -281.018488) (xy 124.254514 -281.007312) (xy 124.251974 -280.983436)
			(xy 124.19457 -280.89479) (xy 124.173996 -280.882598) (xy 124.162058 -280.881836) (xy 124.13076 -280.879093)
			(xy 124.069615 -280.864671) (xy 124.040392 -280.853134) (xy 124.030232 -280.848816) (xy 124.008896 -280.849324)
			(xy 123.920758 -280.891234) (xy 123.906788 -280.90749) (xy 123.90374 -280.918158) (xy 123.895555 -280.944132)
			(xy 123.872875 -280.993643) (xy 123.843386 -281.039425) (xy 123.807686 -281.080549) (xy 123.766501 -281.116178)
			(xy 123.720668 -281.145589) (xy 123.671119 -281.168184) (xy 123.618861 -281.183504) (xy 123.564955 -281.191237)
			(xy 123.537726 -281.191716) (xy 123.51437 -281.19135) (xy 123.468011 -281.18562) (xy 123.44527 -281.180286)
			(xy 123.435618 -281.178) (xy 123.416568 -281.18054) (xy 123.337828 -281.225752) (xy 123.32589 -281.240992)
			(xy 123.323096 -281.250644) (xy 123.315064 -281.276752) (xy 123.292514 -281.326504) (xy 123.263095 -281.37253)
			(xy 123.22741 -281.413886) (xy 123.186189 -281.449728) (xy 123.140276 -281.479321) (xy 123.090609 -281.50206)
			(xy 123.038207 -281.517479) (xy 122.98414 -281.525263) (xy 122.956828 -281.525726) (xy 122.929577 -281.525219)
			(xy 122.875628 -281.517466) (xy 122.823332 -281.502114) (xy 122.773753 -281.479477) (xy 122.727901 -281.450013)
			(xy 122.686709 -281.414324) (xy 122.651015 -281.373136) (xy 122.621546 -281.327287) (xy 122.598902 -281.277711)
			(xy 122.583544 -281.225417) (xy 122.575785 -281.171469) (xy 122.57532 -281.144218) (xy 122.575377 -281.133592)
			(xy 122.57652 -281.112371) (xy 122.577606 -281.1018) (xy 122.578876 -281.092148) (xy 122.57405 -281.07386)
			(xy 122.522488 -281.002994) (xy 122.506486 -280.992834) (xy 122.497088 -280.990802) (xy 122.468291 -280.984345)
			(xy 122.413003 -280.963703) (xy 122.361558 -280.934787) (xy 122.315183 -280.898288) (xy 122.274986 -280.855079)
			(xy 122.241928 -280.806192) (xy 122.228864 -280.779728) (xy 122.225054 -280.7716) (xy 121.68505 -280.231596)
			(xy 121.677637 -280.22492) (xy 121.659201 -280.217344) (xy 121.649236 -280.216864) (xy 119.715788 -280.216864)
			(xy 119.687806 -280.216354) (xy 119.632535 -280.207578) (xy 119.579319 -280.190259) (xy 119.529469 -280.164825)
			(xy 119.484215 -280.131902) (xy 119.464074 -280.11247) (xy 117.990366 -278.638762) (xy 117.970985 -278.618579)
			(xy 117.938087 -278.573322) (xy 117.912665 -278.52348) (xy 117.895343 -278.470278) (xy 117.886546 -278.415023)
			(xy 117.885972 -278.387048) (xy 114.364035 -278.387048) (xy 114.379468 -278.408283) (xy 114.404886 -278.458128)
			(xy 114.422205 -278.511333) (xy 114.430999 -278.56659) (xy 114.431572 -278.594566) (xy 114.431572 -280.479754)
			(xy 114.434366 -280.488136) (xy 114.444903 -280.519348) (xy 114.456262 -280.584233) (xy 114.456972 -280.617168)
			(xy 114.456914 -280.627794) (xy 114.455771 -280.649015) (xy 114.454686 -280.659586) (xy 114.453416 -280.669238)
			(xy 114.458242 -280.687526) (xy 114.509804 -280.758392) (xy 114.525806 -280.768552) (xy 114.535204 -280.770584)
			(xy 114.550698 -280.77414) (xy 114.56035 -280.776426) (xy 114.5794 -280.773886) (xy 114.65814 -280.728674)
			(xy 114.670078 -280.713434) (xy 114.672872 -280.703782) (xy 114.680948 -280.677689) (xy 114.703493 -280.627938)
			(xy 114.732906 -280.581913) (xy 114.768585 -280.540556) (xy 114.8098 -280.504713) (xy 114.855708 -280.475118)
			(xy 114.905369 -280.452376) (xy 114.957767 -280.436953) (xy 115.01183 -280.429165) (xy 115.03914 -280.4287)
			(xy 115.064312 -280.429085) (xy 115.114219 -280.435709) (xy 115.162823 -280.448835) (xy 115.186206 -280.458164)
			(xy 115.196366 -280.462482) (xy 115.217702 -280.461974) (xy 115.30584 -280.420064) (xy 115.31981 -280.403808)
			(xy 115.322858 -280.39314) (xy 115.331613 -280.365225) (xy 115.356551 -280.312302) (xy 115.389277 -280.263808)
			(xy 115.429026 -280.220881) (xy 115.474864 -280.184527) (xy 115.525716 -280.1556) (xy 115.580389 -280.134778)
			(xy 115.6376 -280.122549) (xy 115.666774 -280.120344) (xy 115.678458 -280.119582) (xy 115.698524 -280.108406)
			(xy 115.75796 -280.02484) (xy 115.762024 -280.002234) (xy 115.758722 -279.991058) (xy 115.751959 -279.965556)
			(xy 115.744691 -279.913298) (xy 115.744244 -279.886918) (xy 115.74473 -279.859667) (xy 115.752486 -279.805719)
			(xy 115.767841 -279.753424) (xy 115.790483 -279.703847) (xy 115.819949 -279.657997) (xy 115.85564 -279.616806)
			(xy 115.896831 -279.581115) (xy 115.942681 -279.551649) (xy 115.992258 -279.529007) (xy 116.044553 -279.513652)
			(xy 116.098501 -279.505896) (xy 116.153003 -279.505896) (xy 116.206951 -279.513652) (xy 116.259246 -279.529007)
			(xy 116.308823 -279.551649) (xy 116.354673 -279.581115) (xy 116.395864 -279.616806) (xy 116.431555 -279.657997)
			(xy 116.461021 -279.703847) (xy 116.483663 -279.753424) (xy 116.499018 -279.805719) (xy 116.506774 -279.859667)
			(xy 116.50726 -279.886918) (xy 116.506766 -279.915792) (xy 116.498083 -279.972884) (xy 116.480887 -280.028012)
			(xy 116.455572 -280.079916) (xy 116.422718 -280.127408) (xy 116.383076 -280.1694) (xy 116.337553 -280.204933)
			(xy 116.287192 -280.233192) (xy 116.233144 -280.253531) (xy 116.176647 -280.265485) (xy 116.14785 -280.267664)
			(xy 116.136166 -280.268426) (xy 116.1161 -280.279602) (xy 116.056664 -280.363168) (xy 116.0526 -280.385774)
			(xy 116.055902 -280.39695) (xy 116.062667 -280.422452) (xy 116.069934 -280.47471) (xy 116.07038 -280.50109)
			(xy 116.069612 -280.535173) (xy 116.05748 -280.602251) (xy 116.04625 -280.63444) (xy 116.042186 -280.645616)
			(xy 116.044726 -280.669492) (xy 116.10213 -280.758138) (xy 116.122704 -280.77033) (xy 116.134642 -280.771092)
			(xy 116.163251 -280.773544) (xy 116.219318 -280.785925) (xy 116.272897 -280.806565) (xy 116.32278 -280.834999)
			(xy 116.367841 -280.870584) (xy 116.407062 -280.912517) (xy 116.43956 -280.959853) (xy 116.4646 -281.011523)
			(xy 116.481617 -281.066361) (xy 116.490227 -281.123129) (xy 116.49075 -281.151838) (xy 116.490264 -281.179089)
			(xy 116.482508 -281.233037) (xy 116.467153 -281.285332) (xy 116.444511 -281.334909) (xy 116.415045 -281.380759)
			(xy 116.379354 -281.42195) (xy 116.338163 -281.457641) (xy 116.292313 -281.487107) (xy 116.242736 -281.509749)
			(xy 116.190441 -281.525104) (xy 116.136493 -281.53286) (xy 116.081991 -281.53286) (xy 116.028043 -281.525104)
			(xy 115.975748 -281.509749) (xy 115.926171 -281.487107) (xy 115.880321 -281.457641) (xy 115.83913 -281.42195)
			(xy 115.803439 -281.380759) (xy 115.773973 -281.334909) (xy 115.751331 -281.285332) (xy 115.735976 -281.233037)
			(xy 115.72822 -281.179089) (xy 115.727734 -281.151838) (xy 115.728483 -281.117754) (xy 115.740627 -281.050676)
			(xy 115.751864 -281.018488) (xy 115.755928 -281.007312) (xy 115.753388 -280.983436) (xy 115.695984 -280.89479)
			(xy 115.67541 -280.882598) (xy 115.663472 -280.881836) (xy 115.632174 -280.879089) (xy 115.571029 -280.86467)
			(xy 115.541806 -280.853134) (xy 115.531646 -280.848816) (xy 115.51031 -280.849324) (xy 115.422172 -280.891234)
			(xy 115.408202 -280.90749) (xy 115.405154 -280.918158) (xy 115.396957 -280.944128) (xy 115.374278 -280.993638)
			(xy 115.34479 -281.039419) (xy 115.309091 -281.080543) (xy 115.267908 -281.116173) (xy 115.222077 -281.145584)
			(xy 115.17253 -281.16818) (xy 115.120273 -281.183501) (xy 115.066368 -281.191236) (xy 115.03914 -281.191716)
			(xy 115.015784 -281.191347) (xy 114.969426 -281.185619) (xy 114.946684 -281.180286) (xy 114.937032 -281.178)
			(xy 114.917982 -281.18054) (xy 114.839242 -281.225752) (xy 114.827304 -281.240992) (xy 114.82451 -281.250644)
			(xy 114.816466 -281.276748) (xy 114.793917 -281.326499) (xy 114.764499 -281.372524) (xy 114.728816 -281.413881)
			(xy 114.687596 -281.449723) (xy 114.641685 -281.479316) (xy 114.59202 -281.502056) (xy 114.539619 -281.517476)
			(xy 114.485554 -281.525262) (xy 114.458242 -281.525726) (xy 114.430991 -281.525206) (xy 114.377043 -281.517455)
			(xy 114.324747 -281.502105) (xy 114.275169 -281.479469) (xy 114.229316 -281.450007) (xy 114.188123 -281.414319)
			(xy 114.152429 -281.373132) (xy 114.12296 -281.327284) (xy 114.100316 -281.277709) (xy 114.084958 -281.225416)
			(xy 114.077199 -281.171469) (xy 114.076734 -281.144218) (xy 114.076791 -281.133592) (xy 114.077934 -281.112371)
			(xy 114.07902 -281.1018) (xy 114.08029 -281.092148) (xy 114.075464 -281.07386) (xy 114.023902 -281.002994)
			(xy 114.0079 -280.992834) (xy 113.998502 -280.990802) (xy 113.970202 -280.984435) (xy 113.915815 -280.964275)
			(xy 113.865106 -280.936112) (xy 113.819246 -280.900596) (xy 113.779292 -280.858547) (xy 113.746165 -280.810933)
			(xy 113.720629 -280.758853) (xy 113.703272 -280.703506) (xy 113.694495 -280.64617) (xy 113.693956 -280.617168)
			(xy 113.694681 -280.584235) (xy 113.706052 -280.519356) (xy 113.716562 -280.488136) (xy 113.719356 -280.479754)
			(xy 113.719356 -278.762968) (xy 113.718908 -278.752998) (xy 113.711313 -278.734562) (xy 113.704624 -278.727154)
			(xy 112.73917 -277.7617) (xy 112.71976 -277.741544) (xy 112.686866 -277.69628) (xy 112.661449 -277.646431)
			(xy 112.644134 -277.593223) (xy 112.635345 -277.537963) (xy 112.634776 -277.509986) (xy 111.163271 -277.509986)
			(xy 111.165568 -277.515226) (xy 111.17987 -277.565886) (xy 111.187065 -277.618032) (xy 111.187484 -277.644352)
			(xy 111.187 -277.671605) (xy 111.179249 -277.725556) (xy 111.163898 -277.777855) (xy 111.141259 -277.827437)
			(xy 111.111794 -277.873291) (xy 111.076102 -277.914485) (xy 111.03491 -277.950179) (xy 110.989058 -277.979648)
			(xy 110.939478 -278.002289) (xy 110.88718 -278.017644) (xy 110.833229 -278.025398) (xy 110.805976 -278.02586)
			(xy 110.779505 -278.025464) (xy 110.72707 -278.018167) (xy 110.676147 -278.003687) (xy 110.627717 -277.982304)
			(xy 110.582709 -277.954428) (xy 110.541989 -277.920596) (xy 110.506339 -277.881457) (xy 110.476445 -277.837763)
			(xy 110.452882 -277.790355) (xy 110.436101 -277.740144) (xy 110.430818 -277.714202) (xy 110.428532 -277.701756)
			(xy 110.413292 -277.682198) (xy 110.31347 -277.638002) (xy 110.288832 -277.639526) (xy 110.27791 -277.646384)
			(xy 110.255255 -277.659759) (xy 110.207064 -277.680861) (xy 110.156431 -277.695147) (xy 110.104317 -277.702345)
			(xy 110.078012 -277.702772) (xy 110.050758 -277.702333) (xy 109.996804 -277.694577) (xy 109.944504 -277.679221)
			(xy 109.894921 -277.656577) (xy 109.849066 -277.627107) (xy 109.807872 -277.591411) (xy 109.772179 -277.550215)
			(xy 109.742711 -277.504358) (xy 109.720071 -277.454774) (xy 109.704718 -277.402472) (xy 109.696965 -277.348518)
			(xy 109.696504 -277.321264) (xy 109.696948 -277.293893) (xy 109.704771 -277.239713) (xy 109.720265 -277.187209)
			(xy 109.743112 -277.137463) (xy 109.772841 -277.091497) (xy 109.790484 -277.070566) (xy 109.79658 -277.063454)
			(xy 109.80293 -277.046436) (xy 109.80293 -276.961092) (xy 109.79658 -276.944074) (xy 109.790484 -276.936962)
			(xy 109.772858 -276.916019) (xy 109.743145 -276.870049) (xy 109.720307 -276.820304) (xy 109.704812 -276.767806)
			(xy 109.69698 -276.713632) (xy 109.696504 -276.686264) (xy 109.697083 -276.656788) (xy 109.706142 -276.598536)
			(xy 109.724056 -276.542372) (xy 109.750396 -276.489632) (xy 109.784537 -276.441572) (xy 109.804708 -276.420072)
			(xy 109.811249 -276.412742) (xy 109.81869 -276.394578) (xy 109.819186 -276.384766) (xy 109.819186 -276.331426)
			(xy 109.81182 -276.324568) (xy 109.804477 -276.318045) (xy 109.786323 -276.310594) (xy 109.776514 -276.31009)
			(xy 109.74451 -276.31009) (xy 109.734698 -276.310593) (xy 109.716533 -276.318027) (xy 109.709204 -276.324568)
			(xy 109.687705 -276.344742) (xy 109.639645 -276.378886) (xy 109.586906 -276.405232) (xy 109.530741 -276.423153)
			(xy 109.472489 -276.432223) (xy 109.443012 -276.432772) (xy 109.415758 -276.432333) (xy 109.361804 -276.424577)
			(xy 109.309504 -276.409221) (xy 109.259921 -276.386577) (xy 109.214066 -276.357107) (xy 109.172872 -276.321411)
			(xy 109.137179 -276.280215) (xy 109.107711 -276.234358) (xy 109.085071 -276.184774) (xy 109.069718 -276.132472)
			(xy 109.061965 -276.078518) (xy 109.061504 -276.051264) (xy 107.367832 -276.051264) (xy 107.367832 -277.278846)
			(xy 107.367292 -277.306813) (xy 107.358556 -277.362061) (xy 107.341291 -277.415264) (xy 107.31592 -277.465114)
			(xy 107.283067 -277.510384) (xy 107.263692 -277.53056) (xy 105.73004 -279.064212) (xy 105.723386 -279.071643)
			(xy 105.715796 -279.090065) (xy 105.715308 -279.100026) (xy 105.715308 -279.893014) (xy 105.715749 -279.902985)
			(xy 105.723347 -279.921422) (xy 105.73004 -279.928828) (xy 106.069384 -280.268172) (xy 106.077512 -280.271982)
			(xy 106.10172 -280.283887) (xy 106.146792 -280.313529) (xy 106.187242 -280.349222) (xy 106.222262 -280.390255)
			(xy 106.251155 -280.435811) (xy 106.273346 -280.484982) (xy 106.288391 -280.536787) (xy 106.295992 -280.590195)
			(xy 106.29646 -280.617168) (xy 106.296402 -280.627794) (xy 106.295259 -280.649015) (xy 106.294174 -280.659586)
			(xy 106.292904 -280.669238) (xy 106.29773 -280.687526) (xy 106.349292 -280.758392) (xy 106.365294 -280.768552)
			(xy 106.374692 -280.770584) (xy 106.390186 -280.77414) (xy 106.399838 -280.776426) (xy 106.418888 -280.773886)
			(xy 106.497628 -280.728674) (xy 106.509566 -280.713434) (xy 106.51236 -280.703782) (xy 106.520447 -280.677692)
			(xy 106.542991 -280.627942) (xy 106.572402 -280.581917) (xy 106.60808 -280.54056) (xy 106.649294 -280.504717)
			(xy 106.6952 -280.475122) (xy 106.74486 -280.452379) (xy 106.797257 -280.436956) (xy 106.851318 -280.429166)
			(xy 106.878628 -280.4287) (xy 106.9038 -280.429089) (xy 106.953707 -280.435711) (xy 107.002311 -280.448836)
			(xy 107.025694 -280.458164) (xy 107.035854 -280.462482) (xy 107.05719 -280.461974) (xy 107.145328 -280.420064)
			(xy 107.159298 -280.403808) (xy 107.162346 -280.39314) (xy 107.171111 -280.365228) (xy 107.196048 -280.312306)
			(xy 107.228773 -280.263812) (xy 107.26852 -280.220885) (xy 107.314357 -280.184531) (xy 107.365207 -280.155603)
			(xy 107.419879 -280.13478) (xy 107.477089 -280.12255) (xy 107.506262 -280.120344) (xy 107.517946 -280.119582)
			(xy 107.538012 -280.108406) (xy 107.597448 -280.02484) (xy 107.601512 -280.002234) (xy 107.59821 -279.991058)
			(xy 107.591446 -279.965556) (xy 107.584179 -279.913298) (xy 107.583732 -279.886918) (xy 107.584218 -279.859667)
			(xy 107.591974 -279.805719) (xy 107.607329 -279.753424) (xy 107.629971 -279.703847) (xy 107.659437 -279.657997)
			(xy 107.695128 -279.616806) (xy 107.736319 -279.581115) (xy 107.782169 -279.551649) (xy 107.831746 -279.529007)
			(xy 107.884041 -279.513652) (xy 107.937989 -279.505896) (xy 107.992491 -279.505896) (xy 108.046439 -279.513652)
			(xy 108.098734 -279.529007) (xy 108.148311 -279.551649) (xy 108.194161 -279.581115) (xy 108.235352 -279.616806)
			(xy 108.271043 -279.657997) (xy 108.300509 -279.703847) (xy 108.323151 -279.753424) (xy 108.338506 -279.805719)
			(xy 108.346262 -279.859667) (xy 108.346748 -279.886918) (xy 108.346265 -279.915793) (xy 108.337582 -279.972885)
			(xy 108.320385 -280.028015) (xy 108.295069 -280.07992) (xy 108.262214 -280.127412) (xy 108.222571 -280.169404)
			(xy 108.177046 -280.204936) (xy 108.126683 -280.233195) (xy 108.072634 -280.253533) (xy 108.016135 -280.265486)
			(xy 107.987338 -280.267664) (xy 107.975654 -280.268426) (xy 107.955588 -280.279602) (xy 107.896152 -280.363168)
			(xy 107.892088 -280.385774) (xy 107.89539 -280.39695) (xy 107.902155 -280.422452) (xy 107.909422 -280.47471)
			(xy 107.909868 -280.50109) (xy 107.9091 -280.535173) (xy 107.896969 -280.602251) (xy 107.885738 -280.63444)
			(xy 107.881674 -280.645616) (xy 107.884214 -280.669492) (xy 107.941618 -280.758138) (xy 107.962192 -280.77033)
			(xy 107.97413 -280.771092) (xy 108.002738 -280.773554) (xy 108.058804 -280.785934) (xy 108.112384 -280.806572)
			(xy 108.162267 -280.835004) (xy 108.207328 -280.870588) (xy 108.24655 -280.912521) (xy 108.279047 -280.959856)
			(xy 108.304087 -281.011525) (xy 108.321105 -281.066362) (xy 108.329715 -281.12313) (xy 108.330238 -281.151838)
			(xy 108.329752 -281.179089) (xy 108.321996 -281.233037) (xy 108.306641 -281.285332) (xy 108.283999 -281.334909)
			(xy 108.254533 -281.380759) (xy 108.218842 -281.42195) (xy 108.177651 -281.457641) (xy 108.131801 -281.487107)
			(xy 108.082224 -281.509749) (xy 108.029929 -281.525104) (xy 107.975981 -281.53286) (xy 107.921479 -281.53286)
			(xy 107.867531 -281.525104) (xy 107.815236 -281.509749) (xy 107.765659 -281.487107) (xy 107.719809 -281.457641)
			(xy 107.678618 -281.42195) (xy 107.642927 -281.380759) (xy 107.613461 -281.334909) (xy 107.590819 -281.285332)
			(xy 107.575464 -281.233037) (xy 107.567708 -281.179089) (xy 107.567222 -281.151838) (xy 107.567971 -281.117754)
			(xy 107.580116 -281.050676) (xy 107.591352 -281.018488) (xy 107.595416 -281.007312) (xy 107.592876 -280.983436)
			(xy 107.535472 -280.89479) (xy 107.514898 -280.882598) (xy 107.50296 -280.881836) (xy 107.471662 -280.879092)
			(xy 107.410517 -280.864671) (xy 107.381294 -280.853134) (xy 107.371134 -280.848816) (xy 107.349798 -280.849324)
			(xy 107.26166 -280.891234) (xy 107.24769 -280.90749) (xy 107.244642 -280.918158) (xy 107.236455 -280.944132)
			(xy 107.213776 -280.993642) (xy 107.184286 -281.039424) (xy 107.148587 -281.080548) (xy 107.107402 -281.116177)
			(xy 107.06157 -281.145588) (xy 107.012021 -281.168184) (xy 106.959763 -281.183504) (xy 106.905857 -281.191237)
			(xy 106.878628 -281.191716) (xy 106.855272 -281.19135) (xy 106.808913 -281.185619) (xy 106.786172 -281.180286)
			(xy 106.77652 -281.178) (xy 106.75747 -281.18054) (xy 106.67873 -281.225752) (xy 106.666792 -281.240992)
			(xy 106.663998 -281.250644) (xy 106.655965 -281.276752) (xy 106.633414 -281.326504) (xy 106.603996 -281.372529)
			(xy 106.568311 -281.413886) (xy 106.52709 -281.449727) (xy 106.481177 -281.47932) (xy 106.431511 -281.502059)
			(xy 106.379109 -281.517479) (xy 106.325042 -281.525263) (xy 106.29773 -281.525726) (xy 106.270479 -281.525217)
			(xy 106.21653 -281.517464) (xy 106.164234 -281.502113) (xy 106.114656 -281.479475) (xy 106.068803 -281.450012)
			(xy 106.027611 -281.414323) (xy 105.991917 -281.373135) (xy 105.962448 -281.327287) (xy 105.939804 -281.277711)
			(xy 105.924446 -281.225417) (xy 105.916687 -281.171469) (xy 105.916222 -281.144218) (xy 105.916279 -281.133592)
			(xy 105.917422 -281.112371) (xy 105.918508 -281.1018) (xy 105.919778 -281.092148) (xy 105.914952 -281.07386)
			(xy 105.86339 -281.002994) (xy 105.847388 -280.992834) (xy 105.83799 -280.990802) (xy 105.809193 -280.984344)
			(xy 105.753906 -280.963702) (xy 105.70246 -280.934786) (xy 105.656085 -280.898288) (xy 105.615888 -280.855079)
			(xy 105.58283 -280.806192) (xy 105.569766 -280.779728) (xy 105.565956 -280.7716) (xy 105.107486 -280.31313)
			(xy 105.088093 -280.292958) (xy 105.055196 -280.247698) (xy 105.029776 -280.197854) (xy 105.012456 -280.144649)
			(xy 105.003664 -280.089392) (xy 105.003092 -280.061416) (xy 99.78771 -280.061416) (xy 99.78771 -283.166312)
			(xy 99.7882 -283.176317) (xy 99.795862 -283.194803) (xy 99.810015 -283.20895) (xy 99.828504 -283.216604)
			(xy 99.83851 -283.217112) (xy 101.849936 -283.217112) (xy 101.858527 -283.216823) (xy 101.874768 -283.211226)
			(xy 101.888244 -283.200572) (xy 101.893116 -283.19349) (xy 101.945694 -283.109162) (xy 101.947218 -283.083)
			(xy 101.941376 -283.071316) (xy 101.929272 -283.04518) (xy 101.912182 -282.990179) (xy 101.903536 -282.933236)
			(xy 101.903022 -282.904438) (xy 101.903506 -282.876863) (xy 101.911444 -282.822288) (xy 101.92716 -282.769425)
			(xy 101.950327 -282.719377) (xy 101.98046 -282.673188) (xy 102.016932 -282.631821) (xy 102.037642 -282.613608)
			(xy 102.045768 -282.606015) (xy 102.055101 -282.585855) (xy 102.055676 -282.574746) (xy 102.055676 -282.49753)
			(xy 102.055108 -282.486425) (xy 102.045748 -282.466281) (xy 102.037642 -282.458668) (xy 102.016932 -282.440453)
			(xy 101.980459 -282.399083) (xy 101.950324 -282.352891) (xy 101.927154 -282.302842) (xy 101.911433 -282.249978)
			(xy 101.903487 -282.195401) (xy 101.903484 -282.140248) (xy 101.911422 -282.08567) (xy 101.927137 -282.032804)
			(xy 101.9503 -281.982752) (xy 101.980429 -281.936557) (xy 102.016897 -281.895181) (xy 102.037642 -281.877008)
			(xy 102.045768 -281.869415) (xy 102.055101 -281.849255) (xy 102.055676 -281.838146) (xy 102.055676 -281.76093)
			(xy 102.055108 -281.749825) (xy 102.045748 -281.729681) (xy 102.037642 -281.722068) (xy 102.016937 -281.703852)
			(xy 101.980475 -281.662479) (xy 101.950348 -281.616289) (xy 101.927185 -281.566243) (xy 101.911467 -281.513383)
			(xy 101.903523 -281.458811) (xy 101.903022 -281.431238) (xy 101.903483 -281.403984) (xy 101.911236 -281.350031)
			(xy 101.926589 -281.29773) (xy 101.949229 -281.248147) (xy 101.978697 -281.202291) (xy 102.014391 -281.161097)
			(xy 102.055585 -281.125402) (xy 102.10144 -281.095933) (xy 102.151023 -281.073291) (xy 102.203323 -281.057937)
			(xy 102.257276 -281.050183) (xy 102.28453 -281.04973) (xy 102.312391 -281.050232) (xy 102.367521 -281.058326)
			(xy 102.420887 -281.074353) (xy 102.471355 -281.097971) (xy 102.517851 -281.128679) (xy 102.559386 -281.165823)
			(xy 102.595077 -281.208613) (xy 102.624165 -281.256139) (xy 102.646031 -281.307391) (xy 102.653592 -281.33421)
			(xy 102.655878 -281.3431) (xy 102.666546 -281.35834) (xy 102.738428 -281.406092) (xy 102.756462 -281.410156)
			(xy 102.765606 -281.408886) (xy 102.778621 -281.407202) (xy 102.804807 -281.405421) (xy 102.81793 -281.40533)
			(xy 102.831053 -281.405436) (xy 102.857238 -281.407214) (xy 102.870254 -281.408886) (xy 102.879398 -281.410156)
			(xy 102.897432 -281.406092) (xy 102.969314 -281.35834) (xy 102.979982 -281.3431) (xy 102.982268 -281.33421)
			(xy 102.989861 -281.307404) (xy 103.011747 -281.256172) (xy 103.040845 -281.208664) (xy 103.076538 -281.165888)
			(xy 103.118068 -281.128753) (xy 103.164553 -281.098046) (xy 103.215007 -281.074421) (xy 103.268358 -281.058378)
			(xy 103.323475 -281.050258) (xy 103.35133 -281.04973) (xy 103.37858 -281.050195) (xy 103.432526 -281.057956)
			(xy 103.484818 -281.073315) (xy 103.534392 -281.09596) (xy 103.580239 -281.125429) (xy 103.621425 -281.161123)
			(xy 103.657112 -281.202316) (xy 103.686573 -281.248168) (xy 103.709209 -281.297746) (xy 103.724558 -281.35004)
			(xy 103.732309 -281.403987) (xy 103.732838 -281.431238) (xy 103.73237 -281.458536) (xy 103.724584 -281.512575)
			(xy 103.709177 -281.564953) (xy 103.686463 -281.614601) (xy 103.656907 -281.660505) (xy 103.639366 -281.681428)
			(xy 103.633016 -281.688794) (xy 103.626666 -281.706574) (xy 103.630222 -281.795982) (xy 103.637842 -281.813254)
			(xy 103.6447 -281.820112) (xy 103.665809 -281.84176) (xy 103.701602 -281.890489) (xy 103.729263 -281.944252)
			(xy 103.748101 -282.001704) (xy 103.757644 -282.061407) (xy 103.758238 -282.091638) (xy 103.757751 -282.119278)
			(xy 103.749776 -282.173979) (xy 103.733984 -282.226955) (xy 103.710707 -282.277094) (xy 103.680433 -282.323347)
			(xy 103.66248 -282.344368) (xy 103.654098 -282.35402) (xy 103.648256 -282.378404) (xy 103.675434 -282.484576)
			(xy 103.692452 -282.503118) (xy 103.70439 -282.507436) (xy 103.731798 -282.517774) (xy 103.783315 -282.545651)
			(xy 103.829962 -282.58108) (xy 103.870639 -282.623228) (xy 103.904391 -282.671103) (xy 103.930421 -282.723577)
			(xy 103.948118 -282.779415) (xy 103.957065 -282.837304) (xy 103.957628 -282.866592) (xy 103.957459 -282.881194)
			(xy 103.955171 -282.910309) (xy 103.953056 -282.924758) (xy 103.951532 -282.935934) (xy 103.957628 -282.95727)
			(xy 104.015032 -283.024326) (xy 104.022638 -283.032275) (xy 104.042649 -283.041364) (xy 104.05364 -283.041852)
			(xy 104.1908 -283.041852) (xy 104.201795 -283.041377) (xy 104.221816 -283.032293) (xy 104.229408 -283.024326)
			(xy 104.286812 -282.95727) (xy 104.292908 -282.935934) (xy 104.291384 -282.924758) (xy 104.289261 -282.91031)
			(xy 104.28697 -282.881194) (xy 104.286812 -282.866592) (xy 104.287276 -282.83934) (xy 104.295034 -282.785391)
			(xy 104.310391 -282.733095) (xy 104.333034 -282.683517) (xy 104.362503 -282.637667) (xy 104.398197 -282.596477)
			(xy 104.439389 -282.560786) (xy 104.485242 -282.531321) (xy 104.534822 -282.508681) (xy 104.587118 -282.493328)
			(xy 104.641068 -282.485574) (xy 104.66832 -282.485084) (xy 104.69569 -282.485557) (xy 104.749867 -282.493383)
			(xy 104.802369 -282.508872) (xy 104.852119 -282.531705) (xy 104.898095 -282.561414) (xy 104.919018 -282.579064)
			(xy 104.92613 -282.58516) (xy 104.943148 -282.59151) (xy 105.028492 -282.59151) (xy 105.04551 -282.58516)
			(xy 105.052622 -282.579064) (xy 105.073552 -282.561421) (xy 105.119518 -282.531692) (xy 105.169265 -282.508848)
			(xy 105.221769 -282.493358) (xy 105.275949 -282.485541) (xy 105.30332 -282.485084) (xy 105.330571 -282.485571)
			(xy 105.384517 -282.49333) (xy 105.436809 -282.508687) (xy 105.486385 -282.531329) (xy 105.532233 -282.560796)
			(xy 105.573422 -282.596487) (xy 105.609112 -282.637677) (xy 105.638577 -282.683526) (xy 105.661218 -282.733102)
			(xy 105.676573 -282.785395) (xy 105.68433 -282.839341) (xy 105.684828 -282.866592) (xy 105.684331 -282.894687)
			(xy 105.676097 -282.95027) (xy 105.659806 -283.004046) (xy 105.648252 -283.02966) (xy 105.642664 -283.041598)
			(xy 105.644188 -283.067252) (xy 105.697274 -283.151072) (xy 105.702158 -283.158064) (xy 105.715567 -283.168588)
			(xy 105.731677 -283.174156) (xy 105.7402 -283.17444) (xy 107.771438 -283.17444) (xy 107.803069 -283.174959)
			(xy 107.865789 -283.183219) (xy 107.926895 -283.199592) (xy 107.985342 -283.223798) (xy 108.040131 -283.255425)
			(xy 108.090324 -283.293929) (xy 108.113068 -283.315918) (xy 108.42371 -283.626814) (xy 108.431151 -283.633512)
			(xy 108.44965 -283.641115) (xy 108.46965 -283.641095) (xy 108.479082 -283.637736) (xy 108.49356 -283.631894)
			(xy 108.510324 -283.606494) (xy 108.510324 -282.941776) (xy 108.510876 -282.911793) (xy 108.520248 -282.852565)
			(xy 108.538774 -282.795533) (xy 108.565997 -282.742103) (xy 108.601246 -282.693592) (xy 108.622084 -282.672028)
			(xy 108.777786 -282.51658) (xy 108.784824 -282.508906) (xy 108.792547 -282.489592) (xy 108.791921 -282.4688)
			(xy 108.787946 -282.459176) (xy 108.740702 -282.35783) (xy 108.71327 -282.342082) (xy 108.697014 -282.343352)
			(xy 108.66374 -282.344876) (xy 108.636488 -282.344415) (xy 108.582537 -282.336664) (xy 108.530239 -282.321312)
			(xy 108.480658 -282.298674) (xy 108.434803 -282.26921) (xy 108.393609 -282.233519) (xy 108.357914 -282.192329)
			(xy 108.328445 -282.146478) (xy 108.305802 -282.096899) (xy 108.290445 -282.044602) (xy 108.282687 -281.990652)
			(xy 108.282687 -281.936148) (xy 108.290445 -281.882198) (xy 108.305802 -281.829901) (xy 108.328445 -281.780322)
			(xy 108.357914 -281.734471) (xy 108.393609 -281.693281) (xy 108.434803 -281.65759) (xy 108.480658 -281.628126)
			(xy 108.530239 -281.605488) (xy 108.582537 -281.590136) (xy 108.636488 -281.582385) (xy 108.66374 -281.58186)
			(xy 108.690637 -281.582324) (xy 108.743897 -281.589888) (xy 108.795566 -281.60486) (xy 108.844619 -281.626942)
			(xy 108.890083 -281.655698) (xy 108.931056 -281.690556) (xy 108.949236 -281.710384) (xy 108.956348 -281.718512)
			(xy 108.976414 -281.727402) (xy 108.987336 -281.727402) (xy 108.997339 -281.726908) (xy 109.015819 -281.719242)
			(xy 109.029961 -281.70509) (xy 109.037614 -281.686605) (xy 109.038136 -281.676602) (xy 109.038136 -281.627072)
			(xy 109.037706 -281.617005) (xy 109.029977 -281.598414) (xy 109.02315 -281.591004) (xy 108.86821 -281.436318)
			(xy 108.847419 -281.414723) (xy 108.812208 -281.36621) (xy 108.785029 -281.312782) (xy 108.766551 -281.255757)
			(xy 108.757231 -281.196543) (xy 108.756704 -281.16657) (xy 108.757192 -281.139337) (xy 108.764946 -281.085426)
			(xy 108.780293 -281.033168) (xy 108.80292 -280.983625) (xy 108.832367 -280.937806) (xy 108.868034 -280.896643)
			(xy 108.909196 -280.860974) (xy 108.955014 -280.831526) (xy 109.004556 -280.808897) (xy 109.056815 -280.793549)
			(xy 109.110725 -280.785793) (xy 109.137958 -280.785316) (xy 109.167927 -280.785884) (xy 109.227134 -280.795218)
			(xy 109.284153 -280.813693) (xy 109.337582 -280.840857) (xy 109.386106 -280.87604) (xy 109.407706 -280.896822)
			(xy 109.689138 -281.178254) (xy 109.709933 -281.199848) (xy 109.745152 -281.248358) (xy 109.772339 -281.301785)
			(xy 109.790824 -281.358811) (xy 109.80015 -281.418028) (xy 109.800644 -281.448002) (xy 109.800644 -282.414218)
			(xy 109.800071 -282.444185) (xy 109.790729 -282.503386) (xy 109.772245 -282.560398) (xy 109.745074 -282.613818)
			(xy 109.709884 -282.662334) (xy 109.689138 -282.683966) (xy 109.48924 -282.883864) (xy 109.482242 -282.891456)
			(xy 109.474491 -282.910573) (xy 109.474939 -282.931196) (xy 109.478826 -282.94076) (xy 109.5248 -283.041852)
			(xy 109.552232 -283.058108) (xy 109.56798 -283.057092) (xy 109.594904 -283.056076) (xy 109.622155 -283.056562)
			(xy 109.676104 -283.064319) (xy 109.728399 -283.079674) (xy 109.777977 -283.102315) (xy 109.823828 -283.131782)
			(xy 109.865019 -283.167473) (xy 109.900711 -283.208663) (xy 109.930179 -283.254513) (xy 109.952822 -283.30409)
			(xy 109.968179 -283.356385) (xy 109.975937 -283.410333) (xy 109.976412 -283.437584) (xy 109.975865 -283.467061)
			(xy 109.966798 -283.525315) (xy 109.948878 -283.58148) (xy 109.922531 -283.63422) (xy 109.888385 -283.68228)
			(xy 109.868208 -283.703776) (xy 109.861633 -283.71116) (xy 109.854197 -283.729459) (xy 109.85373 -283.739336)
			(xy 109.85373 -283.792422) (xy 109.864652 -283.802836) (xy 110.390178 -284.328616) (xy 110.397602 -284.335396)
			(xy 110.416199 -284.342995) (xy 110.426246 -284.343348) (xy 111.62665 -284.343348) (xy 111.637559 -284.342899)
			(xy 111.657452 -284.333958) (xy 111.665004 -284.326076) (xy 111.722662 -284.259782) (xy 111.728758 -284.238954)
			(xy 111.727234 -284.228032) (xy 111.725545 -284.214954) (xy 111.723768 -284.188641) (xy 111.723678 -284.175454)
			(xy 111.724243 -284.145329) (xy 111.733709 -284.085827) (xy 111.752415 -284.028554) (xy 111.779894 -283.974935)
			(xy 111.815463 -283.926305) (xy 111.836454 -283.90469) (xy 111.84382 -283.897578) (xy 111.85144 -283.878782)
			(xy 111.85144 -283.786326) (xy 111.84382 -283.76753) (xy 111.836454 -283.760418) (xy 111.815477 -283.738793)
			(xy 111.779922 -283.690158) (xy 111.75245 -283.63654) (xy 111.733745 -283.579272) (xy 111.72427 -283.519777)
			(xy 111.723678 -283.489654) (xy 111.724275 -283.459817) (xy 111.733586 -283.400873) (xy 111.74222 -283.372306)
			(xy 111.745522 -283.361892) (xy 111.743236 -283.340302) (xy 111.693198 -283.25572) (xy 111.675418 -283.243274)
			(xy 111.66475 -283.241242) (xy 111.636901 -283.235368) (xy 111.583216 -283.216467) (xy 111.532939 -283.189795)
			(xy 111.487185 -283.155945) (xy 111.446971 -283.115669) (xy 111.413192 -283.069863) (xy 111.386597 -283.019544)
			(xy 111.367778 -282.965831) (xy 111.361982 -282.937966) (xy 111.359442 -282.925774) (xy 111.343694 -282.905962)
			(xy 111.243618 -282.862528) (xy 111.218472 -282.86456) (xy 111.207804 -282.871164) (xy 111.184811 -282.885157)
			(xy 111.135732 -282.907254) (xy 111.084039 -282.922249) (xy 111.030754 -282.929846) (xy 111.003842 -282.930346)
			(xy 110.985824 -282.930111) (xy 110.94995 -282.926674) (xy 110.932214 -282.923488) (xy 110.922816 -282.92171)
			(xy 110.903766 -282.92552) (xy 110.828582 -282.973272) (xy 110.817152 -282.98902) (xy 110.814866 -282.998418)
			(xy 110.807482 -283.025468) (xy 110.785868 -283.077205) (xy 110.756912 -283.12522) (xy 110.721238 -283.168478)
			(xy 110.679616 -283.206048) (xy 110.632941 -283.237118) (xy 110.582221 -283.261021) (xy 110.528547 -283.27724)
			(xy 110.473077 -283.285426) (xy 110.445042 -283.285946) (xy 110.417786 -283.285486) (xy 110.363829 -283.277734)
			(xy 110.311523 -283.262382) (xy 110.261936 -283.239743) (xy 110.216074 -283.210276) (xy 110.174874 -283.174583)
			(xy 110.139172 -283.13339) (xy 110.109696 -283.087535) (xy 110.087046 -283.037952) (xy 110.071683 -282.98565)
			(xy 110.06392 -282.931694) (xy 110.063534 -282.904438) (xy 110.064018 -282.876862) (xy 110.071955 -282.822285)
			(xy 110.087668 -282.76942) (xy 110.110831 -282.719369) (xy 110.140959 -282.673175) (xy 110.177427 -282.631801)
			(xy 110.198154 -282.613608) (xy 110.206279 -282.606014) (xy 110.215609 -282.585855) (xy 110.216188 -282.574746)
			(xy 110.216188 -282.49753) (xy 110.21562 -282.486425) (xy 110.206262 -282.46628) (xy 110.198154 -282.458668)
			(xy 110.177443 -282.440454) (xy 110.14097 -282.399083) (xy 110.110833 -282.352892) (xy 110.087663 -282.302843)
			(xy 110.071941 -282.249978) (xy 110.063995 -282.195401) (xy 110.063992 -282.140248) (xy 110.07193 -282.08567)
			(xy 110.087645 -282.032803) (xy 110.110809 -281.982751) (xy 110.14094 -281.936556) (xy 110.177408 -281.895181)
			(xy 110.198154 -281.877008) (xy 110.206279 -281.869414) (xy 110.215609 -281.849255) (xy 110.216188 -281.838146)
			(xy 110.216188 -281.76093) (xy 110.21562 -281.749825) (xy 110.206262 -281.72968) (xy 110.198154 -281.722068)
			(xy 110.177449 -281.703852) (xy 110.140985 -281.66248) (xy 110.110857 -281.61629) (xy 110.087693 -281.566243)
			(xy 110.071975 -281.513384) (xy 110.064031 -281.458812) (xy 110.063534 -281.431238) (xy 110.063995 -281.403984)
			(xy 110.071748 -281.350032) (xy 110.087101 -281.297732) (xy 110.109742 -281.248149) (xy 110.139209 -281.202295)
			(xy 110.174904 -281.161101) (xy 110.216098 -281.125407) (xy 110.261953 -281.09594) (xy 110.311535 -281.073299)
			(xy 110.363836 -281.057947) (xy 110.417788 -281.050194) (xy 110.445042 -281.04973) (xy 110.472902 -281.050232)
			(xy 110.528031 -281.058328) (xy 110.581396 -281.074356) (xy 110.631862 -281.097975) (xy 110.678357 -281.128684)
			(xy 110.719891 -281.165828) (xy 110.75558 -281.208617) (xy 110.784667 -281.256143) (xy 110.806532 -281.307394)
			(xy 110.814104 -281.33421) (xy 110.81639 -281.3431) (xy 110.827058 -281.35834) (xy 110.89894 -281.406092)
			(xy 110.916974 -281.410156) (xy 110.926118 -281.408886) (xy 110.939133 -281.407202) (xy 110.965319 -281.405422)
			(xy 110.978442 -281.40533) (xy 110.991565 -281.405437) (xy 111.01775 -281.407215) (xy 111.030766 -281.408886)
			(xy 111.03991 -281.410156) (xy 111.057944 -281.406092) (xy 111.129826 -281.35834) (xy 111.140494 -281.3431)
			(xy 111.14278 -281.33421) (xy 111.150373 -281.307405) (xy 111.172259 -281.256173) (xy 111.201358 -281.208666)
			(xy 111.237051 -281.165891) (xy 111.278581 -281.128757) (xy 111.325066 -281.098052) (xy 111.37552 -281.074428)
			(xy 111.428871 -281.058387) (xy 111.483987 -281.050269) (xy 111.511842 -281.04973) (xy 111.53909 -281.050219)
			(xy 111.593031 -281.057981) (xy 111.645319 -281.07334) (xy 111.694888 -281.095984) (xy 111.740731 -281.125452)
			(xy 111.781913 -281.161144) (xy 111.817596 -281.202333) (xy 111.847054 -281.248182) (xy 111.869688 -281.297756)
			(xy 111.885036 -281.350047) (xy 111.892787 -281.40399) (xy 111.89335 -281.431238) (xy 111.892882 -281.458536)
			(xy 111.885096 -281.512576) (xy 111.86969 -281.564954) (xy 111.846977 -281.614602) (xy 111.81742 -281.660507)
			(xy 111.799878 -281.681428) (xy 111.793528 -281.688794) (xy 111.787178 -281.706574) (xy 111.790734 -281.795982)
			(xy 111.798354 -281.813254) (xy 111.805212 -281.820112) (xy 111.826321 -281.84176) (xy 111.862112 -281.890489)
			(xy 111.889772 -281.944252) (xy 111.908609 -282.001704) (xy 111.918152 -282.061408) (xy 111.91875 -282.091638)
			(xy 111.918263 -282.119278) (xy 111.910288 -282.173979) (xy 111.894497 -282.226955) (xy 111.87122 -282.277095)
			(xy 111.840947 -282.323348) (xy 111.822992 -282.344368) (xy 111.81461 -282.35402) (xy 111.808768 -282.378404)
			(xy 111.835946 -282.484576) (xy 111.852964 -282.503118) (xy 111.864902 -282.507436) (xy 111.892309 -282.517775)
			(xy 111.943825 -282.545652) (xy 111.99047 -282.581082) (xy 112.031147 -282.62323) (xy 112.064897 -282.671105)
			(xy 112.090926 -282.723578) (xy 112.108623 -282.779416) (xy 112.117569 -282.837304) (xy 112.11814 -282.866592)
			(xy 112.117539 -282.896428) (xy 112.108222 -282.955371) (xy 112.099598 -282.98394) (xy 112.096296 -282.994354)
			(xy 112.098582 -283.015944) (xy 112.14862 -283.100526) (xy 112.1664 -283.112972) (xy 112.177068 -283.115004)
			(xy 112.202871 -283.120406) (xy 112.252785 -283.13737) (xy 112.299888 -283.161044) (xy 112.343283 -283.190979)
			(xy 112.382143 -283.226602) (xy 112.415729 -283.267237) (xy 112.4434 -283.312109) (xy 112.46463 -283.360363)
			(xy 112.479014 -283.41108) (xy 112.486278 -283.463295) (xy 112.486694 -283.489654) (xy 112.486128 -283.519779)
			(xy 112.476663 -283.579282) (xy 112.457959 -283.636556) (xy 112.430483 -283.690177) (xy 112.394918 -283.738812)
			(xy 112.373918 -283.760418) (xy 112.366552 -283.76753) (xy 112.358932 -283.786326) (xy 112.358932 -283.878782)
			(xy 112.366552 -283.897578) (xy 112.373918 -283.90469) (xy 112.391577 -283.922753) (xy 112.42246 -283.962727)
			(xy 112.447787 -284.006433) (xy 112.467113 -284.053105) (xy 112.473994 -284.07741) (xy 112.47755 -284.090872)
			(xy 112.496346 -284.109922) (xy 112.594898 -284.136338) (xy 112.603561 -284.138269) (xy 112.621232 -284.136763)
			(xy 112.637337 -284.129338) (xy 112.64392 -284.123384) (xy 113.373662 -283.393642) (xy 113.379519 -283.387356)
			(xy 113.387005 -283.371906) (xy 113.388943 -283.354846) (xy 113.387378 -283.346398) (xy 113.365534 -283.249878)
			(xy 113.348262 -283.230574) (xy 113.335816 -283.226002) (xy 113.313482 -283.217639) (xy 113.270912 -283.196141)
			(xy 113.231346 -283.169516) (xy 113.213134 -283.15412) (xy 113.206022 -283.148024) (xy 113.189004 -283.141674)
			(xy 113.10366 -283.141674) (xy 113.086642 -283.148024) (xy 113.07953 -283.15412) (xy 113.058599 -283.171763)
			(xy 113.012633 -283.201491) (xy 112.962886 -283.224337) (xy 112.910383 -283.23983) (xy 112.856203 -283.247653)
			(xy 112.828832 -283.2481) (xy 112.801578 -283.247639) (xy 112.747625 -283.239886) (xy 112.695324 -283.224533)
			(xy 112.645741 -283.201893) (xy 112.599885 -283.172426) (xy 112.558689 -283.136733) (xy 112.522993 -283.095541)
			(xy 112.493523 -283.049687) (xy 112.470878 -283.000106) (xy 112.455521 -282.947806) (xy 112.447763 -282.893854)
			(xy 112.447763 -282.839346) (xy 112.455521 -282.785394) (xy 112.470878 -282.733094) (xy 112.493523 -282.683513)
			(xy 112.522993 -282.637659) (xy 112.558689 -282.596467) (xy 112.599885 -282.560774) (xy 112.645741 -282.531307)
			(xy 112.695324 -282.508667) (xy 112.747625 -282.493314) (xy 112.801578 -282.485561) (xy 112.828832 -282.485084)
			(xy 112.856201 -282.485558) (xy 112.910378 -282.493386) (xy 112.962879 -282.508876) (xy 113.012628 -282.53171)
			(xy 113.058602 -282.56142) (xy 113.07953 -282.579064) (xy 113.086642 -282.58516) (xy 113.10366 -282.59151)
			(xy 113.189004 -282.59151) (xy 113.206022 -282.58516) (xy 113.213134 -282.579064) (xy 113.234065 -282.561421)
			(xy 113.280031 -282.531694) (xy 113.329778 -282.508852) (xy 113.382281 -282.493363) (xy 113.436461 -282.485548)
			(xy 113.463832 -282.485084) (xy 113.491082 -282.485572) (xy 113.545027 -282.493332) (xy 113.597318 -282.50869)
			(xy 113.646892 -282.531333) (xy 113.692739 -282.5608) (xy 113.733926 -282.596491) (xy 113.769615 -282.637681)
			(xy 113.799079 -282.683529) (xy 113.821718 -282.733104) (xy 113.837073 -282.785397) (xy 113.84483 -282.839342)
			(xy 113.84534 -282.866592) (xy 113.844913 -282.893286) (xy 113.837501 -282.946158) (xy 113.82278 -282.997476)
			(xy 113.81232 -283.02204) (xy 113.806986 -283.033978) (xy 113.809018 -283.059378) (xy 113.862358 -283.141674)
			(xy 113.867221 -283.148603) (xy 113.880559 -283.159012) (xy 113.896569 -283.164479) (xy 113.90503 -283.164788)
			(xy 116.928392 -283.164788) (xy 116.958372 -283.165346) (xy 117.017594 -283.174729) (xy 117.074617 -283.193265)
			(xy 117.128036 -283.220497) (xy 117.176535 -283.255754) (xy 117.19814 -283.276548) (xy 117.239796 -283.318458)
			(xy 117.249152 -283.326668) (xy 117.272909 -283.333964) (xy 117.285262 -283.332428) (xy 117.380258 -283.31414)
			(xy 117.40007 -283.298392) (xy 117.404896 -283.286708) (xy 117.416645 -283.260737) (xy 117.446717 -283.212316)
			(xy 117.483669 -283.168917) (xy 117.526675 -283.131509) (xy 117.550438 -283.115766) (xy 117.560344 -283.10967)
			(xy 117.572282 -283.090112) (xy 117.582188 -282.999688) (xy 117.58282 -282.988301) (xy 117.575294 -282.966805)
			(xy 117.56771 -282.958286) (xy 117.310154 -282.700984) (xy 117.289363 -282.679389) (xy 117.254153 -282.630877)
			(xy 117.226975 -282.577449) (xy 117.2085 -282.520423) (xy 117.199184 -282.461208) (xy 117.198648 -282.431236)
			(xy 117.198648 -282.362148) (xy 117.198256 -282.352913) (xy 117.191718 -282.335639) (xy 117.179474 -282.321811)
			(xy 117.17147 -282.31719) (xy 117.079268 -282.268676) (xy 117.051328 -282.2702) (xy 117.039644 -282.278328)
			(xy 117.015726 -282.294058) (xy 116.964171 -282.318941) (xy 116.909479 -282.335844) (xy 116.852875 -282.344388)
			(xy 116.824252 -282.344876) (xy 116.797005 -282.344387) (xy 116.743067 -282.336625) (xy 116.690783 -282.321267)
			(xy 116.641216 -282.298625) (xy 116.595375 -282.26916) (xy 116.554194 -282.233472) (xy 116.518511 -282.192286)
			(xy 116.489052 -282.146442) (xy 116.466416 -282.096872) (xy 116.451065 -282.044586) (xy 116.44331 -281.990647)
			(xy 116.44331 -281.936153) (xy 116.451065 -281.882214) (xy 116.466416 -281.829928) (xy 116.489052 -281.780358)
			(xy 116.518511 -281.734514) (xy 116.554194 -281.693328) (xy 116.595375 -281.65764) (xy 116.641216 -281.628175)
			(xy 116.690783 -281.605533) (xy 116.743067 -281.590175) (xy 116.797005 -281.582413) (xy 116.824252 -281.58186)
			(xy 116.852872 -281.582374) (xy 116.909471 -281.590924) (xy 116.964161 -281.607824) (xy 117.015716 -281.632697)
			(xy 117.039644 -281.648408) (xy 117.051328 -281.656536) (xy 117.079268 -281.65806) (xy 117.17147 -281.609546)
			(xy 117.179448 -281.604895) (xy 117.19167 -281.591071) (xy 117.198202 -281.573814) (xy 117.198648 -281.564588)
			(xy 117.198648 -281.01671) (xy 117.199134 -280.989477) (xy 117.206885 -280.935565) (xy 117.22223 -280.883305)
			(xy 117.244856 -280.833761) (xy 117.274303 -280.787941) (xy 117.30997 -280.746778) (xy 117.351133 -280.711111)
			(xy 117.396953 -280.681664) (xy 117.446497 -280.659038) (xy 117.498757 -280.643693) (xy 117.552669 -280.635942)
			(xy 117.607135 -280.635942) (xy 117.661047 -280.643693) (xy 117.713307 -280.659038) (xy 117.762851 -280.681664)
			(xy 117.808671 -280.711111) (xy 117.849834 -280.746778) (xy 117.885501 -280.787941) (xy 117.914948 -280.833761)
			(xy 117.937574 -280.883305) (xy 117.952919 -280.935565) (xy 117.96067 -280.989477) (xy 117.961156 -281.01671)
			(xy 117.961156 -282.252166) (xy 117.961593 -282.26223) (xy 117.96933 -282.280811) (xy 117.976142 -282.288234)
			(xy 118.442486 -282.754578) (xy 118.451507 -282.762585) (xy 118.474426 -282.770004) (xy 118.486428 -282.768802)
			(xy 118.579646 -282.754324) (xy 118.59895 -282.740354) (xy 118.604792 -282.729432) (xy 118.616514 -282.707558)
			(xy 118.64478 -282.666768) (xy 118.678099 -282.629991) (xy 118.69674 -282.613608) (xy 118.704866 -282.606015)
			(xy 118.7142 -282.585855) (xy 118.714774 -282.574746) (xy 118.714774 -282.49753) (xy 118.714206 -282.486425)
			(xy 118.704846 -282.466282) (xy 118.69674 -282.458668) (xy 118.67603 -282.440453) (xy 118.639558 -282.399083)
			(xy 118.609422 -282.352891) (xy 118.586253 -282.302842) (xy 118.570531 -282.249978) (xy 118.562586 -282.195401)
			(xy 118.562582 -282.140248) (xy 118.570521 -282.08567) (xy 118.586235 -282.032804) (xy 118.609398 -281.982752)
			(xy 118.639528 -281.936557) (xy 118.675995 -281.895181) (xy 118.69674 -281.877008) (xy 118.704866 -281.869415)
			(xy 118.7142 -281.849255) (xy 118.714774 -281.838146) (xy 118.714774 -281.76093) (xy 118.714206 -281.749825)
			(xy 118.704846 -281.729682) (xy 118.69674 -281.722068) (xy 118.676035 -281.703852) (xy 118.639573 -281.662479)
			(xy 118.609446 -281.616289) (xy 118.586283 -281.566242) (xy 118.570566 -281.513383) (xy 118.562621 -281.458811)
			(xy 118.56212 -281.431238) (xy 118.562581 -281.403984) (xy 118.570333 -281.350031) (xy 118.585687 -281.29773)
			(xy 118.608327 -281.248147) (xy 118.637795 -281.202291) (xy 118.673489 -281.161096) (xy 118.714683 -281.125401)
			(xy 118.760538 -281.095932) (xy 118.81012 -281.07329) (xy 118.862421 -281.057936) (xy 118.916374 -281.050181)
			(xy 118.943628 -281.04973) (xy 118.971489 -281.050231) (xy 119.026619 -281.058326) (xy 119.079986 -281.074352)
			(xy 119.130454 -281.09797) (xy 119.17695 -281.128678) (xy 119.218485 -281.165822) (xy 119.254176 -281.208612)
			(xy 119.283264 -281.256139) (xy 119.30513 -281.30739) (xy 119.31269 -281.33421) (xy 119.314976 -281.3431)
			(xy 119.325644 -281.35834) (xy 119.397526 -281.406092) (xy 119.41556 -281.410156) (xy 119.424704 -281.408886)
			(xy 119.437719 -281.407202) (xy 119.463905 -281.405421) (xy 119.477028 -281.40533) (xy 119.490151 -281.405436)
			(xy 119.516336 -281.407214) (xy 119.529352 -281.408886) (xy 119.538496 -281.410156) (xy 119.55653 -281.406092)
			(xy 119.628412 -281.35834) (xy 119.63908 -281.3431) (xy 119.641366 -281.33421) (xy 119.648959 -281.307404)
			(xy 119.670845 -281.256172) (xy 119.699943 -281.208663) (xy 119.735636 -281.165887) (xy 119.777165 -281.128752)
			(xy 119.823651 -281.098045) (xy 119.874105 -281.07442) (xy 119.927456 -281.058376) (xy 119.982573 -281.050256)
			(xy 120.010428 -281.04973) (xy 120.037679 -281.050195) (xy 120.091624 -281.057956) (xy 120.143917 -281.073315)
			(xy 120.193491 -281.095959) (xy 120.239338 -281.125429) (xy 120.280524 -281.161123) (xy 120.316211 -281.202315)
			(xy 120.345673 -281.248167) (xy 120.368309 -281.297745) (xy 120.383658 -281.35004) (xy 120.391409 -281.403987)
			(xy 120.391936 -281.431238) (xy 120.391468 -281.458536) (xy 120.383682 -281.512575) (xy 120.368275 -281.564953)
			(xy 120.345561 -281.614601) (xy 120.316004 -281.660505) (xy 120.298464 -281.681428) (xy 120.292114 -281.688794)
			(xy 120.285764 -281.706574) (xy 120.28932 -281.795982) (xy 120.29694 -281.813254) (xy 120.303798 -281.820112)
			(xy 120.324907 -281.84176) (xy 120.3607 -281.890489) (xy 120.388361 -281.944252) (xy 120.407199 -282.001704)
			(xy 120.416742 -282.061407) (xy 120.417336 -282.091638) (xy 120.416849 -282.119278) (xy 120.408874 -282.173979)
			(xy 120.393082 -282.226955) (xy 120.369805 -282.277094) (xy 120.33953 -282.323346) (xy 120.321578 -282.344368)
			(xy 120.313196 -282.35402) (xy 120.307354 -282.378404) (xy 120.334532 -282.484576) (xy 120.35155 -282.503118)
			(xy 120.363488 -282.507436) (xy 120.390896 -282.517774) (xy 120.442414 -282.54565) (xy 120.48906 -282.58108)
			(xy 120.529738 -282.623228) (xy 120.56349 -282.671102) (xy 120.58952 -282.723576) (xy 120.607217 -282.779415)
			(xy 120.616164 -282.837304) (xy 120.616726 -282.866592) (xy 120.616177 -282.893854) (xy 120.946347 -282.893854)
			(xy 120.946347 -282.839346) (xy 120.954105 -282.785392) (xy 120.969462 -282.733092) (xy 120.992107 -282.683509)
			(xy 121.021577 -282.637654) (xy 121.057273 -282.59646) (xy 121.098469 -282.560766) (xy 121.144325 -282.531298)
			(xy 121.193909 -282.508656) (xy 121.24621 -282.493301) (xy 121.300164 -282.485546) (xy 121.327418 -282.485084)
			(xy 121.35479 -282.485519) (xy 121.408971 -282.493341) (xy 121.461475 -282.508836) (xy 121.511222 -282.531686)
			(xy 121.557186 -282.561418) (xy 121.578116 -282.579064) (xy 121.585228 -282.58516) (xy 121.602246 -282.59151)
			(xy 121.68759 -282.59151) (xy 121.704608 -282.58516) (xy 121.71172 -282.579064) (xy 121.732667 -282.561443)
			(xy 121.778636 -282.53173) (xy 121.82838 -282.508891) (xy 121.880877 -282.493396) (xy 121.93505 -282.485561)
			(xy 121.962418 -282.485084) (xy 121.989668 -282.485587) (xy 122.043612 -282.493345) (xy 122.095904 -282.508702)
			(xy 122.145478 -282.531343) (xy 122.191325 -282.56081) (xy 122.232512 -282.5965) (xy 122.268201 -282.637689)
			(xy 122.297665 -282.683538) (xy 122.320305 -282.733113) (xy 122.335658 -282.785405) (xy 122.343414 -282.83935)
			(xy 122.343414 -282.89385) (xy 122.335658 -282.947795) (xy 122.320305 -283.000087) (xy 122.297665 -283.049662)
			(xy 122.268201 -283.095511) (xy 122.232512 -283.1367) (xy 122.191325 -283.17239) (xy 122.145478 -283.201857)
			(xy 122.095904 -283.224498) (xy 122.043612 -283.239855) (xy 121.989668 -283.247613) (xy 121.962418 -283.2481)
			(xy 121.935048 -283.247623) (xy 121.88087 -283.239808) (xy 121.828367 -283.224321) (xy 121.778619 -283.201482)
			(xy 121.732652 -283.17176) (xy 121.71172 -283.15412) (xy 121.704608 -283.148024) (xy 121.68759 -283.141674)
			(xy 121.602246 -283.141674) (xy 121.585228 -283.148024) (xy 121.578116 -283.15412) (xy 121.557191 -283.171768)
			(xy 121.511216 -283.201478) (xy 121.461467 -283.224312) (xy 121.408965 -283.239801) (xy 121.354788 -283.247627)
			(xy 121.327418 -283.2481) (xy 121.300164 -283.247654) (xy 121.24621 -283.239899) (xy 121.193909 -283.224544)
			(xy 121.144325 -283.201902) (xy 121.098469 -283.172434) (xy 121.057273 -283.13674) (xy 121.021577 -283.095546)
			(xy 120.992107 -283.049691) (xy 120.969462 -283.000108) (xy 120.954105 -282.947808) (xy 120.946347 -282.893854)
			(xy 120.616177 -282.893854) (xy 120.616125 -282.896428) (xy 120.606808 -282.955371) (xy 120.598184 -282.98394)
			(xy 120.594882 -282.994354) (xy 120.597168 -283.015944) (xy 120.647206 -283.100526) (xy 120.664986 -283.112972)
			(xy 120.675654 -283.115004) (xy 120.701453 -283.120411) (xy 120.751358 -283.137383) (xy 120.798451 -283.161063)
			(xy 120.841836 -283.191) (xy 120.880687 -283.226625) (xy 120.914264 -283.267258) (xy 120.941928 -283.312127)
			(xy 120.963152 -283.360377) (xy 120.977532 -283.411089) (xy 120.984795 -283.463298) (xy 120.98528 -283.489654)
			(xy 120.984714 -283.519779) (xy 120.975248 -283.579282) (xy 120.956544 -283.636555) (xy 120.929067 -283.690176)
			(xy 120.893501 -283.738809) (xy 120.872504 -283.760418) (xy 120.865138 -283.76753) (xy 120.857518 -283.786326)
			(xy 120.857518 -283.878782) (xy 120.865138 -283.897578) (xy 120.872504 -283.90469) (xy 120.893478 -283.926317)
			(xy 120.929027 -283.974953) (xy 120.956493 -284.028571) (xy 120.975195 -284.085838) (xy 120.984667 -284.145332)
			(xy 120.98528 -284.175454) (xy 120.984794 -284.202705) (xy 120.977038 -284.256653) (xy 120.961683 -284.308948)
			(xy 120.939041 -284.358525) (xy 120.909575 -284.404375) (xy 120.873884 -284.445566) (xy 120.832693 -284.481257)
			(xy 120.786843 -284.510723) (xy 120.737266 -284.533365) (xy 120.684971 -284.54872) (xy 120.631023 -284.556476)
			(xy 120.576521 -284.556476) (xy 120.522573 -284.54872) (xy 120.470278 -284.533365) (xy 120.420701 -284.510723)
			(xy 120.374851 -284.481257) (xy 120.33366 -284.445566) (xy 120.297969 -284.404375) (xy 120.268503 -284.358525)
			(xy 120.245861 -284.308948) (xy 120.230506 -284.256653) (xy 120.22275 -284.202705) (xy 120.222264 -284.175454)
			(xy 120.222829 -284.145329) (xy 120.232295 -284.085827) (xy 120.251 -284.028553) (xy 120.278478 -283.974934)
			(xy 120.314046 -283.926303) (xy 120.33504 -283.90469) (xy 120.342406 -283.897578) (xy 120.350026 -283.878782)
			(xy 120.350026 -283.786326) (xy 120.342406 -283.76753) (xy 120.33504 -283.760418) (xy 120.314063 -283.738792)
			(xy 120.27851 -283.690157) (xy 120.251039 -283.63654) (xy 120.232334 -283.579272) (xy 120.22286 -283.519776)
			(xy 120.222264 -283.489654) (xy 120.222861 -283.459817) (xy 120.232172 -283.400873) (xy 120.240806 -283.372306)
			(xy 120.244108 -283.361892) (xy 120.241822 -283.340302) (xy 120.191784 -283.25572) (xy 120.174004 -283.243274)
			(xy 120.163336 -283.241242) (xy 120.135487 -283.235368) (xy 120.081805 -283.216465) (xy 120.031529 -283.189791)
			(xy 119.985776 -283.155941) (xy 119.945564 -283.115665) (xy 119.911786 -283.069859) (xy 119.885193 -283.019541)
			(xy 119.866375 -282.965828) (xy 119.860568 -282.937966) (xy 119.858028 -282.925774) (xy 119.84228 -282.905962)
			(xy 119.742204 -282.862528) (xy 119.717058 -282.86456) (xy 119.70639 -282.871164) (xy 119.683397 -282.885156)
			(xy 119.634318 -282.907251) (xy 119.582625 -282.922244) (xy 119.529339 -282.929839) (xy 119.502428 -282.930346)
			(xy 119.48441 -282.93011) (xy 119.448536 -282.926672) (xy 119.4308 -282.923488) (xy 119.421402 -282.92171)
			(xy 119.402352 -282.92552) (xy 119.327168 -282.973272) (xy 119.315738 -282.98902) (xy 119.313452 -282.998418)
			(xy 119.306068 -283.025467) (xy 119.284453 -283.077203) (xy 119.255497 -283.125217) (xy 119.219823 -283.168474)
			(xy 119.1782 -283.206042) (xy 119.131526 -283.237111) (xy 119.080805 -283.261012) (xy 119.027132 -283.277229)
			(xy 118.971663 -283.285413) (xy 118.943628 -283.285946) (xy 118.91264 -283.284676) (xy 118.901718 -283.283914)
			(xy 118.88216 -283.290518) (xy 118.819168 -283.348684) (xy 118.811795 -283.356208) (xy 118.803394 -283.375499)
			(xy 118.802912 -283.386022) (xy 118.802912 -284.583886) (xy 118.802355 -284.613866) (xy 118.792972 -284.673088)
			(xy 118.774437 -284.730112) (xy 118.747206 -284.783532) (xy 118.711949 -284.832032) (xy 118.691152 -284.853634)
			(xy 117.073426 -286.471106) (xy 117.066578 -286.478504) (xy 117.058841 -286.497102) (xy 117.05844 -286.507174)
			(xy 117.05844 -294.532304) (xy 117.058906 -294.542615) (xy 117.067015 -294.561572) (xy 117.081954 -294.575785)
			(xy 117.09146 -294.579802) (xy 117.195346 -294.619172) (xy 117.225826 -294.611552) (xy 117.23624 -294.599614)
			(xy 117.254434 -294.579676) (xy 117.295473 -294.544617) (xy 117.341045 -294.515694) (xy 117.390239 -294.493484)
			(xy 117.442072 -294.478431) (xy 117.49551 -294.470835) (xy 117.522498 -294.470328) (xy 117.549748 -294.470791)
			(xy 117.603694 -294.478547) (xy 117.655988 -294.493902) (xy 117.705563 -294.516542) (xy 117.751412 -294.546007)
			(xy 117.792601 -294.581697) (xy 117.828292 -294.622886) (xy 117.857757 -294.668735) (xy 117.880398 -294.718311)
			(xy 117.895752 -294.770604) (xy 117.903509 -294.82455) (xy 117.903509 -294.851836) (xy 118.705882 -294.851836)
			(xy 118.709953 -294.796214) (xy 118.722079 -294.741777) (xy 118.742002 -294.689686) (xy 118.769298 -294.641051)
			(xy 118.803384 -294.596908) (xy 118.843533 -294.558199) (xy 118.888891 -294.525748) (xy 118.938491 -294.500247)
			(xy 118.991275 -294.48224) (xy 119.046118 -294.47211) (xy 119.101852 -294.470073) (xy 119.157289 -294.476173)
			(xy 119.211246 -294.490279) (xy 119.262575 -294.512091) (xy 119.310181 -294.541145) (xy 119.353049 -294.57682)
			(xy 119.390266 -294.618357) (xy 119.421039 -294.66487) (xy 119.444711 -294.715367) (xy 119.460779 -294.768774)
			(xy 119.468899 -294.82395) (xy 119.469408 -294.851836) (xy 119.468899 -294.879722) (xy 119.460779 -294.934898)
			(xy 119.444711 -294.988305) (xy 119.421039 -295.038802) (xy 119.390266 -295.085315) (xy 119.353049 -295.126852)
			(xy 119.310181 -295.162527) (xy 119.262575 -295.191581) (xy 119.211246 -295.213393) (xy 119.157289 -295.227499)
			(xy 119.101852 -295.233599) (xy 119.046118 -295.231562) (xy 118.991275 -295.221432) (xy 118.938491 -295.203425)
			(xy 118.888891 -295.177924) (xy 118.843533 -295.145473) (xy 118.803384 -295.106764) (xy 118.769298 -295.062621)
			(xy 118.742002 -295.013986) (xy 118.722079 -294.961895) (xy 118.709953 -294.907458) (xy 118.705882 -294.851836)
			(xy 117.903509 -294.851836) (xy 117.903509 -294.87905) (xy 117.895752 -294.932996) (xy 117.880398 -294.985289)
			(xy 117.857757 -295.034865) (xy 117.828292 -295.080714) (xy 117.792601 -295.121903) (xy 117.751412 -295.157593)
			(xy 117.705563 -295.187058) (xy 117.655988 -295.209698) (xy 117.603694 -295.225053) (xy 117.549748 -295.232809)
			(xy 117.522498 -295.233344) (xy 117.495178 -295.232876) (xy 117.441096 -295.225079) (xy 117.388681 -295.209645)
			(xy 117.339004 -295.18689) (xy 117.293082 -295.157279) (xy 117.251856 -295.121419) (xy 117.216168 -295.080043)
			(xy 117.186749 -295.033998) (xy 117.175026 -295.009316) (xy 117.169184 -294.996362) (xy 117.146578 -294.980614)
			(xy 117.029484 -294.971724) (xy 117.004846 -294.983916) (xy 116.997226 -294.995854) (xy 116.986123 -295.012545)
			(xy 116.960926 -295.043728) (xy 116.946934 -295.058084) (xy 116.489734 -295.515284) (xy 116.478812 -295.525698)
			(xy 116.478812 -295.578784) (xy 116.479284 -295.588656) (xy 116.486746 -295.606936) (xy 116.49329 -295.614344)
			(xy 116.513463 -295.635844) (xy 116.547607 -295.683903) (xy 116.573952 -295.736642) (xy 116.591869 -295.792807)
			(xy 116.600933 -295.851059) (xy 116.601494 -295.880536) (xy 116.60102 -295.907905) (xy 116.593191 -295.962081)
			(xy 116.5777 -296.014581) (xy 116.554864 -296.064329) (xy 116.525153 -296.110302) (xy 116.507514 -296.131234)
			(xy 116.501418 -296.138346) (xy 116.495068 -296.155364) (xy 116.495068 -296.240708) (xy 116.501418 -296.257726)
			(xy 116.507514 -296.264838) (xy 116.52515 -296.285771) (xy 116.554867 -296.331739) (xy 116.577705 -296.381484)
			(xy 116.593195 -296.433984) (xy 116.601018 -296.488159) (xy 116.601014 -296.542896) (xy 116.593183 -296.597069)
			(xy 116.577686 -296.649567) (xy 116.554841 -296.699308) (xy 116.525118 -296.745272) (xy 116.507514 -296.766234)
			(xy 116.501418 -296.773346) (xy 116.495068 -296.790364) (xy 116.495068 -296.875708) (xy 116.501418 -296.892726)
			(xy 116.507514 -296.899838) (xy 116.52515 -296.920771) (xy 116.554867 -296.966739) (xy 116.577705 -297.016484)
			(xy 116.593195 -297.068984) (xy 116.601018 -297.123159) (xy 116.601014 -297.177896) (xy 116.593183 -297.232069)
			(xy 116.577686 -297.284567) (xy 116.554841 -297.334308) (xy 116.525118 -297.380272) (xy 116.507514 -297.401234)
			(xy 116.501418 -297.408346) (xy 116.495068 -297.425364) (xy 116.495068 -297.510708) (xy 116.501418 -297.527726)
			(xy 116.507514 -297.534838) (xy 116.52515 -297.555771) (xy 116.554867 -297.601739) (xy 116.577705 -297.651484)
			(xy 116.593195 -297.703984) (xy 116.601018 -297.758159) (xy 116.601014 -297.812896) (xy 116.593183 -297.867069)
			(xy 116.577686 -297.919567) (xy 116.554841 -297.969308) (xy 116.525118 -298.015272) (xy 116.507514 -298.036234)
			(xy 116.501418 -298.043346) (xy 116.495068 -298.060364) (xy 116.495068 -298.145708) (xy 116.501418 -298.162726)
			(xy 116.507514 -298.169838) (xy 116.525153 -298.19077) (xy 116.554874 -298.236738) (xy 116.577711 -298.286485)
			(xy 116.593195 -298.338988) (xy 116.601008 -298.393166) (xy 116.601494 -298.420536) (xy 120.153684 -298.420536)
			(xy 120.154151 -298.393166) (xy 120.161965 -298.338986) (xy 120.177453 -298.286482) (xy 120.200295 -298.236735)
			(xy 120.230021 -298.190769) (xy 120.247664 -298.169838) (xy 120.25376 -298.162726) (xy 120.26011 -298.145708)
			(xy 120.26011 -298.060364) (xy 120.25376 -298.043346) (xy 120.247664 -298.036234) (xy 120.230057 -298.015273)
			(xy 120.200328 -297.969311) (xy 120.177478 -297.91957) (xy 120.161978 -297.867072) (xy 120.154145 -297.812896)
			(xy 120.154141 -297.758158) (xy 120.161966 -297.703981) (xy 120.177459 -297.651481) (xy 120.200302 -297.601736)
			(xy 120.230024 -297.55577) (xy 120.247664 -297.534838) (xy 120.25376 -297.527726) (xy 120.26011 -297.510708)
			(xy 120.26011 -297.425364) (xy 120.25376 -297.408346) (xy 120.247664 -297.401234) (xy 120.230057 -297.380273)
			(xy 120.200328 -297.334311) (xy 120.177478 -297.28457) (xy 120.161978 -297.232072) (xy 120.154145 -297.177896)
			(xy 120.154141 -297.123158) (xy 120.161966 -297.068981) (xy 120.177459 -297.016481) (xy 120.200302 -296.966736)
			(xy 120.230024 -296.92077) (xy 120.247664 -296.899838) (xy 120.25376 -296.892726) (xy 120.26011 -296.875708)
			(xy 120.26011 -296.790364) (xy 120.25376 -296.773346) (xy 120.247664 -296.766234) (xy 120.230057 -296.745273)
			(xy 120.200328 -296.699311) (xy 120.177478 -296.64957) (xy 120.161978 -296.597072) (xy 120.154145 -296.542896)
			(xy 120.154141 -296.488158) (xy 120.161966 -296.433981) (xy 120.177459 -296.381481) (xy 120.200302 -296.331736)
			(xy 120.230024 -296.28577) (xy 120.247664 -296.264838) (xy 120.25376 -296.257726) (xy 120.26011 -296.240708)
			(xy 120.26011 -296.155364) (xy 120.25376 -296.138346) (xy 120.247664 -296.131234) (xy 120.230057 -296.110273)
			(xy 120.200328 -296.064311) (xy 120.177478 -296.01457) (xy 120.161978 -295.962072) (xy 120.154145 -295.907896)
			(xy 120.154141 -295.853158) (xy 120.161966 -295.798981) (xy 120.177459 -295.746481) (xy 120.200302 -295.696736)
			(xy 120.230024 -295.65077) (xy 120.247664 -295.629838) (xy 120.25376 -295.622726) (xy 120.26011 -295.605708)
			(xy 120.26011 -295.520364) (xy 120.25376 -295.503346) (xy 120.247664 -295.496234) (xy 120.230022 -295.475305)
			(xy 120.200312 -295.42933) (xy 120.177477 -295.379582) (xy 120.161986 -295.327081) (xy 120.154158 -295.272905)
			(xy 120.153684 -295.245536) (xy 120.154189 -295.218284) (xy 120.161941 -295.164335) (xy 120.177292 -295.112039)
			(xy 120.199929 -295.062459) (xy 120.229393 -295.016606) (xy 120.265082 -294.975414) (xy 120.306271 -294.939719)
			(xy 120.352121 -294.910251) (xy 120.401697 -294.887607) (xy 120.453992 -294.87225) (xy 120.50794 -294.864492)
			(xy 120.535192 -294.864028) (xy 120.562562 -294.864492) (xy 120.616742 -294.872309) (xy 120.669245 -294.887798)
			(xy 120.718992 -294.910641) (xy 120.764959 -294.940366) (xy 120.78589 -294.958008) (xy 120.793002 -294.964104)
			(xy 120.81002 -294.970454) (xy 120.895364 -294.970454) (xy 120.912382 -294.964104) (xy 120.919494 -294.958008)
			(xy 120.940419 -294.94036) (xy 120.986393 -294.910649) (xy 121.036143 -294.887815) (xy 121.088645 -294.872326)
			(xy 121.142822 -294.8645) (xy 121.170192 -294.864028) (xy 121.197446 -294.864463) (xy 121.2514 -294.87222)
			(xy 121.303701 -294.887577) (xy 121.353283 -294.910221) (xy 121.399138 -294.939691) (xy 121.440332 -294.975388)
			(xy 121.476026 -295.016584) (xy 121.505493 -295.062441) (xy 121.528133 -295.112026) (xy 121.543486 -295.164327)
			(xy 121.551239 -295.218282) (xy 121.5517 -295.245536) (xy 121.551255 -295.272907) (xy 121.543432 -295.327087)
			(xy 121.527938 -295.37959) (xy 121.505092 -295.429337) (xy 121.475363 -295.475303) (xy 121.45772 -295.496234)
			(xy 121.451624 -295.503346) (xy 121.445274 -295.520364) (xy 121.445274 -295.605708) (xy 121.451624 -295.622726)
			(xy 121.45772 -295.629838) (xy 121.475394 -295.650743) (xy 121.505114 -295.696717) (xy 121.527954 -295.746468)
			(xy 121.543446 -295.798974) (xy 121.55127 -295.853155) (xy 121.551266 -295.907899) (xy 121.543434 -295.962079)
			(xy 121.527935 -296.014583) (xy 121.505088 -296.064331) (xy 121.475361 -296.1103) (xy 121.45772 -296.131234)
			(xy 121.451624 -296.138346) (xy 121.445274 -296.155364) (xy 121.445274 -296.240708) (xy 121.451624 -296.257726)
			(xy 121.45772 -296.264838) (xy 121.475394 -296.285743) (xy 121.505114 -296.331717) (xy 121.527954 -296.381468)
			(xy 121.543446 -296.433974) (xy 121.55127 -296.488155) (xy 121.551266 -296.542899) (xy 121.543434 -296.597079)
			(xy 121.527935 -296.649583) (xy 121.505088 -296.699331) (xy 121.475361 -296.7453) (xy 121.45772 -296.766234)
			(xy 121.451624 -296.773346) (xy 121.445274 -296.790364) (xy 121.445274 -296.875708) (xy 121.451624 -296.892726)
			(xy 121.45772 -296.899838) (xy 121.475394 -296.920743) (xy 121.505114 -296.966717) (xy 121.527954 -297.016468)
			(xy 121.543446 -297.068974) (xy 121.55127 -297.123155) (xy 121.551266 -297.177899) (xy 121.543434 -297.232079)
			(xy 121.527935 -297.284583) (xy 121.505088 -297.334331) (xy 121.475361 -297.3803) (xy 121.45772 -297.401234)
			(xy 121.451624 -297.408346) (xy 121.445274 -297.425364) (xy 121.445274 -297.510708) (xy 121.451624 -297.527726)
			(xy 121.45772 -297.534838) (xy 121.475394 -297.555743) (xy 121.505114 -297.601717) (xy 121.527954 -297.651468)
			(xy 121.543446 -297.703974) (xy 121.55127 -297.758155) (xy 121.551266 -297.812899) (xy 121.543434 -297.867079)
			(xy 121.527935 -297.919583) (xy 121.505088 -297.969331) (xy 121.475361 -298.0153) (xy 121.45772 -298.036234)
			(xy 121.451624 -298.043346) (xy 121.445274 -298.060364) (xy 121.445274 -298.145708) (xy 121.451624 -298.162726)
			(xy 121.45772 -298.169838) (xy 121.475347 -298.19078) (xy 121.50506 -298.23675) (xy 121.527898 -298.286495)
			(xy 121.543392 -298.338994) (xy 121.551224 -298.393168) (xy 121.5517 -298.420536) (xy 121.551256 -298.447789)
			(xy 121.543494 -298.501738) (xy 121.528134 -298.554034) (xy 121.505488 -298.603612) (xy 121.476017 -298.649463)
			(xy 121.440321 -298.690653) (xy 121.399127 -298.726344) (xy 121.353273 -298.755809) (xy 121.303693 -298.778449)
			(xy 121.251395 -298.793803) (xy 121.197445 -298.801559) (xy 121.170192 -298.802044) (xy 121.142821 -298.801596)
			(xy 121.088641 -298.793776) (xy 121.036137 -298.778284) (xy 120.98639 -298.755437) (xy 120.940425 -298.725708)
			(xy 120.919494 -298.708064) (xy 120.912382 -298.701968) (xy 120.895364 -298.695618) (xy 120.81002 -298.695618)
			(xy 120.793002 -298.701968) (xy 120.78589 -298.708064) (xy 120.764968 -298.725716) (xy 120.718993 -298.755427)
			(xy 120.669243 -298.778261) (xy 120.61674 -298.793749) (xy 120.562562 -298.801573) (xy 120.535192 -298.802044)
			(xy 120.507942 -298.80153) (xy 120.453997 -298.793773) (xy 120.401705 -298.778419) (xy 120.35213 -298.755779)
			(xy 120.306282 -298.726316) (xy 120.265093 -298.690627) (xy 120.229401 -298.649441) (xy 120.199934 -298.603594)
			(xy 120.177291 -298.554021) (xy 120.161933 -298.50173) (xy 120.154172 -298.447786) (xy 120.153684 -298.420536)
			(xy 116.601494 -298.420536) (xy 116.601005 -298.447785) (xy 116.593245 -298.501728) (xy 116.577886 -298.554018)
			(xy 116.555243 -298.603589) (xy 116.525775 -298.649434) (xy 116.490084 -298.690619) (xy 116.448894 -298.726305)
			(xy 116.403046 -298.755767) (xy 116.353471 -298.778404) (xy 116.301179 -298.793755) (xy 116.247235 -298.801509)
			(xy 116.219986 -298.802044) (xy 116.192617 -298.801571) (xy 116.13844 -298.793745) (xy 116.085939 -298.778254)
			(xy 116.036191 -298.755418) (xy 115.990218 -298.725705) (xy 115.969288 -298.708064) (xy 115.962176 -298.701968)
			(xy 115.945158 -298.695618) (xy 115.859814 -298.695618) (xy 115.842796 -298.701968) (xy 115.835684 -298.708064)
			(xy 115.814753 -298.725707) (xy 115.768787 -298.755433) (xy 115.71904 -298.778277) (xy 115.666536 -298.793766)
			(xy 115.612357 -298.801583) (xy 115.584986 -298.802044) (xy 115.557734 -298.801557) (xy 115.503786 -298.793799)
			(xy 115.451491 -298.778443) (xy 115.401913 -298.755802) (xy 115.356062 -298.726336) (xy 115.314871 -298.690645)
			(xy 115.279177 -298.649455) (xy 115.249709 -298.603606) (xy 115.227064 -298.554029) (xy 115.211705 -298.501735)
			(xy 115.203944 -298.447788) (xy 115.203478 -298.420536) (xy 115.203954 -298.393167) (xy 115.211785 -298.338993)
			(xy 115.227279 -298.286494) (xy 115.250116 -298.236748) (xy 115.279828 -298.190777) (xy 115.297458 -298.169838)
			(xy 115.303554 -298.162726) (xy 115.309904 -298.145708) (xy 115.309904 -298.060364) (xy 115.303554 -298.043346)
			(xy 115.297458 -298.036234) (xy 115.279813 -298.015302) (xy 115.250081 -297.969334) (xy 115.227229 -297.919586)
			(xy 115.211727 -297.867082) (xy 115.203893 -297.8129) (xy 115.203889 -297.758154) (xy 115.211715 -297.703971)
			(xy 115.22721 -297.651465) (xy 115.250055 -297.601714) (xy 115.279781 -297.555742) (xy 115.297458 -297.534838)
			(xy 115.303554 -297.527726) (xy 115.309904 -297.510708) (xy 115.309904 -297.425364) (xy 115.303554 -297.408346)
			(xy 115.297458 -297.401234) (xy 115.279813 -297.380302) (xy 115.250081 -297.334334) (xy 115.227229 -297.284586)
			(xy 115.211727 -297.232082) (xy 115.203893 -297.1779) (xy 115.203889 -297.123154) (xy 115.211715 -297.068971)
			(xy 115.22721 -297.016465) (xy 115.250055 -296.966714) (xy 115.279781 -296.920742) (xy 115.297458 -296.899838)
			(xy 115.303554 -296.892726) (xy 115.309904 -296.875708) (xy 115.309904 -296.790364) (xy 115.303554 -296.773346)
			(xy 115.297458 -296.766234) (xy 115.279813 -296.745302) (xy 115.250081 -296.699334) (xy 115.227229 -296.649586)
			(xy 115.211727 -296.597082) (xy 115.203893 -296.5429) (xy 115.203889 -296.488154) (xy 115.211715 -296.433971)
			(xy 115.22721 -296.381465) (xy 115.250055 -296.331714) (xy 115.279781 -296.285742) (xy 115.297458 -296.264838)
			(xy 115.303554 -296.257726) (xy 115.309904 -296.240708) (xy 115.309904 -296.155364) (xy 115.303554 -296.138346)
			(xy 115.297458 -296.131234) (xy 115.279813 -296.110302) (xy 115.250081 -296.064334) (xy 115.227229 -296.014586)
			(xy 115.211727 -295.962082) (xy 115.203893 -295.9079) (xy 115.203889 -295.853154) (xy 115.211715 -295.798971)
			(xy 115.22721 -295.746465) (xy 115.250055 -295.696714) (xy 115.279781 -295.650742) (xy 115.297458 -295.629838)
			(xy 115.303554 -295.622726) (xy 115.309904 -295.605708) (xy 115.309904 -295.520364) (xy 115.303554 -295.503346)
			(xy 115.297458 -295.496234) (xy 115.279812 -295.475304) (xy 115.250077 -295.42934) (xy 115.227226 -295.379594)
			(xy 115.211729 -295.327089) (xy 115.203904 -295.272908) (xy 115.203478 -295.245536) (xy 115.203938 -295.218281)
			(xy 115.211691 -295.164325) (xy 115.227044 -295.112022) (xy 115.249684 -295.062437) (xy 115.279151 -295.016578)
			(xy 115.314845 -294.97538) (xy 115.356038 -294.939681) (xy 115.401893 -294.910208) (xy 115.451475 -294.887561)
			(xy 115.503777 -294.872202) (xy 115.557731 -294.864442) (xy 115.584986 -294.864028) (xy 115.614464 -294.864575)
			(xy 115.672718 -294.873641) (xy 115.728885 -294.891559) (xy 115.781627 -294.917903) (xy 115.82969 -294.952045)
			(xy 115.851178 -294.972232) (xy 115.85856 -294.978813) (xy 115.876859 -294.986257) (xy 115.886738 -294.98671)
			(xy 115.939824 -294.98671) (xy 115.950238 -294.975788) (xy 116.280946 -294.645334) (xy 116.287788 -294.637935)
			(xy 116.295507 -294.619336) (xy 116.295932 -294.609266) (xy 116.295932 -286.328104) (xy 116.296503 -286.298136)
			(xy 116.305842 -286.238933) (xy 116.324323 -286.181918) (xy 116.351491 -286.128494) (xy 116.386677 -286.079975)
			(xy 116.407438 -286.058356) (xy 117.838728 -284.62732) (xy 117.845534 -284.61984) (xy 117.853137 -284.601118)
			(xy 117.852943 -284.580912) (xy 117.849396 -284.57144) (xy 117.806216 -284.470348) (xy 117.780054 -284.453584)
			(xy 117.76456 -284.453838) (xy 117.755416 -284.454092) (xy 117.45468 -284.454092) (xy 117.424698 -284.45354)
			(xy 117.365471 -284.444166) (xy 117.308441 -284.425638) (xy 117.255015 -284.398411) (xy 117.206508 -284.363157)
			(xy 117.184932 -284.342332) (xy 116.78539 -283.942536) (xy 116.777967 -283.935756) (xy 116.759369 -283.928161)
			(xy 116.749322 -283.927804) (xy 113.93932 -283.927804) (xy 113.92929 -283.928247) (xy 113.910722 -283.935829)
			(xy 113.903252 -283.942536) (xy 112.851438 -284.994604) (xy 112.829823 -285.015383) (xy 112.781318 -285.050621)
			(xy 112.727899 -285.07784) (xy 112.670881 -285.096372) (xy 112.611667 -285.105761) (xy 112.58169 -285.106364)
			(xy 110.247176 -285.106364) (xy 110.217193 -285.105812) (xy 110.157965 -285.096439) (xy 110.100934 -285.077913)
			(xy 110.047504 -285.05069) (xy 109.998994 -285.01544) (xy 109.977428 -284.994604) (xy 109.359954 -284.376876)
			(xy 109.352514 -284.370168) (xy 109.334011 -284.362544) (xy 109.313998 -284.362542) (xy 109.304582 -284.365954)
			(xy 109.290104 -284.371796) (xy 109.27334 -284.397196) (xy 109.27334 -284.662372) (xy 109.273783 -284.672402)
			(xy 109.281366 -284.690968) (xy 109.288072 -284.69844) (xy 110.818168 -286.228282) (xy 110.838948 -286.249896)
			(xy 110.874186 -286.298401) (xy 110.901405 -286.35182) (xy 110.919936 -286.408838) (xy 110.929323 -286.468053)
			(xy 110.929928 -286.49803) (xy 110.929928 -286.874966) (xy 110.929373 -286.904947) (xy 110.919994 -286.964171)
			(xy 110.901461 -287.021197) (xy 110.874232 -287.074621) (xy 110.838978 -287.123124) (xy 110.818168 -287.144714)
			(xy 110.217458 -287.74517) (xy 110.210616 -287.752569) (xy 110.202898 -287.771168) (xy 110.202472 -287.781238)
			(xy 110.202472 -291.386514) (xy 110.2019 -291.416481) (xy 110.192558 -291.475683) (xy 110.174076 -291.532696)
			(xy 110.146906 -291.586118) (xy 110.111719 -291.634636) (xy 110.090966 -291.656262) (xy 108.912914 -292.83406)
			(xy 108.906076 -292.841461) (xy 108.898361 -292.860059) (xy 108.897928 -292.870128) (xy 108.897928 -294.199564)
			(xy 110.64951 -294.199564) (xy 110.653581 -294.143942) (xy 110.665707 -294.089505) (xy 110.68563 -294.037414)
			(xy 110.712926 -293.988779) (xy 110.747012 -293.944636) (xy 110.787161 -293.905927) (xy 110.832519 -293.873476)
			(xy 110.882119 -293.847975) (xy 110.934903 -293.829968) (xy 110.989746 -293.819838) (xy 111.04548 -293.817801)
			(xy 111.100917 -293.823901) (xy 111.154874 -293.838007) (xy 111.206203 -293.859819) (xy 111.253809 -293.888873)
			(xy 111.296677 -293.924548) (xy 111.333894 -293.966085) (xy 111.364667 -294.012598) (xy 111.388339 -294.063095)
			(xy 111.404407 -294.116502) (xy 111.412527 -294.171678) (xy 111.413036 -294.199564) (xy 111.412527 -294.22745)
			(xy 111.404407 -294.282626) (xy 111.388339 -294.336033) (xy 111.364667 -294.38653) (xy 111.333894 -294.433043)
			(xy 111.296677 -294.47458) (xy 111.253809 -294.510255) (xy 111.206203 -294.539309) (xy 111.154874 -294.561121)
			(xy 111.100917 -294.575227) (xy 111.04548 -294.581327) (xy 110.989746 -294.57929) (xy 110.934903 -294.56916)
			(xy 110.882119 -294.551153) (xy 110.832519 -294.525652) (xy 110.787161 -294.493201) (xy 110.747012 -294.454492)
			(xy 110.712926 -294.410349) (xy 110.68563 -294.361714) (xy 110.665707 -294.309623) (xy 110.653581 -294.255186)
			(xy 110.64951 -294.199564) (xy 108.897928 -294.199564) (xy 108.897928 -294.787066) (xy 108.898601 -294.799133)
			(xy 108.909616 -294.820607) (xy 108.91901 -294.828214) (xy 108.995718 -294.883586) (xy 109.020102 -294.887396)
			(xy 109.031532 -294.883332) (xy 109.060742 -294.874302) (xy 109.121105 -294.864608) (xy 109.151674 -294.864028)
			(xy 109.178927 -294.86449) (xy 109.232879 -294.872244) (xy 109.285178 -294.887598) (xy 109.334759 -294.910239)
			(xy 109.380613 -294.939707) (xy 109.421806 -294.975401) (xy 109.457499 -295.016595) (xy 109.486965 -295.06245)
			(xy 109.509606 -295.112032) (xy 109.524958 -295.164331) (xy 109.532711 -295.218283) (xy 109.533182 -295.245536)
			(xy 109.532708 -295.272905) (xy 109.524879 -295.32708) (xy 109.509387 -295.379581) (xy 109.486551 -295.429328)
			(xy 109.456839 -295.4753) (xy 109.439202 -295.496234) (xy 109.433106 -295.503346) (xy 109.426756 -295.520364)
			(xy 109.426756 -295.605708) (xy 109.433106 -295.622726) (xy 109.439202 -295.629838) (xy 109.456839 -295.650771)
			(xy 109.486556 -295.696739) (xy 109.509395 -295.746484) (xy 109.524885 -295.798983) (xy 109.532709 -295.853159)
			(xy 109.532705 -295.907896) (xy 109.524874 -295.96207) (xy 109.509376 -296.014567) (xy 109.48653 -296.064309)
			(xy 109.456806 -296.110272) (xy 109.439202 -296.131234) (xy 109.433106 -296.138346) (xy 109.426756 -296.155364)
			(xy 109.426756 -296.240708) (xy 109.433106 -296.257726) (xy 109.439202 -296.264838) (xy 109.456839 -296.285771)
			(xy 109.486556 -296.331739) (xy 109.509395 -296.381484) (xy 109.524885 -296.433983) (xy 109.532709 -296.488159)
			(xy 109.532705 -296.542896) (xy 109.524874 -296.59707) (xy 109.509376 -296.649567) (xy 109.48653 -296.699309)
			(xy 109.456806 -296.745272) (xy 109.439202 -296.766234) (xy 109.433106 -296.773346) (xy 109.426756 -296.790364)
			(xy 109.426756 -296.875708) (xy 109.433106 -296.892726) (xy 109.439202 -296.899838) (xy 109.456839 -296.920771)
			(xy 109.486556 -296.966739) (xy 109.509395 -297.016484) (xy 109.524885 -297.068983) (xy 109.532709 -297.123159)
			(xy 109.532705 -297.177896) (xy 109.524874 -297.23207) (xy 109.509376 -297.284567) (xy 109.48653 -297.334309)
			(xy 109.456806 -297.380272) (xy 109.439202 -297.401234) (xy 109.433106 -297.408346) (xy 109.426756 -297.425364)
			(xy 109.426756 -297.510708) (xy 109.433106 -297.527726) (xy 109.439202 -297.534838) (xy 109.456839 -297.555771)
			(xy 109.486556 -297.601739) (xy 109.509395 -297.651484) (xy 109.524885 -297.703983) (xy 109.532709 -297.758159)
			(xy 109.532705 -297.812896) (xy 109.524874 -297.86707) (xy 109.509376 -297.919567) (xy 109.48653 -297.969309)
			(xy 109.456806 -298.015272) (xy 109.439202 -298.036234) (xy 109.433106 -298.043346) (xy 109.426756 -298.060364)
			(xy 109.426756 -298.145708) (xy 109.433106 -298.162726) (xy 109.439202 -298.169838) (xy 109.456842 -298.19077)
			(xy 109.486563 -298.236738) (xy 109.509401 -298.286485) (xy 109.524886 -298.338988) (xy 109.532699 -298.393166)
			(xy 109.533182 -298.420536) (xy 110.562898 -298.420536) (xy 110.563386 -298.393167) (xy 110.571198 -298.338988)
			(xy 110.586682 -298.286486) (xy 110.609519 -298.236738) (xy 110.639239 -298.19077) (xy 110.656878 -298.169838)
			(xy 110.662974 -298.162726) (xy 110.669324 -298.145708) (xy 110.669324 -298.060364) (xy 110.662974 -298.043346)
			(xy 110.656878 -298.036234) (xy 110.639275 -298.015272) (xy 110.609552 -297.969308) (xy 110.586708 -297.919566)
			(xy 110.571211 -297.867069) (xy 110.56338 -297.812895) (xy 110.563376 -297.758159) (xy 110.571199 -297.703984)
			(xy 110.586689 -297.651485) (xy 110.609526 -297.60174) (xy 110.639242 -297.555772) (xy 110.656878 -297.534838)
			(xy 110.662974 -297.527726) (xy 110.669324 -297.510708) (xy 110.669324 -297.425364) (xy 110.662974 -297.408346)
			(xy 110.656878 -297.401234) (xy 110.639275 -297.380272) (xy 110.609552 -297.334308) (xy 110.586708 -297.284566)
			(xy 110.571211 -297.232069) (xy 110.56338 -297.177895) (xy 110.563376 -297.123159) (xy 110.571199 -297.068984)
			(xy 110.586689 -297.016485) (xy 110.609526 -296.96674) (xy 110.639242 -296.920772) (xy 110.656878 -296.899838)
			(xy 110.662974 -296.892726) (xy 110.669324 -296.875708) (xy 110.669324 -296.790364) (xy 110.662974 -296.773346)
			(xy 110.656878 -296.766234) (xy 110.639275 -296.745272) (xy 110.609552 -296.699308) (xy 110.586708 -296.649566)
			(xy 110.571211 -296.597069) (xy 110.56338 -296.542895) (xy 110.563376 -296.488159) (xy 110.571199 -296.433984)
			(xy 110.586689 -296.381485) (xy 110.609526 -296.33174) (xy 110.639242 -296.285772) (xy 110.656878 -296.264838)
			(xy 110.662974 -296.257726) (xy 110.669324 -296.240708) (xy 110.669324 -296.155364) (xy 110.662974 -296.138346)
			(xy 110.656878 -296.131234) (xy 110.639275 -296.110272) (xy 110.609552 -296.064308) (xy 110.586708 -296.014566)
			(xy 110.571211 -295.962069) (xy 110.56338 -295.907895) (xy 110.563376 -295.853159) (xy 110.571199 -295.798984)
			(xy 110.586689 -295.746485) (xy 110.609526 -295.69674) (xy 110.639242 -295.650772) (xy 110.656878 -295.629838)
			(xy 110.662974 -295.622726) (xy 110.669324 -295.605708) (xy 110.669324 -295.520364) (xy 110.662974 -295.503346)
			(xy 110.656878 -295.496234) (xy 110.639238 -295.475303) (xy 110.609527 -295.429329) (xy 110.586692 -295.379582)
			(xy 110.571201 -295.327081) (xy 110.563372 -295.272905) (xy 110.562898 -295.245536) (xy 110.563389 -295.218284)
			(xy 110.571141 -295.164334) (xy 110.586493 -295.112036) (xy 110.609132 -295.062455) (xy 110.638596 -295.016602)
			(xy 110.674287 -294.975409) (xy 110.715478 -294.939714) (xy 110.761329 -294.910246) (xy 110.810908 -294.887603)
			(xy 110.863204 -294.872247) (xy 110.917154 -294.864491) (xy 110.944406 -294.864028) (xy 110.971777 -294.864484)
			(xy 111.025956 -294.872303) (xy 111.07846 -294.887794) (xy 111.128207 -294.910638) (xy 111.174173 -294.940365)
			(xy 111.195104 -294.958008) (xy 111.202216 -294.964104) (xy 111.219234 -294.970454) (xy 111.304578 -294.970454)
			(xy 111.321596 -294.964104) (xy 111.328708 -294.958008) (xy 111.349627 -294.940353) (xy 111.395603 -294.910643)
			(xy 111.445354 -294.88781) (xy 111.497858 -294.872323) (xy 111.552036 -294.864499) (xy 111.579406 -294.864028)
			(xy 111.606661 -294.86445) (xy 111.660615 -294.872209) (xy 111.712916 -294.887567) (xy 111.762498 -294.910213)
			(xy 111.808353 -294.939685) (xy 111.849547 -294.975383) (xy 111.88524 -295.016581) (xy 111.914707 -295.062439)
			(xy 111.937347 -295.112024) (xy 111.9527 -295.164326) (xy 111.960453 -295.218281) (xy 111.960914 -295.245536)
			(xy 111.960466 -295.272907) (xy 111.952643 -295.327087) (xy 111.93715 -295.37959) (xy 111.914304 -295.429336)
			(xy 111.884576 -295.475303) (xy 111.866934 -295.496234) (xy 111.860838 -295.503346) (xy 111.854488 -295.520364)
			(xy 111.854488 -295.605708) (xy 111.860838 -295.622726) (xy 111.866934 -295.629838) (xy 111.884612 -295.650741)
			(xy 111.914338 -295.696713) (xy 111.937184 -295.746464) (xy 111.952679 -295.798971) (xy 111.960505 -295.853154)
			(xy 111.960501 -295.9079) (xy 111.952667 -295.962082) (xy 111.937164 -296.014587) (xy 111.914312 -296.064334)
			(xy 111.884579 -296.110302) (xy 111.866934 -296.131234) (xy 111.860838 -296.138346) (xy 111.854488 -296.155364)
			(xy 111.854488 -296.240708) (xy 111.860838 -296.257726) (xy 111.866934 -296.264838) (xy 111.884612 -296.285741)
			(xy 111.914338 -296.331713) (xy 111.937184 -296.381464) (xy 111.952679 -296.433971) (xy 111.960505 -296.488154)
			(xy 111.960501 -296.5429) (xy 111.952667 -296.597082) (xy 111.937164 -296.649587) (xy 111.914312 -296.699334)
			(xy 111.884579 -296.745302) (xy 111.866934 -296.766234) (xy 111.860838 -296.773346) (xy 111.854488 -296.790364)
			(xy 111.854488 -296.875708) (xy 111.860838 -296.892726) (xy 111.866934 -296.899838) (xy 111.884612 -296.920741)
			(xy 111.914338 -296.966713) (xy 111.937184 -297.016464) (xy 111.952679 -297.068971) (xy 111.960505 -297.123154)
			(xy 111.960501 -297.1779) (xy 111.952667 -297.232082) (xy 111.937164 -297.284587) (xy 111.914312 -297.334334)
			(xy 111.884579 -297.380302) (xy 111.866934 -297.401234) (xy 111.860838 -297.408346) (xy 111.854488 -297.425364)
			(xy 111.854488 -297.510708) (xy 111.860838 -297.527726) (xy 111.866934 -297.534838) (xy 111.884612 -297.555741)
			(xy 111.914338 -297.601713) (xy 111.937184 -297.651464) (xy 111.952679 -297.703971) (xy 111.960505 -297.758154)
			(xy 111.960501 -297.8129) (xy 111.952667 -297.867082) (xy 111.937164 -297.919587) (xy 111.914312 -297.969334)
			(xy 111.884579 -298.015302) (xy 111.866934 -298.036234) (xy 111.860838 -298.043346) (xy 111.854488 -298.060364)
			(xy 111.854488 -298.145708) (xy 111.860838 -298.162726) (xy 111.866934 -298.169838) (xy 111.884563 -298.190778)
			(xy 111.914275 -298.236749) (xy 111.937112 -298.286495) (xy 111.952606 -298.338993) (xy 111.960438 -298.393167)
			(xy 111.960914 -298.420536) (xy 111.960456 -298.447788) (xy 111.952694 -298.501736) (xy 111.937335 -298.554031)
			(xy 111.91469 -298.603608) (xy 111.885221 -298.649458) (xy 111.849526 -298.690648) (xy 111.808334 -298.726339)
			(xy 111.762482 -298.755805) (xy 111.712903 -298.778446) (xy 111.660607 -298.793801) (xy 111.606658 -298.801558)
			(xy 111.579406 -298.802044) (xy 111.552035 -298.801588) (xy 111.497855 -298.79377) (xy 111.445351 -298.778279)
			(xy 111.395605 -298.755435) (xy 111.349639 -298.725707) (xy 111.328708 -298.708064) (xy 111.321596 -298.701968)
			(xy 111.304578 -298.695618) (xy 111.219234 -298.695618) (xy 111.202216 -298.701968) (xy 111.195104 -298.708064)
			(xy 111.174177 -298.725709) (xy 111.128203 -298.755421) (xy 111.078454 -298.778257) (xy 111.025953 -298.793746)
			(xy 110.971776 -298.801572) (xy 110.944406 -298.802044) (xy 110.917157 -298.801517) (xy 110.863212 -298.793762)
			(xy 110.81092 -298.778409) (xy 110.761346 -298.755772) (xy 110.715497 -298.726309) (xy 110.674308 -298.690622)
			(xy 110.638616 -298.649437) (xy 110.609149 -298.603591) (xy 110.586505 -298.554019) (xy 110.571147 -298.501729)
			(xy 110.563386 -298.447785) (xy 110.562898 -298.420536) (xy 109.533182 -298.420536) (xy 109.532693 -298.447785)
			(xy 109.524932 -298.501727) (xy 109.509574 -298.554016) (xy 109.48693 -298.603587) (xy 109.457463 -298.649431)
			(xy 109.421771 -298.690615) (xy 109.380581 -298.7263) (xy 109.334733 -298.75576) (xy 109.285158 -298.778396)
			(xy 109.232867 -298.793746) (xy 109.178923 -298.801498) (xy 109.151674 -298.802044) (xy 109.124305 -298.80157)
			(xy 109.070129 -298.793742) (xy 109.017629 -298.77825) (xy 108.967882 -298.755413) (xy 108.921911 -298.7257)
			(xy 108.900976 -298.708064) (xy 108.893864 -298.701968) (xy 108.876846 -298.695618) (xy 108.791502 -298.695618)
			(xy 108.774484 -298.701968) (xy 108.767372 -298.708064) (xy 108.746441 -298.725706) (xy 108.700474 -298.755431)
			(xy 108.650728 -298.778273) (xy 108.598224 -298.793761) (xy 108.544044 -298.801576) (xy 108.516674 -298.802044)
			(xy 108.489423 -298.801556) (xy 108.435476 -298.793797) (xy 108.383183 -298.77844) (xy 108.333606 -298.755798)
			(xy 108.287757 -298.726332) (xy 108.246566 -298.690641) (xy 108.210874 -298.649451) (xy 108.181407 -298.603603)
			(xy 108.158763 -298.554027) (xy 108.143405 -298.501734) (xy 108.135644 -298.447787) (xy 108.135166 -298.420536)
			(xy 108.135642 -298.393168) (xy 108.143476 -298.338995) (xy 108.158972 -298.286498) (xy 108.181813 -298.236756)
			(xy 108.21153 -298.190789) (xy 108.229146 -298.169838) (xy 108.235242 -298.162726) (xy 108.241592 -298.145708)
			(xy 108.241592 -298.060364) (xy 108.235242 -298.043346) (xy 108.229146 -298.036234) (xy 108.211502 -298.015302)
			(xy 108.181771 -297.969333) (xy 108.158919 -297.919586) (xy 108.143417 -297.867081) (xy 108.135584 -297.8129)
			(xy 108.13558 -297.758155) (xy 108.143406 -297.703972) (xy 108.1589 -297.651465) (xy 108.181744 -297.601714)
			(xy 108.211469 -297.555742) (xy 108.229146 -297.534838) (xy 108.235242 -297.527726) (xy 108.241592 -297.510708)
			(xy 108.241592 -297.425364) (xy 108.235242 -297.408346) (xy 108.229146 -297.401234) (xy 108.211502 -297.380302)
			(xy 108.181771 -297.334333) (xy 108.158919 -297.284586) (xy 108.143417 -297.232081) (xy 108.135584 -297.1779)
			(xy 108.13558 -297.123155) (xy 108.143406 -297.068972) (xy 108.1589 -297.016465) (xy 108.181744 -296.966714)
			(xy 108.211469 -296.920742) (xy 108.229146 -296.899838) (xy 108.235242 -296.892726) (xy 108.241592 -296.875708)
			(xy 108.241592 -296.790364) (xy 108.235242 -296.773346) (xy 108.229146 -296.766234) (xy 108.211502 -296.745302)
			(xy 108.181771 -296.699333) (xy 108.158919 -296.649586) (xy 108.143417 -296.597081) (xy 108.135584 -296.5429)
			(xy 108.13558 -296.488155) (xy 108.143406 -296.433972) (xy 108.1589 -296.381465) (xy 108.181744 -296.331714)
			(xy 108.211469 -296.285742) (xy 108.229146 -296.264838) (xy 108.235242 -296.257726) (xy 108.241592 -296.240708)
			(xy 108.241592 -296.155364) (xy 108.235242 -296.138346) (xy 108.229146 -296.131234) (xy 108.211502 -296.110302)
			(xy 108.181771 -296.064333) (xy 108.158919 -296.014586) (xy 108.143417 -295.962081) (xy 108.135584 -295.9079)
			(xy 108.13558 -295.853155) (xy 108.143406 -295.798972) (xy 108.1589 -295.746465) (xy 108.181744 -295.696714)
			(xy 108.211469 -295.650742) (xy 108.229146 -295.629838) (xy 108.235242 -295.622726) (xy 108.241592 -295.605708)
			(xy 108.241846 -295.52011) (xy 108.235496 -295.503346) (xy 108.229146 -295.496234) (xy 108.211527 -295.475295)
			(xy 108.181849 -295.429318) (xy 108.159057 -295.379568) (xy 108.143619 -295.327067) (xy 108.135854 -295.272898)
			(xy 108.13542 -295.245536) (xy 108.13542 -292.691058) (xy 108.135994 -292.661091) (xy 108.14534 -292.601892)
			(xy 108.163825 -292.544881) (xy 108.190996 -292.491462) (xy 108.226185 -292.442947) (xy 108.246926 -292.42131)
			(xy 109.424978 -291.243512) (xy 109.431829 -291.236115) (xy 109.439571 -291.217517) (xy 109.439964 -291.207444)
			(xy 109.439964 -287.602168) (xy 109.440538 -287.572201) (xy 109.449882 -287.513002) (xy 109.468368 -287.455992)
			(xy 109.495541 -287.402573) (xy 109.530732 -287.35406) (xy 109.55147 -287.33242) (xy 109.71276 -287.17113)
			(xy 109.720066 -287.163184) (xy 109.727827 -287.143062) (xy 109.727746 -287.132268) (xy 109.722666 -287.0454)
			(xy 109.71276 -287.026604) (xy 109.704124 -287.019746) (xy 109.691424 -287.00948) (xy 109.667639 -286.9871)
			(xy 109.656626 -286.975042) (xy 109.648244 -286.965644) (xy 109.624622 -286.957008) (xy 109.515402 -286.972502)
			(xy 109.495082 -286.987234) (xy 109.489494 -286.998918) (xy 109.476023 -287.025861) (xy 109.443363 -287.076479)
			(xy 109.404661 -287.122642) (xy 109.360518 -287.163632) (xy 109.311619 -287.198814) (xy 109.258725 -287.227641)
			(xy 109.202655 -287.249665) (xy 109.144282 -287.264545) (xy 109.084512 -287.272048) (xy 109.054392 -287.272476)
			(xy 109.022761 -287.27198) (xy 108.96004 -287.263722) (xy 108.898934 -287.247347) (xy 108.840488 -287.223136)
			(xy 108.785703 -287.191503) (xy 108.735515 -287.15299) (xy 108.690784 -287.108255) (xy 108.652275 -287.058064)
			(xy 108.620646 -287.003276) (xy 108.59644 -286.944828) (xy 108.58007 -286.88372) (xy 108.571817 -286.820999)
			(xy 108.571284 -286.789368) (xy 108.571284 -286.175196) (xy 108.570809 -286.165229) (xy 108.563235 -286.14679)
			(xy 108.556552 -286.139382) (xy 107.796584 -285.379668) (xy 107.774587 -285.356941) (xy 107.736116 -285.306736)
			(xy 107.704529 -285.251938) (xy 107.680365 -285.193485) (xy 107.664038 -285.132379) (xy 107.655829 -285.069663)
			(xy 107.65536 -285.038038) (xy 107.65536 -284.245304) (xy 107.654822 -284.235317) (xy 107.647105 -284.216888)
			(xy 107.640374 -284.20949) (xy 107.586272 -284.155388) (xy 107.578861 -284.148709) (xy 107.560424 -284.141139)
			(xy 107.550458 -284.140656) (xy 104.586278 -284.140656) (xy 104.552678 -284.140029) (xy 104.48614 -284.1306)
			(xy 104.45369 -284.12186) (xy 104.442768 -284.118812) (xy 104.420416 -284.122368) (xy 104.337104 -284.179518)
			(xy 104.325674 -284.199076) (xy 104.324658 -284.210252) (xy 104.321577 -284.238327) (xy 104.308195 -284.293196)
			(xy 104.286869 -284.345492) (xy 104.258065 -284.394072) (xy 104.222412 -284.437873) (xy 104.180691 -284.475939)
			(xy 104.133813 -284.507437) (xy 104.082803 -284.531679) (xy 104.028776 -284.548134) (xy 103.972913 -284.556443)
			(xy 103.944674 -284.556962) (xy 103.917424 -284.556497) (xy 103.863478 -284.548737) (xy 103.811186 -284.533378)
			(xy 103.761612 -284.510733) (xy 103.715765 -284.481264) (xy 103.67458 -284.44557) (xy 103.638893 -284.404377)
			(xy 103.609432 -284.358525) (xy 103.586797 -284.308947) (xy 103.571448 -284.256652) (xy 103.563698 -284.202705)
			(xy 103.563166 -284.175454) (xy 103.563281 -284.162395) (xy 103.565062 -284.136338) (xy 103.566722 -284.123384)
			(xy 103.568246 -284.112208) (xy 103.56215 -284.09138) (xy 103.504492 -284.02534) (xy 103.496906 -284.0175)
			(xy 103.477036 -284.008543) (xy 103.466138 -284.008068) (xy 103.002334 -284.008068) (xy 102.992371 -284.008553)
			(xy 102.973944 -284.016137) (xy 102.96652 -284.0228) (xy 102.947724 -284.04185) (xy 102.925007 -284.063871)
			(xy 102.874816 -284.102389) (xy 102.820024 -284.134023) (xy 102.76157 -284.158231) (xy 102.700456 -284.174599)
			(xy 102.637728 -284.182847) (xy 102.606094 -284.183328) (xy 99.83851 -284.183328) (xy 99.828489 -284.183746)
			(xy 99.809974 -284.191416) (xy 99.795805 -284.205589) (xy 99.788143 -284.224107) (xy 99.78771 -284.234128)
			(xy 99.78771 -286.343598) (xy 99.788092 -286.35243) (xy 99.794072 -286.369051) (xy 99.799394 -286.37611)
			(xy 99.822762 -286.404558) (xy 99.837748 -286.413448) (xy 99.846384 -286.415226) (xy 99.928067 -286.43244)
			(xy 100.089836 -286.473713) (xy 100.249437 -286.522707) (xy 100.406501 -286.579307) (xy 100.560667 -286.643384)
			(xy 100.711577 -286.71479) (xy 100.858885 -286.79336) (xy 101.00225 -286.878912) (xy 101.141342 -286.97125)
			(xy 101.275839 -287.07016) (xy 101.405432 -287.175415) (xy 101.529821 -287.28677) (xy 101.64872 -287.40397)
			(xy 101.761854 -287.526744) (xy 101.868963 -287.654809) (xy 101.969798 -287.78787) (xy 102.064128 -287.925618)
			(xy 102.151734 -288.067737) (xy 102.232416 -288.213899) (xy 102.305986 -288.363767) (xy 102.372275 -288.516994)
			(xy 102.43113 -288.673227) (xy 102.482415 -288.832106) (xy 102.526011 -288.993265) (xy 102.56182 -289.156331)
			(xy 102.589756 -289.320929) (xy 102.609758 -289.486678) (xy 102.621777 -289.653196) (xy 102.625786 -289.820099)
			(xy 102.621777 -289.987002) (xy 102.609758 -290.153521) (xy 102.589757 -290.31927) (xy 102.56182 -290.483867)
			(xy 102.526012 -290.646933) (xy 102.482415 -290.808092) (xy 102.43113 -290.966971) (xy 102.372275 -291.123205)
			(xy 102.305986 -291.276432) (xy 102.232417 -291.426299) (xy 102.151735 -291.572461) (xy 102.064129 -291.714581)
			(xy 101.969799 -291.852329) (xy 101.868964 -291.985389) (xy 101.761855 -292.113454) (xy 101.648721 -292.236228)
			(xy 101.529823 -292.353429) (xy 101.405433 -292.464784) (xy 101.27584 -292.570039) (xy 101.141343 -292.668949)
			(xy 101.002251 -292.761287) (xy 100.858886 -292.846839) (xy 100.711579 -292.925409) (xy 100.560668 -292.996815)
			(xy 100.406503 -293.060892) (xy 100.249439 -293.117493) (xy 100.089838 -293.166486) (xy 99.928069 -293.20776)
			(xy 99.846384 -293.224966) (xy 99.837748 -293.226744) (xy 99.822762 -293.235634) (xy 99.799394 -293.264082)
			(xy 99.793988 -293.271093) (xy 99.788008 -293.287745) (xy 99.78771 -293.296594) (xy 99.78771 -294.851836)
			(xy 102.046784 -294.851836) (xy 102.050855 -294.796214) (xy 102.062981 -294.741777) (xy 102.082904 -294.689686)
			(xy 102.1102 -294.641051) (xy 102.144286 -294.596908) (xy 102.184435 -294.558199) (xy 102.229793 -294.525748)
			(xy 102.279393 -294.500247) (xy 102.332177 -294.48224) (xy 102.38702 -294.47211) (xy 102.442754 -294.470073)
			(xy 102.498191 -294.476173) (xy 102.552148 -294.490279) (xy 102.603477 -294.512091) (xy 102.651083 -294.541145)
			(xy 102.693951 -294.57682) (xy 102.731168 -294.618357) (xy 102.761941 -294.66487) (xy 102.785613 -294.715367)
			(xy 102.801681 -294.768774) (xy 102.809801 -294.82395) (xy 102.81031 -294.851836) (xy 102.809801 -294.879722)
			(xy 102.801681 -294.934898) (xy 102.785613 -294.988305) (xy 102.761941 -295.038802) (xy 102.731168 -295.085315)
			(xy 102.693951 -295.126852) (xy 102.651083 -295.162527) (xy 102.603477 -295.191581) (xy 102.552148 -295.213393)
			(xy 102.498191 -295.227499) (xy 102.442754 -295.233599) (xy 102.38702 -295.231562) (xy 102.332177 -295.221432)
			(xy 102.279393 -295.203425) (xy 102.229793 -295.177924) (xy 102.184435 -295.145473) (xy 102.144286 -295.106764)
			(xy 102.1102 -295.062621) (xy 102.082904 -295.013986) (xy 102.062981 -294.961895) (xy 102.050855 -294.907458)
			(xy 102.046784 -294.851836) (xy 99.78771 -294.851836) (xy 99.78771 -298.420536) (xy 103.494586 -298.420536)
			(xy 103.495077 -298.393167) (xy 103.502889 -298.338989) (xy 103.518373 -298.286486) (xy 103.541209 -298.236739)
			(xy 103.570928 -298.190771) (xy 103.588566 -298.169838) (xy 103.594662 -298.162726) (xy 103.601012 -298.145708)
			(xy 103.601012 -298.060364) (xy 103.594662 -298.043346) (xy 103.588566 -298.036234) (xy 103.570959 -298.015273)
			(xy 103.54123 -297.969311) (xy 103.51838 -297.91957) (xy 103.502879 -297.867072) (xy 103.495046 -297.812896)
			(xy 103.495042 -297.758158) (xy 103.502868 -297.703981) (xy 103.518361 -297.651481) (xy 103.541204 -297.601736)
			(xy 103.570926 -297.55577) (xy 103.588566 -297.534838) (xy 103.594662 -297.527726) (xy 103.601012 -297.510708)
			(xy 103.601012 -297.425364) (xy 103.594662 -297.408346) (xy 103.588566 -297.401234) (xy 103.570959 -297.380273)
			(xy 103.54123 -297.334311) (xy 103.51838 -297.28457) (xy 103.502879 -297.232072) (xy 103.495046 -297.177896)
			(xy 103.495042 -297.123158) (xy 103.502868 -297.068981) (xy 103.518361 -297.016481) (xy 103.541204 -296.966736)
			(xy 103.570926 -296.92077) (xy 103.588566 -296.899838) (xy 103.594662 -296.892726) (xy 103.601012 -296.875708)
			(xy 103.601012 -296.790364) (xy 103.594662 -296.773346) (xy 103.588566 -296.766234) (xy 103.570959 -296.745273)
			(xy 103.54123 -296.699311) (xy 103.51838 -296.64957) (xy 103.502879 -296.597072) (xy 103.495046 -296.542896)
			(xy 103.495042 -296.488158) (xy 103.502868 -296.433981) (xy 103.518361 -296.381481) (xy 103.541204 -296.331736)
			(xy 103.570926 -296.28577) (xy 103.588566 -296.264838) (xy 103.594662 -296.257726) (xy 103.601012 -296.240708)
			(xy 103.601012 -296.155364) (xy 103.594662 -296.138346) (xy 103.588566 -296.131234) (xy 103.570959 -296.110273)
			(xy 103.54123 -296.064311) (xy 103.51838 -296.01457) (xy 103.502879 -295.962072) (xy 103.495046 -295.907896)
			(xy 103.495042 -295.853158) (xy 103.502868 -295.798981) (xy 103.518361 -295.746481) (xy 103.541204 -295.696736)
			(xy 103.570926 -295.65077) (xy 103.588566 -295.629838) (xy 103.594662 -295.622726) (xy 103.601012 -295.605708)
			(xy 103.601012 -295.520364) (xy 103.594662 -295.503346) (xy 103.588566 -295.496234) (xy 103.570924 -295.475304)
			(xy 103.541214 -295.42933) (xy 103.518379 -295.379582) (xy 103.502888 -295.327081) (xy 103.49506 -295.272905)
			(xy 103.494586 -295.245536) (xy 103.495089 -295.218284) (xy 103.502841 -295.164335) (xy 103.518192 -295.112038)
			(xy 103.54083 -295.062459) (xy 103.570293 -295.016606) (xy 103.605983 -294.975413) (xy 103.647172 -294.939719)
			(xy 103.693022 -294.91025) (xy 103.742599 -294.887607) (xy 103.794894 -294.87225) (xy 103.848842 -294.864492)
			(xy 103.876094 -294.864028) (xy 103.903464 -294.864491) (xy 103.957644 -294.872308) (xy 104.010147 -294.887798)
			(xy 104.059894 -294.91064) (xy 104.105861 -294.940366) (xy 104.126792 -294.958008) (xy 104.133904 -294.964104)
			(xy 104.150922 -294.970454) (xy 104.236266 -294.970454) (xy 104.253284 -294.964104) (xy 104.260396 -294.958008)
			(xy 104.28132 -294.940359) (xy 104.327295 -294.910648) (xy 104.377044 -294.887814) (xy 104.429547 -294.872325)
			(xy 104.483724 -294.8645) (xy 104.511094 -294.864028) (xy 104.538348 -294.864461) (xy 104.592302 -294.872218)
			(xy 104.644603 -294.887575) (xy 104.694185 -294.91022) (xy 104.74004 -294.93969) (xy 104.781234 -294.975387)
			(xy 104.816928 -295.016584) (xy 104.846395 -295.062441) (xy 104.869035 -295.112025) (xy 104.884388 -295.164327)
			(xy 104.892141 -295.218282) (xy 104.892602 -295.245536) (xy 104.892157 -295.272907) (xy 104.884334 -295.327087)
			(xy 104.86884 -295.37959) (xy 104.845993 -295.429337) (xy 104.816265 -295.475303) (xy 104.798622 -295.496234)
			(xy 104.792526 -295.503346) (xy 104.786176 -295.520364) (xy 104.786176 -295.605708) (xy 104.792526 -295.622726)
			(xy 104.798622 -295.629838) (xy 104.816296 -295.650743) (xy 104.846016 -295.696717) (xy 104.868856 -295.746468)
			(xy 104.884347 -295.798974) (xy 104.892171 -295.853155) (xy 104.892167 -295.907899) (xy 104.884336 -295.962079)
			(xy 104.868837 -296.014583) (xy 104.845989 -296.064331) (xy 104.816263 -296.1103) (xy 104.798622 -296.131234)
			(xy 104.792526 -296.138346) (xy 104.786176 -296.155364) (xy 104.786176 -296.240708) (xy 104.792526 -296.257726)
			(xy 104.798622 -296.264838) (xy 104.816296 -296.285743) (xy 104.846016 -296.331717) (xy 104.868856 -296.381468)
			(xy 104.884347 -296.433974) (xy 104.892171 -296.488155) (xy 104.892167 -296.542899) (xy 104.884336 -296.597079)
			(xy 104.868837 -296.649583) (xy 104.845989 -296.699331) (xy 104.816263 -296.7453) (xy 104.798622 -296.766234)
			(xy 104.792526 -296.773346) (xy 104.786176 -296.790364) (xy 104.786176 -296.875708) (xy 104.792526 -296.892726)
			(xy 104.798622 -296.899838) (xy 104.816296 -296.920743) (xy 104.846016 -296.966717) (xy 104.868856 -297.016468)
			(xy 104.884347 -297.068974) (xy 104.892171 -297.123155) (xy 104.892167 -297.177899) (xy 104.884336 -297.232079)
			(xy 104.868837 -297.284583) (xy 104.845989 -297.334331) (xy 104.816263 -297.3803) (xy 104.798622 -297.401234)
			(xy 104.792526 -297.408346) (xy 104.786176 -297.425364) (xy 104.786176 -297.510708) (xy 104.792526 -297.527726)
			(xy 104.798622 -297.534838) (xy 104.816296 -297.555743) (xy 104.846016 -297.601717) (xy 104.868856 -297.651468)
			(xy 104.884347 -297.703974) (xy 104.892171 -297.758155) (xy 104.892167 -297.812899) (xy 104.884336 -297.867079)
			(xy 104.868837 -297.919583) (xy 104.845989 -297.969331) (xy 104.816263 -298.0153) (xy 104.798622 -298.036234)
			(xy 104.792526 -298.043346) (xy 104.786176 -298.060364) (xy 104.786176 -298.145708) (xy 104.792526 -298.162726)
			(xy 104.798622 -298.169838) (xy 104.816249 -298.19078) (xy 104.845962 -298.23675) (xy 104.8688 -298.286495)
			(xy 104.884294 -298.338994) (xy 104.892126 -298.393168) (xy 104.892602 -298.420536) (xy 104.892156 -298.447788)
			(xy 104.884394 -298.501738) (xy 104.869034 -298.554034) (xy 104.846388 -298.603611) (xy 104.816918 -298.649462)
			(xy 104.781222 -298.690652) (xy 104.740028 -298.726343) (xy 104.694175 -298.755808) (xy 104.644594 -298.778449)
			(xy 104.592297 -298.793803) (xy 104.538346 -298.801559) (xy 104.511094 -298.802044) (xy 104.483723 -298.801595)
			(xy 104.429543 -298.793775) (xy 104.377039 -298.778283) (xy 104.327292 -298.755437) (xy 104.281327 -298.725708)
			(xy 104.260396 -298.708064) (xy 104.253284 -298.701968) (xy 104.236266 -298.695618) (xy 104.150922 -298.695618)
			(xy 104.133904 -298.701968) (xy 104.126792 -298.708064) (xy 104.105869 -298.725715) (xy 104.059894 -298.755426)
			(xy 104.010145 -298.77826) (xy 103.957642 -298.793749) (xy 103.903464 -298.801573) (xy 103.876094 -298.802044)
			(xy 103.848844 -298.801528) (xy 103.794899 -298.793772) (xy 103.742607 -298.778417) (xy 103.693033 -298.755778)
			(xy 103.647184 -298.726315) (xy 103.605995 -298.690626) (xy 103.570303 -298.64944) (xy 103.540836 -298.603594)
			(xy 103.518193 -298.554021) (xy 103.502835 -298.50173) (xy 103.495074 -298.447786) (xy 103.494586 -298.420536)
			(xy 99.78771 -298.420536) (xy 99.78771 -301.424086) (xy 102.823518 -301.424086) (xy 102.823971 -301.396715)
			(xy 102.831792 -301.342535) (xy 102.847283 -301.290032) (xy 102.870128 -301.240285) (xy 102.899855 -301.194319)
			(xy 102.917498 -301.173388) (xy 102.923594 -301.166276) (xy 102.929944 -301.149258) (xy 102.929944 -301.063914)
			(xy 102.923594 -301.046896) (xy 102.917498 -301.039784) (xy 102.899845 -301.018862) (xy 102.870123 -300.972891)
			(xy 102.84728 -300.923143) (xy 102.831786 -300.87064) (xy 102.823959 -300.81646) (xy 102.823961 -300.761719)
			(xy 102.831791 -300.707539) (xy 102.847287 -300.655037) (xy 102.870133 -300.60529) (xy 102.899858 -300.559321)
			(xy 102.917498 -300.538388) (xy 102.923594 -300.531276) (xy 102.929944 -300.514258) (xy 102.929944 -300.428914)
			(xy 102.923594 -300.411896) (xy 102.917498 -300.404784) (xy 102.899845 -300.383862) (xy 102.870123 -300.337891)
			(xy 102.84728 -300.288143) (xy 102.831786 -300.23564) (xy 102.823959 -300.18146) (xy 102.823961 -300.126719)
			(xy 102.831791 -300.072539) (xy 102.847287 -300.020037) (xy 102.870133 -299.97029) (xy 102.899858 -299.924321)
			(xy 102.917498 -299.903388) (xy 102.923594 -299.896276) (xy 102.929944 -299.879258) (xy 102.929944 -299.793914)
			(xy 102.923594 -299.776896) (xy 102.917498 -299.769784) (xy 102.899885 -299.748831) (xy 102.870169 -299.702864)
			(xy 102.847328 -299.653122) (xy 102.831831 -299.600626) (xy 102.823996 -299.546454) (xy 102.823518 -299.519086)
			(xy 102.824004 -299.491835) (xy 102.83176 -299.437887) (xy 102.847115 -299.385592) (xy 102.869757 -299.336015)
			(xy 102.899223 -299.290165) (xy 102.934914 -299.248974) (xy 102.976105 -299.213283) (xy 103.021955 -299.183817)
			(xy 103.071532 -299.161175) (xy 103.123827 -299.14582) (xy 103.177775 -299.138064) (xy 103.232277 -299.138064)
			(xy 103.286225 -299.14582) (xy 103.33852 -299.161175) (xy 103.388097 -299.183817) (xy 103.433947 -299.213283)
			(xy 103.475138 -299.248974) (xy 103.510829 -299.290165) (xy 103.540295 -299.336015) (xy 103.562937 -299.385592)
			(xy 103.578292 -299.437887) (xy 103.586048 -299.491835) (xy 103.586534 -299.519086) (xy 103.586076 -299.546457)
			(xy 103.578259 -299.600637) (xy 103.562769 -299.653141) (xy 103.539925 -299.702887) (xy 103.510197 -299.748853)
			(xy 103.492554 -299.769784) (xy 103.486458 -299.776896) (xy 103.480108 -299.793914) (xy 103.480108 -299.879258)
			(xy 103.486458 -299.896276) (xy 103.492554 -299.903388) (xy 103.510182 -299.924331) (xy 103.539909 -299.970297)
			(xy 103.562756 -300.020041) (xy 103.578254 -300.072542) (xy 103.586084 -300.126719) (xy 103.586086 -300.18146)
			(xy 103.578259 -300.235637) (xy 103.562763 -300.288139) (xy 103.539919 -300.337885) (xy 103.510194 -300.383852)
			(xy 103.492554 -300.404784) (xy 103.486458 -300.411896) (xy 103.480108 -300.428914) (xy 103.480108 -300.514258)
			(xy 103.486458 -300.531276) (xy 103.492554 -300.538388) (xy 103.510182 -300.559331) (xy 103.539909 -300.605297)
			(xy 103.562756 -300.655041) (xy 103.578254 -300.707542) (xy 103.586084 -300.761719) (xy 103.586086 -300.81646)
			(xy 103.578259 -300.870637) (xy 103.562763 -300.923139) (xy 103.539919 -300.972885) (xy 103.510194 -301.018852)
			(xy 103.492554 -301.039784) (xy 103.486458 -301.046896) (xy 103.480108 -301.063914) (xy 103.480108 -301.149258)
			(xy 103.486458 -301.166276) (xy 103.492554 -301.173388) (xy 103.510194 -301.19432) (xy 103.539907 -301.240292)
			(xy 103.562744 -301.290039) (xy 103.578234 -301.34254) (xy 103.586061 -301.396717) (xy 103.586534 -301.424086)
			(xy 103.586048 -301.451337) (xy 103.582224 -301.477934) (xy 106.455718 -301.477934) (xy 106.4562 -301.450564)
			(xy 106.464013 -301.396386) (xy 106.479498 -301.343883) (xy 106.502337 -301.294135) (xy 106.532058 -301.248168)
			(xy 106.549698 -301.227236) (xy 106.555794 -301.220124) (xy 106.562144 -301.203106) (xy 106.562144 -301.117762)
			(xy 106.555794 -301.100744) (xy 106.549698 -301.093632) (xy 106.532092 -301.072672) (xy 106.502368 -301.026708)
			(xy 106.479522 -300.976966) (xy 106.464025 -300.924469) (xy 106.456193 -300.870294) (xy 106.45619 -300.815557)
			(xy 106.464014 -300.761382) (xy 106.479504 -300.708882) (xy 106.502343 -300.659137) (xy 106.532061 -300.613169)
			(xy 106.549698 -300.592236) (xy 106.555794 -300.585124) (xy 106.562144 -300.568106) (xy 106.562144 -300.482762)
			(xy 106.555794 -300.465744) (xy 106.549698 -300.458632) (xy 106.532092 -300.437672) (xy 106.502368 -300.391708)
			(xy 106.479522 -300.341966) (xy 106.464025 -300.289469) (xy 106.456193 -300.235294) (xy 106.45619 -300.180557)
			(xy 106.464014 -300.126382) (xy 106.479504 -300.073882) (xy 106.502343 -300.024137) (xy 106.532061 -299.978169)
			(xy 106.549698 -299.957236) (xy 106.555794 -299.950124) (xy 106.562144 -299.933106) (xy 106.562144 -299.847762)
			(xy 106.555794 -299.830744) (xy 106.549698 -299.823632) (xy 106.53206 -299.802699) (xy 106.502348 -299.756726)
			(xy 106.479512 -299.706979) (xy 106.464021 -299.654479) (xy 106.456192 -299.600303) (xy 106.455718 -299.572934)
			(xy 106.456204 -299.545683) (xy 106.46396 -299.491735) (xy 106.479315 -299.43944) (xy 106.501957 -299.389863)
			(xy 106.531423 -299.344013) (xy 106.567114 -299.302822) (xy 106.608305 -299.267131) (xy 106.654155 -299.237665)
			(xy 106.703732 -299.215023) (xy 106.756027 -299.199668) (xy 106.809975 -299.191912) (xy 106.864477 -299.191912)
			(xy 106.918425 -299.199668) (xy 106.97072 -299.215023) (xy 107.020297 -299.237665) (xy 107.066147 -299.267131)
			(xy 107.107338 -299.302822) (xy 107.143029 -299.344013) (xy 107.172495 -299.389863) (xy 107.195137 -299.43944)
			(xy 107.210492 -299.491735) (xy 107.218248 -299.545683) (xy 107.218734 -299.572934) (xy 107.218304 -299.600306)
			(xy 107.21048 -299.654487) (xy 107.194983 -299.706991) (xy 107.172133 -299.756737) (xy 107.1424 -299.802702)
			(xy 107.124754 -299.823632) (xy 107.118658 -299.830744) (xy 107.112308 -299.847762) (xy 107.112308 -299.933106)
			(xy 107.118658 -299.950124) (xy 107.124754 -299.957236) (xy 107.142429 -299.978141) (xy 107.172154 -300.024113)
			(xy 107.194998 -300.073864) (xy 107.210493 -300.126371) (xy 107.218318 -300.180553) (xy 107.218315 -300.235298)
			(xy 107.210482 -300.28948) (xy 107.19498 -300.341984) (xy 107.172129 -300.391732) (xy 107.142398 -300.4377)
			(xy 107.124754 -300.458632) (xy 107.118658 -300.465744) (xy 107.112308 -300.482762) (xy 107.112308 -300.568106)
			(xy 107.118658 -300.585124) (xy 107.124754 -300.592236) (xy 107.142429 -300.613141) (xy 107.172154 -300.659113)
			(xy 107.194998 -300.708864) (xy 107.210493 -300.761371) (xy 107.218318 -300.815553) (xy 107.218315 -300.870298)
			(xy 107.210482 -300.92448) (xy 107.19498 -300.976984) (xy 107.172129 -301.026732) (xy 107.142398 -301.0727)
			(xy 107.124754 -301.093632) (xy 107.118658 -301.100744) (xy 107.112308 -301.117762) (xy 107.112308 -301.203106)
			(xy 107.118658 -301.220124) (xy 107.124754 -301.227236) (xy 107.142369 -301.248187) (xy 107.172086 -301.294154)
			(xy 107.194928 -301.343897) (xy 107.210424 -301.396393) (xy 107.214428 -301.424086) (xy 109.663738 -301.424086)
			(xy 109.664187 -301.396715) (xy 109.672007 -301.342535) (xy 109.6875 -301.290031) (xy 109.710346 -301.240285)
			(xy 109.740075 -301.194319) (xy 109.757718 -301.173388) (xy 109.763814 -301.166276) (xy 109.770164 -301.149258)
			(xy 109.770164 -301.063914) (xy 109.763814 -301.046896) (xy 109.757718 -301.039784) (xy 109.740064 -301.018862)
			(xy 109.71034 -300.972892) (xy 109.687496 -300.923144) (xy 109.672002 -300.870641) (xy 109.664175 -300.816461)
			(xy 109.664176 -300.761718) (xy 109.672006 -300.707539) (xy 109.687504 -300.655036) (xy 109.710351 -300.605289)
			(xy 109.740077 -300.559321) (xy 109.757718 -300.538388) (xy 109.763814 -300.531276) (xy 109.770164 -300.514258)
			(xy 109.770164 -300.428914) (xy 109.763814 -300.411896) (xy 109.757718 -300.404784) (xy 109.740064 -300.383862)
			(xy 109.71034 -300.337892) (xy 109.687496 -300.288144) (xy 109.672002 -300.235641) (xy 109.664175 -300.181461)
			(xy 109.664176 -300.126718) (xy 109.672006 -300.072539) (xy 109.687504 -300.020036) (xy 109.710351 -299.970289)
			(xy 109.740077 -299.924321) (xy 109.757718 -299.903388) (xy 109.763814 -299.896276) (xy 109.770164 -299.879258)
			(xy 109.770164 -299.793914) (xy 109.763814 -299.776896) (xy 109.757718 -299.769784) (xy 109.740108 -299.748829)
			(xy 109.710391 -299.702863) (xy 109.687549 -299.653121) (xy 109.672051 -299.600625) (xy 109.664216 -299.546454)
			(xy 109.663738 -299.519086) (xy 109.664224 -299.491835) (xy 109.67198 -299.437887) (xy 109.687335 -299.385592)
			(xy 109.709977 -299.336015) (xy 109.739443 -299.290165) (xy 109.775134 -299.248974) (xy 109.816325 -299.213283)
			(xy 109.862175 -299.183817) (xy 109.911752 -299.161175) (xy 109.964047 -299.14582) (xy 110.017995 -299.138064)
			(xy 110.072497 -299.138064) (xy 110.126445 -299.14582) (xy 110.17874 -299.161175) (xy 110.228317 -299.183817)
			(xy 110.274167 -299.213283) (xy 110.315358 -299.248974) (xy 110.351049 -299.290165) (xy 110.380515 -299.336015)
			(xy 110.403157 -299.385592) (xy 110.418512 -299.437887) (xy 110.426268 -299.491835) (xy 110.426754 -299.519086)
			(xy 110.426291 -299.546456) (xy 110.418474 -299.600636) (xy 110.402985 -299.65314) (xy 110.380142 -299.702887)
			(xy 110.350416 -299.748853) (xy 110.332774 -299.769784) (xy 110.326678 -299.776896) (xy 110.320328 -299.793914)
			(xy 110.320328 -299.879258) (xy 110.326678 -299.896276) (xy 110.332774 -299.903388) (xy 110.350401 -299.924332)
			(xy 110.380126 -299.970298) (xy 110.402972 -300.020042) (xy 110.41847 -300.072543) (xy 110.4263 -300.12672)
			(xy 110.426301 -300.181459) (xy 110.418474 -300.235637) (xy 110.40298 -300.288138) (xy 110.380136 -300.337884)
			(xy 110.350414 -300.383851) (xy 110.332774 -300.404784) (xy 110.326678 -300.411896) (xy 110.320328 -300.428914)
			(xy 110.320328 -300.514258) (xy 110.326678 -300.531276) (xy 110.332774 -300.538388) (xy 110.350401 -300.559332)
			(xy 110.380126 -300.605298) (xy 110.402972 -300.655042) (xy 110.41847 -300.707543) (xy 110.4263 -300.76172)
			(xy 110.426301 -300.816459) (xy 110.418474 -300.870637) (xy 110.40298 -300.923138) (xy 110.380136 -300.972884)
			(xy 110.350414 -301.018851) (xy 110.332774 -301.039784) (xy 110.326678 -301.046896) (xy 110.320328 -301.063914)
			(xy 110.320328 -301.149258) (xy 110.326678 -301.166276) (xy 110.332774 -301.173388) (xy 110.350417 -301.194317)
			(xy 110.380129 -301.24029) (xy 110.402965 -301.290039) (xy 110.418455 -301.34254) (xy 110.426281 -301.396717)
			(xy 110.426754 -301.424086) (xy 110.426268 -301.451337) (xy 110.422444 -301.477934) (xy 113.295938 -301.477934)
			(xy 113.296415 -301.450564) (xy 113.304229 -301.396385) (xy 113.319715 -301.343882) (xy 113.342554 -301.294135)
			(xy 113.372277 -301.248168) (xy 113.389918 -301.227236) (xy 113.396014 -301.220124) (xy 113.402364 -301.203106)
			(xy 113.402364 -301.117762) (xy 113.396014 -301.100744) (xy 113.389918 -301.093632) (xy 113.372311 -301.072672)
			(xy 113.342586 -301.026709) (xy 113.319739 -300.976967) (xy 113.30424 -300.924469) (xy 113.296409 -300.870294)
			(xy 113.296405 -300.815557) (xy 113.304229 -300.761381) (xy 113.319721 -300.708881) (xy 113.342561 -300.659136)
			(xy 113.37228 -300.613169) (xy 113.389918 -300.592236) (xy 113.396014 -300.585124) (xy 113.402364 -300.568106)
			(xy 113.402364 -300.482762) (xy 113.396014 -300.465744) (xy 113.389918 -300.458632) (xy 113.372311 -300.437672)
			(xy 113.342586 -300.391709) (xy 113.319739 -300.341967) (xy 113.30424 -300.289469) (xy 113.296409 -300.235294)
			(xy 113.296405 -300.180557) (xy 113.304229 -300.126381) (xy 113.319721 -300.073881) (xy 113.342561 -300.024136)
			(xy 113.37228 -299.978169) (xy 113.389918 -299.957236) (xy 113.396014 -299.950124) (xy 113.402364 -299.933106)
			(xy 113.402364 -299.847762) (xy 113.396014 -299.830744) (xy 113.389918 -299.823632) (xy 113.372283 -299.802696)
			(xy 113.34257 -299.756725) (xy 113.319733 -299.706978) (xy 113.304241 -299.654478) (xy 113.296412 -299.600303)
			(xy 113.295938 -299.572934) (xy 113.296424 -299.545683) (xy 113.30418 -299.491735) (xy 113.319535 -299.43944)
			(xy 113.342177 -299.389863) (xy 113.371643 -299.344013) (xy 113.407334 -299.302822) (xy 113.448525 -299.267131)
			(xy 113.494375 -299.237665) (xy 113.543952 -299.215023) (xy 113.596247 -299.199668) (xy 113.650195 -299.191912)
			(xy 113.704697 -299.191912) (xy 113.758645 -299.199668) (xy 113.81094 -299.215023) (xy 113.860517 -299.237665)
			(xy 113.906367 -299.267131) (xy 113.947558 -299.302822) (xy 113.983249 -299.344013) (xy 114.012715 -299.389863)
			(xy 114.035357 -299.43944) (xy 114.050712 -299.491735) (xy 114.058468 -299.545683) (xy 114.058954 -299.572934)
			(xy 114.058519 -299.600305) (xy 114.050695 -299.654486) (xy 114.0352 -299.70699) (xy 114.012351 -299.756737)
			(xy 113.982619 -299.802702) (xy 113.964974 -299.823632) (xy 113.958878 -299.830744) (xy 113.952528 -299.847762)
			(xy 113.952528 -299.933106) (xy 113.958878 -299.950124) (xy 113.964974 -299.957236) (xy 113.982648 -299.978142)
			(xy 114.012371 -300.024114) (xy 114.035215 -300.073865) (xy 114.050708 -300.126371) (xy 114.058534 -300.180553)
			(xy 114.05853 -300.235298) (xy 114.050697 -300.289479) (xy 114.035197 -300.341983) (xy 114.012347 -300.391731)
			(xy 113.982617 -300.437699) (xy 113.964974 -300.458632) (xy 113.958878 -300.465744) (xy 113.952528 -300.482762)
			(xy 113.952528 -300.568106) (xy 113.958878 -300.585124) (xy 113.964974 -300.592236) (xy 113.982648 -300.613142)
			(xy 114.012371 -300.659114) (xy 114.035215 -300.708865) (xy 114.050708 -300.761371) (xy 114.058534 -300.815553)
			(xy 114.05853 -300.870298) (xy 114.050697 -300.924479) (xy 114.035197 -300.976983) (xy 114.012347 -301.026731)
			(xy 113.982617 -301.072699) (xy 113.964974 -301.093632) (xy 113.958878 -301.100744) (xy 113.952528 -301.117762)
			(xy 113.952528 -301.203106) (xy 113.958878 -301.220124) (xy 113.964974 -301.227236) (xy 113.982593 -301.248185)
			(xy 114.012308 -301.294153) (xy 114.035149 -301.343896) (xy 114.050644 -301.396393) (xy 114.054649 -301.424086)
			(xy 121.416826 -301.424086) (xy 121.417278 -301.396715) (xy 121.425098 -301.342535) (xy 121.44059 -301.290032)
			(xy 121.463435 -301.240285) (xy 121.493163 -301.194319) (xy 121.510806 -301.173388) (xy 121.516902 -301.166276)
			(xy 121.523252 -301.149258) (xy 121.523252 -301.063914) (xy 121.516902 -301.046896) (xy 121.510806 -301.039784)
			(xy 121.493152 -301.018862) (xy 121.46343 -300.972892) (xy 121.440587 -300.923144) (xy 121.425092 -300.87064)
			(xy 121.417265 -300.81646) (xy 121.417267 -300.761718) (xy 121.425097 -300.707539) (xy 121.440594 -300.655037)
			(xy 121.46344 -300.60529) (xy 121.493165 -300.559321) (xy 121.510806 -300.538388) (xy 121.516902 -300.531276)
			(xy 121.523252 -300.514258) (xy 121.523252 -300.428914) (xy 121.516902 -300.411896) (xy 121.510806 -300.404784)
			(xy 121.493152 -300.383862) (xy 121.46343 -300.337892) (xy 121.440587 -300.288144) (xy 121.425092 -300.23564)
			(xy 121.417265 -300.18146) (xy 121.417267 -300.126718) (xy 121.425097 -300.072539) (xy 121.440594 -300.020037)
			(xy 121.46344 -299.97029) (xy 121.493165 -299.924321) (xy 121.510806 -299.903388) (xy 121.516902 -299.896276)
			(xy 121.523252 -299.879258) (xy 121.523252 -299.793914) (xy 121.516902 -299.776896) (xy 121.510806 -299.769784)
			(xy 121.493194 -299.74883) (xy 121.463478 -299.702864) (xy 121.440636 -299.653122) (xy 121.425139 -299.600626)
			(xy 121.417304 -299.546454) (xy 121.416826 -299.519086) (xy 121.417312 -299.491835) (xy 121.425068 -299.437887)
			(xy 121.440423 -299.385592) (xy 121.463065 -299.336015) (xy 121.492531 -299.290165) (xy 121.528222 -299.248974)
			(xy 121.569413 -299.213283) (xy 121.615263 -299.183817) (xy 121.66484 -299.161175) (xy 121.717135 -299.14582)
			(xy 121.771083 -299.138064) (xy 121.825585 -299.138064) (xy 121.879533 -299.14582) (xy 121.931828 -299.161175)
			(xy 121.981405 -299.183817) (xy 122.027255 -299.213283) (xy 122.068446 -299.248974) (xy 122.104137 -299.290165)
			(xy 122.133603 -299.336015) (xy 122.156245 -299.385592) (xy 122.1716 -299.437887) (xy 122.179356 -299.491835)
			(xy 122.179842 -299.519086) (xy 122.179382 -299.546457) (xy 122.171565 -299.600637) (xy 122.156075 -299.65314)
			(xy 122.133232 -299.702887) (xy 122.103505 -299.748853) (xy 122.085862 -299.769784) (xy 122.079766 -299.776896)
			(xy 122.073416 -299.793914) (xy 122.073416 -299.879258) (xy 122.079766 -299.896276) (xy 122.085862 -299.903388)
			(xy 122.103489 -299.924332) (xy 122.133216 -299.970297) (xy 122.156062 -300.020042) (xy 122.17156 -300.072542)
			(xy 122.17939 -300.126719) (xy 122.179392 -300.18146) (xy 122.171565 -300.235637) (xy 122.15607 -300.288139)
			(xy 122.133226 -300.337884) (xy 122.103502 -300.383852) (xy 122.085862 -300.404784) (xy 122.079766 -300.411896)
			(xy 122.073416 -300.428914) (xy 122.073416 -300.514258) (xy 122.079766 -300.531276) (xy 122.085862 -300.538388)
			(xy 122.103489 -300.559332) (xy 122.133216 -300.605297) (xy 122.156062 -300.655042) (xy 122.17156 -300.707542)
			(xy 122.17939 -300.761719) (xy 122.179392 -300.81646) (xy 122.171565 -300.870637) (xy 122.15607 -300.923139)
			(xy 122.133226 -300.972884) (xy 122.103502 -301.018852) (xy 122.085862 -301.039784) (xy 122.079766 -301.046896)
			(xy 122.073416 -301.063914) (xy 122.073416 -301.149258) (xy 122.079766 -301.166276) (xy 122.085862 -301.173388)
			(xy 122.103503 -301.194319) (xy 122.133216 -301.240291) (xy 122.156052 -301.290039) (xy 122.171543 -301.34254)
			(xy 122.179369 -301.396717) (xy 122.179842 -301.424086) (xy 122.179356 -301.451337) (xy 122.175532 -301.477934)
			(xy 125.049026 -301.477934) (xy 125.049506 -301.450564) (xy 125.057319 -301.396385) (xy 125.072805 -301.343882)
			(xy 125.095644 -301.294135) (xy 125.125366 -301.248168) (xy 125.143006 -301.227236) (xy 125.149102 -301.220124)
			(xy 125.155452 -301.203106) (xy 125.155452 -301.117762) (xy 125.149102 -301.100744) (xy 125.143006 -301.093632)
			(xy 125.125399 -301.072672) (xy 125.095675 -301.026708) (xy 125.072829 -300.976966) (xy 125.057331 -300.924469)
			(xy 125.0495 -300.870294) (xy 125.049496 -300.815557) (xy 125.05732 -300.761381) (xy 125.072811 -300.708882)
			(xy 125.09565 -300.659137) (xy 125.125369 -300.613169) (xy 125.143006 -300.592236) (xy 125.149102 -300.585124)
			(xy 125.155452 -300.568106) (xy 125.155452 -300.482762) (xy 125.149102 -300.465744) (xy 125.143006 -300.458632)
			(xy 125.125399 -300.437672) (xy 125.095675 -300.391708) (xy 125.072829 -300.341966) (xy 125.057331 -300.289469)
			(xy 125.0495 -300.235294) (xy 125.049496 -300.180557) (xy 125.05732 -300.126381) (xy 125.072811 -300.073882)
			(xy 125.09565 -300.024137) (xy 125.125369 -299.978169) (xy 125.143006 -299.957236) (xy 125.149102 -299.950124)
			(xy 125.155452 -299.933106) (xy 125.155452 -299.847762) (xy 125.149102 -299.830744) (xy 125.143006 -299.823632)
			(xy 125.125369 -299.802698) (xy 125.095657 -299.756726) (xy 125.07282 -299.706979) (xy 125.057329 -299.654479)
			(xy 125.0495 -299.600303) (xy 125.049026 -299.572934) (xy 125.049512 -299.545683) (xy 125.057268 -299.491735)
			(xy 125.072623 -299.43944) (xy 125.095265 -299.389863) (xy 125.124731 -299.344013) (xy 125.160422 -299.302822)
			(xy 125.201613 -299.267131) (xy 125.247463 -299.237665) (xy 125.29704 -299.215023) (xy 125.349335 -299.199668)
			(xy 125.403283 -299.191912) (xy 125.457785 -299.191912) (xy 125.511733 -299.199668) (xy 125.564028 -299.215023)
			(xy 125.613605 -299.237665) (xy 125.659455 -299.267131) (xy 125.700646 -299.302822) (xy 125.736337 -299.344013)
			(xy 125.765803 -299.389863) (xy 125.788445 -299.43944) (xy 125.8038 -299.491735) (xy 125.811556 -299.545683)
			(xy 125.812042 -299.572934) (xy 125.81161 -299.600306) (xy 125.803786 -299.654487) (xy 125.78829 -299.706991)
			(xy 125.76544 -299.756737) (xy 125.735707 -299.802702) (xy 125.718062 -299.823632) (xy 125.711966 -299.830744)
			(xy 125.705616 -299.847762) (xy 125.705616 -299.933106) (xy 125.711966 -299.950124) (xy 125.718062 -299.957236)
			(xy 125.735736 -299.978142) (xy 125.765461 -300.024114) (xy 125.788305 -300.073864) (xy 125.803799 -300.126371)
			(xy 125.811625 -300.180553) (xy 125.811621 -300.235298) (xy 125.803788 -300.289479) (xy 125.788287 -300.341984)
			(xy 125.765436 -300.391731) (xy 125.735706 -300.437699) (xy 125.718062 -300.458632) (xy 125.711966 -300.465744)
			(xy 125.705616 -300.482762) (xy 125.705616 -300.568106) (xy 125.711966 -300.585124) (xy 125.718062 -300.592236)
			(xy 125.735736 -300.613142) (xy 125.765461 -300.659114) (xy 125.788305 -300.708864) (xy 125.803799 -300.761371)
			(xy 125.811625 -300.815553) (xy 125.811621 -300.870298) (xy 125.803788 -300.924479) (xy 125.788287 -300.976984)
			(xy 125.765436 -301.026731) (xy 125.735706 -301.072699) (xy 125.718062 -301.093632) (xy 125.711966 -301.100744)
			(xy 125.705616 -301.117762) (xy 125.705616 -301.203106) (xy 125.711966 -301.220124) (xy 125.718062 -301.227236)
			(xy 125.735679 -301.248186) (xy 125.765395 -301.294153) (xy 125.788236 -301.343896) (xy 125.803732 -301.396393)
			(xy 125.807736 -301.424086) (xy 128.257046 -301.424086) (xy 128.257493 -301.396715) (xy 128.265313 -301.342535)
			(xy 128.280806 -301.290031) (xy 128.303653 -301.240284) (xy 128.333382 -301.194319) (xy 128.351026 -301.173388)
			(xy 128.357122 -301.166276) (xy 128.363472 -301.149258) (xy 128.363472 -301.063914) (xy 128.357122 -301.046896)
			(xy 128.351026 -301.039784) (xy 128.333372 -301.018862) (xy 128.303647 -300.972893) (xy 128.280803 -300.923145)
			(xy 128.265308 -300.870641) (xy 128.257481 -300.816461) (xy 128.257482 -300.761718) (xy 128.265312 -300.707539)
			(xy 128.28081 -300.655036) (xy 128.303658 -300.605289) (xy 128.333384 -300.559321) (xy 128.351026 -300.538388)
			(xy 128.357122 -300.531276) (xy 128.363472 -300.514258) (xy 128.363472 -300.428914) (xy 128.357122 -300.411896)
			(xy 128.351026 -300.404784) (xy 128.333372 -300.383862) (xy 128.303647 -300.337893) (xy 128.280803 -300.288145)
			(xy 128.265308 -300.235641) (xy 128.257481 -300.181461) (xy 128.257482 -300.126718) (xy 128.265312 -300.072539)
			(xy 128.28081 -300.020036) (xy 128.303658 -299.970289) (xy 128.333384 -299.924321) (xy 128.351026 -299.903388)
			(xy 128.357122 -299.896276) (xy 128.363472 -299.879258) (xy 128.363472 -299.793914) (xy 128.357122 -299.776896)
			(xy 128.351026 -299.769784) (xy 128.333417 -299.748828) (xy 128.3037 -299.702862) (xy 128.280858 -299.653121)
			(xy 128.26536 -299.600625) (xy 128.257524 -299.546454) (xy 128.257046 -299.519086) (xy 128.257532 -299.491835)
			(xy 128.265288 -299.437887) (xy 128.280643 -299.385592) (xy 128.303285 -299.336015) (xy 128.332751 -299.290165)
			(xy 128.368442 -299.248974) (xy 128.409633 -299.213283) (xy 128.455483 -299.183817) (xy 128.50506 -299.161175)
			(xy 128.557355 -299.14582) (xy 128.611303 -299.138064) (xy 128.665805 -299.138064) (xy 128.719753 -299.14582)
			(xy 128.772048 -299.161175) (xy 128.821625 -299.183817) (xy 128.867475 -299.213283) (xy 128.908666 -299.248974)
			(xy 128.944357 -299.290165) (xy 128.973823 -299.336015) (xy 128.996465 -299.385592) (xy 129.01182 -299.437887)
			(xy 129.019576 -299.491835) (xy 129.020062 -299.519086) (xy 129.019597 -299.546456) (xy 129.01178 -299.600636)
			(xy 128.996292 -299.653139) (xy 128.973449 -299.702886) (xy 128.943724 -299.748853) (xy 128.926082 -299.769784)
			(xy 128.919986 -299.776896) (xy 128.913636 -299.793914) (xy 128.913636 -299.879258) (xy 128.919986 -299.896276)
			(xy 128.926082 -299.903388) (xy 128.943709 -299.924332) (xy 128.973433 -299.970298) (xy 128.996279 -300.020043)
			(xy 129.011776 -300.072543) (xy 129.019606 -300.12672) (xy 129.019607 -300.181459) (xy 129.01178 -300.235637)
			(xy 128.996286 -300.288138) (xy 128.973443 -300.337883) (xy 128.943721 -300.383851) (xy 128.926082 -300.404784)
			(xy 128.919986 -300.411896) (xy 128.913636 -300.428914) (xy 128.913636 -300.514258) (xy 128.919986 -300.531276)
			(xy 128.926082 -300.538388) (xy 128.943709 -300.559332) (xy 128.973433 -300.605298) (xy 128.996279 -300.655043)
			(xy 129.011776 -300.707543) (xy 129.019606 -300.76172) (xy 129.019607 -300.816459) (xy 129.01178 -300.870637)
			(xy 128.996286 -300.923138) (xy 128.973443 -300.972883) (xy 128.943721 -301.018851) (xy 128.926082 -301.039784)
			(xy 128.919986 -301.046896) (xy 128.913636 -301.063914) (xy 128.913636 -301.149258) (xy 128.919986 -301.166276)
			(xy 128.926082 -301.173388) (xy 128.943726 -301.194316) (xy 128.973438 -301.24029) (xy 128.996273 -301.290038)
			(xy 129.011763 -301.34254) (xy 129.019589 -301.396717) (xy 129.020062 -301.424086) (xy 129.019576 -301.451337)
			(xy 129.015752 -301.477934) (xy 131.889246 -301.477934) (xy 131.889721 -301.450564) (xy 131.897535 -301.396385)
			(xy 131.913021 -301.343881) (xy 131.935861 -301.294134) (xy 131.965585 -301.248168) (xy 131.983226 -301.227236)
			(xy 131.989322 -301.220124) (xy 131.995672 -301.203106) (xy 131.995672 -301.117762) (xy 131.989322 -301.100744)
			(xy 131.983226 -301.093632) (xy 131.965619 -301.072672) (xy 131.935893 -301.026709) (xy 131.913045 -300.976967)
			(xy 131.897546 -300.924469) (xy 131.889715 -300.870295) (xy 131.889711 -300.815557) (xy 131.897535 -300.761381)
			(xy 131.913027 -300.708881) (xy 131.935868 -300.659136) (xy 131.965588 -300.613169) (xy 131.983226 -300.592236)
			(xy 131.989322 -300.585124) (xy 131.995672 -300.568106) (xy 131.995672 -300.482762) (xy 131.989322 -300.465744)
			(xy 131.983226 -300.458632) (xy 131.965619 -300.437672) (xy 131.935893 -300.391709) (xy 131.913045 -300.341967)
			(xy 131.897546 -300.289469) (xy 131.889715 -300.235295) (xy 131.889711 -300.180557) (xy 131.897535 -300.126381)
			(xy 131.913027 -300.073881) (xy 131.935868 -300.024136) (xy 131.965588 -299.978169) (xy 131.983226 -299.957236)
			(xy 131.989322 -299.950124) (xy 131.995672 -299.933106) (xy 131.995672 -299.847762) (xy 131.989322 -299.830744)
			(xy 131.983226 -299.823632) (xy 131.965592 -299.802695) (xy 131.935879 -299.756724) (xy 131.913041 -299.706978)
			(xy 131.897549 -299.654478) (xy 131.88972 -299.600303) (xy 131.889246 -299.572934) (xy 131.889732 -299.545683)
			(xy 131.897488 -299.491735) (xy 131.912843 -299.43944) (xy 131.935485 -299.389863) (xy 131.964951 -299.344013)
			(xy 132.000642 -299.302822) (xy 132.041833 -299.267131) (xy 132.087683 -299.237665) (xy 132.13726 -299.215023)
			(xy 132.189555 -299.199668) (xy 132.243503 -299.191912) (xy 132.298005 -299.191912) (xy 132.351953 -299.199668)
			(xy 132.404248 -299.215023) (xy 132.453825 -299.237665) (xy 132.499675 -299.267131) (xy 132.540866 -299.302822)
			(xy 132.576557 -299.344013) (xy 132.606023 -299.389863) (xy 132.628665 -299.43944) (xy 132.64402 -299.491735)
			(xy 132.651776 -299.545683) (xy 132.652262 -299.572934) (xy 132.651825 -299.600305) (xy 132.644002 -299.654486)
			(xy 132.628506 -299.70699) (xy 132.605658 -299.756736) (xy 132.575927 -299.802702) (xy 132.558282 -299.823632)
			(xy 132.552186 -299.830744) (xy 132.545836 -299.847762) (xy 132.545836 -299.933106) (xy 132.552186 -299.950124)
			(xy 132.558282 -299.957236) (xy 132.575956 -299.978142) (xy 132.605678 -300.024115) (xy 132.628521 -300.073865)
			(xy 132.644014 -300.126371) (xy 132.65184 -300.180553) (xy 132.651836 -300.235298) (xy 132.644003 -300.289479)
			(xy 132.628503 -300.341983) (xy 132.605654 -300.39173) (xy 132.575925 -300.437699) (xy 132.558282 -300.458632)
			(xy 132.552186 -300.465744) (xy 132.545836 -300.482762) (xy 132.545836 -300.568106) (xy 132.552186 -300.585124)
			(xy 132.558282 -300.592236) (xy 132.575956 -300.613142) (xy 132.605678 -300.659115) (xy 132.628521 -300.708865)
			(xy 132.644014 -300.761371) (xy 132.65184 -300.815553) (xy 132.651836 -300.870298) (xy 132.644003 -300.924479)
			(xy 132.628503 -300.976983) (xy 132.605654 -301.02673) (xy 132.575925 -301.072699) (xy 132.558282 -301.093632)
			(xy 132.552186 -301.100744) (xy 132.545836 -301.117762) (xy 132.545836 -301.203106) (xy 132.552186 -301.220124)
			(xy 132.558282 -301.227236) (xy 132.575902 -301.248184) (xy 132.605617 -301.294152) (xy 132.628457 -301.343895)
			(xy 132.643953 -301.396393) (xy 132.651786 -301.450566) (xy 132.652262 -301.477934) (xy 132.651776 -301.505185)
			(xy 132.64402 -301.559133) (xy 132.628665 -301.611428) (xy 132.606023 -301.661005) (xy 132.576557 -301.706855)
			(xy 132.540866 -301.748046) (xy 132.499675 -301.783737) (xy 132.453825 -301.813203) (xy 132.404248 -301.835845)
			(xy 132.351953 -301.8512) (xy 132.298005 -301.858956) (xy 132.243503 -301.858956) (xy 132.189555 -301.8512)
			(xy 132.13726 -301.835845) (xy 132.087683 -301.813203) (xy 132.041833 -301.783737) (xy 132.000642 -301.748046)
			(xy 131.964951 -301.706855) (xy 131.935485 -301.661005) (xy 131.912843 -301.611428) (xy 131.897488 -301.559133)
			(xy 131.889732 -301.505185) (xy 131.889246 -301.477934) (xy 129.015752 -301.477934) (xy 129.01182 -301.505285)
			(xy 128.996465 -301.55758) (xy 128.973823 -301.607157) (xy 128.944357 -301.653007) (xy 128.908666 -301.694198)
			(xy 128.867475 -301.729889) (xy 128.821625 -301.759355) (xy 128.772048 -301.781997) (xy 128.719753 -301.797352)
			(xy 128.665805 -301.805108) (xy 128.611303 -301.805108) (xy 128.557355 -301.797352) (xy 128.50506 -301.781997)
			(xy 128.455483 -301.759355) (xy 128.409633 -301.729889) (xy 128.368442 -301.694198) (xy 128.332751 -301.653007)
			(xy 128.303285 -301.607157) (xy 128.280643 -301.55758) (xy 128.265288 -301.505285) (xy 128.257532 -301.451337)
			(xy 128.257046 -301.424086) (xy 125.807736 -301.424086) (xy 125.811565 -301.450566) (xy 125.812042 -301.477934)
			(xy 125.811556 -301.505185) (xy 125.8038 -301.559133) (xy 125.788445 -301.611428) (xy 125.765803 -301.661005)
			(xy 125.736337 -301.706855) (xy 125.700646 -301.748046) (xy 125.659455 -301.783737) (xy 125.613605 -301.813203)
			(xy 125.564028 -301.835845) (xy 125.511733 -301.8512) (xy 125.457785 -301.858956) (xy 125.403283 -301.858956)
			(xy 125.349335 -301.8512) (xy 125.29704 -301.835845) (xy 125.247463 -301.813203) (xy 125.201613 -301.783737)
			(xy 125.160422 -301.748046) (xy 125.124731 -301.706855) (xy 125.095265 -301.661005) (xy 125.072623 -301.611428)
			(xy 125.057268 -301.559133) (xy 125.049512 -301.505185) (xy 125.049026 -301.477934) (xy 122.175532 -301.477934)
			(xy 122.1716 -301.505285) (xy 122.156245 -301.55758) (xy 122.133603 -301.607157) (xy 122.104137 -301.653007)
			(xy 122.068446 -301.694198) (xy 122.027255 -301.729889) (xy 121.981405 -301.759355) (xy 121.931828 -301.781997)
			(xy 121.879533 -301.797352) (xy 121.825585 -301.805108) (xy 121.771083 -301.805108) (xy 121.717135 -301.797352)
			(xy 121.66484 -301.781997) (xy 121.615263 -301.759355) (xy 121.569413 -301.729889) (xy 121.528222 -301.694198)
			(xy 121.492531 -301.653007) (xy 121.463065 -301.607157) (xy 121.440423 -301.55758) (xy 121.425068 -301.505285)
			(xy 121.417312 -301.451337) (xy 121.416826 -301.424086) (xy 114.054649 -301.424086) (xy 114.058478 -301.450566)
			(xy 114.058954 -301.477934) (xy 114.058468 -301.505185) (xy 114.050712 -301.559133) (xy 114.035357 -301.611428)
			(xy 114.012715 -301.661005) (xy 113.983249 -301.706855) (xy 113.947558 -301.748046) (xy 113.906367 -301.783737)
			(xy 113.860517 -301.813203) (xy 113.81094 -301.835845) (xy 113.758645 -301.8512) (xy 113.704697 -301.858956)
			(xy 113.650195 -301.858956) (xy 113.596247 -301.8512) (xy 113.543952 -301.835845) (xy 113.494375 -301.813203)
			(xy 113.448525 -301.783737) (xy 113.407334 -301.748046) (xy 113.371643 -301.706855) (xy 113.342177 -301.661005)
			(xy 113.319535 -301.611428) (xy 113.30418 -301.559133) (xy 113.296424 -301.505185) (xy 113.295938 -301.477934)
			(xy 110.422444 -301.477934) (xy 110.418512 -301.505285) (xy 110.403157 -301.55758) (xy 110.380515 -301.607157)
			(xy 110.351049 -301.653007) (xy 110.315358 -301.694198) (xy 110.274167 -301.729889) (xy 110.228317 -301.759355)
			(xy 110.17874 -301.781997) (xy 110.126445 -301.797352) (xy 110.072497 -301.805108) (xy 110.017995 -301.805108)
			(xy 109.964047 -301.797352) (xy 109.911752 -301.781997) (xy 109.862175 -301.759355) (xy 109.816325 -301.729889)
			(xy 109.775134 -301.694198) (xy 109.739443 -301.653007) (xy 109.709977 -301.607157) (xy 109.687335 -301.55758)
			(xy 109.67198 -301.505285) (xy 109.664224 -301.451337) (xy 109.663738 -301.424086) (xy 107.214428 -301.424086)
			(xy 107.218257 -301.450566) (xy 107.218734 -301.477934) (xy 107.218248 -301.505185) (xy 107.210492 -301.559133)
			(xy 107.195137 -301.611428) (xy 107.172495 -301.661005) (xy 107.143029 -301.706855) (xy 107.107338 -301.748046)
			(xy 107.066147 -301.783737) (xy 107.020297 -301.813203) (xy 106.97072 -301.835845) (xy 106.918425 -301.8512)
			(xy 106.864477 -301.858956) (xy 106.809975 -301.858956) (xy 106.756027 -301.8512) (xy 106.703732 -301.835845)
			(xy 106.654155 -301.813203) (xy 106.608305 -301.783737) (xy 106.567114 -301.748046) (xy 106.531423 -301.706855)
			(xy 106.501957 -301.661005) (xy 106.479315 -301.611428) (xy 106.46396 -301.559133) (xy 106.456204 -301.505185)
			(xy 106.455718 -301.477934) (xy 103.582224 -301.477934) (xy 103.578292 -301.505285) (xy 103.562937 -301.55758)
			(xy 103.540295 -301.607157) (xy 103.510829 -301.653007) (xy 103.475138 -301.694198) (xy 103.433947 -301.729889)
			(xy 103.388097 -301.759355) (xy 103.33852 -301.781997) (xy 103.286225 -301.797352) (xy 103.232277 -301.805108)
			(xy 103.177775 -301.805108) (xy 103.123827 -301.797352) (xy 103.071532 -301.781997) (xy 103.021955 -301.759355)
			(xy 102.976105 -301.729889) (xy 102.934914 -301.694198) (xy 102.899223 -301.653007) (xy 102.869757 -301.607157)
			(xy 102.847115 -301.55758) (xy 102.83176 -301.505285) (xy 102.824004 -301.451337) (xy 102.823518 -301.424086)
			(xy 99.78771 -301.424086) (xy 99.78771 -302.925734) (xy 102.235508 -302.925734) (xy 102.235992 -302.898364)
			(xy 102.243805 -302.844186) (xy 102.25929 -302.791683) (xy 102.282128 -302.741936) (xy 102.311849 -302.695968)
			(xy 102.329488 -302.675036) (xy 102.335584 -302.667924) (xy 102.341934 -302.650906) (xy 102.341934 -302.565562)
			(xy 102.335584 -302.548544) (xy 102.329488 -302.541432) (xy 102.311849 -302.5205) (xy 102.282137 -302.474527)
			(xy 102.259302 -302.42478) (xy 102.24381 -302.372279) (xy 102.235982 -302.318103) (xy 102.235508 -302.290734)
			(xy 102.235994 -302.263483) (xy 102.24375 -302.209535) (xy 102.259105 -302.15724) (xy 102.281747 -302.107663)
			(xy 102.311213 -302.061813) (xy 102.346904 -302.020622) (xy 102.388095 -301.984931) (xy 102.433945 -301.955465)
			(xy 102.483522 -301.932823) (xy 102.535817 -301.917468) (xy 102.589765 -301.909712) (xy 102.644267 -301.909712)
			(xy 102.698215 -301.917468) (xy 102.75051 -301.932823) (xy 102.800087 -301.955465) (xy 102.845937 -301.984931)
			(xy 102.887128 -302.020622) (xy 102.922819 -302.061813) (xy 102.952285 -302.107663) (xy 102.974927 -302.15724)
			(xy 102.990282 -302.209535) (xy 102.998038 -302.263483) (xy 102.998524 -302.290734) (xy 102.998096 -302.318106)
			(xy 102.990272 -302.372287) (xy 102.974775 -302.424792) (xy 102.951924 -302.474538) (xy 102.92219 -302.520502)
			(xy 102.904544 -302.541432) (xy 102.898448 -302.548544) (xy 102.892098 -302.565562) (xy 102.892098 -302.650906)
			(xy 102.898448 -302.667924) (xy 102.904544 -302.675036) (xy 102.922174 -302.695975) (xy 102.951886 -302.741947)
			(xy 102.974723 -302.791693) (xy 102.990216 -302.844191) (xy 102.998048 -302.898365) (xy 102.998524 -302.925734)
			(xy 105.655618 -302.925734) (xy 105.6561 -302.898364) (xy 105.663913 -302.844186) (xy 105.679398 -302.791683)
			(xy 105.702237 -302.741935) (xy 105.731958 -302.695968) (xy 105.749598 -302.675036) (xy 105.755694 -302.667924)
			(xy 105.762044 -302.650906) (xy 105.762044 -302.565562) (xy 105.755694 -302.548544) (xy 105.749598 -302.541432)
			(xy 105.73196 -302.520499) (xy 105.702248 -302.474526) (xy 105.679412 -302.424779) (xy 105.663921 -302.372279)
			(xy 105.656092 -302.318103) (xy 105.655618 -302.290734) (xy 105.656104 -302.263483) (xy 105.66386 -302.209535)
			(xy 105.679215 -302.15724) (xy 105.701857 -302.107663) (xy 105.731323 -302.061813) (xy 105.767014 -302.020622)
			(xy 105.808205 -301.984931) (xy 105.854055 -301.955465) (xy 105.903632 -301.932823) (xy 105.955927 -301.917468)
			(xy 106.009875 -301.909712) (xy 106.064377 -301.909712) (xy 106.118325 -301.917468) (xy 106.17062 -301.932823)
			(xy 106.220197 -301.955465) (xy 106.266047 -301.984931) (xy 106.307238 -302.020622) (xy 106.342929 -302.061813)
			(xy 106.372395 -302.107663) (xy 106.395037 -302.15724) (xy 106.410392 -302.209535) (xy 106.418148 -302.263483)
			(xy 106.418634 -302.290734) (xy 106.418204 -302.318106) (xy 106.41038 -302.372287) (xy 106.394883 -302.424791)
			(xy 106.372033 -302.474537) (xy 106.3423 -302.520502) (xy 106.324654 -302.541432) (xy 106.318558 -302.548544)
			(xy 106.312208 -302.565562) (xy 106.312208 -302.650906) (xy 106.318558 -302.667924) (xy 106.324654 -302.675036)
			(xy 106.342269 -302.695987) (xy 106.371986 -302.741954) (xy 106.394828 -302.791697) (xy 106.410324 -302.844193)
			(xy 106.418157 -302.898366) (xy 106.418634 -302.925734) (xy 107.043728 -302.925734) (xy 107.044207 -302.898364)
			(xy 107.052021 -302.844185) (xy 107.067506 -302.791682) (xy 107.090345 -302.741935) (xy 107.120068 -302.695968)
			(xy 107.137708 -302.675036) (xy 107.143804 -302.667924) (xy 107.150154 -302.650906) (xy 107.150154 -302.565562)
			(xy 107.143804 -302.548544) (xy 107.137708 -302.541432) (xy 107.120072 -302.520498) (xy 107.090359 -302.474526)
			(xy 107.067523 -302.424779) (xy 107.052031 -302.372278) (xy 107.044202 -302.318103) (xy 107.043728 -302.290734)
			(xy 107.044214 -302.263483) (xy 107.05197 -302.209535) (xy 107.067325 -302.15724) (xy 107.089967 -302.107663)
			(xy 107.119433 -302.061813) (xy 107.155124 -302.020622) (xy 107.196315 -301.984931) (xy 107.242165 -301.955465)
			(xy 107.291742 -301.932823) (xy 107.344037 -301.917468) (xy 107.397985 -301.909712) (xy 107.452487 -301.909712)
			(xy 107.506435 -301.917468) (xy 107.55873 -301.932823) (xy 107.608307 -301.955465) (xy 107.654157 -301.984931)
			(xy 107.695348 -302.020622) (xy 107.731039 -302.061813) (xy 107.760505 -302.107663) (xy 107.783147 -302.15724)
			(xy 107.798502 -302.209535) (xy 107.806258 -302.263483) (xy 107.806744 -302.290734) (xy 107.806312 -302.318106)
			(xy 107.798488 -302.372287) (xy 107.782992 -302.424791) (xy 107.760142 -302.474537) (xy 107.730409 -302.520502)
			(xy 107.712764 -302.541432) (xy 107.706668 -302.548544) (xy 107.700318 -302.565562) (xy 107.700318 -302.650906)
			(xy 107.706668 -302.667924) (xy 107.712764 -302.675036) (xy 107.730381 -302.695986) (xy 107.760097 -302.741953)
			(xy 107.782938 -302.791696) (xy 107.798434 -302.844193) (xy 107.806267 -302.898366) (xy 107.806744 -302.925734)
			(xy 109.075728 -302.925734) (xy 109.076207 -302.898364) (xy 109.084021 -302.844185) (xy 109.099506 -302.791682)
			(xy 109.122345 -302.741935) (xy 109.152068 -302.695968) (xy 109.169708 -302.675036) (xy 109.175804 -302.667924)
			(xy 109.182154 -302.650906) (xy 109.182154 -302.565562) (xy 109.175804 -302.548544) (xy 109.169708 -302.541432)
			(xy 109.152072 -302.520498) (xy 109.122359 -302.474526) (xy 109.099523 -302.424779) (xy 109.084031 -302.372278)
			(xy 109.076202 -302.318103) (xy 109.075728 -302.290734) (xy 109.076214 -302.263483) (xy 109.08397 -302.209535)
			(xy 109.099325 -302.15724) (xy 109.121967 -302.107663) (xy 109.151433 -302.061813) (xy 109.187124 -302.020622)
			(xy 109.228315 -301.984931) (xy 109.274165 -301.955465) (xy 109.323742 -301.932823) (xy 109.376037 -301.917468)
			(xy 109.429985 -301.909712) (xy 109.484487 -301.909712) (xy 109.538435 -301.917468) (xy 109.59073 -301.932823)
			(xy 109.640307 -301.955465) (xy 109.686157 -301.984931) (xy 109.727348 -302.020622) (xy 109.763039 -302.061813)
			(xy 109.792505 -302.107663) (xy 109.815147 -302.15724) (xy 109.830502 -302.209535) (xy 109.838258 -302.263483)
			(xy 109.838744 -302.290734) (xy 109.838312 -302.318106) (xy 109.830488 -302.372287) (xy 109.814992 -302.424791)
			(xy 109.792142 -302.474537) (xy 109.762409 -302.520502) (xy 109.744764 -302.541432) (xy 109.738668 -302.548544)
			(xy 109.732318 -302.565562) (xy 109.732318 -302.650906) (xy 109.738668 -302.667924) (xy 109.744764 -302.675036)
			(xy 109.762381 -302.695986) (xy 109.792097 -302.741953) (xy 109.814938 -302.791696) (xy 109.830434 -302.844193)
			(xy 109.838267 -302.898366) (xy 109.838744 -302.925734) (xy 113.883948 -302.925734) (xy 113.884422 -302.898364)
			(xy 113.892236 -302.844185) (xy 113.907723 -302.791681) (xy 113.930563 -302.741934) (xy 113.960287 -302.695967)
			(xy 113.977928 -302.675036) (xy 113.984024 -302.667924) (xy 113.990374 -302.650906) (xy 113.990374 -302.565562)
			(xy 113.984024 -302.548544) (xy 113.977928 -302.541432) (xy 113.960295 -302.520495) (xy 113.930581 -302.474524)
			(xy 113.907744 -302.424778) (xy 113.892251 -302.372278) (xy 113.884422 -302.318103) (xy 113.883948 -302.290734)
			(xy 113.884434 -302.263483) (xy 113.89219 -302.209535) (xy 113.907545 -302.15724) (xy 113.930187 -302.107663)
			(xy 113.959653 -302.061813) (xy 113.995344 -302.020622) (xy 114.036535 -301.984931) (xy 114.082385 -301.955465)
			(xy 114.131962 -301.932823) (xy 114.184257 -301.917468) (xy 114.238205 -301.909712) (xy 114.292707 -301.909712)
			(xy 114.346655 -301.917468) (xy 114.39895 -301.932823) (xy 114.448527 -301.955465) (xy 114.494377 -301.984931)
			(xy 114.535568 -302.020622) (xy 114.571259 -302.061813) (xy 114.600725 -302.107663) (xy 114.623367 -302.15724)
			(xy 114.638722 -302.209535) (xy 114.646478 -302.263483) (xy 114.646964 -302.290734) (xy 114.646527 -302.318105)
			(xy 114.638703 -302.372286) (xy 114.623208 -302.42479) (xy 114.60036 -302.474536) (xy 114.570628 -302.520502)
			(xy 114.552984 -302.541432) (xy 114.546888 -302.548544) (xy 114.540538 -302.565562) (xy 114.540538 -302.650906)
			(xy 114.546888 -302.667924) (xy 114.552984 -302.675036) (xy 114.570604 -302.695983) (xy 114.600319 -302.741952)
			(xy 114.623159 -302.791695) (xy 114.638655 -302.844193) (xy 114.646488 -302.898366) (xy 114.646964 -302.925734)
			(xy 114.646478 -302.952985) (xy 114.638722 -303.006933) (xy 114.623367 -303.059228) (xy 114.600725 -303.108805)
			(xy 114.571259 -303.154655) (xy 114.535568 -303.195846) (xy 114.494377 -303.231537) (xy 114.448527 -303.261003)
			(xy 114.39895 -303.283645) (xy 114.346655 -303.299) (xy 114.292707 -303.306756) (xy 114.238205 -303.306756)
			(xy 114.184257 -303.299) (xy 114.131962 -303.283645) (xy 114.082385 -303.261003) (xy 114.036535 -303.231537)
			(xy 113.995344 -303.195846) (xy 113.959653 -303.154655) (xy 113.930187 -303.108805) (xy 113.907545 -303.059228)
			(xy 113.89219 -303.006933) (xy 113.884434 -302.952985) (xy 113.883948 -302.925734) (xy 109.838744 -302.925734)
			(xy 109.838258 -302.952985) (xy 109.830502 -303.006933) (xy 109.815147 -303.059228) (xy 109.792505 -303.108805)
			(xy 109.763039 -303.154655) (xy 109.727348 -303.195846) (xy 109.686157 -303.231537) (xy 109.640307 -303.261003)
			(xy 109.59073 -303.283645) (xy 109.538435 -303.299) (xy 109.484487 -303.306756) (xy 109.429985 -303.306756)
			(xy 109.376037 -303.299) (xy 109.323742 -303.283645) (xy 109.274165 -303.261003) (xy 109.228315 -303.231537)
			(xy 109.187124 -303.195846) (xy 109.151433 -303.154655) (xy 109.121967 -303.108805) (xy 109.099325 -303.059228)
			(xy 109.08397 -303.006933) (xy 109.076214 -302.952985) (xy 109.075728 -302.925734) (xy 107.806744 -302.925734)
			(xy 107.806258 -302.952985) (xy 107.798502 -303.006933) (xy 107.783147 -303.059228) (xy 107.760505 -303.108805)
			(xy 107.731039 -303.154655) (xy 107.695348 -303.195846) (xy 107.654157 -303.231537) (xy 107.608307 -303.261003)
			(xy 107.55873 -303.283645) (xy 107.506435 -303.299) (xy 107.452487 -303.306756) (xy 107.397985 -303.306756)
			(xy 107.344037 -303.299) (xy 107.291742 -303.283645) (xy 107.242165 -303.261003) (xy 107.196315 -303.231537)
			(xy 107.155124 -303.195846) (xy 107.119433 -303.154655) (xy 107.089967 -303.108805) (xy 107.067325 -303.059228)
			(xy 107.05197 -303.006933) (xy 107.044214 -302.952985) (xy 107.043728 -302.925734) (xy 106.418634 -302.925734)
			(xy 106.418148 -302.952985) (xy 106.410392 -303.006933) (xy 106.395037 -303.059228) (xy 106.372395 -303.108805)
			(xy 106.342929 -303.154655) (xy 106.307238 -303.195846) (xy 106.266047 -303.231537) (xy 106.220197 -303.261003)
			(xy 106.17062 -303.283645) (xy 106.118325 -303.299) (xy 106.064377 -303.306756) (xy 106.009875 -303.306756)
			(xy 105.955927 -303.299) (xy 105.903632 -303.283645) (xy 105.854055 -303.261003) (xy 105.808205 -303.231537)
			(xy 105.767014 -303.195846) (xy 105.731323 -303.154655) (xy 105.701857 -303.108805) (xy 105.679215 -303.059228)
			(xy 105.66386 -303.006933) (xy 105.656104 -302.952985) (xy 105.655618 -302.925734) (xy 102.998524 -302.925734)
			(xy 102.998038 -302.952985) (xy 102.990282 -303.006933) (xy 102.974927 -303.059228) (xy 102.952285 -303.108805)
			(xy 102.922819 -303.154655) (xy 102.887128 -303.195846) (xy 102.845937 -303.231537) (xy 102.800087 -303.261003)
			(xy 102.75051 -303.283645) (xy 102.698215 -303.299) (xy 102.644267 -303.306756) (xy 102.589765 -303.306756)
			(xy 102.535817 -303.299) (xy 102.483522 -303.283645) (xy 102.433945 -303.261003) (xy 102.388095 -303.231537)
			(xy 102.346904 -303.195846) (xy 102.311213 -303.154655) (xy 102.281747 -303.108805) (xy 102.259105 -303.059228)
			(xy 102.24375 -303.006933) (xy 102.235994 -302.952985) (xy 102.235508 -302.925734) (xy 99.78771 -302.925734)
			(xy 99.78771 -310.242712) (xy 100.471984 -310.242712) (xy 100.476055 -310.18709) (xy 100.488181 -310.132653)
			(xy 100.508104 -310.080562) (xy 100.5354 -310.031927) (xy 100.569486 -309.987784) (xy 100.609635 -309.949075)
			(xy 100.654993 -309.916624) (xy 100.704593 -309.891123) (xy 100.757377 -309.873116) (xy 100.81222 -309.862986)
			(xy 100.867954 -309.860949) (xy 100.923391 -309.867049) (xy 100.977348 -309.881155) (xy 101.028677 -309.902967)
			(xy 101.076283 -309.932021) (xy 101.119151 -309.967696) (xy 101.156368 -310.009233) (xy 101.187141 -310.055746)
			(xy 101.210813 -310.106243) (xy 101.226881 -310.15965) (xy 101.235001 -310.214826) (xy 101.23551 -310.242712)
			(xy 101.487984 -310.242712) (xy 101.492055 -310.18709) (xy 101.504181 -310.132653) (xy 101.524104 -310.080562)
			(xy 101.5514 -310.031927) (xy 101.585486 -309.987784) (xy 101.625635 -309.949075) (xy 101.670993 -309.916624)
			(xy 101.720593 -309.891123) (xy 101.773377 -309.873116) (xy 101.82822 -309.862986) (xy 101.883954 -309.860949)
			(xy 101.939391 -309.867049) (xy 101.993348 -309.881155) (xy 102.044677 -309.902967) (xy 102.092283 -309.932021)
			(xy 102.135151 -309.967696) (xy 102.172368 -310.009233) (xy 102.203141 -310.055746) (xy 102.226813 -310.106243)
			(xy 102.242881 -310.15965) (xy 102.251001 -310.214826) (xy 102.25151 -310.242712) (xy 102.503984 -310.242712)
			(xy 102.508055 -310.18709) (xy 102.520181 -310.132653) (xy 102.540104 -310.080562) (xy 102.5674 -310.031927)
			(xy 102.601486 -309.987784) (xy 102.641635 -309.949075) (xy 102.686993 -309.916624) (xy 102.736593 -309.891123)
			(xy 102.789377 -309.873116) (xy 102.84422 -309.862986) (xy 102.899954 -309.860949) (xy 102.955391 -309.867049)
			(xy 103.009348 -309.881155) (xy 103.060677 -309.902967) (xy 103.108283 -309.932021) (xy 103.151151 -309.967696)
			(xy 103.188368 -310.009233) (xy 103.219141 -310.055746) (xy 103.242813 -310.106243) (xy 103.258881 -310.15965)
			(xy 103.267001 -310.214826) (xy 103.26751 -310.242712) (xy 103.519984 -310.242712) (xy 103.524055 -310.18709)
			(xy 103.536181 -310.132653) (xy 103.556104 -310.080562) (xy 103.5834 -310.031927) (xy 103.617486 -309.987784)
			(xy 103.657635 -309.949075) (xy 103.702993 -309.916624) (xy 103.752593 -309.891123) (xy 103.805377 -309.873116)
			(xy 103.86022 -309.862986) (xy 103.915954 -309.860949) (xy 103.971391 -309.867049) (xy 104.025348 -309.881155)
			(xy 104.076677 -309.902967) (xy 104.124283 -309.932021) (xy 104.167151 -309.967696) (xy 104.204368 -310.009233)
			(xy 104.235141 -310.055746) (xy 104.258813 -310.106243) (xy 104.274881 -310.15965) (xy 104.283001 -310.214826)
			(xy 104.28351 -310.242712) (xy 104.535984 -310.242712) (xy 104.540055 -310.18709) (xy 104.552181 -310.132653)
			(xy 104.572104 -310.080562) (xy 104.5994 -310.031927) (xy 104.633486 -309.987784) (xy 104.673635 -309.949075)
			(xy 104.718993 -309.916624) (xy 104.768593 -309.891123) (xy 104.821377 -309.873116) (xy 104.87622 -309.862986)
			(xy 104.931954 -309.860949) (xy 104.987391 -309.867049) (xy 105.041348 -309.881155) (xy 105.092677 -309.902967)
			(xy 105.140283 -309.932021) (xy 105.183151 -309.967696) (xy 105.220368 -310.009233) (xy 105.251141 -310.055746)
			(xy 105.274813 -310.106243) (xy 105.290881 -310.15965) (xy 105.299001 -310.214826) (xy 105.29951 -310.242712)
			(xy 105.551984 -310.242712) (xy 105.556055 -310.18709) (xy 105.568181 -310.132653) (xy 105.588104 -310.080562)
			(xy 105.6154 -310.031927) (xy 105.649486 -309.987784) (xy 105.689635 -309.949075) (xy 105.734993 -309.916624)
			(xy 105.784593 -309.891123) (xy 105.837377 -309.873116) (xy 105.89222 -309.862986) (xy 105.947954 -309.860949)
			(xy 106.003391 -309.867049) (xy 106.057348 -309.881155) (xy 106.108677 -309.902967) (xy 106.156283 -309.932021)
			(xy 106.199151 -309.967696) (xy 106.236368 -310.009233) (xy 106.267141 -310.055746) (xy 106.290813 -310.106243)
			(xy 106.306881 -310.15965) (xy 106.315001 -310.214826) (xy 106.31551 -310.242712) (xy 106.567984 -310.242712)
			(xy 106.572055 -310.18709) (xy 106.584181 -310.132653) (xy 106.604104 -310.080562) (xy 106.6314 -310.031927)
			(xy 106.665486 -309.987784) (xy 106.705635 -309.949075) (xy 106.750993 -309.916624) (xy 106.800593 -309.891123)
			(xy 106.853377 -309.873116) (xy 106.90822 -309.862986) (xy 106.963954 -309.860949) (xy 107.019391 -309.867049)
			(xy 107.073348 -309.881155) (xy 107.124677 -309.902967) (xy 107.172283 -309.932021) (xy 107.215151 -309.967696)
			(xy 107.252368 -310.009233) (xy 107.283141 -310.055746) (xy 107.306813 -310.106243) (xy 107.322881 -310.15965)
			(xy 107.331001 -310.214826) (xy 107.33151 -310.242712) (xy 107.583984 -310.242712) (xy 107.588055 -310.18709)
			(xy 107.600181 -310.132653) (xy 107.620104 -310.080562) (xy 107.6474 -310.031927) (xy 107.681486 -309.987784)
			(xy 107.721635 -309.949075) (xy 107.766993 -309.916624) (xy 107.816593 -309.891123) (xy 107.869377 -309.873116)
			(xy 107.92422 -309.862986) (xy 107.979954 -309.860949) (xy 108.035391 -309.867049) (xy 108.089348 -309.881155)
			(xy 108.140677 -309.902967) (xy 108.188283 -309.932021) (xy 108.231151 -309.967696) (xy 108.268368 -310.009233)
			(xy 108.299141 -310.055746) (xy 108.322813 -310.106243) (xy 108.338881 -310.15965) (xy 108.347001 -310.214826)
			(xy 108.34751 -310.242712) (xy 108.599984 -310.242712) (xy 108.604055 -310.18709) (xy 108.616181 -310.132653)
			(xy 108.636104 -310.080562) (xy 108.6634 -310.031927) (xy 108.697486 -309.987784) (xy 108.737635 -309.949075)
			(xy 108.782993 -309.916624) (xy 108.832593 -309.891123) (xy 108.885377 -309.873116) (xy 108.94022 -309.862986)
			(xy 108.995954 -309.860949) (xy 109.051391 -309.867049) (xy 109.105348 -309.881155) (xy 109.156677 -309.902967)
			(xy 109.204283 -309.932021) (xy 109.247151 -309.967696) (xy 109.284368 -310.009233) (xy 109.315141 -310.055746)
			(xy 109.338813 -310.106243) (xy 109.354881 -310.15965) (xy 109.363001 -310.214826) (xy 109.36351 -310.242712)
			(xy 109.615984 -310.242712) (xy 109.620055 -310.18709) (xy 109.632181 -310.132653) (xy 109.652104 -310.080562)
			(xy 109.6794 -310.031927) (xy 109.713486 -309.987784) (xy 109.753635 -309.949075) (xy 109.798993 -309.916624)
			(xy 109.848593 -309.891123) (xy 109.901377 -309.873116) (xy 109.95622 -309.862986) (xy 110.011954 -309.860949)
			(xy 110.067391 -309.867049) (xy 110.121348 -309.881155) (xy 110.172677 -309.902967) (xy 110.220283 -309.932021)
			(xy 110.263151 -309.967696) (xy 110.300368 -310.009233) (xy 110.331141 -310.055746) (xy 110.354813 -310.106243)
			(xy 110.370881 -310.15965) (xy 110.379001 -310.214826) (xy 110.37951 -310.242712) (xy 110.379001 -310.270598)
			(xy 110.370881 -310.325774) (xy 110.354813 -310.379181) (xy 110.331141 -310.429678) (xy 110.300368 -310.476191)
			(xy 110.263151 -310.517728) (xy 110.220283 -310.553403) (xy 110.172677 -310.582457) (xy 110.121348 -310.604269)
			(xy 110.067391 -310.618375) (xy 110.011954 -310.624475) (xy 109.95622 -310.622438) (xy 109.901377 -310.612308)
			(xy 109.848593 -310.594301) (xy 109.798993 -310.5688) (xy 109.753635 -310.536349) (xy 109.713486 -310.49764)
			(xy 109.6794 -310.453497) (xy 109.652104 -310.404862) (xy 109.632181 -310.352771) (xy 109.620055 -310.298334)
			(xy 109.615984 -310.242712) (xy 109.36351 -310.242712) (xy 109.363001 -310.270598) (xy 109.354881 -310.325774)
			(xy 109.338813 -310.379181) (xy 109.315141 -310.429678) (xy 109.284368 -310.476191) (xy 109.247151 -310.517728)
			(xy 109.204283 -310.553403) (xy 109.156677 -310.582457) (xy 109.105348 -310.604269) (xy 109.051391 -310.618375)
			(xy 108.995954 -310.624475) (xy 108.94022 -310.622438) (xy 108.885377 -310.612308) (xy 108.832593 -310.594301)
			(xy 108.782993 -310.5688) (xy 108.737635 -310.536349) (xy 108.697486 -310.49764) (xy 108.6634 -310.453497)
			(xy 108.636104 -310.404862) (xy 108.616181 -310.352771) (xy 108.604055 -310.298334) (xy 108.599984 -310.242712)
			(xy 108.34751 -310.242712) (xy 108.347001 -310.270598) (xy 108.338881 -310.325774) (xy 108.322813 -310.379181)
			(xy 108.299141 -310.429678) (xy 108.268368 -310.476191) (xy 108.231151 -310.517728) (xy 108.188283 -310.553403)
			(xy 108.140677 -310.582457) (xy 108.089348 -310.604269) (xy 108.035391 -310.618375) (xy 107.979954 -310.624475)
			(xy 107.92422 -310.622438) (xy 107.869377 -310.612308) (xy 107.816593 -310.594301) (xy 107.766993 -310.5688)
			(xy 107.721635 -310.536349) (xy 107.681486 -310.49764) (xy 107.6474 -310.453497) (xy 107.620104 -310.404862)
			(xy 107.600181 -310.352771) (xy 107.588055 -310.298334) (xy 107.583984 -310.242712) (xy 107.33151 -310.242712)
			(xy 107.331001 -310.270598) (xy 107.322881 -310.325774) (xy 107.306813 -310.379181) (xy 107.283141 -310.429678)
			(xy 107.252368 -310.476191) (xy 107.215151 -310.517728) (xy 107.172283 -310.553403) (xy 107.124677 -310.582457)
			(xy 107.073348 -310.604269) (xy 107.019391 -310.618375) (xy 106.963954 -310.624475) (xy 106.90822 -310.622438)
			(xy 106.853377 -310.612308) (xy 106.800593 -310.594301) (xy 106.750993 -310.5688) (xy 106.705635 -310.536349)
			(xy 106.665486 -310.49764) (xy 106.6314 -310.453497) (xy 106.604104 -310.404862) (xy 106.584181 -310.352771)
			(xy 106.572055 -310.298334) (xy 106.567984 -310.242712) (xy 106.31551 -310.242712) (xy 106.315001 -310.270598)
			(xy 106.306881 -310.325774) (xy 106.290813 -310.379181) (xy 106.267141 -310.429678) (xy 106.236368 -310.476191)
			(xy 106.199151 -310.517728) (xy 106.156283 -310.553403) (xy 106.108677 -310.582457) (xy 106.057348 -310.604269)
			(xy 106.003391 -310.618375) (xy 105.947954 -310.624475) (xy 105.89222 -310.622438) (xy 105.837377 -310.612308)
			(xy 105.784593 -310.594301) (xy 105.734993 -310.5688) (xy 105.689635 -310.536349) (xy 105.649486 -310.49764)
			(xy 105.6154 -310.453497) (xy 105.588104 -310.404862) (xy 105.568181 -310.352771) (xy 105.556055 -310.298334)
			(xy 105.551984 -310.242712) (xy 105.29951 -310.242712) (xy 105.299001 -310.270598) (xy 105.290881 -310.325774)
			(xy 105.274813 -310.379181) (xy 105.251141 -310.429678) (xy 105.220368 -310.476191) (xy 105.183151 -310.517728)
			(xy 105.140283 -310.553403) (xy 105.092677 -310.582457) (xy 105.041348 -310.604269) (xy 104.987391 -310.618375)
			(xy 104.931954 -310.624475) (xy 104.87622 -310.622438) (xy 104.821377 -310.612308) (xy 104.768593 -310.594301)
			(xy 104.718993 -310.5688) (xy 104.673635 -310.536349) (xy 104.633486 -310.49764) (xy 104.5994 -310.453497)
			(xy 104.572104 -310.404862) (xy 104.552181 -310.352771) (xy 104.540055 -310.298334) (xy 104.535984 -310.242712)
			(xy 104.28351 -310.242712) (xy 104.283001 -310.270598) (xy 104.274881 -310.325774) (xy 104.258813 -310.379181)
			(xy 104.235141 -310.429678) (xy 104.204368 -310.476191) (xy 104.167151 -310.517728) (xy 104.124283 -310.553403)
			(xy 104.076677 -310.582457) (xy 104.025348 -310.604269) (xy 103.971391 -310.618375) (xy 103.915954 -310.624475)
			(xy 103.86022 -310.622438) (xy 103.805377 -310.612308) (xy 103.752593 -310.594301) (xy 103.702993 -310.5688)
			(xy 103.657635 -310.536349) (xy 103.617486 -310.49764) (xy 103.5834 -310.453497) (xy 103.556104 -310.404862)
			(xy 103.536181 -310.352771) (xy 103.524055 -310.298334) (xy 103.519984 -310.242712) (xy 103.26751 -310.242712)
			(xy 103.267001 -310.270598) (xy 103.258881 -310.325774) (xy 103.242813 -310.379181) (xy 103.219141 -310.429678)
			(xy 103.188368 -310.476191) (xy 103.151151 -310.517728) (xy 103.108283 -310.553403) (xy 103.060677 -310.582457)
			(xy 103.009348 -310.604269) (xy 102.955391 -310.618375) (xy 102.899954 -310.624475) (xy 102.84422 -310.622438)
			(xy 102.789377 -310.612308) (xy 102.736593 -310.594301) (xy 102.686993 -310.5688) (xy 102.641635 -310.536349)
			(xy 102.601486 -310.49764) (xy 102.5674 -310.453497) (xy 102.540104 -310.404862) (xy 102.520181 -310.352771)
			(xy 102.508055 -310.298334) (xy 102.503984 -310.242712) (xy 102.25151 -310.242712) (xy 102.251001 -310.270598)
			(xy 102.242881 -310.325774) (xy 102.226813 -310.379181) (xy 102.203141 -310.429678) (xy 102.172368 -310.476191)
			(xy 102.135151 -310.517728) (xy 102.092283 -310.553403) (xy 102.044677 -310.582457) (xy 101.993348 -310.604269)
			(xy 101.939391 -310.618375) (xy 101.883954 -310.624475) (xy 101.82822 -310.622438) (xy 101.773377 -310.612308)
			(xy 101.720593 -310.594301) (xy 101.670993 -310.5688) (xy 101.625635 -310.536349) (xy 101.585486 -310.49764)
			(xy 101.5514 -310.453497) (xy 101.524104 -310.404862) (xy 101.504181 -310.352771) (xy 101.492055 -310.298334)
			(xy 101.487984 -310.242712) (xy 101.23551 -310.242712) (xy 101.235001 -310.270598) (xy 101.226881 -310.325774)
			(xy 101.210813 -310.379181) (xy 101.187141 -310.429678) (xy 101.156368 -310.476191) (xy 101.119151 -310.517728)
			(xy 101.076283 -310.553403) (xy 101.028677 -310.582457) (xy 100.977348 -310.604269) (xy 100.923391 -310.618375)
			(xy 100.867954 -310.624475) (xy 100.81222 -310.622438) (xy 100.757377 -310.612308) (xy 100.704593 -310.594301)
			(xy 100.654993 -310.5688) (xy 100.609635 -310.536349) (xy 100.569486 -310.49764) (xy 100.5354 -310.453497)
			(xy 100.508104 -310.404862) (xy 100.488181 -310.352771) (xy 100.476055 -310.298334) (xy 100.471984 -310.242712)
			(xy 99.78771 -310.242712) (xy 99.78771 -311.258712) (xy 100.471984 -311.258712) (xy 100.476055 -311.20309)
			(xy 100.488181 -311.148653) (xy 100.508104 -311.096562) (xy 100.5354 -311.047927) (xy 100.569486 -311.003784)
			(xy 100.609635 -310.965075) (xy 100.654993 -310.932624) (xy 100.704593 -310.907123) (xy 100.757377 -310.889116)
			(xy 100.81222 -310.878986) (xy 100.867954 -310.876949) (xy 100.923391 -310.883049) (xy 100.977348 -310.897155)
			(xy 101.028677 -310.918967) (xy 101.076283 -310.948021) (xy 101.119151 -310.983696) (xy 101.156368 -311.025233)
			(xy 101.187141 -311.071746) (xy 101.210813 -311.122243) (xy 101.226881 -311.17565) (xy 101.235001 -311.230826)
			(xy 101.23551 -311.258712) (xy 101.487984 -311.258712) (xy 101.492055 -311.20309) (xy 101.504181 -311.148653)
			(xy 101.524104 -311.096562) (xy 101.5514 -311.047927) (xy 101.585486 -311.003784) (xy 101.625635 -310.965075)
			(xy 101.670993 -310.932624) (xy 101.720593 -310.907123) (xy 101.773377 -310.889116) (xy 101.82822 -310.878986)
			(xy 101.883954 -310.876949) (xy 101.939391 -310.883049) (xy 101.993348 -310.897155) (xy 102.044677 -310.918967)
			(xy 102.092283 -310.948021) (xy 102.135151 -310.983696) (xy 102.172368 -311.025233) (xy 102.203141 -311.071746)
			(xy 102.226813 -311.122243) (xy 102.242881 -311.17565) (xy 102.251001 -311.230826) (xy 102.25151 -311.258712)
			(xy 102.503984 -311.258712) (xy 102.508055 -311.20309) (xy 102.520181 -311.148653) (xy 102.540104 -311.096562)
			(xy 102.5674 -311.047927) (xy 102.601486 -311.003784) (xy 102.641635 -310.965075) (xy 102.686993 -310.932624)
			(xy 102.736593 -310.907123) (xy 102.789377 -310.889116) (xy 102.84422 -310.878986) (xy 102.899954 -310.876949)
			(xy 102.955391 -310.883049) (xy 103.009348 -310.897155) (xy 103.060677 -310.918967) (xy 103.108283 -310.948021)
			(xy 103.151151 -310.983696) (xy 103.188368 -311.025233) (xy 103.219141 -311.071746) (xy 103.242813 -311.122243)
			(xy 103.258881 -311.17565) (xy 103.267001 -311.230826) (xy 103.26751 -311.258712) (xy 103.519984 -311.258712)
			(xy 103.524055 -311.20309) (xy 103.536181 -311.148653) (xy 103.556104 -311.096562) (xy 103.5834 -311.047927)
			(xy 103.617486 -311.003784) (xy 103.657635 -310.965075) (xy 103.702993 -310.932624) (xy 103.752593 -310.907123)
			(xy 103.805377 -310.889116) (xy 103.86022 -310.878986) (xy 103.915954 -310.876949) (xy 103.971391 -310.883049)
			(xy 104.025348 -310.897155) (xy 104.076677 -310.918967) (xy 104.124283 -310.948021) (xy 104.167151 -310.983696)
			(xy 104.204368 -311.025233) (xy 104.235141 -311.071746) (xy 104.258813 -311.122243) (xy 104.274881 -311.17565)
			(xy 104.283001 -311.230826) (xy 104.28351 -311.258712) (xy 104.535984 -311.258712) (xy 104.540055 -311.20309)
			(xy 104.552181 -311.148653) (xy 104.572104 -311.096562) (xy 104.5994 -311.047927) (xy 104.633486 -311.003784)
			(xy 104.673635 -310.965075) (xy 104.718993 -310.932624) (xy 104.768593 -310.907123) (xy 104.821377 -310.889116)
			(xy 104.87622 -310.878986) (xy 104.931954 -310.876949) (xy 104.987391 -310.883049) (xy 105.041348 -310.897155)
			(xy 105.092677 -310.918967) (xy 105.140283 -310.948021) (xy 105.183151 -310.983696) (xy 105.220368 -311.025233)
			(xy 105.251141 -311.071746) (xy 105.274813 -311.122243) (xy 105.290881 -311.17565) (xy 105.299001 -311.230826)
			(xy 105.29951 -311.258712) (xy 105.551984 -311.258712) (xy 105.556055 -311.20309) (xy 105.568181 -311.148653)
			(xy 105.588104 -311.096562) (xy 105.6154 -311.047927) (xy 105.649486 -311.003784) (xy 105.689635 -310.965075)
			(xy 105.734993 -310.932624) (xy 105.784593 -310.907123) (xy 105.837377 -310.889116) (xy 105.89222 -310.878986)
			(xy 105.947954 -310.876949) (xy 106.003391 -310.883049) (xy 106.057348 -310.897155) (xy 106.108677 -310.918967)
			(xy 106.156283 -310.948021) (xy 106.199151 -310.983696) (xy 106.236368 -311.025233) (xy 106.267141 -311.071746)
			(xy 106.290813 -311.122243) (xy 106.306881 -311.17565) (xy 106.315001 -311.230826) (xy 106.31551 -311.258712)
			(xy 106.567984 -311.258712) (xy 106.572055 -311.20309) (xy 106.584181 -311.148653) (xy 106.604104 -311.096562)
			(xy 106.6314 -311.047927) (xy 106.665486 -311.003784) (xy 106.705635 -310.965075) (xy 106.750993 -310.932624)
			(xy 106.800593 -310.907123) (xy 106.853377 -310.889116) (xy 106.90822 -310.878986) (xy 106.963954 -310.876949)
			(xy 107.019391 -310.883049) (xy 107.073348 -310.897155) (xy 107.124677 -310.918967) (xy 107.172283 -310.948021)
			(xy 107.215151 -310.983696) (xy 107.252368 -311.025233) (xy 107.283141 -311.071746) (xy 107.306813 -311.122243)
			(xy 107.322881 -311.17565) (xy 107.331001 -311.230826) (xy 107.33151 -311.258712) (xy 107.583984 -311.258712)
			(xy 107.588055 -311.20309) (xy 107.600181 -311.148653) (xy 107.620104 -311.096562) (xy 107.6474 -311.047927)
			(xy 107.681486 -311.003784) (xy 107.721635 -310.965075) (xy 107.766993 -310.932624) (xy 107.816593 -310.907123)
			(xy 107.869377 -310.889116) (xy 107.92422 -310.878986) (xy 107.979954 -310.876949) (xy 108.035391 -310.883049)
			(xy 108.089348 -310.897155) (xy 108.140677 -310.918967) (xy 108.188283 -310.948021) (xy 108.231151 -310.983696)
			(xy 108.268368 -311.025233) (xy 108.299141 -311.071746) (xy 108.322813 -311.122243) (xy 108.338881 -311.17565)
			(xy 108.347001 -311.230826) (xy 108.34751 -311.258712) (xy 108.599984 -311.258712) (xy 108.604055 -311.20309)
			(xy 108.616181 -311.148653) (xy 108.636104 -311.096562) (xy 108.6634 -311.047927) (xy 108.697486 -311.003784)
			(xy 108.737635 -310.965075) (xy 108.782993 -310.932624) (xy 108.832593 -310.907123) (xy 108.885377 -310.889116)
			(xy 108.94022 -310.878986) (xy 108.995954 -310.876949) (xy 109.051391 -310.883049) (xy 109.105348 -310.897155)
			(xy 109.156677 -310.918967) (xy 109.204283 -310.948021) (xy 109.247151 -310.983696) (xy 109.284368 -311.025233)
			(xy 109.315141 -311.071746) (xy 109.338813 -311.122243) (xy 109.354881 -311.17565) (xy 109.363001 -311.230826)
			(xy 109.36351 -311.258712) (xy 109.615984 -311.258712) (xy 109.620055 -311.20309) (xy 109.632181 -311.148653)
			(xy 109.652104 -311.096562) (xy 109.6794 -311.047927) (xy 109.713486 -311.003784) (xy 109.753635 -310.965075)
			(xy 109.798993 -310.932624) (xy 109.848593 -310.907123) (xy 109.901377 -310.889116) (xy 109.95622 -310.878986)
			(xy 110.011954 -310.876949) (xy 110.067391 -310.883049) (xy 110.121348 -310.897155) (xy 110.172677 -310.918967)
			(xy 110.220283 -310.948021) (xy 110.263151 -310.983696) (xy 110.300368 -311.025233) (xy 110.331141 -311.071746)
			(xy 110.354813 -311.122243) (xy 110.370881 -311.17565) (xy 110.379001 -311.230826) (xy 110.37951 -311.258712)
			(xy 110.379001 -311.286598) (xy 110.370881 -311.341774) (xy 110.354813 -311.395181) (xy 110.331141 -311.445678)
			(xy 110.300368 -311.492191) (xy 110.263151 -311.533728) (xy 110.220283 -311.569403) (xy 110.172677 -311.598457)
			(xy 110.121348 -311.620269) (xy 110.067391 -311.634375) (xy 110.011954 -311.640475) (xy 109.95622 -311.638438)
			(xy 109.901377 -311.628308) (xy 109.848593 -311.610301) (xy 109.798993 -311.5848) (xy 109.753635 -311.552349)
			(xy 109.713486 -311.51364) (xy 109.6794 -311.469497) (xy 109.652104 -311.420862) (xy 109.632181 -311.368771)
			(xy 109.620055 -311.314334) (xy 109.615984 -311.258712) (xy 109.36351 -311.258712) (xy 109.363001 -311.286598)
			(xy 109.354881 -311.341774) (xy 109.338813 -311.395181) (xy 109.315141 -311.445678) (xy 109.284368 -311.492191)
			(xy 109.247151 -311.533728) (xy 109.204283 -311.569403) (xy 109.156677 -311.598457) (xy 109.105348 -311.620269)
			(xy 109.051391 -311.634375) (xy 108.995954 -311.640475) (xy 108.94022 -311.638438) (xy 108.885377 -311.628308)
			(xy 108.832593 -311.610301) (xy 108.782993 -311.5848) (xy 108.737635 -311.552349) (xy 108.697486 -311.51364)
			(xy 108.6634 -311.469497) (xy 108.636104 -311.420862) (xy 108.616181 -311.368771) (xy 108.604055 -311.314334)
			(xy 108.599984 -311.258712) (xy 108.34751 -311.258712) (xy 108.347001 -311.286598) (xy 108.338881 -311.341774)
			(xy 108.322813 -311.395181) (xy 108.299141 -311.445678) (xy 108.268368 -311.492191) (xy 108.231151 -311.533728)
			(xy 108.188283 -311.569403) (xy 108.140677 -311.598457) (xy 108.089348 -311.620269) (xy 108.035391 -311.634375)
			(xy 107.979954 -311.640475) (xy 107.92422 -311.638438) (xy 107.869377 -311.628308) (xy 107.816593 -311.610301)
			(xy 107.766993 -311.5848) (xy 107.721635 -311.552349) (xy 107.681486 -311.51364) (xy 107.6474 -311.469497)
			(xy 107.620104 -311.420862) (xy 107.600181 -311.368771) (xy 107.588055 -311.314334) (xy 107.583984 -311.258712)
			(xy 107.33151 -311.258712) (xy 107.331001 -311.286598) (xy 107.322881 -311.341774) (xy 107.306813 -311.395181)
			(xy 107.283141 -311.445678) (xy 107.252368 -311.492191) (xy 107.215151 -311.533728) (xy 107.172283 -311.569403)
			(xy 107.124677 -311.598457) (xy 107.073348 -311.620269) (xy 107.019391 -311.634375) (xy 106.963954 -311.640475)
			(xy 106.90822 -311.638438) (xy 106.853377 -311.628308) (xy 106.800593 -311.610301) (xy 106.750993 -311.5848)
			(xy 106.705635 -311.552349) (xy 106.665486 -311.51364) (xy 106.6314 -311.469497) (xy 106.604104 -311.420862)
			(xy 106.584181 -311.368771) (xy 106.572055 -311.314334) (xy 106.567984 -311.258712) (xy 106.31551 -311.258712)
			(xy 106.315001 -311.286598) (xy 106.306881 -311.341774) (xy 106.290813 -311.395181) (xy 106.267141 -311.445678)
			(xy 106.236368 -311.492191) (xy 106.199151 -311.533728) (xy 106.156283 -311.569403) (xy 106.108677 -311.598457)
			(xy 106.057348 -311.620269) (xy 106.003391 -311.634375) (xy 105.947954 -311.640475) (xy 105.89222 -311.638438)
			(xy 105.837377 -311.628308) (xy 105.784593 -311.610301) (xy 105.734993 -311.5848) (xy 105.689635 -311.552349)
			(xy 105.649486 -311.51364) (xy 105.6154 -311.469497) (xy 105.588104 -311.420862) (xy 105.568181 -311.368771)
			(xy 105.556055 -311.314334) (xy 105.551984 -311.258712) (xy 105.29951 -311.258712) (xy 105.299001 -311.286598)
			(xy 105.290881 -311.341774) (xy 105.274813 -311.395181) (xy 105.251141 -311.445678) (xy 105.220368 -311.492191)
			(xy 105.183151 -311.533728) (xy 105.140283 -311.569403) (xy 105.092677 -311.598457) (xy 105.041348 -311.620269)
			(xy 104.987391 -311.634375) (xy 104.931954 -311.640475) (xy 104.87622 -311.638438) (xy 104.821377 -311.628308)
			(xy 104.768593 -311.610301) (xy 104.718993 -311.5848) (xy 104.673635 -311.552349) (xy 104.633486 -311.51364)
			(xy 104.5994 -311.469497) (xy 104.572104 -311.420862) (xy 104.552181 -311.368771) (xy 104.540055 -311.314334)
			(xy 104.535984 -311.258712) (xy 104.28351 -311.258712) (xy 104.283001 -311.286598) (xy 104.274881 -311.341774)
			(xy 104.258813 -311.395181) (xy 104.235141 -311.445678) (xy 104.204368 -311.492191) (xy 104.167151 -311.533728)
			(xy 104.124283 -311.569403) (xy 104.076677 -311.598457) (xy 104.025348 -311.620269) (xy 103.971391 -311.634375)
			(xy 103.915954 -311.640475) (xy 103.86022 -311.638438) (xy 103.805377 -311.628308) (xy 103.752593 -311.610301)
			(xy 103.702993 -311.5848) (xy 103.657635 -311.552349) (xy 103.617486 -311.51364) (xy 103.5834 -311.469497)
			(xy 103.556104 -311.420862) (xy 103.536181 -311.368771) (xy 103.524055 -311.314334) (xy 103.519984 -311.258712)
			(xy 103.26751 -311.258712) (xy 103.267001 -311.286598) (xy 103.258881 -311.341774) (xy 103.242813 -311.395181)
			(xy 103.219141 -311.445678) (xy 103.188368 -311.492191) (xy 103.151151 -311.533728) (xy 103.108283 -311.569403)
			(xy 103.060677 -311.598457) (xy 103.009348 -311.620269) (xy 102.955391 -311.634375) (xy 102.899954 -311.640475)
			(xy 102.84422 -311.638438) (xy 102.789377 -311.628308) (xy 102.736593 -311.610301) (xy 102.686993 -311.5848)
			(xy 102.641635 -311.552349) (xy 102.601486 -311.51364) (xy 102.5674 -311.469497) (xy 102.540104 -311.420862)
			(xy 102.520181 -311.368771) (xy 102.508055 -311.314334) (xy 102.503984 -311.258712) (xy 102.25151 -311.258712)
			(xy 102.251001 -311.286598) (xy 102.242881 -311.341774) (xy 102.226813 -311.395181) (xy 102.203141 -311.445678)
			(xy 102.172368 -311.492191) (xy 102.135151 -311.533728) (xy 102.092283 -311.569403) (xy 102.044677 -311.598457)
			(xy 101.993348 -311.620269) (xy 101.939391 -311.634375) (xy 101.883954 -311.640475) (xy 101.82822 -311.638438)
			(xy 101.773377 -311.628308) (xy 101.720593 -311.610301) (xy 101.670993 -311.5848) (xy 101.625635 -311.552349)
			(xy 101.585486 -311.51364) (xy 101.5514 -311.469497) (xy 101.524104 -311.420862) (xy 101.504181 -311.368771)
			(xy 101.492055 -311.314334) (xy 101.487984 -311.258712) (xy 101.23551 -311.258712) (xy 101.235001 -311.286598)
			(xy 101.226881 -311.341774) (xy 101.210813 -311.395181) (xy 101.187141 -311.445678) (xy 101.156368 -311.492191)
			(xy 101.119151 -311.533728) (xy 101.076283 -311.569403) (xy 101.028677 -311.598457) (xy 100.977348 -311.620269)
			(xy 100.923391 -311.634375) (xy 100.867954 -311.640475) (xy 100.81222 -311.638438) (xy 100.757377 -311.628308)
			(xy 100.704593 -311.610301) (xy 100.654993 -311.5848) (xy 100.609635 -311.552349) (xy 100.569486 -311.51364)
			(xy 100.5354 -311.469497) (xy 100.508104 -311.420862) (xy 100.488181 -311.368771) (xy 100.476055 -311.314334)
			(xy 100.471984 -311.258712) (xy 99.78771 -311.258712) (xy 99.78771 -312.274712) (xy 100.471984 -312.274712)
			(xy 100.476055 -312.21909) (xy 100.488181 -312.164653) (xy 100.508104 -312.112562) (xy 100.5354 -312.063927)
			(xy 100.569486 -312.019784) (xy 100.609635 -311.981075) (xy 100.654993 -311.948624) (xy 100.704593 -311.923123)
			(xy 100.757377 -311.905116) (xy 100.81222 -311.894986) (xy 100.867954 -311.892949) (xy 100.923391 -311.899049)
			(xy 100.977348 -311.913155) (xy 101.028677 -311.934967) (xy 101.076283 -311.964021) (xy 101.119151 -311.999696)
			(xy 101.156368 -312.041233) (xy 101.187141 -312.087746) (xy 101.210813 -312.138243) (xy 101.226881 -312.19165)
			(xy 101.235001 -312.246826) (xy 101.23551 -312.274712) (xy 101.487984 -312.274712) (xy 101.492055 -312.21909)
			(xy 101.504181 -312.164653) (xy 101.524104 -312.112562) (xy 101.5514 -312.063927) (xy 101.585486 -312.019784)
			(xy 101.625635 -311.981075) (xy 101.670993 -311.948624) (xy 101.720593 -311.923123) (xy 101.773377 -311.905116)
			(xy 101.82822 -311.894986) (xy 101.883954 -311.892949) (xy 101.939391 -311.899049) (xy 101.993348 -311.913155)
			(xy 102.044677 -311.934967) (xy 102.092283 -311.964021) (xy 102.135151 -311.999696) (xy 102.172368 -312.041233)
			(xy 102.203141 -312.087746) (xy 102.226813 -312.138243) (xy 102.242881 -312.19165) (xy 102.251001 -312.246826)
			(xy 102.25151 -312.274712) (xy 102.503984 -312.274712) (xy 102.508055 -312.21909) (xy 102.520181 -312.164653)
			(xy 102.540104 -312.112562) (xy 102.5674 -312.063927) (xy 102.601486 -312.019784) (xy 102.641635 -311.981075)
			(xy 102.686993 -311.948624) (xy 102.736593 -311.923123) (xy 102.789377 -311.905116) (xy 102.84422 -311.894986)
			(xy 102.899954 -311.892949) (xy 102.955391 -311.899049) (xy 103.009348 -311.913155) (xy 103.060677 -311.934967)
			(xy 103.108283 -311.964021) (xy 103.151151 -311.999696) (xy 103.188368 -312.041233) (xy 103.219141 -312.087746)
			(xy 103.242813 -312.138243) (xy 103.258881 -312.19165) (xy 103.267001 -312.246826) (xy 103.26751 -312.274712)
			(xy 103.519984 -312.274712) (xy 103.524055 -312.21909) (xy 103.536181 -312.164653) (xy 103.556104 -312.112562)
			(xy 103.5834 -312.063927) (xy 103.617486 -312.019784) (xy 103.657635 -311.981075) (xy 103.702993 -311.948624)
			(xy 103.752593 -311.923123) (xy 103.805377 -311.905116) (xy 103.86022 -311.894986) (xy 103.915954 -311.892949)
			(xy 103.971391 -311.899049) (xy 104.025348 -311.913155) (xy 104.076677 -311.934967) (xy 104.124283 -311.964021)
			(xy 104.167151 -311.999696) (xy 104.204368 -312.041233) (xy 104.235141 -312.087746) (xy 104.258813 -312.138243)
			(xy 104.274881 -312.19165) (xy 104.283001 -312.246826) (xy 104.28351 -312.274712) (xy 104.535984 -312.274712)
			(xy 104.540055 -312.21909) (xy 104.552181 -312.164653) (xy 104.572104 -312.112562) (xy 104.5994 -312.063927)
			(xy 104.633486 -312.019784) (xy 104.673635 -311.981075) (xy 104.718993 -311.948624) (xy 104.768593 -311.923123)
			(xy 104.821377 -311.905116) (xy 104.87622 -311.894986) (xy 104.931954 -311.892949) (xy 104.987391 -311.899049)
			(xy 105.041348 -311.913155) (xy 105.092677 -311.934967) (xy 105.140283 -311.964021) (xy 105.183151 -311.999696)
			(xy 105.220368 -312.041233) (xy 105.251141 -312.087746) (xy 105.274813 -312.138243) (xy 105.290881 -312.19165)
			(xy 105.299001 -312.246826) (xy 105.29951 -312.274712) (xy 105.551984 -312.274712) (xy 105.556055 -312.21909)
			(xy 105.568181 -312.164653) (xy 105.588104 -312.112562) (xy 105.6154 -312.063927) (xy 105.649486 -312.019784)
			(xy 105.689635 -311.981075) (xy 105.734993 -311.948624) (xy 105.784593 -311.923123) (xy 105.837377 -311.905116)
			(xy 105.89222 -311.894986) (xy 105.947954 -311.892949) (xy 106.003391 -311.899049) (xy 106.057348 -311.913155)
			(xy 106.108677 -311.934967) (xy 106.156283 -311.964021) (xy 106.199151 -311.999696) (xy 106.236368 -312.041233)
			(xy 106.267141 -312.087746) (xy 106.290813 -312.138243) (xy 106.306881 -312.19165) (xy 106.315001 -312.246826)
			(xy 106.31551 -312.274712) (xy 106.567984 -312.274712) (xy 106.572055 -312.21909) (xy 106.584181 -312.164653)
			(xy 106.604104 -312.112562) (xy 106.6314 -312.063927) (xy 106.665486 -312.019784) (xy 106.705635 -311.981075)
			(xy 106.750993 -311.948624) (xy 106.800593 -311.923123) (xy 106.853377 -311.905116) (xy 106.90822 -311.894986)
			(xy 106.963954 -311.892949) (xy 107.019391 -311.899049) (xy 107.073348 -311.913155) (xy 107.124677 -311.934967)
			(xy 107.172283 -311.964021) (xy 107.215151 -311.999696) (xy 107.252368 -312.041233) (xy 107.283141 -312.087746)
			(xy 107.306813 -312.138243) (xy 107.322881 -312.19165) (xy 107.331001 -312.246826) (xy 107.33151 -312.274712)
			(xy 107.583984 -312.274712) (xy 107.588055 -312.21909) (xy 107.600181 -312.164653) (xy 107.620104 -312.112562)
			(xy 107.6474 -312.063927) (xy 107.681486 -312.019784) (xy 107.721635 -311.981075) (xy 107.766993 -311.948624)
			(xy 107.816593 -311.923123) (xy 107.869377 -311.905116) (xy 107.92422 -311.894986) (xy 107.979954 -311.892949)
			(xy 108.035391 -311.899049) (xy 108.089348 -311.913155) (xy 108.140677 -311.934967) (xy 108.188283 -311.964021)
			(xy 108.231151 -311.999696) (xy 108.268368 -312.041233) (xy 108.299141 -312.087746) (xy 108.322813 -312.138243)
			(xy 108.338881 -312.19165) (xy 108.347001 -312.246826) (xy 108.34751 -312.274712) (xy 108.599984 -312.274712)
			(xy 108.604055 -312.21909) (xy 108.616181 -312.164653) (xy 108.636104 -312.112562) (xy 108.6634 -312.063927)
			(xy 108.697486 -312.019784) (xy 108.737635 -311.981075) (xy 108.782993 -311.948624) (xy 108.832593 -311.923123)
			(xy 108.885377 -311.905116) (xy 108.94022 -311.894986) (xy 108.995954 -311.892949) (xy 109.051391 -311.899049)
			(xy 109.105348 -311.913155) (xy 109.156677 -311.934967) (xy 109.204283 -311.964021) (xy 109.247151 -311.999696)
			(xy 109.284368 -312.041233) (xy 109.315141 -312.087746) (xy 109.338813 -312.138243) (xy 109.354881 -312.19165)
			(xy 109.363001 -312.246826) (xy 109.36351 -312.274712) (xy 109.615984 -312.274712) (xy 109.620055 -312.21909)
			(xy 109.632181 -312.164653) (xy 109.652104 -312.112562) (xy 109.6794 -312.063927) (xy 109.713486 -312.019784)
			(xy 109.753635 -311.981075) (xy 109.798993 -311.948624) (xy 109.848593 -311.923123) (xy 109.901377 -311.905116)
			(xy 109.95622 -311.894986) (xy 110.011954 -311.892949) (xy 110.067391 -311.899049) (xy 110.121348 -311.913155)
			(xy 110.172677 -311.934967) (xy 110.220283 -311.964021) (xy 110.263151 -311.999696) (xy 110.300368 -312.041233)
			(xy 110.331141 -312.087746) (xy 110.354813 -312.138243) (xy 110.370881 -312.19165) (xy 110.379001 -312.246826)
			(xy 110.37951 -312.274712) (xy 110.379001 -312.302598) (xy 110.370881 -312.357774) (xy 110.354813 -312.411181)
			(xy 110.331141 -312.461678) (xy 110.300368 -312.508191) (xy 110.263151 -312.549728) (xy 110.220283 -312.585403)
			(xy 110.172677 -312.614457) (xy 110.121348 -312.636269) (xy 110.067391 -312.650375) (xy 110.011954 -312.656475)
			(xy 109.95622 -312.654438) (xy 109.901377 -312.644308) (xy 109.848593 -312.626301) (xy 109.798993 -312.6008)
			(xy 109.753635 -312.568349) (xy 109.713486 -312.52964) (xy 109.6794 -312.485497) (xy 109.652104 -312.436862)
			(xy 109.632181 -312.384771) (xy 109.620055 -312.330334) (xy 109.615984 -312.274712) (xy 109.36351 -312.274712)
			(xy 109.363001 -312.302598) (xy 109.354881 -312.357774) (xy 109.338813 -312.411181) (xy 109.315141 -312.461678)
			(xy 109.284368 -312.508191) (xy 109.247151 -312.549728) (xy 109.204283 -312.585403) (xy 109.156677 -312.614457)
			(xy 109.105348 -312.636269) (xy 109.051391 -312.650375) (xy 108.995954 -312.656475) (xy 108.94022 -312.654438)
			(xy 108.885377 -312.644308) (xy 108.832593 -312.626301) (xy 108.782993 -312.6008) (xy 108.737635 -312.568349)
			(xy 108.697486 -312.52964) (xy 108.6634 -312.485497) (xy 108.636104 -312.436862) (xy 108.616181 -312.384771)
			(xy 108.604055 -312.330334) (xy 108.599984 -312.274712) (xy 108.34751 -312.274712) (xy 108.347001 -312.302598)
			(xy 108.338881 -312.357774) (xy 108.322813 -312.411181) (xy 108.299141 -312.461678) (xy 108.268368 -312.508191)
			(xy 108.231151 -312.549728) (xy 108.188283 -312.585403) (xy 108.140677 -312.614457) (xy 108.089348 -312.636269)
			(xy 108.035391 -312.650375) (xy 107.979954 -312.656475) (xy 107.92422 -312.654438) (xy 107.869377 -312.644308)
			(xy 107.816593 -312.626301) (xy 107.766993 -312.6008) (xy 107.721635 -312.568349) (xy 107.681486 -312.52964)
			(xy 107.6474 -312.485497) (xy 107.620104 -312.436862) (xy 107.600181 -312.384771) (xy 107.588055 -312.330334)
			(xy 107.583984 -312.274712) (xy 107.33151 -312.274712) (xy 107.331001 -312.302598) (xy 107.322881 -312.357774)
			(xy 107.306813 -312.411181) (xy 107.283141 -312.461678) (xy 107.252368 -312.508191) (xy 107.215151 -312.549728)
			(xy 107.172283 -312.585403) (xy 107.124677 -312.614457) (xy 107.073348 -312.636269) (xy 107.019391 -312.650375)
			(xy 106.963954 -312.656475) (xy 106.90822 -312.654438) (xy 106.853377 -312.644308) (xy 106.800593 -312.626301)
			(xy 106.750993 -312.6008) (xy 106.705635 -312.568349) (xy 106.665486 -312.52964) (xy 106.6314 -312.485497)
			(xy 106.604104 -312.436862) (xy 106.584181 -312.384771) (xy 106.572055 -312.330334) (xy 106.567984 -312.274712)
			(xy 106.31551 -312.274712) (xy 106.315001 -312.302598) (xy 106.306881 -312.357774) (xy 106.290813 -312.411181)
			(xy 106.267141 -312.461678) (xy 106.236368 -312.508191) (xy 106.199151 -312.549728) (xy 106.156283 -312.585403)
			(xy 106.108677 -312.614457) (xy 106.057348 -312.636269) (xy 106.003391 -312.650375) (xy 105.947954 -312.656475)
			(xy 105.89222 -312.654438) (xy 105.837377 -312.644308) (xy 105.784593 -312.626301) (xy 105.734993 -312.6008)
			(xy 105.689635 -312.568349) (xy 105.649486 -312.52964) (xy 105.6154 -312.485497) (xy 105.588104 -312.436862)
			(xy 105.568181 -312.384771) (xy 105.556055 -312.330334) (xy 105.551984 -312.274712) (xy 105.29951 -312.274712)
			(xy 105.299001 -312.302598) (xy 105.290881 -312.357774) (xy 105.274813 -312.411181) (xy 105.251141 -312.461678)
			(xy 105.220368 -312.508191) (xy 105.183151 -312.549728) (xy 105.140283 -312.585403) (xy 105.092677 -312.614457)
			(xy 105.041348 -312.636269) (xy 104.987391 -312.650375) (xy 104.931954 -312.656475) (xy 104.87622 -312.654438)
			(xy 104.821377 -312.644308) (xy 104.768593 -312.626301) (xy 104.718993 -312.6008) (xy 104.673635 -312.568349)
			(xy 104.633486 -312.52964) (xy 104.5994 -312.485497) (xy 104.572104 -312.436862) (xy 104.552181 -312.384771)
			(xy 104.540055 -312.330334) (xy 104.535984 -312.274712) (xy 104.28351 -312.274712) (xy 104.283001 -312.302598)
			(xy 104.274881 -312.357774) (xy 104.258813 -312.411181) (xy 104.235141 -312.461678) (xy 104.204368 -312.508191)
			(xy 104.167151 -312.549728) (xy 104.124283 -312.585403) (xy 104.076677 -312.614457) (xy 104.025348 -312.636269)
			(xy 103.971391 -312.650375) (xy 103.915954 -312.656475) (xy 103.86022 -312.654438) (xy 103.805377 -312.644308)
			(xy 103.752593 -312.626301) (xy 103.702993 -312.6008) (xy 103.657635 -312.568349) (xy 103.617486 -312.52964)
			(xy 103.5834 -312.485497) (xy 103.556104 -312.436862) (xy 103.536181 -312.384771) (xy 103.524055 -312.330334)
			(xy 103.519984 -312.274712) (xy 103.26751 -312.274712) (xy 103.267001 -312.302598) (xy 103.258881 -312.357774)
			(xy 103.242813 -312.411181) (xy 103.219141 -312.461678) (xy 103.188368 -312.508191) (xy 103.151151 -312.549728)
			(xy 103.108283 -312.585403) (xy 103.060677 -312.614457) (xy 103.009348 -312.636269) (xy 102.955391 -312.650375)
			(xy 102.899954 -312.656475) (xy 102.84422 -312.654438) (xy 102.789377 -312.644308) (xy 102.736593 -312.626301)
			(xy 102.686993 -312.6008) (xy 102.641635 -312.568349) (xy 102.601486 -312.52964) (xy 102.5674 -312.485497)
			(xy 102.540104 -312.436862) (xy 102.520181 -312.384771) (xy 102.508055 -312.330334) (xy 102.503984 -312.274712)
			(xy 102.25151 -312.274712) (xy 102.251001 -312.302598) (xy 102.242881 -312.357774) (xy 102.226813 -312.411181)
			(xy 102.203141 -312.461678) (xy 102.172368 -312.508191) (xy 102.135151 -312.549728) (xy 102.092283 -312.585403)
			(xy 102.044677 -312.614457) (xy 101.993348 -312.636269) (xy 101.939391 -312.650375) (xy 101.883954 -312.656475)
			(xy 101.82822 -312.654438) (xy 101.773377 -312.644308) (xy 101.720593 -312.626301) (xy 101.670993 -312.6008)
			(xy 101.625635 -312.568349) (xy 101.585486 -312.52964) (xy 101.5514 -312.485497) (xy 101.524104 -312.436862)
			(xy 101.504181 -312.384771) (xy 101.492055 -312.330334) (xy 101.487984 -312.274712) (xy 101.23551 -312.274712)
			(xy 101.235001 -312.302598) (xy 101.226881 -312.357774) (xy 101.210813 -312.411181) (xy 101.187141 -312.461678)
			(xy 101.156368 -312.508191) (xy 101.119151 -312.549728) (xy 101.076283 -312.585403) (xy 101.028677 -312.614457)
			(xy 100.977348 -312.636269) (xy 100.923391 -312.650375) (xy 100.867954 -312.656475) (xy 100.81222 -312.654438)
			(xy 100.757377 -312.644308) (xy 100.704593 -312.626301) (xy 100.654993 -312.6008) (xy 100.609635 -312.568349)
			(xy 100.569486 -312.52964) (xy 100.5354 -312.485497) (xy 100.508104 -312.436862) (xy 100.488181 -312.384771)
			(xy 100.476055 -312.330334) (xy 100.471984 -312.274712) (xy 99.78771 -312.274712) (xy 99.78771 -313.290712)
			(xy 100.471984 -313.290712) (xy 100.476055 -313.23509) (xy 100.488181 -313.180653) (xy 100.508104 -313.128562)
			(xy 100.5354 -313.079927) (xy 100.569486 -313.035784) (xy 100.609635 -312.997075) (xy 100.654993 -312.964624)
			(xy 100.704593 -312.939123) (xy 100.757377 -312.921116) (xy 100.81222 -312.910986) (xy 100.867954 -312.908949)
			(xy 100.923391 -312.915049) (xy 100.977348 -312.929155) (xy 101.028677 -312.950967) (xy 101.076283 -312.980021)
			(xy 101.119151 -313.015696) (xy 101.156368 -313.057233) (xy 101.187141 -313.103746) (xy 101.210813 -313.154243)
			(xy 101.226881 -313.20765) (xy 101.235001 -313.262826) (xy 101.23551 -313.290712) (xy 101.487984 -313.290712)
			(xy 101.492055 -313.23509) (xy 101.504181 -313.180653) (xy 101.524104 -313.128562) (xy 101.5514 -313.079927)
			(xy 101.585486 -313.035784) (xy 101.625635 -312.997075) (xy 101.670993 -312.964624) (xy 101.720593 -312.939123)
			(xy 101.773377 -312.921116) (xy 101.82822 -312.910986) (xy 101.883954 -312.908949) (xy 101.939391 -312.915049)
			(xy 101.993348 -312.929155) (xy 102.044677 -312.950967) (xy 102.092283 -312.980021) (xy 102.135151 -313.015696)
			(xy 102.172368 -313.057233) (xy 102.203141 -313.103746) (xy 102.226813 -313.154243) (xy 102.242881 -313.20765)
			(xy 102.251001 -313.262826) (xy 102.25151 -313.290712) (xy 102.503984 -313.290712) (xy 102.508055 -313.23509)
			(xy 102.520181 -313.180653) (xy 102.540104 -313.128562) (xy 102.5674 -313.079927) (xy 102.601486 -313.035784)
			(xy 102.641635 -312.997075) (xy 102.686993 -312.964624) (xy 102.736593 -312.939123) (xy 102.789377 -312.921116)
			(xy 102.84422 -312.910986) (xy 102.899954 -312.908949) (xy 102.955391 -312.915049) (xy 103.009348 -312.929155)
			(xy 103.060677 -312.950967) (xy 103.108283 -312.980021) (xy 103.151151 -313.015696) (xy 103.188368 -313.057233)
			(xy 103.219141 -313.103746) (xy 103.242813 -313.154243) (xy 103.258881 -313.20765) (xy 103.267001 -313.262826)
			(xy 103.26751 -313.290712) (xy 103.519984 -313.290712) (xy 103.524055 -313.23509) (xy 103.536181 -313.180653)
			(xy 103.556104 -313.128562) (xy 103.5834 -313.079927) (xy 103.617486 -313.035784) (xy 103.657635 -312.997075)
			(xy 103.702993 -312.964624) (xy 103.752593 -312.939123) (xy 103.805377 -312.921116) (xy 103.86022 -312.910986)
			(xy 103.915954 -312.908949) (xy 103.971391 -312.915049) (xy 104.025348 -312.929155) (xy 104.076677 -312.950967)
			(xy 104.124283 -312.980021) (xy 104.167151 -313.015696) (xy 104.204368 -313.057233) (xy 104.235141 -313.103746)
			(xy 104.258813 -313.154243) (xy 104.274881 -313.20765) (xy 104.283001 -313.262826) (xy 104.28351 -313.290712)
			(xy 104.535984 -313.290712) (xy 104.540055 -313.23509) (xy 104.552181 -313.180653) (xy 104.572104 -313.128562)
			(xy 104.5994 -313.079927) (xy 104.633486 -313.035784) (xy 104.673635 -312.997075) (xy 104.718993 -312.964624)
			(xy 104.768593 -312.939123) (xy 104.821377 -312.921116) (xy 104.87622 -312.910986) (xy 104.931954 -312.908949)
			(xy 104.987391 -312.915049) (xy 105.041348 -312.929155) (xy 105.092677 -312.950967) (xy 105.140283 -312.980021)
			(xy 105.183151 -313.015696) (xy 105.220368 -313.057233) (xy 105.251141 -313.103746) (xy 105.274813 -313.154243)
			(xy 105.290881 -313.20765) (xy 105.299001 -313.262826) (xy 105.29951 -313.290712) (xy 105.551984 -313.290712)
			(xy 105.556055 -313.23509) (xy 105.568181 -313.180653) (xy 105.588104 -313.128562) (xy 105.6154 -313.079927)
			(xy 105.649486 -313.035784) (xy 105.689635 -312.997075) (xy 105.734993 -312.964624) (xy 105.784593 -312.939123)
			(xy 105.837377 -312.921116) (xy 105.89222 -312.910986) (xy 105.947954 -312.908949) (xy 106.003391 -312.915049)
			(xy 106.057348 -312.929155) (xy 106.108677 -312.950967) (xy 106.156283 -312.980021) (xy 106.199151 -313.015696)
			(xy 106.236368 -313.057233) (xy 106.267141 -313.103746) (xy 106.290813 -313.154243) (xy 106.306881 -313.20765)
			(xy 106.315001 -313.262826) (xy 106.31551 -313.290712) (xy 106.567984 -313.290712) (xy 106.572055 -313.23509)
			(xy 106.584181 -313.180653) (xy 106.604104 -313.128562) (xy 106.6314 -313.079927) (xy 106.665486 -313.035784)
			(xy 106.705635 -312.997075) (xy 106.750993 -312.964624) (xy 106.800593 -312.939123) (xy 106.853377 -312.921116)
			(xy 106.90822 -312.910986) (xy 106.963954 -312.908949) (xy 107.019391 -312.915049) (xy 107.073348 -312.929155)
			(xy 107.124677 -312.950967) (xy 107.172283 -312.980021) (xy 107.215151 -313.015696) (xy 107.252368 -313.057233)
			(xy 107.283141 -313.103746) (xy 107.306813 -313.154243) (xy 107.322881 -313.20765) (xy 107.331001 -313.262826)
			(xy 107.33151 -313.290712) (xy 107.583984 -313.290712) (xy 107.588055 -313.23509) (xy 107.600181 -313.180653)
			(xy 107.620104 -313.128562) (xy 107.6474 -313.079927) (xy 107.681486 -313.035784) (xy 107.721635 -312.997075)
			(xy 107.766993 -312.964624) (xy 107.816593 -312.939123) (xy 107.869377 -312.921116) (xy 107.92422 -312.910986)
			(xy 107.979954 -312.908949) (xy 108.035391 -312.915049) (xy 108.089348 -312.929155) (xy 108.140677 -312.950967)
			(xy 108.188283 -312.980021) (xy 108.231151 -313.015696) (xy 108.268368 -313.057233) (xy 108.299141 -313.103746)
			(xy 108.322813 -313.154243) (xy 108.338881 -313.20765) (xy 108.347001 -313.262826) (xy 108.34751 -313.290712)
			(xy 108.599984 -313.290712) (xy 108.604055 -313.23509) (xy 108.616181 -313.180653) (xy 108.636104 -313.128562)
			(xy 108.6634 -313.079927) (xy 108.697486 -313.035784) (xy 108.737635 -312.997075) (xy 108.782993 -312.964624)
			(xy 108.832593 -312.939123) (xy 108.885377 -312.921116) (xy 108.94022 -312.910986) (xy 108.995954 -312.908949)
			(xy 109.051391 -312.915049) (xy 109.105348 -312.929155) (xy 109.156677 -312.950967) (xy 109.204283 -312.980021)
			(xy 109.247151 -313.015696) (xy 109.284368 -313.057233) (xy 109.315141 -313.103746) (xy 109.338813 -313.154243)
			(xy 109.354881 -313.20765) (xy 109.363001 -313.262826) (xy 109.36351 -313.290712) (xy 109.615984 -313.290712)
			(xy 109.620055 -313.23509) (xy 109.632181 -313.180653) (xy 109.652104 -313.128562) (xy 109.6794 -313.079927)
			(xy 109.713486 -313.035784) (xy 109.753635 -312.997075) (xy 109.798993 -312.964624) (xy 109.848593 -312.939123)
			(xy 109.901377 -312.921116) (xy 109.95622 -312.910986) (xy 110.011954 -312.908949) (xy 110.067391 -312.915049)
			(xy 110.121348 -312.929155) (xy 110.172677 -312.950967) (xy 110.220283 -312.980021) (xy 110.263151 -313.015696)
			(xy 110.300368 -313.057233) (xy 110.331141 -313.103746) (xy 110.354813 -313.154243) (xy 110.370881 -313.20765)
			(xy 110.379001 -313.262826) (xy 110.37951 -313.290712) (xy 110.379001 -313.318598) (xy 110.370881 -313.373774)
			(xy 110.354813 -313.427181) (xy 110.331141 -313.477678) (xy 110.300368 -313.524191) (xy 110.263151 -313.565728)
			(xy 110.220283 -313.601403) (xy 110.172677 -313.630457) (xy 110.121348 -313.652269) (xy 110.067391 -313.666375)
			(xy 110.011954 -313.672475) (xy 109.95622 -313.670438) (xy 109.901377 -313.660308) (xy 109.848593 -313.642301)
			(xy 109.798993 -313.6168) (xy 109.753635 -313.584349) (xy 109.713486 -313.54564) (xy 109.6794 -313.501497)
			(xy 109.652104 -313.452862) (xy 109.632181 -313.400771) (xy 109.620055 -313.346334) (xy 109.615984 -313.290712)
			(xy 109.36351 -313.290712) (xy 109.363001 -313.318598) (xy 109.354881 -313.373774) (xy 109.338813 -313.427181)
			(xy 109.315141 -313.477678) (xy 109.284368 -313.524191) (xy 109.247151 -313.565728) (xy 109.204283 -313.601403)
			(xy 109.156677 -313.630457) (xy 109.105348 -313.652269) (xy 109.051391 -313.666375) (xy 108.995954 -313.672475)
			(xy 108.94022 -313.670438) (xy 108.885377 -313.660308) (xy 108.832593 -313.642301) (xy 108.782993 -313.6168)
			(xy 108.737635 -313.584349) (xy 108.697486 -313.54564) (xy 108.6634 -313.501497) (xy 108.636104 -313.452862)
			(xy 108.616181 -313.400771) (xy 108.604055 -313.346334) (xy 108.599984 -313.290712) (xy 108.34751 -313.290712)
			(xy 108.347001 -313.318598) (xy 108.338881 -313.373774) (xy 108.322813 -313.427181) (xy 108.299141 -313.477678)
			(xy 108.268368 -313.524191) (xy 108.231151 -313.565728) (xy 108.188283 -313.601403) (xy 108.140677 -313.630457)
			(xy 108.089348 -313.652269) (xy 108.035391 -313.666375) (xy 107.979954 -313.672475) (xy 107.92422 -313.670438)
			(xy 107.869377 -313.660308) (xy 107.816593 -313.642301) (xy 107.766993 -313.6168) (xy 107.721635 -313.584349)
			(xy 107.681486 -313.54564) (xy 107.6474 -313.501497) (xy 107.620104 -313.452862) (xy 107.600181 -313.400771)
			(xy 107.588055 -313.346334) (xy 107.583984 -313.290712) (xy 107.33151 -313.290712) (xy 107.331001 -313.318598)
			(xy 107.322881 -313.373774) (xy 107.306813 -313.427181) (xy 107.283141 -313.477678) (xy 107.252368 -313.524191)
			(xy 107.215151 -313.565728) (xy 107.172283 -313.601403) (xy 107.124677 -313.630457) (xy 107.073348 -313.652269)
			(xy 107.019391 -313.666375) (xy 106.963954 -313.672475) (xy 106.90822 -313.670438) (xy 106.853377 -313.660308)
			(xy 106.800593 -313.642301) (xy 106.750993 -313.6168) (xy 106.705635 -313.584349) (xy 106.665486 -313.54564)
			(xy 106.6314 -313.501497) (xy 106.604104 -313.452862) (xy 106.584181 -313.400771) (xy 106.572055 -313.346334)
			(xy 106.567984 -313.290712) (xy 106.31551 -313.290712) (xy 106.315001 -313.318598) (xy 106.306881 -313.373774)
			(xy 106.290813 -313.427181) (xy 106.267141 -313.477678) (xy 106.236368 -313.524191) (xy 106.199151 -313.565728)
			(xy 106.156283 -313.601403) (xy 106.108677 -313.630457) (xy 106.057348 -313.652269) (xy 106.003391 -313.666375)
			(xy 105.947954 -313.672475) (xy 105.89222 -313.670438) (xy 105.837377 -313.660308) (xy 105.784593 -313.642301)
			(xy 105.734993 -313.6168) (xy 105.689635 -313.584349) (xy 105.649486 -313.54564) (xy 105.6154 -313.501497)
			(xy 105.588104 -313.452862) (xy 105.568181 -313.400771) (xy 105.556055 -313.346334) (xy 105.551984 -313.290712)
			(xy 105.29951 -313.290712) (xy 105.299001 -313.318598) (xy 105.290881 -313.373774) (xy 105.274813 -313.427181)
			(xy 105.251141 -313.477678) (xy 105.220368 -313.524191) (xy 105.183151 -313.565728) (xy 105.140283 -313.601403)
			(xy 105.092677 -313.630457) (xy 105.041348 -313.652269) (xy 104.987391 -313.666375) (xy 104.931954 -313.672475)
			(xy 104.87622 -313.670438) (xy 104.821377 -313.660308) (xy 104.768593 -313.642301) (xy 104.718993 -313.6168)
			(xy 104.673635 -313.584349) (xy 104.633486 -313.54564) (xy 104.5994 -313.501497) (xy 104.572104 -313.452862)
			(xy 104.552181 -313.400771) (xy 104.540055 -313.346334) (xy 104.535984 -313.290712) (xy 104.28351 -313.290712)
			(xy 104.283001 -313.318598) (xy 104.274881 -313.373774) (xy 104.258813 -313.427181) (xy 104.235141 -313.477678)
			(xy 104.204368 -313.524191) (xy 104.167151 -313.565728) (xy 104.124283 -313.601403) (xy 104.076677 -313.630457)
			(xy 104.025348 -313.652269) (xy 103.971391 -313.666375) (xy 103.915954 -313.672475) (xy 103.86022 -313.670438)
			(xy 103.805377 -313.660308) (xy 103.752593 -313.642301) (xy 103.702993 -313.6168) (xy 103.657635 -313.584349)
			(xy 103.617486 -313.54564) (xy 103.5834 -313.501497) (xy 103.556104 -313.452862) (xy 103.536181 -313.400771)
			(xy 103.524055 -313.346334) (xy 103.519984 -313.290712) (xy 103.26751 -313.290712) (xy 103.267001 -313.318598)
			(xy 103.258881 -313.373774) (xy 103.242813 -313.427181) (xy 103.219141 -313.477678) (xy 103.188368 -313.524191)
			(xy 103.151151 -313.565728) (xy 103.108283 -313.601403) (xy 103.060677 -313.630457) (xy 103.009348 -313.652269)
			(xy 102.955391 -313.666375) (xy 102.899954 -313.672475) (xy 102.84422 -313.670438) (xy 102.789377 -313.660308)
			(xy 102.736593 -313.642301) (xy 102.686993 -313.6168) (xy 102.641635 -313.584349) (xy 102.601486 -313.54564)
			(xy 102.5674 -313.501497) (xy 102.540104 -313.452862) (xy 102.520181 -313.400771) (xy 102.508055 -313.346334)
			(xy 102.503984 -313.290712) (xy 102.25151 -313.290712) (xy 102.251001 -313.318598) (xy 102.242881 -313.373774)
			(xy 102.226813 -313.427181) (xy 102.203141 -313.477678) (xy 102.172368 -313.524191) (xy 102.135151 -313.565728)
			(xy 102.092283 -313.601403) (xy 102.044677 -313.630457) (xy 101.993348 -313.652269) (xy 101.939391 -313.666375)
			(xy 101.883954 -313.672475) (xy 101.82822 -313.670438) (xy 101.773377 -313.660308) (xy 101.720593 -313.642301)
			(xy 101.670993 -313.6168) (xy 101.625635 -313.584349) (xy 101.585486 -313.54564) (xy 101.5514 -313.501497)
			(xy 101.524104 -313.452862) (xy 101.504181 -313.400771) (xy 101.492055 -313.346334) (xy 101.487984 -313.290712)
			(xy 101.23551 -313.290712) (xy 101.235001 -313.318598) (xy 101.226881 -313.373774) (xy 101.210813 -313.427181)
			(xy 101.187141 -313.477678) (xy 101.156368 -313.524191) (xy 101.119151 -313.565728) (xy 101.076283 -313.601403)
			(xy 101.028677 -313.630457) (xy 100.977348 -313.652269) (xy 100.923391 -313.666375) (xy 100.867954 -313.672475)
			(xy 100.81222 -313.670438) (xy 100.757377 -313.660308) (xy 100.704593 -313.642301) (xy 100.654993 -313.6168)
			(xy 100.609635 -313.584349) (xy 100.569486 -313.54564) (xy 100.5354 -313.501497) (xy 100.508104 -313.452862)
			(xy 100.488181 -313.400771) (xy 100.476055 -313.346334) (xy 100.471984 -313.290712) (xy 99.78771 -313.290712)
			(xy 99.78771 -314.306712) (xy 101.487984 -314.306712) (xy 101.492055 -314.25109) (xy 101.504181 -314.196653)
			(xy 101.524104 -314.144562) (xy 101.5514 -314.095927) (xy 101.585486 -314.051784) (xy 101.625635 -314.013075)
			(xy 101.670993 -313.980624) (xy 101.720593 -313.955123) (xy 101.773377 -313.937116) (xy 101.82822 -313.926986)
			(xy 101.883954 -313.924949) (xy 101.939391 -313.931049) (xy 101.993348 -313.945155) (xy 102.044677 -313.966967)
			(xy 102.092283 -313.996021) (xy 102.135151 -314.031696) (xy 102.172368 -314.073233) (xy 102.203141 -314.119746)
			(xy 102.226813 -314.170243) (xy 102.242881 -314.22365) (xy 102.251001 -314.278826) (xy 102.25151 -314.306712)
			(xy 102.503984 -314.306712) (xy 102.508055 -314.25109) (xy 102.520181 -314.196653) (xy 102.540104 -314.144562)
			(xy 102.5674 -314.095927) (xy 102.601486 -314.051784) (xy 102.641635 -314.013075) (xy 102.686993 -313.980624)
			(xy 102.736593 -313.955123) (xy 102.789377 -313.937116) (xy 102.84422 -313.926986) (xy 102.899954 -313.924949)
			(xy 102.955391 -313.931049) (xy 103.009348 -313.945155) (xy 103.060677 -313.966967) (xy 103.108283 -313.996021)
			(xy 103.151151 -314.031696) (xy 103.188368 -314.073233) (xy 103.219141 -314.119746) (xy 103.242813 -314.170243)
			(xy 103.258881 -314.22365) (xy 103.267001 -314.278826) (xy 103.26751 -314.306712) (xy 103.519984 -314.306712)
			(xy 103.524055 -314.25109) (xy 103.536181 -314.196653) (xy 103.556104 -314.144562) (xy 103.5834 -314.095927)
			(xy 103.617486 -314.051784) (xy 103.657635 -314.013075) (xy 103.702993 -313.980624) (xy 103.752593 -313.955123)
			(xy 103.805377 -313.937116) (xy 103.86022 -313.926986) (xy 103.915954 -313.924949) (xy 103.971391 -313.931049)
			(xy 104.025348 -313.945155) (xy 104.076677 -313.966967) (xy 104.124283 -313.996021) (xy 104.167151 -314.031696)
			(xy 104.204368 -314.073233) (xy 104.235141 -314.119746) (xy 104.258813 -314.170243) (xy 104.274881 -314.22365)
			(xy 104.283001 -314.278826) (xy 104.28351 -314.306712) (xy 104.535984 -314.306712) (xy 104.540055 -314.25109)
			(xy 104.552181 -314.196653) (xy 104.572104 -314.144562) (xy 104.5994 -314.095927) (xy 104.633486 -314.051784)
			(xy 104.673635 -314.013075) (xy 104.718993 -313.980624) (xy 104.768593 -313.955123) (xy 104.821377 -313.937116)
			(xy 104.87622 -313.926986) (xy 104.931954 -313.924949) (xy 104.987391 -313.931049) (xy 105.041348 -313.945155)
			(xy 105.092677 -313.966967) (xy 105.140283 -313.996021) (xy 105.183151 -314.031696) (xy 105.220368 -314.073233)
			(xy 105.251141 -314.119746) (xy 105.274813 -314.170243) (xy 105.290881 -314.22365) (xy 105.299001 -314.278826)
			(xy 105.29951 -314.306712) (xy 105.551984 -314.306712) (xy 105.556055 -314.25109) (xy 105.568181 -314.196653)
			(xy 105.588104 -314.144562) (xy 105.6154 -314.095927) (xy 105.649486 -314.051784) (xy 105.689635 -314.013075)
			(xy 105.734993 -313.980624) (xy 105.784593 -313.955123) (xy 105.837377 -313.937116) (xy 105.89222 -313.926986)
			(xy 105.947954 -313.924949) (xy 106.003391 -313.931049) (xy 106.057348 -313.945155) (xy 106.108677 -313.966967)
			(xy 106.156283 -313.996021) (xy 106.199151 -314.031696) (xy 106.236368 -314.073233) (xy 106.267141 -314.119746)
			(xy 106.290813 -314.170243) (xy 106.306881 -314.22365) (xy 106.315001 -314.278826) (xy 106.31551 -314.306712)
			(xy 106.567984 -314.306712) (xy 106.572055 -314.25109) (xy 106.584181 -314.196653) (xy 106.604104 -314.144562)
			(xy 106.6314 -314.095927) (xy 106.665486 -314.051784) (xy 106.705635 -314.013075) (xy 106.750993 -313.980624)
			(xy 106.800593 -313.955123) (xy 106.853377 -313.937116) (xy 106.90822 -313.926986) (xy 106.963954 -313.924949)
			(xy 107.019391 -313.931049) (xy 107.073348 -313.945155) (xy 107.124677 -313.966967) (xy 107.172283 -313.996021)
			(xy 107.215151 -314.031696) (xy 107.252368 -314.073233) (xy 107.283141 -314.119746) (xy 107.306813 -314.170243)
			(xy 107.322881 -314.22365) (xy 107.331001 -314.278826) (xy 107.33151 -314.306712) (xy 107.583984 -314.306712)
			(xy 107.588055 -314.25109) (xy 107.600181 -314.196653) (xy 107.620104 -314.144562) (xy 107.6474 -314.095927)
			(xy 107.681486 -314.051784) (xy 107.721635 -314.013075) (xy 107.766993 -313.980624) (xy 107.816593 -313.955123)
			(xy 107.869377 -313.937116) (xy 107.92422 -313.926986) (xy 107.979954 -313.924949) (xy 108.035391 -313.931049)
			(xy 108.089348 -313.945155) (xy 108.140677 -313.966967) (xy 108.188283 -313.996021) (xy 108.231151 -314.031696)
			(xy 108.268368 -314.073233) (xy 108.299141 -314.119746) (xy 108.322813 -314.170243) (xy 108.338881 -314.22365)
			(xy 108.347001 -314.278826) (xy 108.34751 -314.306712) (xy 108.599984 -314.306712) (xy 108.604055 -314.25109)
			(xy 108.616181 -314.196653) (xy 108.636104 -314.144562) (xy 108.6634 -314.095927) (xy 108.697486 -314.051784)
			(xy 108.737635 -314.013075) (xy 108.782993 -313.980624) (xy 108.832593 -313.955123) (xy 108.885377 -313.937116)
			(xy 108.94022 -313.926986) (xy 108.995954 -313.924949) (xy 109.051391 -313.931049) (xy 109.105348 -313.945155)
			(xy 109.156677 -313.966967) (xy 109.204283 -313.996021) (xy 109.247151 -314.031696) (xy 109.284368 -314.073233)
			(xy 109.315141 -314.119746) (xy 109.338813 -314.170243) (xy 109.354881 -314.22365) (xy 109.363001 -314.278826)
			(xy 109.36351 -314.306712) (xy 109.615984 -314.306712) (xy 109.620055 -314.25109) (xy 109.632181 -314.196653)
			(xy 109.652104 -314.144562) (xy 109.6794 -314.095927) (xy 109.713486 -314.051784) (xy 109.753635 -314.013075)
			(xy 109.798993 -313.980624) (xy 109.848593 -313.955123) (xy 109.901377 -313.937116) (xy 109.95622 -313.926986)
			(xy 110.011954 -313.924949) (xy 110.067391 -313.931049) (xy 110.121348 -313.945155) (xy 110.172677 -313.966967)
			(xy 110.220283 -313.996021) (xy 110.263151 -314.031696) (xy 110.300368 -314.073233) (xy 110.331141 -314.119746)
			(xy 110.354813 -314.170243) (xy 110.370881 -314.22365) (xy 110.379001 -314.278826) (xy 110.37951 -314.306712)
			(xy 110.379001 -314.334598) (xy 110.370881 -314.389774) (xy 110.354813 -314.443181) (xy 110.331141 -314.493678)
			(xy 110.300368 -314.540191) (xy 110.263151 -314.581728) (xy 110.220283 -314.617403) (xy 110.172677 -314.646457)
			(xy 110.121348 -314.668269) (xy 110.067391 -314.682375) (xy 110.011954 -314.688475) (xy 109.95622 -314.686438)
			(xy 109.901377 -314.676308) (xy 109.848593 -314.658301) (xy 109.798993 -314.6328) (xy 109.753635 -314.600349)
			(xy 109.713486 -314.56164) (xy 109.6794 -314.517497) (xy 109.652104 -314.468862) (xy 109.632181 -314.416771)
			(xy 109.620055 -314.362334) (xy 109.615984 -314.306712) (xy 109.36351 -314.306712) (xy 109.363001 -314.334598)
			(xy 109.354881 -314.389774) (xy 109.338813 -314.443181) (xy 109.315141 -314.493678) (xy 109.284368 -314.540191)
			(xy 109.247151 -314.581728) (xy 109.204283 -314.617403) (xy 109.156677 -314.646457) (xy 109.105348 -314.668269)
			(xy 109.051391 -314.682375) (xy 108.995954 -314.688475) (xy 108.94022 -314.686438) (xy 108.885377 -314.676308)
			(xy 108.832593 -314.658301) (xy 108.782993 -314.6328) (xy 108.737635 -314.600349) (xy 108.697486 -314.56164)
			(xy 108.6634 -314.517497) (xy 108.636104 -314.468862) (xy 108.616181 -314.416771) (xy 108.604055 -314.362334)
			(xy 108.599984 -314.306712) (xy 108.34751 -314.306712) (xy 108.347001 -314.334598) (xy 108.338881 -314.389774)
			(xy 108.322813 -314.443181) (xy 108.299141 -314.493678) (xy 108.268368 -314.540191) (xy 108.231151 -314.581728)
			(xy 108.188283 -314.617403) (xy 108.140677 -314.646457) (xy 108.089348 -314.668269) (xy 108.035391 -314.682375)
			(xy 107.979954 -314.688475) (xy 107.92422 -314.686438) (xy 107.869377 -314.676308) (xy 107.816593 -314.658301)
			(xy 107.766993 -314.6328) (xy 107.721635 -314.600349) (xy 107.681486 -314.56164) (xy 107.6474 -314.517497)
			(xy 107.620104 -314.468862) (xy 107.600181 -314.416771) (xy 107.588055 -314.362334) (xy 107.583984 -314.306712)
			(xy 107.33151 -314.306712) (xy 107.331001 -314.334598) (xy 107.322881 -314.389774) (xy 107.306813 -314.443181)
			(xy 107.283141 -314.493678) (xy 107.252368 -314.540191) (xy 107.215151 -314.581728) (xy 107.172283 -314.617403)
			(xy 107.124677 -314.646457) (xy 107.073348 -314.668269) (xy 107.019391 -314.682375) (xy 106.963954 -314.688475)
			(xy 106.90822 -314.686438) (xy 106.853377 -314.676308) (xy 106.800593 -314.658301) (xy 106.750993 -314.6328)
			(xy 106.705635 -314.600349) (xy 106.665486 -314.56164) (xy 106.6314 -314.517497) (xy 106.604104 -314.468862)
			(xy 106.584181 -314.416771) (xy 106.572055 -314.362334) (xy 106.567984 -314.306712) (xy 106.31551 -314.306712)
			(xy 106.315001 -314.334598) (xy 106.306881 -314.389774) (xy 106.290813 -314.443181) (xy 106.267141 -314.493678)
			(xy 106.236368 -314.540191) (xy 106.199151 -314.581728) (xy 106.156283 -314.617403) (xy 106.108677 -314.646457)
			(xy 106.057348 -314.668269) (xy 106.003391 -314.682375) (xy 105.947954 -314.688475) (xy 105.89222 -314.686438)
			(xy 105.837377 -314.676308) (xy 105.784593 -314.658301) (xy 105.734993 -314.6328) (xy 105.689635 -314.600349)
			(xy 105.649486 -314.56164) (xy 105.6154 -314.517497) (xy 105.588104 -314.468862) (xy 105.568181 -314.416771)
			(xy 105.556055 -314.362334) (xy 105.551984 -314.306712) (xy 105.29951 -314.306712) (xy 105.299001 -314.334598)
			(xy 105.290881 -314.389774) (xy 105.274813 -314.443181) (xy 105.251141 -314.493678) (xy 105.220368 -314.540191)
			(xy 105.183151 -314.581728) (xy 105.140283 -314.617403) (xy 105.092677 -314.646457) (xy 105.041348 -314.668269)
			(xy 104.987391 -314.682375) (xy 104.931954 -314.688475) (xy 104.87622 -314.686438) (xy 104.821377 -314.676308)
			(xy 104.768593 -314.658301) (xy 104.718993 -314.6328) (xy 104.673635 -314.600349) (xy 104.633486 -314.56164)
			(xy 104.5994 -314.517497) (xy 104.572104 -314.468862) (xy 104.552181 -314.416771) (xy 104.540055 -314.362334)
			(xy 104.535984 -314.306712) (xy 104.28351 -314.306712) (xy 104.283001 -314.334598) (xy 104.274881 -314.389774)
			(xy 104.258813 -314.443181) (xy 104.235141 -314.493678) (xy 104.204368 -314.540191) (xy 104.167151 -314.581728)
			(xy 104.124283 -314.617403) (xy 104.076677 -314.646457) (xy 104.025348 -314.668269) (xy 103.971391 -314.682375)
			(xy 103.915954 -314.688475) (xy 103.86022 -314.686438) (xy 103.805377 -314.676308) (xy 103.752593 -314.658301)
			(xy 103.702993 -314.6328) (xy 103.657635 -314.600349) (xy 103.617486 -314.56164) (xy 103.5834 -314.517497)
			(xy 103.556104 -314.468862) (xy 103.536181 -314.416771) (xy 103.524055 -314.362334) (xy 103.519984 -314.306712)
			(xy 103.26751 -314.306712) (xy 103.267001 -314.334598) (xy 103.258881 -314.389774) (xy 103.242813 -314.443181)
			(xy 103.219141 -314.493678) (xy 103.188368 -314.540191) (xy 103.151151 -314.581728) (xy 103.108283 -314.617403)
			(xy 103.060677 -314.646457) (xy 103.009348 -314.668269) (xy 102.955391 -314.682375) (xy 102.899954 -314.688475)
			(xy 102.84422 -314.686438) (xy 102.789377 -314.676308) (xy 102.736593 -314.658301) (xy 102.686993 -314.6328)
			(xy 102.641635 -314.600349) (xy 102.601486 -314.56164) (xy 102.5674 -314.517497) (xy 102.540104 -314.468862)
			(xy 102.520181 -314.416771) (xy 102.508055 -314.362334) (xy 102.503984 -314.306712) (xy 102.25151 -314.306712)
			(xy 102.251001 -314.334598) (xy 102.242881 -314.389774) (xy 102.226813 -314.443181) (xy 102.203141 -314.493678)
			(xy 102.172368 -314.540191) (xy 102.135151 -314.581728) (xy 102.092283 -314.617403) (xy 102.044677 -314.646457)
			(xy 101.993348 -314.668269) (xy 101.939391 -314.682375) (xy 101.883954 -314.688475) (xy 101.82822 -314.686438)
			(xy 101.773377 -314.676308) (xy 101.720593 -314.658301) (xy 101.670993 -314.6328) (xy 101.625635 -314.600349)
			(xy 101.585486 -314.56164) (xy 101.5514 -314.517497) (xy 101.524104 -314.468862) (xy 101.504181 -314.416771)
			(xy 101.492055 -314.362334) (xy 101.487984 -314.306712) (xy 99.78771 -314.306712) (xy 99.78771 -315.322712)
			(xy 101.487984 -315.322712) (xy 101.492055 -315.26709) (xy 101.504181 -315.212653) (xy 101.524104 -315.160562)
			(xy 101.5514 -315.111927) (xy 101.585486 -315.067784) (xy 101.625635 -315.029075) (xy 101.670993 -314.996624)
			(xy 101.720593 -314.971123) (xy 101.773377 -314.953116) (xy 101.82822 -314.942986) (xy 101.883954 -314.940949)
			(xy 101.939391 -314.947049) (xy 101.993348 -314.961155) (xy 102.044677 -314.982967) (xy 102.092283 -315.012021)
			(xy 102.135151 -315.047696) (xy 102.172368 -315.089233) (xy 102.203141 -315.135746) (xy 102.226813 -315.186243)
			(xy 102.242881 -315.23965) (xy 102.251001 -315.294826) (xy 102.25151 -315.322712) (xy 102.503984 -315.322712)
			(xy 102.508055 -315.26709) (xy 102.520181 -315.212653) (xy 102.540104 -315.160562) (xy 102.5674 -315.111927)
			(xy 102.601486 -315.067784) (xy 102.641635 -315.029075) (xy 102.686993 -314.996624) (xy 102.736593 -314.971123)
			(xy 102.789377 -314.953116) (xy 102.84422 -314.942986) (xy 102.899954 -314.940949) (xy 102.955391 -314.947049)
			(xy 103.009348 -314.961155) (xy 103.060677 -314.982967) (xy 103.108283 -315.012021) (xy 103.151151 -315.047696)
			(xy 103.188368 -315.089233) (xy 103.219141 -315.135746) (xy 103.242813 -315.186243) (xy 103.258881 -315.23965)
			(xy 103.267001 -315.294826) (xy 103.26751 -315.322712) (xy 103.519984 -315.322712) (xy 103.524055 -315.26709)
			(xy 103.536181 -315.212653) (xy 103.556104 -315.160562) (xy 103.5834 -315.111927) (xy 103.617486 -315.067784)
			(xy 103.657635 -315.029075) (xy 103.702993 -314.996624) (xy 103.752593 -314.971123) (xy 103.805377 -314.953116)
			(xy 103.86022 -314.942986) (xy 103.915954 -314.940949) (xy 103.971391 -314.947049) (xy 104.025348 -314.961155)
			(xy 104.076677 -314.982967) (xy 104.124283 -315.012021) (xy 104.167151 -315.047696) (xy 104.204368 -315.089233)
			(xy 104.235141 -315.135746) (xy 104.258813 -315.186243) (xy 104.274881 -315.23965) (xy 104.283001 -315.294826)
			(xy 104.28351 -315.322712) (xy 104.535984 -315.322712) (xy 104.540055 -315.26709) (xy 104.552181 -315.212653)
			(xy 104.572104 -315.160562) (xy 104.5994 -315.111927) (xy 104.633486 -315.067784) (xy 104.673635 -315.029075)
			(xy 104.718993 -314.996624) (xy 104.768593 -314.971123) (xy 104.821377 -314.953116) (xy 104.87622 -314.942986)
			(xy 104.931954 -314.940949) (xy 104.987391 -314.947049) (xy 105.041348 -314.961155) (xy 105.092677 -314.982967)
			(xy 105.140283 -315.012021) (xy 105.183151 -315.047696) (xy 105.220368 -315.089233) (xy 105.251141 -315.135746)
			(xy 105.274813 -315.186243) (xy 105.290881 -315.23965) (xy 105.299001 -315.294826) (xy 105.29951 -315.322712)
			(xy 105.551984 -315.322712) (xy 105.556055 -315.26709) (xy 105.568181 -315.212653) (xy 105.588104 -315.160562)
			(xy 105.6154 -315.111927) (xy 105.649486 -315.067784) (xy 105.689635 -315.029075) (xy 105.734993 -314.996624)
			(xy 105.784593 -314.971123) (xy 105.837377 -314.953116) (xy 105.89222 -314.942986) (xy 105.947954 -314.940949)
			(xy 106.003391 -314.947049) (xy 106.057348 -314.961155) (xy 106.108677 -314.982967) (xy 106.156283 -315.012021)
			(xy 106.199151 -315.047696) (xy 106.236368 -315.089233) (xy 106.267141 -315.135746) (xy 106.290813 -315.186243)
			(xy 106.306881 -315.23965) (xy 106.315001 -315.294826) (xy 106.31551 -315.322712) (xy 106.567984 -315.322712)
			(xy 106.572055 -315.26709) (xy 106.584181 -315.212653) (xy 106.604104 -315.160562) (xy 106.6314 -315.111927)
			(xy 106.665486 -315.067784) (xy 106.705635 -315.029075) (xy 106.750993 -314.996624) (xy 106.800593 -314.971123)
			(xy 106.853377 -314.953116) (xy 106.90822 -314.942986) (xy 106.963954 -314.940949) (xy 107.019391 -314.947049)
			(xy 107.073348 -314.961155) (xy 107.124677 -314.982967) (xy 107.172283 -315.012021) (xy 107.215151 -315.047696)
			(xy 107.252368 -315.089233) (xy 107.283141 -315.135746) (xy 107.306813 -315.186243) (xy 107.322881 -315.23965)
			(xy 107.331001 -315.294826) (xy 107.33151 -315.322712) (xy 107.583984 -315.322712) (xy 107.588055 -315.26709)
			(xy 107.600181 -315.212653) (xy 107.620104 -315.160562) (xy 107.6474 -315.111927) (xy 107.681486 -315.067784)
			(xy 107.721635 -315.029075) (xy 107.766993 -314.996624) (xy 107.816593 -314.971123) (xy 107.869377 -314.953116)
			(xy 107.92422 -314.942986) (xy 107.979954 -314.940949) (xy 108.035391 -314.947049) (xy 108.089348 -314.961155)
			(xy 108.140677 -314.982967) (xy 108.188283 -315.012021) (xy 108.231151 -315.047696) (xy 108.268368 -315.089233)
			(xy 108.299141 -315.135746) (xy 108.322813 -315.186243) (xy 108.338881 -315.23965) (xy 108.347001 -315.294826)
			(xy 108.34751 -315.322712) (xy 108.599984 -315.322712) (xy 108.604055 -315.26709) (xy 108.616181 -315.212653)
			(xy 108.636104 -315.160562) (xy 108.6634 -315.111927) (xy 108.697486 -315.067784) (xy 108.737635 -315.029075)
			(xy 108.782993 -314.996624) (xy 108.832593 -314.971123) (xy 108.885377 -314.953116) (xy 108.94022 -314.942986)
			(xy 108.995954 -314.940949) (xy 109.051391 -314.947049) (xy 109.105348 -314.961155) (xy 109.156677 -314.982967)
			(xy 109.204283 -315.012021) (xy 109.247151 -315.047696) (xy 109.284368 -315.089233) (xy 109.315141 -315.135746)
			(xy 109.338813 -315.186243) (xy 109.354881 -315.23965) (xy 109.363001 -315.294826) (xy 109.36351 -315.322712)
			(xy 109.615984 -315.322712) (xy 109.620055 -315.26709) (xy 109.632181 -315.212653) (xy 109.652104 -315.160562)
			(xy 109.6794 -315.111927) (xy 109.713486 -315.067784) (xy 109.753635 -315.029075) (xy 109.798993 -314.996624)
			(xy 109.848593 -314.971123) (xy 109.901377 -314.953116) (xy 109.95622 -314.942986) (xy 110.011954 -314.940949)
			(xy 110.067391 -314.947049) (xy 110.121348 -314.961155) (xy 110.172677 -314.982967) (xy 110.220283 -315.012021)
			(xy 110.263151 -315.047696) (xy 110.300368 -315.089233) (xy 110.331141 -315.135746) (xy 110.354813 -315.186243)
			(xy 110.370881 -315.23965) (xy 110.379001 -315.294826) (xy 110.37951 -315.322712) (xy 110.379001 -315.350598)
			(xy 110.370881 -315.405774) (xy 110.354813 -315.459181) (xy 110.331141 -315.509678) (xy 110.300368 -315.556191)
			(xy 110.263151 -315.597728) (xy 110.220283 -315.633403) (xy 110.172677 -315.662457) (xy 110.121348 -315.684269)
			(xy 110.067391 -315.698375) (xy 110.011954 -315.704475) (xy 109.95622 -315.702438) (xy 109.901377 -315.692308)
			(xy 109.848593 -315.674301) (xy 109.798993 -315.6488) (xy 109.753635 -315.616349) (xy 109.713486 -315.57764)
			(xy 109.6794 -315.533497) (xy 109.652104 -315.484862) (xy 109.632181 -315.432771) (xy 109.620055 -315.378334)
			(xy 109.615984 -315.322712) (xy 109.36351 -315.322712) (xy 109.363001 -315.350598) (xy 109.354881 -315.405774)
			(xy 109.338813 -315.459181) (xy 109.315141 -315.509678) (xy 109.284368 -315.556191) (xy 109.247151 -315.597728)
			(xy 109.204283 -315.633403) (xy 109.156677 -315.662457) (xy 109.105348 -315.684269) (xy 109.051391 -315.698375)
			(xy 108.995954 -315.704475) (xy 108.94022 -315.702438) (xy 108.885377 -315.692308) (xy 108.832593 -315.674301)
			(xy 108.782993 -315.6488) (xy 108.737635 -315.616349) (xy 108.697486 -315.57764) (xy 108.6634 -315.533497)
			(xy 108.636104 -315.484862) (xy 108.616181 -315.432771) (xy 108.604055 -315.378334) (xy 108.599984 -315.322712)
			(xy 108.34751 -315.322712) (xy 108.347001 -315.350598) (xy 108.338881 -315.405774) (xy 108.322813 -315.459181)
			(xy 108.299141 -315.509678) (xy 108.268368 -315.556191) (xy 108.231151 -315.597728) (xy 108.188283 -315.633403)
			(xy 108.140677 -315.662457) (xy 108.089348 -315.684269) (xy 108.035391 -315.698375) (xy 107.979954 -315.704475)
			(xy 107.92422 -315.702438) (xy 107.869377 -315.692308) (xy 107.816593 -315.674301) (xy 107.766993 -315.6488)
			(xy 107.721635 -315.616349) (xy 107.681486 -315.57764) (xy 107.6474 -315.533497) (xy 107.620104 -315.484862)
			(xy 107.600181 -315.432771) (xy 107.588055 -315.378334) (xy 107.583984 -315.322712) (xy 107.33151 -315.322712)
			(xy 107.331001 -315.350598) (xy 107.322881 -315.405774) (xy 107.306813 -315.459181) (xy 107.283141 -315.509678)
			(xy 107.252368 -315.556191) (xy 107.215151 -315.597728) (xy 107.172283 -315.633403) (xy 107.124677 -315.662457)
			(xy 107.073348 -315.684269) (xy 107.019391 -315.698375) (xy 106.963954 -315.704475) (xy 106.90822 -315.702438)
			(xy 106.853377 -315.692308) (xy 106.800593 -315.674301) (xy 106.750993 -315.6488) (xy 106.705635 -315.616349)
			(xy 106.665486 -315.57764) (xy 106.6314 -315.533497) (xy 106.604104 -315.484862) (xy 106.584181 -315.432771)
			(xy 106.572055 -315.378334) (xy 106.567984 -315.322712) (xy 106.31551 -315.322712) (xy 106.315001 -315.350598)
			(xy 106.306881 -315.405774) (xy 106.290813 -315.459181) (xy 106.267141 -315.509678) (xy 106.236368 -315.556191)
			(xy 106.199151 -315.597728) (xy 106.156283 -315.633403) (xy 106.108677 -315.662457) (xy 106.057348 -315.684269)
			(xy 106.003391 -315.698375) (xy 105.947954 -315.704475) (xy 105.89222 -315.702438) (xy 105.837377 -315.692308)
			(xy 105.784593 -315.674301) (xy 105.734993 -315.6488) (xy 105.689635 -315.616349) (xy 105.649486 -315.57764)
			(xy 105.6154 -315.533497) (xy 105.588104 -315.484862) (xy 105.568181 -315.432771) (xy 105.556055 -315.378334)
			(xy 105.551984 -315.322712) (xy 105.29951 -315.322712) (xy 105.299001 -315.350598) (xy 105.290881 -315.405774)
			(xy 105.274813 -315.459181) (xy 105.251141 -315.509678) (xy 105.220368 -315.556191) (xy 105.183151 -315.597728)
			(xy 105.140283 -315.633403) (xy 105.092677 -315.662457) (xy 105.041348 -315.684269) (xy 104.987391 -315.698375)
			(xy 104.931954 -315.704475) (xy 104.87622 -315.702438) (xy 104.821377 -315.692308) (xy 104.768593 -315.674301)
			(xy 104.718993 -315.6488) (xy 104.673635 -315.616349) (xy 104.633486 -315.57764) (xy 104.5994 -315.533497)
			(xy 104.572104 -315.484862) (xy 104.552181 -315.432771) (xy 104.540055 -315.378334) (xy 104.535984 -315.322712)
			(xy 104.28351 -315.322712) (xy 104.283001 -315.350598) (xy 104.274881 -315.405774) (xy 104.258813 -315.459181)
			(xy 104.235141 -315.509678) (xy 104.204368 -315.556191) (xy 104.167151 -315.597728) (xy 104.124283 -315.633403)
			(xy 104.076677 -315.662457) (xy 104.025348 -315.684269) (xy 103.971391 -315.698375) (xy 103.915954 -315.704475)
			(xy 103.86022 -315.702438) (xy 103.805377 -315.692308) (xy 103.752593 -315.674301) (xy 103.702993 -315.6488)
			(xy 103.657635 -315.616349) (xy 103.617486 -315.57764) (xy 103.5834 -315.533497) (xy 103.556104 -315.484862)
			(xy 103.536181 -315.432771) (xy 103.524055 -315.378334) (xy 103.519984 -315.322712) (xy 103.26751 -315.322712)
			(xy 103.267001 -315.350598) (xy 103.258881 -315.405774) (xy 103.242813 -315.459181) (xy 103.219141 -315.509678)
			(xy 103.188368 -315.556191) (xy 103.151151 -315.597728) (xy 103.108283 -315.633403) (xy 103.060677 -315.662457)
			(xy 103.009348 -315.684269) (xy 102.955391 -315.698375) (xy 102.899954 -315.704475) (xy 102.84422 -315.702438)
			(xy 102.789377 -315.692308) (xy 102.736593 -315.674301) (xy 102.686993 -315.6488) (xy 102.641635 -315.616349)
			(xy 102.601486 -315.57764) (xy 102.5674 -315.533497) (xy 102.540104 -315.484862) (xy 102.520181 -315.432771)
			(xy 102.508055 -315.378334) (xy 102.503984 -315.322712) (xy 102.25151 -315.322712) (xy 102.251001 -315.350598)
			(xy 102.242881 -315.405774) (xy 102.226813 -315.459181) (xy 102.203141 -315.509678) (xy 102.172368 -315.556191)
			(xy 102.135151 -315.597728) (xy 102.092283 -315.633403) (xy 102.044677 -315.662457) (xy 101.993348 -315.684269)
			(xy 101.939391 -315.698375) (xy 101.883954 -315.704475) (xy 101.82822 -315.702438) (xy 101.773377 -315.692308)
			(xy 101.720593 -315.674301) (xy 101.670993 -315.6488) (xy 101.625635 -315.616349) (xy 101.585486 -315.57764)
			(xy 101.5514 -315.533497) (xy 101.524104 -315.484862) (xy 101.504181 -315.432771) (xy 101.492055 -315.378334)
			(xy 101.487984 -315.322712) (xy 99.78771 -315.322712) (xy 99.78771 -316.338712) (xy 102.503984 -316.338712)
			(xy 102.508055 -316.28309) (xy 102.520181 -316.228653) (xy 102.540104 -316.176562) (xy 102.5674 -316.127927)
			(xy 102.601486 -316.083784) (xy 102.641635 -316.045075) (xy 102.686993 -316.012624) (xy 102.736593 -315.987123)
			(xy 102.789377 -315.969116) (xy 102.84422 -315.958986) (xy 102.899954 -315.956949) (xy 102.955391 -315.963049)
			(xy 103.009348 -315.977155) (xy 103.060677 -315.998967) (xy 103.108283 -316.028021) (xy 103.151151 -316.063696)
			(xy 103.188368 -316.105233) (xy 103.219141 -316.151746) (xy 103.242813 -316.202243) (xy 103.258881 -316.25565)
			(xy 103.267001 -316.310826) (xy 103.26751 -316.338712) (xy 103.519984 -316.338712) (xy 103.524055 -316.28309)
			(xy 103.536181 -316.228653) (xy 103.556104 -316.176562) (xy 103.5834 -316.127927) (xy 103.617486 -316.083784)
			(xy 103.657635 -316.045075) (xy 103.702993 -316.012624) (xy 103.752593 -315.987123) (xy 103.805377 -315.969116)
			(xy 103.86022 -315.958986) (xy 103.915954 -315.956949) (xy 103.971391 -315.963049) (xy 104.025348 -315.977155)
			(xy 104.076677 -315.998967) (xy 104.124283 -316.028021) (xy 104.167151 -316.063696) (xy 104.204368 -316.105233)
			(xy 104.235141 -316.151746) (xy 104.258813 -316.202243) (xy 104.274881 -316.25565) (xy 104.283001 -316.310826)
			(xy 104.28351 -316.338712) (xy 104.535984 -316.338712) (xy 104.540055 -316.28309) (xy 104.552181 -316.228653)
			(xy 104.572104 -316.176562) (xy 104.5994 -316.127927) (xy 104.633486 -316.083784) (xy 104.673635 -316.045075)
			(xy 104.718993 -316.012624) (xy 104.768593 -315.987123) (xy 104.821377 -315.969116) (xy 104.87622 -315.958986)
			(xy 104.931954 -315.956949) (xy 104.987391 -315.963049) (xy 105.041348 -315.977155) (xy 105.092677 -315.998967)
			(xy 105.140283 -316.028021) (xy 105.183151 -316.063696) (xy 105.220368 -316.105233) (xy 105.251141 -316.151746)
			(xy 105.274813 -316.202243) (xy 105.290881 -316.25565) (xy 105.299001 -316.310826) (xy 105.29951 -316.338712)
			(xy 105.551984 -316.338712) (xy 105.556055 -316.28309) (xy 105.568181 -316.228653) (xy 105.588104 -316.176562)
			(xy 105.6154 -316.127927) (xy 105.649486 -316.083784) (xy 105.689635 -316.045075) (xy 105.734993 -316.012624)
			(xy 105.784593 -315.987123) (xy 105.837377 -315.969116) (xy 105.89222 -315.958986) (xy 105.947954 -315.956949)
			(xy 106.003391 -315.963049) (xy 106.057348 -315.977155) (xy 106.108677 -315.998967) (xy 106.156283 -316.028021)
			(xy 106.199151 -316.063696) (xy 106.236368 -316.105233) (xy 106.267141 -316.151746) (xy 106.290813 -316.202243)
			(xy 106.306881 -316.25565) (xy 106.315001 -316.310826) (xy 106.31551 -316.338712) (xy 106.567984 -316.338712)
			(xy 106.572055 -316.28309) (xy 106.584181 -316.228653) (xy 106.604104 -316.176562) (xy 106.6314 -316.127927)
			(xy 106.665486 -316.083784) (xy 106.705635 -316.045075) (xy 106.750993 -316.012624) (xy 106.800593 -315.987123)
			(xy 106.853377 -315.969116) (xy 106.90822 -315.958986) (xy 106.963954 -315.956949) (xy 107.019391 -315.963049)
			(xy 107.073348 -315.977155) (xy 107.124677 -315.998967) (xy 107.172283 -316.028021) (xy 107.215151 -316.063696)
			(xy 107.252368 -316.105233) (xy 107.283141 -316.151746) (xy 107.306813 -316.202243) (xy 107.322881 -316.25565)
			(xy 107.331001 -316.310826) (xy 107.33151 -316.338712) (xy 107.583984 -316.338712) (xy 107.588055 -316.28309)
			(xy 107.600181 -316.228653) (xy 107.620104 -316.176562) (xy 107.6474 -316.127927) (xy 107.681486 -316.083784)
			(xy 107.721635 -316.045075) (xy 107.766993 -316.012624) (xy 107.816593 -315.987123) (xy 107.869377 -315.969116)
			(xy 107.92422 -315.958986) (xy 107.979954 -315.956949) (xy 108.035391 -315.963049) (xy 108.089348 -315.977155)
			(xy 108.140677 -315.998967) (xy 108.188283 -316.028021) (xy 108.231151 -316.063696) (xy 108.268368 -316.105233)
			(xy 108.299141 -316.151746) (xy 108.322813 -316.202243) (xy 108.338881 -316.25565) (xy 108.347001 -316.310826)
			(xy 108.34751 -316.338712) (xy 108.599984 -316.338712) (xy 108.604055 -316.28309) (xy 108.616181 -316.228653)
			(xy 108.636104 -316.176562) (xy 108.6634 -316.127927) (xy 108.697486 -316.083784) (xy 108.737635 -316.045075)
			(xy 108.782993 -316.012624) (xy 108.832593 -315.987123) (xy 108.885377 -315.969116) (xy 108.94022 -315.958986)
			(xy 108.995954 -315.956949) (xy 109.051391 -315.963049) (xy 109.105348 -315.977155) (xy 109.156677 -315.998967)
			(xy 109.204283 -316.028021) (xy 109.247151 -316.063696) (xy 109.284368 -316.105233) (xy 109.315141 -316.151746)
			(xy 109.338813 -316.202243) (xy 109.354881 -316.25565) (xy 109.363001 -316.310826) (xy 109.36351 -316.338712)
			(xy 109.615984 -316.338712) (xy 109.620055 -316.28309) (xy 109.632181 -316.228653) (xy 109.652104 -316.176562)
			(xy 109.6794 -316.127927) (xy 109.713486 -316.083784) (xy 109.753635 -316.045075) (xy 109.798993 -316.012624)
			(xy 109.848593 -315.987123) (xy 109.901377 -315.969116) (xy 109.95622 -315.958986) (xy 110.011954 -315.956949)
			(xy 110.067391 -315.963049) (xy 110.121348 -315.977155) (xy 110.172677 -315.998967) (xy 110.220283 -316.028021)
			(xy 110.263151 -316.063696) (xy 110.300368 -316.105233) (xy 110.331141 -316.151746) (xy 110.354813 -316.202243)
			(xy 110.370881 -316.25565) (xy 110.379001 -316.310826) (xy 110.37951 -316.338712) (xy 110.379001 -316.366598)
			(xy 110.370881 -316.421774) (xy 110.354813 -316.475181) (xy 110.331141 -316.525678) (xy 110.300368 -316.572191)
			(xy 110.263151 -316.613728) (xy 110.220283 -316.649403) (xy 110.172677 -316.678457) (xy 110.121348 -316.700269)
			(xy 110.067391 -316.714375) (xy 110.011954 -316.720475) (xy 109.95622 -316.718438) (xy 109.901377 -316.708308)
			(xy 109.848593 -316.690301) (xy 109.798993 -316.6648) (xy 109.753635 -316.632349) (xy 109.713486 -316.59364)
			(xy 109.6794 -316.549497) (xy 109.652104 -316.500862) (xy 109.632181 -316.448771) (xy 109.620055 -316.394334)
			(xy 109.615984 -316.338712) (xy 109.36351 -316.338712) (xy 109.363001 -316.366598) (xy 109.354881 -316.421774)
			(xy 109.338813 -316.475181) (xy 109.315141 -316.525678) (xy 109.284368 -316.572191) (xy 109.247151 -316.613728)
			(xy 109.204283 -316.649403) (xy 109.156677 -316.678457) (xy 109.105348 -316.700269) (xy 109.051391 -316.714375)
			(xy 108.995954 -316.720475) (xy 108.94022 -316.718438) (xy 108.885377 -316.708308) (xy 108.832593 -316.690301)
			(xy 108.782993 -316.6648) (xy 108.737635 -316.632349) (xy 108.697486 -316.59364) (xy 108.6634 -316.549497)
			(xy 108.636104 -316.500862) (xy 108.616181 -316.448771) (xy 108.604055 -316.394334) (xy 108.599984 -316.338712)
			(xy 108.34751 -316.338712) (xy 108.347001 -316.366598) (xy 108.338881 -316.421774) (xy 108.322813 -316.475181)
			(xy 108.299141 -316.525678) (xy 108.268368 -316.572191) (xy 108.231151 -316.613728) (xy 108.188283 -316.649403)
			(xy 108.140677 -316.678457) (xy 108.089348 -316.700269) (xy 108.035391 -316.714375) (xy 107.979954 -316.720475)
			(xy 107.92422 -316.718438) (xy 107.869377 -316.708308) (xy 107.816593 -316.690301) (xy 107.766993 -316.6648)
			(xy 107.721635 -316.632349) (xy 107.681486 -316.59364) (xy 107.6474 -316.549497) (xy 107.620104 -316.500862)
			(xy 107.600181 -316.448771) (xy 107.588055 -316.394334) (xy 107.583984 -316.338712) (xy 107.33151 -316.338712)
			(xy 107.331001 -316.366598) (xy 107.322881 -316.421774) (xy 107.306813 -316.475181) (xy 107.283141 -316.525678)
			(xy 107.252368 -316.572191) (xy 107.215151 -316.613728) (xy 107.172283 -316.649403) (xy 107.124677 -316.678457)
			(xy 107.073348 -316.700269) (xy 107.019391 -316.714375) (xy 106.963954 -316.720475) (xy 106.90822 -316.718438)
			(xy 106.853377 -316.708308) (xy 106.800593 -316.690301) (xy 106.750993 -316.6648) (xy 106.705635 -316.632349)
			(xy 106.665486 -316.59364) (xy 106.6314 -316.549497) (xy 106.604104 -316.500862) (xy 106.584181 -316.448771)
			(xy 106.572055 -316.394334) (xy 106.567984 -316.338712) (xy 106.31551 -316.338712) (xy 106.315001 -316.366598)
			(xy 106.306881 -316.421774) (xy 106.290813 -316.475181) (xy 106.267141 -316.525678) (xy 106.236368 -316.572191)
			(xy 106.199151 -316.613728) (xy 106.156283 -316.649403) (xy 106.108677 -316.678457) (xy 106.057348 -316.700269)
			(xy 106.003391 -316.714375) (xy 105.947954 -316.720475) (xy 105.89222 -316.718438) (xy 105.837377 -316.708308)
			(xy 105.784593 -316.690301) (xy 105.734993 -316.6648) (xy 105.689635 -316.632349) (xy 105.649486 -316.59364)
			(xy 105.6154 -316.549497) (xy 105.588104 -316.500862) (xy 105.568181 -316.448771) (xy 105.556055 -316.394334)
			(xy 105.551984 -316.338712) (xy 105.29951 -316.338712) (xy 105.299001 -316.366598) (xy 105.290881 -316.421774)
			(xy 105.274813 -316.475181) (xy 105.251141 -316.525678) (xy 105.220368 -316.572191) (xy 105.183151 -316.613728)
			(xy 105.140283 -316.649403) (xy 105.092677 -316.678457) (xy 105.041348 -316.700269) (xy 104.987391 -316.714375)
			(xy 104.931954 -316.720475) (xy 104.87622 -316.718438) (xy 104.821377 -316.708308) (xy 104.768593 -316.690301)
			(xy 104.718993 -316.6648) (xy 104.673635 -316.632349) (xy 104.633486 -316.59364) (xy 104.5994 -316.549497)
			(xy 104.572104 -316.500862) (xy 104.552181 -316.448771) (xy 104.540055 -316.394334) (xy 104.535984 -316.338712)
			(xy 104.28351 -316.338712) (xy 104.283001 -316.366598) (xy 104.274881 -316.421774) (xy 104.258813 -316.475181)
			(xy 104.235141 -316.525678) (xy 104.204368 -316.572191) (xy 104.167151 -316.613728) (xy 104.124283 -316.649403)
			(xy 104.076677 -316.678457) (xy 104.025348 -316.700269) (xy 103.971391 -316.714375) (xy 103.915954 -316.720475)
			(xy 103.86022 -316.718438) (xy 103.805377 -316.708308) (xy 103.752593 -316.690301) (xy 103.702993 -316.6648)
			(xy 103.657635 -316.632349) (xy 103.617486 -316.59364) (xy 103.5834 -316.549497) (xy 103.556104 -316.500862)
			(xy 103.536181 -316.448771) (xy 103.524055 -316.394334) (xy 103.519984 -316.338712) (xy 103.26751 -316.338712)
			(xy 103.267001 -316.366598) (xy 103.258881 -316.421774) (xy 103.242813 -316.475181) (xy 103.219141 -316.525678)
			(xy 103.188368 -316.572191) (xy 103.151151 -316.613728) (xy 103.108283 -316.649403) (xy 103.060677 -316.678457)
			(xy 103.009348 -316.700269) (xy 102.955391 -316.714375) (xy 102.899954 -316.720475) (xy 102.84422 -316.718438)
			(xy 102.789377 -316.708308) (xy 102.736593 -316.690301) (xy 102.686993 -316.6648) (xy 102.641635 -316.632349)
			(xy 102.601486 -316.59364) (xy 102.5674 -316.549497) (xy 102.540104 -316.500862) (xy 102.520181 -316.448771)
			(xy 102.508055 -316.394334) (xy 102.503984 -316.338712) (xy 99.78771 -316.338712) (xy 99.78771 -320.08064)
			(xy 106.2228 -320.08064) (xy 106.223347 -320.051724) (xy 106.23207 -319.994554) (xy 106.249322 -319.939356)
			(xy 106.274709 -319.887394) (xy 106.307647 -319.83986) (xy 106.347383 -319.797841) (xy 106.369866 -319.77965)
			(xy 106.378612 -319.772073) (xy 106.388801 -319.751325) (xy 106.389424 -319.739772) (xy 106.389424 -319.659508)
			(xy 106.388875 -319.647937) (xy 106.378668 -319.627164) (xy 106.369866 -319.61963) (xy 106.34739 -319.601431)
			(xy 106.307656 -319.559412) (xy 106.274717 -319.511878) (xy 106.249328 -319.459919) (xy 106.232069 -319.404723)
			(xy 106.223337 -319.347555) (xy 106.2228 -319.31864) (xy 106.223293 -319.291388) (xy 106.231044 -319.237437)
			(xy 106.246396 -319.18514) (xy 106.269034 -319.135559) (xy 106.298499 -319.089705) (xy 106.334189 -319.048512)
			(xy 106.37538 -319.012818) (xy 106.421231 -318.983349) (xy 106.47081 -318.960707) (xy 106.523106 -318.945351)
			(xy 106.577056 -318.937595) (xy 106.604308 -318.937132) (xy 106.633223 -318.937704) (xy 106.690392 -318.946421)
			(xy 106.74559 -318.963667) (xy 106.797553 -318.989048) (xy 106.845088 -319.021983) (xy 106.887106 -319.061716)
			(xy 106.905298 -319.084198) (xy 106.912865 -319.092954) (xy 106.93362 -319.103141) (xy 106.945176 -319.103756)
			(xy 107.02544 -319.103756) (xy 107.037006 -319.103167) (xy 107.057778 -319.092987) (xy 107.065318 -319.084198)
			(xy 107.082071 -319.063415) (xy 107.120425 -319.026285) (xy 107.163579 -318.994863) (xy 107.210693 -318.969764)
			(xy 107.260845 -318.951478) (xy 107.313056 -318.940361) (xy 107.366308 -318.936631) (xy 107.41956 -318.940361)
			(xy 107.471771 -318.951478) (xy 107.521923 -318.969764) (xy 107.569037 -318.994863) (xy 107.612191 -319.026285)
			(xy 107.650545 -319.063415) (xy 107.667298 -319.084198) (xy 107.674865 -319.092954) (xy 107.69562 -319.103141)
			(xy 107.707176 -319.103756) (xy 107.78744 -319.103756) (xy 107.799006 -319.103167) (xy 107.819778 -319.092987)
			(xy 107.827318 -319.084198) (xy 107.844071 -319.063415) (xy 107.882425 -319.026285) (xy 107.925579 -318.994863)
			(xy 107.972693 -318.969764) (xy 108.022845 -318.951478) (xy 108.075056 -318.940361) (xy 108.128308 -318.936631)
			(xy 108.18156 -318.940361) (xy 108.233771 -318.951478) (xy 108.283923 -318.969764) (xy 108.331037 -318.994863)
			(xy 108.374191 -319.026285) (xy 108.412545 -319.063415) (xy 108.429298 -319.084198) (xy 108.436865 -319.092954)
			(xy 108.45762 -319.103141) (xy 108.469176 -319.103756) (xy 108.54944 -319.103756) (xy 108.561006 -319.103167)
			(xy 108.581778 -319.092987) (xy 108.589318 -319.084198) (xy 108.606071 -319.063415) (xy 108.644425 -319.026285)
			(xy 108.687579 -318.994863) (xy 108.734693 -318.969764) (xy 108.784845 -318.951478) (xy 108.837056 -318.940361)
			(xy 108.890308 -318.936631) (xy 108.94356 -318.940361) (xy 108.995771 -318.951478) (xy 109.045923 -318.969764)
			(xy 109.093037 -318.994863) (xy 109.136191 -319.026285) (xy 109.174545 -319.063415) (xy 109.191298 -319.084198)
			(xy 109.198865 -319.092954) (xy 109.21962 -319.103141) (xy 109.231176 -319.103756) (xy 109.31144 -319.103756)
			(xy 109.323006 -319.103167) (xy 109.343778 -319.092987) (xy 109.351318 -319.084198) (xy 109.368071 -319.063415)
			(xy 109.406425 -319.026285) (xy 109.449579 -318.994863) (xy 109.496693 -318.969764) (xy 109.546845 -318.951478)
			(xy 109.599056 -318.940361) (xy 109.652308 -318.936631) (xy 109.70556 -318.940361) (xy 109.757771 -318.951478)
			(xy 109.807923 -318.969764) (xy 109.855037 -318.994863) (xy 109.898191 -319.026285) (xy 109.936545 -319.063415)
			(xy 109.953298 -319.084198) (xy 109.960865 -319.092954) (xy 109.98162 -319.103141) (xy 109.993176 -319.103756)
			(xy 110.07344 -319.103756) (xy 110.085006 -319.103167) (xy 110.105778 -319.092987) (xy 110.113318 -319.084198)
			(xy 110.130071 -319.063415) (xy 110.168425 -319.026285) (xy 110.211579 -318.994863) (xy 110.258693 -318.969764)
			(xy 110.308845 -318.951478) (xy 110.361056 -318.940361) (xy 110.414308 -318.936631) (xy 110.46756 -318.940361)
			(xy 110.519771 -318.951478) (xy 110.569923 -318.969764) (xy 110.617037 -318.994863) (xy 110.660191 -319.026285)
			(xy 110.698545 -319.063415) (xy 110.715298 -319.084198) (xy 110.722865 -319.092954) (xy 110.74362 -319.103141)
			(xy 110.755176 -319.103756) (xy 110.83544 -319.103756) (xy 110.847006 -319.103167) (xy 110.867778 -319.092987)
			(xy 110.875318 -319.084198) (xy 110.892071 -319.063415) (xy 110.930425 -319.026285) (xy 110.973579 -318.994863)
			(xy 111.020693 -318.969764) (xy 111.070845 -318.951478) (xy 111.123056 -318.940361) (xy 111.176308 -318.936631)
			(xy 111.22956 -318.940361) (xy 111.281771 -318.951478) (xy 111.331923 -318.969764) (xy 111.379037 -318.994863)
			(xy 111.422191 -319.026285) (xy 111.460545 -319.063415) (xy 111.477298 -319.084198) (xy 111.484865 -319.092954)
			(xy 111.50562 -319.103141) (xy 111.517176 -319.103756) (xy 111.59744 -319.103756) (xy 111.609006 -319.103167)
			(xy 111.629778 -319.092987) (xy 111.637318 -319.084198) (xy 111.654071 -319.063415) (xy 111.692425 -319.026285)
			(xy 111.735579 -318.994863) (xy 111.782693 -318.969764) (xy 111.832845 -318.951478) (xy 111.885056 -318.940361)
			(xy 111.938308 -318.936631) (xy 111.99156 -318.940361) (xy 112.043771 -318.951478) (xy 112.093923 -318.969764)
			(xy 112.141037 -318.994863) (xy 112.184191 -319.026285) (xy 112.222545 -319.063415) (xy 112.239298 -319.084198)
			(xy 112.246865 -319.092954) (xy 112.26762 -319.103141) (xy 112.279176 -319.103756) (xy 112.35944 -319.103756)
			(xy 112.371006 -319.103167) (xy 112.391778 -319.092987) (xy 112.399318 -319.084198) (xy 112.416071 -319.063415)
			(xy 112.454425 -319.026285) (xy 112.497579 -318.994863) (xy 112.544693 -318.969764) (xy 112.594845 -318.951478)
			(xy 112.647056 -318.940361) (xy 112.700308 -318.936631) (xy 112.75356 -318.940361) (xy 112.805771 -318.951478)
			(xy 112.855923 -318.969764) (xy 112.903037 -318.994863) (xy 112.946191 -319.026285) (xy 112.984545 -319.063415)
			(xy 113.001298 -319.084198) (xy 113.008865 -319.092954) (xy 113.02962 -319.103141) (xy 113.041176 -319.103756)
			(xy 113.12144 -319.103756) (xy 113.133006 -319.103167) (xy 113.153778 -319.092987) (xy 113.161318 -319.084198)
			(xy 113.178071 -319.063415) (xy 113.216425 -319.026285) (xy 113.259579 -318.994863) (xy 113.306693 -318.969764)
			(xy 113.356845 -318.951478) (xy 113.409056 -318.940361) (xy 113.462308 -318.936631) (xy 113.51556 -318.940361)
			(xy 113.567771 -318.951478) (xy 113.617923 -318.969764) (xy 113.665037 -318.994863) (xy 113.708191 -319.026285)
			(xy 113.746545 -319.063415) (xy 113.763298 -319.084198) (xy 113.770865 -319.092954) (xy 113.79162 -319.103141)
			(xy 113.803176 -319.103756) (xy 113.88344 -319.103756) (xy 113.895006 -319.103167) (xy 113.915778 -319.092987)
			(xy 113.923318 -319.084198) (xy 113.941498 -319.061705) (xy 113.98352 -319.021971) (xy 114.031058 -318.989033)
			(xy 114.083021 -318.963646) (xy 114.13822 -318.946392) (xy 114.195391 -318.937666) (xy 114.224308 -318.937132)
			(xy 114.251563 -318.937548) (xy 114.305518 -318.945307) (xy 114.357819 -318.960666) (xy 114.407402 -318.983313)
			(xy 114.453257 -319.012785) (xy 114.49445 -319.048484) (xy 114.530144 -319.089682) (xy 114.559611 -319.135541)
			(xy 114.582251 -319.185126) (xy 114.597603 -319.237429) (xy 114.605355 -319.291385) (xy 114.605816 -319.31864)
			(xy 114.605286 -319.347557) (xy 114.596564 -319.404729) (xy 114.57931 -319.459929) (xy 114.553921 -319.511891)
			(xy 114.520978 -319.559425) (xy 114.481236 -319.601441) (xy 114.45875 -319.61963) (xy 114.44997 -319.627174)
			(xy 114.439799 -319.647947) (xy 114.439192 -319.659508) (xy 114.439192 -319.739772) (xy 114.439781 -319.751337)
			(xy 114.449963 -319.772108) (xy 114.45875 -319.77965) (xy 114.48122 -319.797857) (xy 114.520954 -319.839875)
			(xy 114.553893 -319.887407) (xy 114.579283 -319.939365) (xy 114.596543 -319.994559) (xy 114.605278 -320.051725)
			(xy 114.605816 -320.08064) (xy 114.605359 -320.107892) (xy 114.597598 -320.16184) (xy 114.582238 -320.214135)
			(xy 114.559593 -320.263712) (xy 114.530123 -320.309562) (xy 114.494429 -320.350751) (xy 114.453236 -320.386442)
			(xy 114.407384 -320.415908) (xy 114.357805 -320.438549) (xy 114.305509 -320.453904) (xy 114.25156 -320.461662)
			(xy 114.224308 -320.462148) (xy 114.19539 -320.461644) (xy 114.138218 -320.452914) (xy 114.083018 -320.435655)
			(xy 114.031056 -320.410261) (xy 113.983522 -320.377314) (xy 113.941507 -320.337569) (xy 113.923318 -320.315082)
			(xy 113.915747 -320.306329) (xy 113.894995 -320.296141) (xy 113.88344 -320.295524) (xy 113.803176 -320.295524)
			(xy 113.791612 -320.296129) (xy 113.77084 -320.306298) (xy 113.763298 -320.315082) (xy 113.746545 -320.335865)
			(xy 113.708191 -320.372995) (xy 113.665037 -320.404417) (xy 113.617923 -320.429516) (xy 113.567771 -320.447802)
			(xy 113.51556 -320.458919) (xy 113.462308 -320.462649) (xy 113.409056 -320.458919) (xy 113.356845 -320.447802)
			(xy 113.306693 -320.429516) (xy 113.259579 -320.404417) (xy 113.216425 -320.372995) (xy 113.178071 -320.335865)
			(xy 113.161318 -320.315082) (xy 113.153747 -320.306329) (xy 113.132995 -320.296141) (xy 113.12144 -320.295524)
			(xy 113.041176 -320.295524) (xy 113.029612 -320.296129) (xy 113.00884 -320.306298) (xy 113.001298 -320.315082)
			(xy 112.984545 -320.335865) (xy 112.946191 -320.372995) (xy 112.903037 -320.404417) (xy 112.855923 -320.429516)
			(xy 112.805771 -320.447802) (xy 112.75356 -320.458919) (xy 112.700308 -320.462649) (xy 112.647056 -320.458919)
			(xy 112.594845 -320.447802) (xy 112.544693 -320.429516) (xy 112.497579 -320.404417) (xy 112.454425 -320.372995)
			(xy 112.416071 -320.335865) (xy 112.399318 -320.315082) (xy 112.391747 -320.306329) (xy 112.370995 -320.296141)
			(xy 112.35944 -320.295524) (xy 112.279176 -320.295524) (xy 112.267612 -320.296129) (xy 112.24684 -320.306298)
			(xy 112.239298 -320.315082) (xy 112.222545 -320.335865) (xy 112.184191 -320.372995) (xy 112.141037 -320.404417)
			(xy 112.093923 -320.429516) (xy 112.043771 -320.447802) (xy 111.99156 -320.458919) (xy 111.938308 -320.462649)
			(xy 111.885056 -320.458919) (xy 111.832845 -320.447802) (xy 111.782693 -320.429516) (xy 111.735579 -320.404417)
			(xy 111.692425 -320.372995) (xy 111.654071 -320.335865) (xy 111.637318 -320.315082) (xy 111.629747 -320.306329)
			(xy 111.608995 -320.296141) (xy 111.59744 -320.295524) (xy 111.517176 -320.295524) (xy 111.505612 -320.296129)
			(xy 111.48484 -320.306298) (xy 111.477298 -320.315082) (xy 111.460545 -320.335865) (xy 111.422191 -320.372995)
			(xy 111.379037 -320.404417) (xy 111.331923 -320.429516) (xy 111.281771 -320.447802) (xy 111.22956 -320.458919)
			(xy 111.176308 -320.462649) (xy 111.123056 -320.458919) (xy 111.070845 -320.447802) (xy 111.020693 -320.429516)
			(xy 110.973579 -320.404417) (xy 110.930425 -320.372995) (xy 110.892071 -320.335865) (xy 110.875318 -320.315082)
			(xy 110.867747 -320.306329) (xy 110.846995 -320.296141) (xy 110.83544 -320.295524) (xy 110.755176 -320.295524)
			(xy 110.743612 -320.296129) (xy 110.72284 -320.306298) (xy 110.715298 -320.315082) (xy 110.698545 -320.335865)
			(xy 110.660191 -320.372995) (xy 110.617037 -320.404417) (xy 110.569923 -320.429516) (xy 110.519771 -320.447802)
			(xy 110.46756 -320.458919) (xy 110.414308 -320.462649) (xy 110.361056 -320.458919) (xy 110.308845 -320.447802)
			(xy 110.258693 -320.429516) (xy 110.211579 -320.404417) (xy 110.168425 -320.372995) (xy 110.130071 -320.335865)
			(xy 110.113318 -320.315082) (xy 110.105747 -320.306329) (xy 110.084995 -320.296141) (xy 110.07344 -320.295524)
			(xy 109.993176 -320.295524) (xy 109.981612 -320.296129) (xy 109.96084 -320.306298) (xy 109.953298 -320.315082)
			(xy 109.936545 -320.335865) (xy 109.898191 -320.372995) (xy 109.855037 -320.404417) (xy 109.807923 -320.429516)
			(xy 109.757771 -320.447802) (xy 109.70556 -320.458919) (xy 109.652308 -320.462649) (xy 109.599056 -320.458919)
			(xy 109.546845 -320.447802) (xy 109.496693 -320.429516) (xy 109.449579 -320.404417) (xy 109.406425 -320.372995)
			(xy 109.368071 -320.335865) (xy 109.351318 -320.315082) (xy 109.343747 -320.306329) (xy 109.322995 -320.296141)
			(xy 109.31144 -320.295524) (xy 109.231176 -320.295524) (xy 109.219612 -320.296129) (xy 109.19884 -320.306298)
			(xy 109.191298 -320.315082) (xy 109.174545 -320.335865) (xy 109.136191 -320.372995) (xy 109.093037 -320.404417)
			(xy 109.045923 -320.429516) (xy 108.995771 -320.447802) (xy 108.94356 -320.458919) (xy 108.890308 -320.462649)
			(xy 108.837056 -320.458919) (xy 108.784845 -320.447802) (xy 108.734693 -320.429516) (xy 108.687579 -320.404417)
			(xy 108.644425 -320.372995) (xy 108.606071 -320.335865) (xy 108.589318 -320.315082) (xy 108.581747 -320.306329)
			(xy 108.560995 -320.296141) (xy 108.54944 -320.295524) (xy 108.469176 -320.295524) (xy 108.457612 -320.296129)
			(xy 108.43684 -320.306298) (xy 108.429298 -320.315082) (xy 108.412545 -320.335865) (xy 108.374191 -320.372995)
			(xy 108.331037 -320.404417) (xy 108.283923 -320.429516) (xy 108.233771 -320.447802) (xy 108.18156 -320.458919)
			(xy 108.128308 -320.462649) (xy 108.075056 -320.458919) (xy 108.022845 -320.447802) (xy 107.972693 -320.429516)
			(xy 107.925579 -320.404417) (xy 107.882425 -320.372995) (xy 107.844071 -320.335865) (xy 107.827318 -320.315082)
			(xy 107.819747 -320.306329) (xy 107.798995 -320.296141) (xy 107.78744 -320.295524) (xy 107.707176 -320.295524)
			(xy 107.695612 -320.296129) (xy 107.67484 -320.306298) (xy 107.667298 -320.315082) (xy 107.650545 -320.335865)
			(xy 107.612191 -320.372995) (xy 107.569037 -320.404417) (xy 107.521923 -320.429516) (xy 107.471771 -320.447802)
			(xy 107.41956 -320.458919) (xy 107.366308 -320.462649) (xy 107.313056 -320.458919) (xy 107.260845 -320.447802)
			(xy 107.210693 -320.429516) (xy 107.163579 -320.404417) (xy 107.120425 -320.372995) (xy 107.082071 -320.335865)
			(xy 107.065318 -320.315082) (xy 107.057747 -320.306329) (xy 107.036995 -320.296141) (xy 107.02544 -320.295524)
			(xy 106.945176 -320.295524) (xy 106.933612 -320.296129) (xy 106.91284 -320.306298) (xy 106.905298 -320.315082)
			(xy 106.887104 -320.337563) (xy 106.845085 -320.377299) (xy 106.797551 -320.410239) (xy 106.74559 -320.435628)
			(xy 106.690393 -320.452884) (xy 106.633224 -320.461613) (xy 106.604308 -320.462148) (xy 106.577059 -320.461615)
			(xy 106.523115 -320.453861) (xy 106.470823 -320.438508) (xy 106.421249 -320.415871) (xy 106.3754 -320.386409)
			(xy 106.334211 -320.350723) (xy 106.298519 -320.309538) (xy 106.269052 -320.263693) (xy 106.246408 -320.214122)
			(xy 106.23105 -320.161832) (xy 106.223289 -320.107889) (xy 106.2228 -320.08064) (xy 99.78771 -320.08064)
			(xy 99.78771 -324.075806) (xy 102.316788 -324.075806) (xy 102.317374 -324.045828) (xy 102.326764 -323.986613)
			(xy 102.345299 -323.929594) (xy 102.372523 -323.876175) (xy 102.407766 -323.827671) (xy 102.428548 -323.806058)
			(xy 102.630986 -323.60362) (xy 102.637752 -323.596256) (xy 102.645405 -323.577796) (xy 102.645406 -323.557813)
			(xy 102.637757 -323.539351) (xy 102.630986 -323.531992) (xy 102.428548 -323.329554) (xy 102.407761 -323.307943)
			(xy 102.372503 -323.259446) (xy 102.345269 -323.206028) (xy 102.326732 -323.149006) (xy 102.317347 -323.089786)
			(xy 102.316788 -323.059806) (xy 102.317215 -323.032558) (xy 102.324974 -322.978617) (xy 102.340334 -322.92633)
			(xy 102.362982 -322.876764) (xy 102.392457 -322.830927) (xy 102.428159 -322.789754) (xy 102.469359 -322.754083)
			(xy 102.515219 -322.724643) (xy 102.564803 -322.702032) (xy 102.617101 -322.686712) (xy 102.671048 -322.678995)
			(xy 102.698296 -322.678552) (xy 102.72827 -322.679049) (xy 102.787487 -322.688374) (xy 102.844512 -322.706858)
			(xy 102.89794 -322.734045) (xy 102.94645 -322.769263) (xy 102.968044 -322.790058) (xy 103.151686 -322.973954)
			(xy 103.159102 -322.980774) (xy 103.177689 -322.988507) (xy 103.187754 -322.98894) (xy 115.30203 -322.98894)
			(xy 115.312103 -322.988546) (xy 115.330702 -322.980805) (xy 115.338098 -322.973954) (xy 116.306346 -322.005706)
			(xy 116.313182 -321.998303) (xy 116.320903 -321.979706) (xy 116.321332 -321.969638) (xy 116.321332 -307.243734)
			(xy 116.320907 -307.233664) (xy 116.313188 -307.215065) (xy 116.306346 -307.207666) (xy 115.584732 -306.486306)
			(xy 115.563918 -306.464719) (xy 115.528665 -306.416215) (xy 115.501436 -306.362791) (xy 115.482905 -306.305764)
			(xy 115.473527 -306.246539) (xy 115.472972 -306.216558) (xy 115.472972 -303.936146) (xy 115.473587 -303.90617)
			(xy 115.482971 -303.846955) (xy 115.5015 -303.789937) (xy 115.528717 -303.736518) (xy 115.563953 -303.688013)
			(xy 115.584732 -303.666398) (xy 116.061744 -303.189386) (xy 116.083376 -303.168639) (xy 116.131891 -303.133449)
			(xy 116.185312 -303.106278) (xy 116.242324 -303.087794) (xy 116.301525 -303.078452) (xy 116.331492 -303.07788)
			(xy 116.66982 -303.07788) (xy 116.679891 -303.07747) (xy 116.698489 -303.069739) (xy 116.705888 -303.062894)
			(xy 116.896642 -302.871886) (xy 116.918275 -302.85114) (xy 116.96679 -302.81595) (xy 117.02021 -302.788778)
			(xy 117.077222 -302.770294) (xy 117.136423 -302.760952) (xy 117.16639 -302.76038) (xy 117.193626 -302.760818)
			(xy 117.247544 -302.768569) (xy 117.299809 -302.783916) (xy 117.349359 -302.806544) (xy 117.395183 -302.835995)
			(xy 117.436349 -302.871668) (xy 117.472019 -302.912836) (xy 117.501467 -302.958662) (xy 117.524093 -303.008213)
			(xy 117.539436 -303.06048) (xy 117.547184 -303.114398) (xy 117.547644 -303.141634) (xy 117.547109 -303.171606)
			(xy 117.537794 -303.230822) (xy 117.519319 -303.287847) (xy 117.49214 -303.341275) (xy 117.456929 -303.389787)
			(xy 117.436138 -303.411382) (xy 117.2337 -303.61382) (xy 117.226895 -303.621153) (xy 117.219251 -303.639627)
			(xy 117.219261 -303.659621) (xy 117.226922 -303.678088) (xy 117.2337 -303.685448) (xy 117.436138 -303.887886)
			(xy 117.456909 -303.909496) (xy 117.492095 -303.958017) (xy 117.519262 -304.011443) (xy 117.53774 -304.06846)
			(xy 117.547075 -304.127665) (xy 117.547644 -304.157634) (xy 117.5472 -304.184868) (xy 117.539444 -304.238782)
			(xy 117.524094 -304.291043) (xy 117.501463 -304.340588) (xy 117.472012 -304.386409) (xy 117.43634 -304.427571)
			(xy 117.395173 -304.463239) (xy 117.34935 -304.492684) (xy 117.299802 -304.515309) (xy 117.247539 -304.530653)
			(xy 117.193624 -304.538403) (xy 117.16639 -304.538888) (xy 117.136416 -304.538389) (xy 117.0772 -304.529063)
			(xy 117.020175 -304.510578) (xy 116.966747 -304.483393) (xy 116.918236 -304.448176) (xy 116.896642 -304.427382)
			(xy 116.705888 -304.236374) (xy 116.698489 -304.229532) (xy 116.679889 -304.221814) (xy 116.66982 -304.221388)
			(xy 116.66855 -304.221388) (xy 116.658481 -304.221816) (xy 116.639881 -304.229532) (xy 116.632482 -304.236374)
			(xy 116.63172 -304.237136) (xy 116.625018 -304.24461) (xy 116.617434 -304.263175) (xy 116.616988 -304.273204)
			(xy 116.616988 -305.8795) (xy 116.61736 -305.889546) (xy 116.624945 -305.908143) (xy 116.63172 -305.915568)
			(xy 117.353334 -306.636928) (xy 117.374077 -306.658564) (xy 117.409267 -306.707078) (xy 117.436438 -306.760498)
			(xy 117.454923 -306.817509) (xy 117.464267 -306.876709) (xy 117.46484 -306.906676) (xy 117.46484 -322.306696)
			(xy 117.464346 -322.33667) (xy 117.45502 -322.395887) (xy 117.436536 -322.452913) (xy 117.409348 -322.50634)
			(xy 117.374129 -322.55485) (xy 117.353334 -322.576444) (xy 115.908836 -324.020942) (xy 115.887217 -324.041703)
			(xy 115.838698 -324.07689) (xy 115.785274 -324.104059) (xy 115.728259 -324.122539) (xy 115.669056 -324.131878)
			(xy 115.639088 -324.132448) (xy 103.201978 -324.132448) (xy 103.191906 -324.132849) (xy 103.173307 -324.140585)
			(xy 103.16591 -324.147434) (xy 102.968044 -324.345554) (xy 102.946424 -324.366313) (xy 102.897905 -324.401501)
			(xy 102.844481 -324.428669) (xy 102.787467 -324.44715) (xy 102.728264 -324.456489) (xy 102.698296 -324.45706)
			(xy 102.671054 -324.456627) (xy 102.617124 -324.448875) (xy 102.564846 -324.43353) (xy 102.515282 -324.410903)
			(xy 102.469442 -324.381456) (xy 102.428257 -324.345786) (xy 102.392566 -324.30462) (xy 102.363094 -324.258795)
			(xy 102.340441 -324.209244) (xy 102.325068 -324.156973) (xy 102.317288 -324.103048) (xy 102.316788 -324.075806)
			(xy 99.78771 -324.075806) (xy 99.78771 -327.390252) (xy 104.653586 -327.390252) (xy 104.657657 -327.33463)
			(xy 104.669783 -327.280193) (xy 104.689706 -327.228102) (xy 104.717002 -327.179467) (xy 104.751088 -327.135324)
			(xy 104.791237 -327.096615) (xy 104.836595 -327.064164) (xy 104.886195 -327.038663) (xy 104.938979 -327.020656)
			(xy 104.993822 -327.010526) (xy 105.049556 -327.008489) (xy 105.104993 -327.014589) (xy 105.15895 -327.028695)
			(xy 105.210279 -327.050507) (xy 105.257885 -327.079561) (xy 105.300753 -327.115236) (xy 105.33797 -327.156773)
			(xy 105.368743 -327.203286) (xy 105.392415 -327.253783) (xy 105.408483 -327.30719) (xy 105.416603 -327.362366)
			(xy 105.416672 -327.366122) (xy 106.29214 -327.366122) (xy 106.296211 -327.3105) (xy 106.308337 -327.256063)
			(xy 106.32826 -327.203972) (xy 106.355556 -327.155337) (xy 106.389642 -327.111194) (xy 106.429791 -327.072485)
			(xy 106.475149 -327.040034) (xy 106.524749 -327.014533) (xy 106.577533 -326.996526) (xy 106.632376 -326.986396)
			(xy 106.68811 -326.984359) (xy 106.743547 -326.990459) (xy 106.797504 -327.004565) (xy 106.848833 -327.026377)
			(xy 106.896439 -327.055431) (xy 106.939307 -327.091106) (xy 106.976524 -327.132643) (xy 107.007297 -327.179156)
			(xy 107.030969 -327.229653) (xy 107.047037 -327.28306) (xy 107.055157 -327.338236) (xy 107.055666 -327.366122)
			(xy 107.055157 -327.394008) (xy 107.047037 -327.449184) (xy 107.044898 -327.456292) (xy 108.97184 -327.456292)
			(xy 108.975911 -327.40067) (xy 108.988037 -327.346233) (xy 109.00796 -327.294142) (xy 109.035256 -327.245507)
			(xy 109.069342 -327.201364) (xy 109.109491 -327.162655) (xy 109.154849 -327.130204) (xy 109.204449 -327.104703)
			(xy 109.257233 -327.086696) (xy 109.312076 -327.076566) (xy 109.36781 -327.074529) (xy 109.423247 -327.080629)
			(xy 109.477204 -327.094735) (xy 109.528533 -327.116547) (xy 109.576139 -327.145601) (xy 109.619007 -327.181276)
			(xy 109.656224 -327.222813) (xy 109.686997 -327.269326) (xy 109.710669 -327.319823) (xy 109.726737 -327.37323)
			(xy 109.734857 -327.428406) (xy 109.735366 -327.456292) (xy 109.734857 -327.484178) (xy 109.726737 -327.539354)
			(xy 109.710669 -327.592761) (xy 109.686997 -327.643258) (xy 109.656224 -327.689771) (xy 109.619007 -327.731308)
			(xy 109.576139 -327.766983) (xy 109.528533 -327.796037) (xy 109.477204 -327.817849) (xy 109.423247 -327.831955)
			(xy 109.36781 -327.838055) (xy 109.312076 -327.836018) (xy 109.257233 -327.825888) (xy 109.204449 -327.807881)
			(xy 109.154849 -327.78238) (xy 109.109491 -327.749929) (xy 109.069342 -327.71122) (xy 109.035256 -327.667077)
			(xy 109.00796 -327.618442) (xy 108.988037 -327.566351) (xy 108.975911 -327.511914) (xy 108.97184 -327.456292)
			(xy 107.044898 -327.456292) (xy 107.030969 -327.502591) (xy 107.007297 -327.553088) (xy 106.976524 -327.599601)
			(xy 106.939307 -327.641138) (xy 106.896439 -327.676813) (xy 106.848833 -327.705867) (xy 106.797504 -327.727679)
			(xy 106.743547 -327.741785) (xy 106.68811 -327.747885) (xy 106.632376 -327.745848) (xy 106.577533 -327.735718)
			(xy 106.524749 -327.717711) (xy 106.475149 -327.69221) (xy 106.429791 -327.659759) (xy 106.389642 -327.62105)
			(xy 106.355556 -327.576907) (xy 106.32826 -327.528272) (xy 106.308337 -327.476181) (xy 106.296211 -327.421744)
			(xy 106.29214 -327.366122) (xy 105.416672 -327.366122) (xy 105.417112 -327.390252) (xy 105.416603 -327.418138)
			(xy 105.408483 -327.473314) (xy 105.392415 -327.526721) (xy 105.368743 -327.577218) (xy 105.33797 -327.623731)
			(xy 105.300753 -327.665268) (xy 105.257885 -327.700943) (xy 105.210279 -327.729997) (xy 105.15895 -327.751809)
			(xy 105.104993 -327.765915) (xy 105.049556 -327.772015) (xy 104.993822 -327.769978) (xy 104.938979 -327.759848)
			(xy 104.886195 -327.741841) (xy 104.836595 -327.71634) (xy 104.791237 -327.683889) (xy 104.751088 -327.64518)
			(xy 104.717002 -327.601037) (xy 104.689706 -327.552402) (xy 104.669783 -327.500311) (xy 104.657657 -327.445874)
			(xy 104.653586 -327.390252) (xy 99.78771 -327.390252) (xy 99.78771 -328.218292) (xy 103.1908 -328.218292)
			(xy 103.194871 -328.16267) (xy 103.206997 -328.108233) (xy 103.22692 -328.056142) (xy 103.254216 -328.007507)
			(xy 103.288302 -327.963364) (xy 103.328451 -327.924655) (xy 103.373809 -327.892204) (xy 103.423409 -327.866703)
			(xy 103.476193 -327.848696) (xy 103.531036 -327.838566) (xy 103.58677 -327.836529) (xy 103.642207 -327.842629)
			(xy 103.696164 -327.856735) (xy 103.747493 -327.878547) (xy 103.795099 -327.907601) (xy 103.837967 -327.943276)
			(xy 103.875184 -327.984813) (xy 103.905957 -328.031326) (xy 103.929629 -328.081823) (xy 103.945697 -328.13523)
			(xy 103.953817 -328.190406) (xy 103.954326 -328.218292) (xy 103.953817 -328.246178) (xy 103.945697 -328.301354)
			(xy 103.929629 -328.354761) (xy 103.915255 -328.385424) (xy 104.682542 -328.385424) (xy 104.686613 -328.329802)
			(xy 104.698739 -328.275365) (xy 104.718662 -328.223274) (xy 104.745958 -328.174639) (xy 104.780044 -328.130496)
			(xy 104.820193 -328.091787) (xy 104.865551 -328.059336) (xy 104.915151 -328.033835) (xy 104.967935 -328.015828)
			(xy 105.022778 -328.005698) (xy 105.078512 -328.003661) (xy 105.133949 -328.009761) (xy 105.187906 -328.023867)
			(xy 105.239235 -328.045679) (xy 105.286841 -328.074733) (xy 105.329709 -328.110408) (xy 105.366926 -328.151945)
			(xy 105.397699 -328.198458) (xy 105.421371 -328.248955) (xy 105.437439 -328.302362) (xy 105.445559 -328.357538)
			(xy 105.446068 -328.385424) (xy 105.445559 -328.41331) (xy 105.437439 -328.468486) (xy 105.421371 -328.521893)
			(xy 105.397699 -328.57239) (xy 105.366926 -328.618903) (xy 105.329709 -328.66044) (xy 105.286841 -328.696115)
			(xy 105.239235 -328.725169) (xy 105.187906 -328.746981) (xy 105.133949 -328.761087) (xy 105.078512 -328.767187)
			(xy 105.022778 -328.76515) (xy 104.967935 -328.75502) (xy 104.915151 -328.737013) (xy 104.865551 -328.711512)
			(xy 104.820193 -328.679061) (xy 104.780044 -328.640352) (xy 104.745958 -328.596209) (xy 104.718662 -328.547574)
			(xy 104.698739 -328.495483) (xy 104.686613 -328.441046) (xy 104.682542 -328.385424) (xy 103.915255 -328.385424)
			(xy 103.905957 -328.405258) (xy 103.875184 -328.451771) (xy 103.837967 -328.493308) (xy 103.795099 -328.528983)
			(xy 103.747493 -328.558037) (xy 103.696164 -328.579849) (xy 103.642207 -328.593955) (xy 103.58677 -328.600055)
			(xy 103.531036 -328.598018) (xy 103.476193 -328.587888) (xy 103.423409 -328.569881) (xy 103.373809 -328.54438)
			(xy 103.328451 -328.511929) (xy 103.288302 -328.47322) (xy 103.254216 -328.429077) (xy 103.22692 -328.380442)
			(xy 103.206997 -328.328351) (xy 103.194871 -328.273914) (xy 103.1908 -328.218292) (xy 99.78771 -328.218292)
			(xy 99.78771 -329.038204) (xy 102.152194 -329.038204) (xy 102.156265 -328.982582) (xy 102.168391 -328.928145)
			(xy 102.188314 -328.876054) (xy 102.21561 -328.827419) (xy 102.249696 -328.783276) (xy 102.289845 -328.744567)
			(xy 102.335203 -328.712116) (xy 102.384803 -328.686615) (xy 102.437587 -328.668608) (xy 102.49243 -328.658478)
			(xy 102.548164 -328.656441) (xy 102.603601 -328.662541) (xy 102.657558 -328.676647) (xy 102.708887 -328.698459)
			(xy 102.756493 -328.727513) (xy 102.799361 -328.763188) (xy 102.836578 -328.804725) (xy 102.867351 -328.851238)
			(xy 102.891023 -328.901735) (xy 102.907091 -328.955142) (xy 102.915211 -329.010318) (xy 102.91572 -329.038204)
			(xy 102.915211 -329.06609) (xy 102.907091 -329.121266) (xy 102.891023 -329.174673) (xy 102.867351 -329.22517)
			(xy 102.836578 -329.271683) (xy 102.799361 -329.31322) (xy 102.756493 -329.348895) (xy 102.708887 -329.377949)
			(xy 102.657558 -329.399761) (xy 102.603601 -329.413867) (xy 102.548164 -329.419967) (xy 102.49243 -329.41793)
			(xy 102.437587 -329.4078) (xy 102.384803 -329.389793) (xy 102.335203 -329.364292) (xy 102.289845 -329.331841)
			(xy 102.249696 -329.293132) (xy 102.21561 -329.248989) (xy 102.188314 -329.200354) (xy 102.168391 -329.148263)
			(xy 102.156265 -329.093826) (xy 102.152194 -329.038204) (xy 99.78771 -329.038204) (xy 99.78771 -330.181712)
			(xy 99.788136 -330.191781) (xy 99.795854 -330.210381) (xy 99.802696 -330.21778) (xy 99.971098 -330.386182)
			(xy 99.978496 -330.393031) (xy 99.997094 -330.400769) (xy 100.007166 -330.401168)
		)
		(stroke
			(width 0)
			(type solid)
		)
		(fill yes)
		(layer "In5.Cu")
		(net "GND")
	)
	(gr_poly
		(pts
			(xy 357.93426 -331.859128) (xy 357.937615 -331.856453) (xy 357.943487 -331.850199) (xy 357.945944 -331.846682)
			(xy 357.992934 -331.77607) (xy 357.998497 -331.766873) (xy 358.002029 -331.745691) (xy 357.999792 -331.735176)
			(xy 357.997252 -331.727556) (xy 357.996998 -331.727302) (xy 357.987142 -331.703337) (xy 357.973246 -331.653418)
			(xy 357.966209 -331.60208) (xy 357.965756 -331.576172) (xy 357.965756 -331.575918) (xy 357.966242 -331.548649)
			(xy 357.974004 -331.494665) (xy 357.989369 -331.442335) (xy 358.012026 -331.392725) (xy 358.041512 -331.346844)
			(xy 358.077227 -331.305627) (xy 358.118444 -331.269912) (xy 358.164325 -331.240426) (xy 358.213935 -331.217769)
			(xy 358.266265 -331.202404) (xy 358.320249 -331.194642) (xy 358.374787 -331.194642) (xy 358.428771 -331.202404)
			(xy 358.481101 -331.217769) (xy 358.530711 -331.240426) (xy 358.576592 -331.269912) (xy 358.617809 -331.305627)
			(xy 358.653524 -331.346844) (xy 358.68301 -331.392725) (xy 358.705667 -331.442335) (xy 358.721032 -331.494665)
			(xy 358.728794 -331.548649) (xy 358.72928 -331.575918) (xy 358.72881 -331.601878) (xy 358.721712 -331.653313)
			(xy 358.707719 -331.703314) (xy 358.697784 -331.727302) (xy 358.697784 -331.727556) (xy 358.69753 -331.728064)
			(xy 358.693279 -331.739928) (xy 358.695662 -331.764986) (xy 358.702102 -331.775816) (xy 358.720644 -331.80401)
			(xy 358.741472 -331.835506) (xy 358.746806 -331.841856) (xy 358.749092 -331.844142) (xy 358.756487 -331.850996)
			(xy 358.775086 -331.858743) (xy 358.78516 -331.859128) (xy 362.97362 -331.859128) (xy 362.983689 -331.858702)
			(xy 363.002291 -331.850986) (xy 363.009688 -331.844142) (xy 363.14761 -331.70622) (xy 363.154454 -331.698822)
			(xy 363.162173 -331.680222) (xy 363.162596 -331.670152) (xy 363.162596 -330.845414) (xy 363.16243 -330.838911)
			(xy 363.159214 -330.826311) (xy 363.156246 -330.820522) (xy 363.144562 -330.797916) (xy 363.14253 -330.796646)
			(xy 363.131608 -330.790042) (xy 363.128306 -330.788518) (xy 363.117338 -330.784491) (xy 363.094036 -330.785803)
			(xy 363.083602 -330.791058) (xy 363.082586 -330.79182) (xy 363.082332 -330.79182) (xy 363.076236 -330.795376)
			(xy 363.066838 -330.802488) (xy 363.063028 -330.806298) (xy 363.056424 -330.81595) (xy 363.0549 -330.818998)
			(xy 363.042647 -330.842299) (xy 363.012694 -330.885592) (xy 362.977071 -330.924354) (xy 362.936455 -330.957847)
			(xy 362.891618 -330.985436) (xy 362.843413 -331.006596) (xy 362.792755 -331.020925) (xy 362.740609 -331.02815)
			(xy 362.714286 -331.028548) (xy 362.685488 -331.028031) (xy 362.628544 -331.019394) (xy 362.573543 -331.002302)
			(xy 362.521732 -330.977145) (xy 362.474288 -330.944491) (xy 362.432285 -330.905083) (xy 362.396678 -330.859813)
			(xy 362.382054 -330.835) (xy 362.379006 -330.829666) (xy 362.375196 -330.825348) (xy 362.366306 -330.817728)
			(xy 362.333794 -330.7969) (xy 362.319824 -330.796392) (xy 362.246672 -330.792836) (xy 362.235496 -330.793598)
			(xy 362.231731 -330.794317) (xy 362.22446 -330.796738) (xy 362.221018 -330.798424) (xy 362.217462 -330.800202)
			(xy 362.213305 -330.802863) (xy 362.206008 -330.809509) (xy 362.202984 -330.81341) (xy 362.20146 -330.81595)
			(xy 362.186244 -330.838317) (xy 362.150511 -330.878932) (xy 362.109409 -330.914103) (xy 362.063757 -330.943126)
			(xy 362.014469 -330.965421) (xy 361.962529 -330.980543) (xy 361.908976 -330.988189) (xy 361.881928 -330.98867)
			(xy 361.854675 -330.988209) (xy 361.800723 -330.980455) (xy 361.748424 -330.965101) (xy 361.698843 -330.942459)
			(xy 361.652989 -330.912991) (xy 361.611796 -330.877297) (xy 361.576103 -330.836103) (xy 361.546636 -330.790249)
			(xy 361.523996 -330.740667) (xy 361.508643 -330.688367) (xy 361.500891 -330.634415) (xy 361.50042 -330.607162)
			(xy 361.50042 -330.6064) (xy 361.500915 -330.578693) (xy 361.508949 -330.523865) (xy 361.516422 -330.49718)
			(xy 361.517438 -330.494132) (xy 361.51847 -330.48905) (xy 361.518725 -330.478685) (xy 361.517946 -330.473558)
			(xy 361.515914 -330.462128) (xy 361.460288 -330.387198) (xy 361.452726 -330.378016) (xy 361.431526 -330.367295)
			(xy 361.419648 -330.366624) (xy 361.40263 -330.366624) (xy 361.393486 -330.36764) (xy 361.384342 -330.369672)
			(xy 361.375206 -330.372329) (xy 361.359663 -330.38328) (xy 361.354116 -330.391008) (xy 361.337606 -330.419964)
			(xy 361.335835 -330.423706) (xy 361.333411 -330.431621) (xy 361.33278 -330.435712) (xy 361.33151 -330.444348)
			(xy 361.333796 -330.454254) (xy 361.335574 -330.46162) (xy 361.33786 -330.468478) (xy 361.33913 -330.471526)
			(xy 361.339384 -330.472034) (xy 361.350926 -330.497607) (xy 361.367214 -330.551297) (xy 361.375451 -330.606795)
			(xy 361.37596 -330.634848) (xy 361.37547 -330.662096) (xy 361.367708 -330.716036) (xy 361.352348 -330.768322)
			(xy 361.329704 -330.81789) (xy 361.300236 -330.863731) (xy 361.264543 -330.904911) (xy 361.223354 -330.940593)
			(xy 361.177506 -330.97005) (xy 361.127932 -330.992682) (xy 361.075642 -331.008029) (xy 361.0217 -331.015777)
			(xy 360.994452 -331.016356) (xy 360.967386 -331.01588) (xy 360.913799 -331.008223) (xy 360.861832 -330.993069)
			(xy 360.812528 -330.970722) (xy 360.766878 -330.941631) (xy 360.725797 -330.90638) (xy 360.690111 -330.865677)
			(xy 360.660535 -330.820339) (xy 360.637665 -330.771276) (xy 360.621958 -330.719474) (xy 360.61373 -330.665971)
			(xy 360.612944 -330.638912) (xy 360.612944 -330.63434) (xy 360.613651 -330.601949) (xy 360.624631 -330.538105)
			(xy 360.634788 -330.50734) (xy 360.635804 -330.504292) (xy 360.638344 -330.493116) (xy 360.639339 -330.48413)
			(xy 360.635701 -330.466431) (xy 360.631232 -330.458572) (xy 360.62412 -330.447904) (xy 360.61904 -330.440538)
			(xy 360.580686 -330.384912) (xy 360.576876 -330.381356) (xy 360.569764 -330.374244) (xy 360.56062 -330.370434)
			(xy 360.555992 -330.368659) (xy 360.546271 -330.366736) (xy 360.541316 -330.366624) (xy 360.499152 -330.366624)
			(xy 360.490347 -330.367049) (xy 360.473804 -330.373102) (xy 360.46027 -330.384379) (xy 360.455464 -330.39177)
			(xy 360.440478 -330.417678) (xy 360.436143 -330.425923) (xy 360.433162 -330.444293) (xy 360.434636 -330.453492)
			(xy 360.435906 -330.460604) (xy 360.438954 -330.4667) (xy 360.451913 -330.493539) (xy 360.470247 -330.550244)
			(xy 360.479519 -330.609114) (xy 360.480102 -330.638912) (xy 360.480102 -330.643484) (xy 360.479326 -330.670535)
			(xy 360.471078 -330.72402) (xy 360.455355 -330.775802) (xy 360.432473 -330.824843) (xy 360.40289 -330.870158)
			(xy 360.367201 -330.910839) (xy 360.326122 -330.946068) (xy 360.280477 -330.975139) (xy 360.231182 -330.997469)
			(xy 360.179226 -331.012608) (xy 360.125652 -331.020254) (xy 360.098594 -331.020674) (xy 360.071342 -331.02021)
			(xy 360.017394 -331.012452) (xy 359.965099 -330.997095) (xy 359.915521 -330.974452) (xy 359.869672 -330.944983)
			(xy 359.828482 -330.909289) (xy 359.792793 -330.868096) (xy 359.763329 -330.822243) (xy 359.740691 -330.772664)
			(xy 359.725339 -330.720367) (xy 359.717587 -330.666418) (xy 359.717086 -330.639166) (xy 359.717831 -330.604676)
			(xy 359.730232 -330.53682) (xy 359.741724 -330.504292) (xy 359.74274 -330.501752) (xy 359.744284 -330.496372)
			(xy 359.745299 -330.485227) (xy 359.744772 -330.479654) (xy 359.743248 -330.46797) (xy 359.69194 -330.393548)
			(xy 359.69067 -330.391516) (xy 359.687368 -330.385928) (xy 359.678732 -330.377292) (xy 359.672636 -330.373736)
			(xy 359.666286 -330.370434) (xy 359.656888 -330.36764) (xy 359.646982 -330.366624) (xy 352.91776 -330.366624)
			(xy 352.907759 -330.367119) (xy 352.889285 -330.374787) (xy 352.875151 -330.388939) (xy 352.867507 -330.407423)
			(xy 352.86696 -330.417424) (xy 352.86696 -330.48448) (xy 352.867399 -330.494542) (xy 352.875141 -330.51312)
			(xy 352.881946 -330.520548) (xy 353.088956 -330.727558) (xy 353.109738 -330.749171) (xy 353.14498 -330.797676)
			(xy 353.172204 -330.851094) (xy 353.190739 -330.908113) (xy 353.200129 -330.967328) (xy 353.200716 -330.997306)
			(xy 353.200252 -331.024551) (xy 353.192493 -331.078486) (xy 353.177133 -331.130766) (xy 353.154486 -331.180327)
			(xy 353.125014 -331.226158) (xy 353.089316 -331.267327) (xy 353.04812 -331.302992) (xy 353.002265 -331.332429)
			(xy 352.952687 -331.355037) (xy 352.900394 -331.370356) (xy 352.846453 -331.378073) (xy 352.819208 -331.37856)
			(xy 352.78924 -331.37799) (xy 352.730037 -331.368651) (xy 352.673022 -331.35017) (xy 352.619598 -331.323002)
			(xy 352.571078 -331.287815) (xy 352.54946 -331.267054) (xy 352.347022 -331.064616) (xy 352.339661 -331.057847)
			(xy 352.321199 -331.0502) (xy 352.301217 -331.0502) (xy 352.282755 -331.057847) (xy 352.275394 -331.064616)
			(xy 352.072956 -331.267054) (xy 352.051381 -331.287793) (xy 352.002966 -331.322962) (xy 351.949648 -331.35013)
			(xy 351.892738 -331.368628) (xy 351.833636 -331.378001) (xy 351.803716 -331.37856) (xy 351.803208 -331.37856)
			(xy 351.775969 -331.378075) (xy 351.722046 -331.370326) (xy 351.669773 -331.354984) (xy 351.620215 -331.332361)
			(xy 351.574379 -331.302918) (xy 351.533198 -331.267253) (xy 351.497511 -331.226092) (xy 351.468042 -331.180273)
			(xy 351.445391 -331.130728) (xy 351.43002 -331.078464) (xy 351.42224 -331.024545) (xy 351.4217 -330.997306)
			(xy 351.422258 -330.967326) (xy 351.431642 -330.908105) (xy 351.450178 -330.851082) (xy 351.477411 -330.797664)
			(xy 351.512669 -330.749165) (xy 351.53346 -330.727558) (xy 351.707958 -330.55306) (xy 351.714803 -330.545661)
			(xy 351.722529 -330.527063) (xy 351.722944 -330.516992) (xy 351.722944 -330.417424) (xy 351.722461 -330.40741)
			(xy 351.714807 -330.388902) (xy 351.700655 -330.374731) (xy 351.682157 -330.367053) (xy 351.672144 -330.366624)
			(xy 351.584514 -330.366624) (xy 351.574464 -330.366117) (xy 351.555905 -330.358394) (xy 351.548446 -330.351638)
			(xy 351.461324 -330.264516) (xy 351.454488 -330.257114) (xy 351.446781 -330.238516) (xy 351.446338 -330.228448)
			(xy 351.446338 -329.729084) (xy 351.44591 -329.719016) (xy 351.438185 -329.700422) (xy 351.431352 -329.693016)
			(xy 350.128332 -328.39025) (xy 350.107551 -328.368636) (xy 350.072308 -328.320132) (xy 350.045084 -328.266714)
			(xy 350.026549 -328.209695) (xy 350.017157 -328.15048) (xy 350.016572 -328.120502) (xy 350.016572 -306.849018)
			(xy 350.017129 -306.819037) (xy 350.02651 -306.759815) (xy 350.045044 -306.70279) (xy 350.072275 -306.649369)
			(xy 350.10753 -306.600867) (xy 350.128332 -306.57927) (xy 350.967802 -305.7398) (xy 350.974648 -305.732401)
			(xy 350.982382 -305.713804) (xy 350.982788 -305.703732) (xy 350.982788 -304.348388) (xy 350.982298 -304.338383)
			(xy 350.974636 -304.319897) (xy 350.960483 -304.305751) (xy 350.941993 -304.298098) (xy 350.931988 -304.297588)
			(xy 350.929956 -304.297588) (xy 350.919889 -304.298019) (xy 350.901295 -304.305743) (xy 350.893888 -304.312574)
			(xy 350.779334 -304.427382) (xy 350.757758 -304.448118) (xy 350.709341 -304.483282) (xy 350.656023 -304.510445)
			(xy 350.599114 -304.528938) (xy 350.540013 -304.538307) (xy 350.510094 -304.538888) (xy 350.509586 -304.538888)
			(xy 350.482353 -304.538401) (xy 350.428441 -304.530649) (xy 350.37618 -304.515303) (xy 350.326636 -304.492677)
			(xy 350.280815 -304.46323) (xy 350.239651 -304.427563) (xy 350.203982 -304.386401) (xy 350.174533 -304.340582)
			(xy 350.151904 -304.291038) (xy 350.136556 -304.238779) (xy 350.1288 -304.184867) (xy 350.128332 -304.157634)
			(xy 350.128332 -304.157126) (xy 350.128936 -304.127209) (xy 350.138319 -304.068113) (xy 350.15681 -304.011207)
			(xy 350.183958 -303.957884) (xy 350.219096 -303.909453) (xy 350.239838 -303.887886) (xy 350.442276 -303.685448)
			(xy 350.449056 -303.678089) (xy 350.456721 -303.659621) (xy 350.456731 -303.639626) (xy 350.449083 -303.621152)
			(xy 350.442276 -303.61382) (xy 350.239838 -303.411382) (xy 350.219104 -303.389805) (xy 350.183945 -303.341388)
			(xy 350.156788 -303.288069) (xy 350.138301 -303.23116) (xy 350.12894 -303.17206) (xy 350.128332 -303.142142)
			(xy 350.128332 -303.141634) (xy 350.128792 -303.114397) (xy 350.13654 -303.060478) (xy 350.151883 -303.00821)
			(xy 350.174508 -302.958658) (xy 350.203955 -302.91283) (xy 350.239625 -302.871659) (xy 350.280791 -302.835984)
			(xy 350.326615 -302.806531) (xy 350.376165 -302.7839) (xy 350.428431 -302.76855) (xy 350.482349 -302.760796)
			(xy 350.509586 -302.76038) (xy 350.510094 -302.76038) (xy 350.54001 -302.760986) (xy 350.599103 -302.770372)
			(xy 350.656006 -302.788868) (xy 350.709324 -302.816019) (xy 350.75775 -302.851162) (xy 350.779334 -302.871886)
			(xy 350.83311 -302.925734) (xy 353.029012 -302.925734) (xy 353.029495 -302.898364) (xy 353.037308 -302.844186)
			(xy 353.052793 -302.791683) (xy 353.075631 -302.741936) (xy 353.105352 -302.695968) (xy 353.122992 -302.675036)
			(xy 353.123246 -302.674782) (xy 353.128852 -302.667709) (xy 353.135086 -302.650782) (xy 353.135438 -302.641762)
			(xy 353.135438 -302.574706) (xy 353.13507 -302.56569) (xy 353.128829 -302.548774) (xy 353.123246 -302.541686)
			(xy 353.122992 -302.541686) (xy 353.122992 -302.541432) (xy 353.105353 -302.5205) (xy 353.075642 -302.474527)
			(xy 353.052806 -302.424779) (xy 353.037315 -302.372279) (xy 353.029486 -302.318103) (xy 353.029012 -302.290734)
			(xy 353.029498 -302.263483) (xy 353.037254 -302.209535) (xy 353.052609 -302.15724) (xy 353.075251 -302.107663)
			(xy 353.104717 -302.061813) (xy 353.140408 -302.020622) (xy 353.181599 -301.984931) (xy 353.227449 -301.955465)
			(xy 353.277026 -301.932823) (xy 353.329321 -301.917468) (xy 353.383269 -301.909712) (xy 353.437771 -301.909712)
			(xy 353.491719 -301.917468) (xy 353.544014 -301.932823) (xy 353.593591 -301.955465) (xy 353.639441 -301.984931)
			(xy 353.680632 -302.020622) (xy 353.716323 -302.061813) (xy 353.745789 -302.107663) (xy 353.768431 -302.15724)
			(xy 353.783786 -302.209535) (xy 353.791542 -302.263483) (xy 353.792028 -302.290734) (xy 353.791599 -302.318106)
			(xy 353.783775 -302.372287) (xy 353.768278 -302.424791) (xy 353.745428 -302.474538) (xy 353.715694 -302.520502)
			(xy 353.698048 -302.541432) (xy 353.697794 -302.541686) (xy 353.692206 -302.548772) (xy 353.685961 -302.565689)
			(xy 353.685602 -302.574706) (xy 353.685602 -302.641762) (xy 353.685977 -302.650777) (xy 353.692212 -302.667694)
			(xy 353.697794 -302.674782) (xy 353.698048 -302.674782) (xy 353.698048 -302.675036) (xy 353.715662 -302.695988)
			(xy 353.74538 -302.741955) (xy 353.768221 -302.791697) (xy 353.783718 -302.844193) (xy 353.791551 -302.898366)
			(xy 353.792028 -302.925734) (xy 356.449122 -302.925734) (xy 356.449603 -302.898364) (xy 356.457416 -302.844186)
			(xy 356.472902 -302.791682) (xy 356.49574 -302.741935) (xy 356.525462 -302.695968) (xy 356.543102 -302.675036)
			(xy 356.543356 -302.674782) (xy 356.548963 -302.66771) (xy 356.555196 -302.650782) (xy 356.555548 -302.641762)
			(xy 356.555548 -302.574706) (xy 356.555199 -302.565688) (xy 356.548947 -302.548771) (xy 356.543356 -302.541686)
			(xy 356.543102 -302.541686) (xy 356.543102 -302.541432) (xy 356.525465 -302.520498) (xy 356.495753 -302.474526)
			(xy 356.472916 -302.424779) (xy 356.457425 -302.372279) (xy 356.449596 -302.318103) (xy 356.449122 -302.290734)
			(xy 356.449608 -302.263483) (xy 356.457364 -302.209535) (xy 356.472719 -302.15724) (xy 356.495361 -302.107663)
			(xy 356.524827 -302.061813) (xy 356.560518 -302.020622) (xy 356.601709 -301.984931) (xy 356.647559 -301.955465)
			(xy 356.697136 -301.932823) (xy 356.749431 -301.917468) (xy 356.803379 -301.909712) (xy 356.857881 -301.909712)
			(xy 356.911829 -301.917468) (xy 356.964124 -301.932823) (xy 357.013701 -301.955465) (xy 357.059551 -301.984931)
			(xy 357.100742 -302.020622) (xy 357.136433 -302.061813) (xy 357.165899 -302.107663) (xy 357.188541 -302.15724)
			(xy 357.203896 -302.209535) (xy 357.211652 -302.263483) (xy 357.212138 -302.290734) (xy 357.211707 -302.318106)
			(xy 357.203883 -302.372287) (xy 357.188387 -302.424791) (xy 357.165537 -302.474537) (xy 357.135804 -302.520502)
			(xy 357.118158 -302.541432) (xy 357.117904 -302.541686) (xy 357.112318 -302.548773) (xy 357.106071 -302.565689)
			(xy 357.105712 -302.574706) (xy 357.105712 -302.641762) (xy 357.106085 -302.650777) (xy 357.112321 -302.667694)
			(xy 357.117904 -302.674782) (xy 357.118158 -302.674782) (xy 357.118158 -302.675036) (xy 357.135774 -302.695987)
			(xy 357.165491 -302.741954) (xy 357.188332 -302.791696) (xy 357.203828 -302.844193) (xy 357.211661 -302.898366)
			(xy 357.212138 -302.925734) (xy 357.837232 -302.925734) (xy 357.83771 -302.898364) (xy 357.845524 -302.844185)
			(xy 357.86101 -302.791682) (xy 357.883849 -302.741935) (xy 357.913572 -302.695968) (xy 357.931212 -302.675036)
			(xy 357.931466 -302.674782) (xy 357.937074 -302.66771) (xy 357.943306 -302.650782) (xy 357.943658 -302.641762)
			(xy 357.943658 -302.574706) (xy 357.943307 -302.565688) (xy 357.937056 -302.548771) (xy 357.931466 -302.541686)
			(xy 357.931212 -302.541686) (xy 357.931212 -302.541432) (xy 357.913576 -302.520497) (xy 357.883864 -302.474525)
			(xy 357.861027 -302.424779) (xy 357.845535 -302.372278) (xy 357.837706 -302.318103) (xy 357.837232 -302.290734)
			(xy 357.837718 -302.263483) (xy 357.845474 -302.209535) (xy 357.860829 -302.15724) (xy 357.883471 -302.107663)
			(xy 357.912937 -302.061813) (xy 357.948628 -302.020622) (xy 357.989819 -301.984931) (xy 358.035669 -301.955465)
			(xy 358.085246 -301.932823) (xy 358.137541 -301.917468) (xy 358.191489 -301.909712) (xy 358.245991 -301.909712)
			(xy 358.299939 -301.917468) (xy 358.352234 -301.932823) (xy 358.401811 -301.955465) (xy 358.447661 -301.984931)
			(xy 358.488852 -302.020622) (xy 358.524543 -302.061813) (xy 358.554009 -302.107663) (xy 358.576651 -302.15724)
			(xy 358.592006 -302.209535) (xy 358.599762 -302.263483) (xy 358.600248 -302.290734) (xy 358.599815 -302.318106)
			(xy 358.591991 -302.372287) (xy 358.576495 -302.424791) (xy 358.553645 -302.474537) (xy 358.523913 -302.520502)
			(xy 358.506268 -302.541432) (xy 358.506014 -302.541686) (xy 358.500429 -302.548774) (xy 358.494181 -302.56569)
			(xy 358.493822 -302.574706) (xy 358.493822 -302.641762) (xy 358.494193 -302.650778) (xy 358.50043 -302.667695)
			(xy 358.506014 -302.674782) (xy 358.506268 -302.674782) (xy 358.506268 -302.675036) (xy 358.523886 -302.695985)
			(xy 358.553602 -302.741953) (xy 358.576442 -302.791696) (xy 358.591938 -302.844193) (xy 358.599772 -302.898366)
			(xy 358.600248 -302.925734) (xy 359.869232 -302.925734) (xy 359.86971 -302.898364) (xy 359.877524 -302.844185)
			(xy 359.89301 -302.791682) (xy 359.915849 -302.741935) (xy 359.945572 -302.695968) (xy 359.963212 -302.675036)
			(xy 359.963466 -302.674782) (xy 359.969074 -302.66771) (xy 359.975306 -302.650782) (xy 359.975658 -302.641762)
			(xy 359.975658 -302.574706) (xy 359.975307 -302.565688) (xy 359.969056 -302.548771) (xy 359.963466 -302.541686)
			(xy 359.963212 -302.541686) (xy 359.963212 -302.541432) (xy 359.945576 -302.520497) (xy 359.915864 -302.474525)
			(xy 359.893027 -302.424779) (xy 359.877535 -302.372278) (xy 359.869706 -302.318103) (xy 359.869232 -302.290734)
			(xy 359.869718 -302.263483) (xy 359.877474 -302.209535) (xy 359.892829 -302.15724) (xy 359.915471 -302.107663)
			(xy 359.944937 -302.061813) (xy 359.980628 -302.020622) (xy 360.021819 -301.984931) (xy 360.067669 -301.955465)
			(xy 360.117246 -301.932823) (xy 360.169541 -301.917468) (xy 360.223489 -301.909712) (xy 360.277991 -301.909712)
			(xy 360.331939 -301.917468) (xy 360.384234 -301.932823) (xy 360.433811 -301.955465) (xy 360.479661 -301.984931)
			(xy 360.520852 -302.020622) (xy 360.556543 -302.061813) (xy 360.586009 -302.107663) (xy 360.608651 -302.15724)
			(xy 360.624006 -302.209535) (xy 360.631762 -302.263483) (xy 360.632248 -302.290734) (xy 360.631815 -302.318106)
			(xy 360.623991 -302.372287) (xy 360.608495 -302.424791) (xy 360.585645 -302.474537) (xy 360.555913 -302.520502)
			(xy 360.538268 -302.541432) (xy 360.538014 -302.541686) (xy 360.532429 -302.548774) (xy 360.526181 -302.56569)
			(xy 360.525822 -302.574706) (xy 360.525822 -302.641762) (xy 360.526193 -302.650778) (xy 360.53243 -302.667695)
			(xy 360.538014 -302.674782) (xy 360.538268 -302.674782) (xy 360.538268 -302.675036) (xy 360.555886 -302.695985)
			(xy 360.585602 -302.741953) (xy 360.608442 -302.791696) (xy 360.623938 -302.844193) (xy 360.631772 -302.898366)
			(xy 360.632248 -302.925734) (xy 364.677452 -302.925734) (xy 364.677925 -302.898364) (xy 364.685739 -302.844185)
			(xy 364.701226 -302.791681) (xy 364.724067 -302.741934) (xy 364.753791 -302.695967) (xy 364.771432 -302.675036)
			(xy 364.771686 -302.674782) (xy 364.777285 -302.667704) (xy 364.783525 -302.650781) (xy 364.783878 -302.641762)
			(xy 364.783878 -302.574706) (xy 364.783523 -302.565689) (xy 364.777275 -302.548772) (xy 364.771686 -302.541686)
			(xy 364.771432 -302.541686) (xy 364.771432 -302.541432) (xy 364.753799 -302.520495) (xy 364.724086 -302.474524)
			(xy 364.701248 -302.424778) (xy 364.685755 -302.372278) (xy 364.677926 -302.318103) (xy 364.677452 -302.290734)
			(xy 364.677938 -302.263483) (xy 364.685694 -302.209535) (xy 364.701049 -302.15724) (xy 364.723691 -302.107663)
			(xy 364.753157 -302.061813) (xy 364.788848 -302.020622) (xy 364.830039 -301.984931) (xy 364.875889 -301.955465)
			(xy 364.925466 -301.932823) (xy 364.977761 -301.917468) (xy 365.031709 -301.909712) (xy 365.086211 -301.909712)
			(xy 365.140159 -301.917468) (xy 365.192454 -301.932823) (xy 365.242031 -301.955465) (xy 365.287881 -301.984931)
			(xy 365.329072 -302.020622) (xy 365.364763 -302.061813) (xy 365.394229 -302.107663) (xy 365.416871 -302.15724)
			(xy 365.432226 -302.209535) (xy 365.439982 -302.263483) (xy 365.440468 -302.290734) (xy 365.44003 -302.318105)
			(xy 365.432206 -302.372286) (xy 365.416711 -302.42479) (xy 365.393863 -302.474536) (xy 365.364132 -302.520501)
			(xy 365.346488 -302.541432) (xy 365.346234 -302.541686) (xy 365.340639 -302.548767) (xy 365.334399 -302.565688)
			(xy 365.334042 -302.574706) (xy 365.334042 -302.641762) (xy 365.334408 -302.650778) (xy 365.340648 -302.667696)
			(xy 365.346234 -302.674782) (xy 365.346488 -302.674782) (xy 365.346488 -302.675036) (xy 365.364109 -302.695983)
			(xy 365.393824 -302.741951) (xy 365.416663 -302.791695) (xy 365.432159 -302.844193) (xy 365.439992 -302.898366)
			(xy 365.440468 -302.925734) (xy 365.439982 -302.952985) (xy 365.432226 -303.006933) (xy 365.416871 -303.059228)
			(xy 365.394229 -303.108805) (xy 365.364763 -303.154655) (xy 365.329072 -303.195846) (xy 365.287881 -303.231537)
			(xy 365.242031 -303.261003) (xy 365.192454 -303.283645) (xy 365.140159 -303.299) (xy 365.086211 -303.306756)
			(xy 365.031709 -303.306756) (xy 364.977761 -303.299) (xy 364.925466 -303.283645) (xy 364.875889 -303.261003)
			(xy 364.830039 -303.231537) (xy 364.788848 -303.195846) (xy 364.753157 -303.154655) (xy 364.723691 -303.108805)
			(xy 364.701049 -303.059228) (xy 364.685694 -303.006933) (xy 364.677938 -302.952985) (xy 364.677452 -302.925734)
			(xy 360.632248 -302.925734) (xy 360.631762 -302.952985) (xy 360.624006 -303.006933) (xy 360.608651 -303.059228)
			(xy 360.586009 -303.108805) (xy 360.556543 -303.154655) (xy 360.520852 -303.195846) (xy 360.479661 -303.231537)
			(xy 360.433811 -303.261003) (xy 360.384234 -303.283645) (xy 360.331939 -303.299) (xy 360.277991 -303.306756)
			(xy 360.223489 -303.306756) (xy 360.169541 -303.299) (xy 360.117246 -303.283645) (xy 360.067669 -303.261003)
			(xy 360.021819 -303.231537) (xy 359.980628 -303.195846) (xy 359.944937 -303.154655) (xy 359.915471 -303.108805)
			(xy 359.892829 -303.059228) (xy 359.877474 -303.006933) (xy 359.869718 -302.952985) (xy 359.869232 -302.925734)
			(xy 358.600248 -302.925734) (xy 358.599762 -302.952985) (xy 358.592006 -303.006933) (xy 358.576651 -303.059228)
			(xy 358.554009 -303.108805) (xy 358.524543 -303.154655) (xy 358.488852 -303.195846) (xy 358.447661 -303.231537)
			(xy 358.401811 -303.261003) (xy 358.352234 -303.283645) (xy 358.299939 -303.299) (xy 358.245991 -303.306756)
			(xy 358.191489 -303.306756) (xy 358.137541 -303.299) (xy 358.085246 -303.283645) (xy 358.035669 -303.261003)
			(xy 357.989819 -303.231537) (xy 357.948628 -303.195846) (xy 357.912937 -303.154655) (xy 357.883471 -303.108805)
			(xy 357.860829 -303.059228) (xy 357.845474 -303.006933) (xy 357.837718 -302.952985) (xy 357.837232 -302.925734)
			(xy 357.212138 -302.925734) (xy 357.211652 -302.952985) (xy 357.203896 -303.006933) (xy 357.188541 -303.059228)
			(xy 357.165899 -303.108805) (xy 357.136433 -303.154655) (xy 357.100742 -303.195846) (xy 357.059551 -303.231537)
			(xy 357.013701 -303.261003) (xy 356.964124 -303.283645) (xy 356.911829 -303.299) (xy 356.857881 -303.306756)
			(xy 356.803379 -303.306756) (xy 356.749431 -303.299) (xy 356.697136 -303.283645) (xy 356.647559 -303.261003)
			(xy 356.601709 -303.231537) (xy 356.560518 -303.195846) (xy 356.524827 -303.154655) (xy 356.495361 -303.108805)
			(xy 356.472719 -303.059228) (xy 356.457364 -303.006933) (xy 356.449608 -302.952985) (xy 356.449122 -302.925734)
			(xy 353.792028 -302.925734) (xy 353.791542 -302.952985) (xy 353.783786 -303.006933) (xy 353.768431 -303.059228)
			(xy 353.745789 -303.108805) (xy 353.716323 -303.154655) (xy 353.680632 -303.195846) (xy 353.639441 -303.231537)
			(xy 353.593591 -303.261003) (xy 353.544014 -303.283645) (xy 353.491719 -303.299) (xy 353.437771 -303.306756)
			(xy 353.383269 -303.306756) (xy 353.329321 -303.299) (xy 353.277026 -303.283645) (xy 353.227449 -303.261003)
			(xy 353.181599 -303.231537) (xy 353.140408 -303.195846) (xy 353.104717 -303.154655) (xy 353.075251 -303.108805)
			(xy 353.052609 -303.059228) (xy 353.037254 -303.006933) (xy 353.029498 -302.952985) (xy 353.029012 -302.925734)
			(xy 350.83311 -302.925734) (xy 350.970088 -303.062894) (xy 350.977486 -303.069743) (xy 350.996083 -303.077483)
			(xy 351.006156 -303.07788) (xy 351.344992 -303.07788) (xy 351.374908 -303.078486) (xy 351.434001 -303.087872)
			(xy 351.490905 -303.106367) (xy 351.544223 -303.133519) (xy 351.592649 -303.168661) (xy 351.614232 -303.189386)
			(xy 352.015044 -303.590198) (xy 352.035824 -303.611812) (xy 352.071062 -303.660317) (xy 352.098281 -303.713736)
			(xy 352.116811 -303.770754) (xy 352.126196 -303.829969) (xy 352.126804 -303.859946) (xy 352.126804 -306.04079)
			(xy 352.126246 -306.07077) (xy 352.116863 -306.129992) (xy 352.098327 -306.187015) (xy 352.071095 -306.240434)
			(xy 352.035838 -306.288933) (xy 352.015044 -306.310538) (xy 351.175574 -307.150008) (xy 351.168721 -307.157403)
			(xy 351.160978 -307.176002) (xy 351.160588 -307.186076) (xy 351.160588 -327.783444) (xy 351.161024 -327.793477)
			(xy 351.168595 -327.812056) (xy 351.17532 -327.819512) (xy 351.359724 -328.003916) (xy 351.367126 -328.010594)
			(xy 351.385537 -328.018185) (xy 351.405452 -328.018187) (xy 351.414842 -328.014838) (xy 351.42932 -328.008996)
			(xy 351.446338 -327.983342) (xy 351.446338 -309.687976) (xy 351.446766 -309.677909) (xy 351.454491 -309.659314)
			(xy 351.461324 -309.651908) (xy 351.56267 -309.550562) (xy 351.569253 -309.543181) (xy 351.576706 -309.524882)
			(xy 351.577148 -309.515002) (xy 351.577148 -309.507636) (xy 351.577662 -309.497736) (xy 351.585239 -309.479436)
			(xy 351.59188 -309.472076) (xy 351.662492 -309.401464) (xy 351.663 -309.400702) (xy 351.666556 -309.397146)
			(xy 352.620834 -308.442868) (xy 352.62439 -308.439312) (xy 352.625152 -308.438804) (xy 352.695764 -308.368192)
			(xy 352.703119 -308.361539) (xy 352.721419 -308.353947) (xy 352.731324 -308.35346) (xy 352.73869 -308.35346)
			(xy 352.748563 -308.352988) (xy 352.766848 -308.345533) (xy 352.77425 -308.338982) (xy 352.886264 -308.226968)
			(xy 352.893663 -308.220124) (xy 352.912262 -308.212402) (xy 352.922332 -308.211982) (xy 364.546642 -308.211982)
			(xy 364.55477 -308.21122) (xy 364.555278 -308.21122) (xy 364.562801 -308.209627) (xy 364.576501 -308.202663)
			(xy 364.582202 -308.197504) (xy 366.882426 -305.89728) (xy 366.887408 -305.89185) (xy 366.894257 -305.878812)
			(xy 366.895888 -305.871626) (xy 366.895888 -305.871118) (xy 366.896904 -305.86172) (xy 366.896904 -286.175196)
			(xy 366.89648 -286.165126) (xy 366.888765 -286.146522) (xy 366.881918 -286.139128) (xy 366.786668 -286.043878)
			(xy 366.779272 -286.037028) (xy 366.760673 -286.029293) (xy 366.7506 -286.028892) (xy 366.555274 -286.028892)
			(xy 366.545206 -286.029319) (xy 366.526607 -286.03704) (xy 366.519206 -286.043878) (xy 365.932974 -286.63011)
			(xy 365.926121 -286.637506) (xy 365.918379 -286.656104) (xy 365.917988 -286.666178) (xy 365.917988 -294.53586)
			(xy 365.919512 -294.545258) (xy 365.923291 -294.556842) (xy 365.939602 -294.574895) (xy 365.950754 -294.579802)
			(xy 365.995204 -294.596566) (xy 366.0394 -294.61333) (xy 366.04858 -294.616352) (xy 366.06789 -294.616074)
			(xy 366.076992 -294.612822) (xy 366.082326 -294.610536) (xy 366.091724 -294.603678) (xy 366.095534 -294.59936)
			(xy 366.113746 -294.579451) (xy 366.154807 -294.544446) (xy 366.200385 -294.515568) (xy 366.249574 -294.49339)
			(xy 366.301394 -294.478355) (xy 366.354814 -294.470761) (xy 366.381792 -294.470328) (xy 366.409043 -294.470791)
			(xy 366.462989 -294.478546) (xy 366.515283 -294.4939) (xy 366.56486 -294.51654) (xy 366.610709 -294.546005)
			(xy 366.651899 -294.581695) (xy 366.68759 -294.622884) (xy 366.717056 -294.668733) (xy 366.739697 -294.718309)
			(xy 366.755052 -294.770603) (xy 366.762809 -294.824549) (xy 366.762809 -294.879051) (xy 366.755052 -294.932997)
			(xy 366.739697 -294.985291) (xy 366.717056 -295.034867) (xy 366.68759 -295.080716) (xy 366.651899 -295.121905)
			(xy 366.610709 -295.157595) (xy 366.56486 -295.18706) (xy 366.515283 -295.2097) (xy 366.462989 -295.225054)
			(xy 366.409043 -295.232809) (xy 366.381792 -295.233344) (xy 366.354472 -295.232875) (xy 366.300391 -295.225078)
			(xy 366.247976 -295.209643) (xy 366.1983 -295.186887) (xy 366.152379 -295.157277) (xy 366.111153 -295.121416)
			(xy 366.075466 -295.080041) (xy 366.046047 -295.033996) (xy 366.03432 -295.009316) (xy 366.032796 -295.006014)
			(xy 366.029838 -295.000788) (xy 366.021884 -294.991794) (xy 366.017048 -294.988234) (xy 366.01146 -294.984424)
			(xy 366.005618 -294.982392) (xy 365.99241 -294.979598) (xy 365.93526 -294.97528) (xy 365.915194 -294.973756)
			(xy 365.908379 -294.973427) (xy 365.894987 -294.976007) (xy 365.888778 -294.978836) (xy 365.883698 -294.981884)
			(xy 365.875824 -294.988234) (xy 365.814102 -295.049956) (xy 365.806736 -295.057576) (xy 365.352838 -295.511474)
			(xy 365.349311 -295.515201) (xy 365.34367 -295.52377) (xy 365.341662 -295.528492) (xy 365.338106 -295.537128)
			(xy 365.338106 -295.579038) (xy 365.338868 -295.587928) (xy 365.340259 -295.594554) (xy 365.346052 -295.606785)
			(xy 365.350298 -295.612058) (xy 365.352584 -295.614344) (xy 365.372757 -295.635844) (xy 365.406902 -295.683902)
			(xy 365.433247 -295.736642) (xy 365.451165 -295.792807) (xy 365.460229 -295.851059) (xy 365.460788 -295.880536)
			(xy 365.460323 -295.907871) (xy 365.452526 -295.961983) (xy 365.437082 -296.014426) (xy 365.414308 -296.064128)
			(xy 365.384671 -296.110068) (xy 365.367062 -296.13098) (xy 365.366808 -296.131234) (xy 365.364776 -296.133774)
			(xy 365.360744 -296.139492) (xy 365.355608 -296.152501) (xy 365.354616 -296.159428) (xy 365.354362 -296.164254)
			(xy 365.354362 -296.231818) (xy 365.354616 -296.236644) (xy 365.355537 -296.243588) (xy 365.360698 -296.256603)
			(xy 365.364776 -296.262298) (xy 365.366808 -296.264838) (xy 365.367062 -296.265092) (xy 365.384659 -296.286015)
			(xy 365.414304 -296.331948) (xy 365.437086 -296.381643) (xy 365.452537 -296.434084) (xy 365.460341 -296.488193)
			(xy 365.460337 -296.542862) (xy 365.452525 -296.59697) (xy 365.437067 -296.649407) (xy 365.414278 -296.6991)
			(xy 365.384626 -296.745029) (xy 365.367062 -296.76598) (xy 365.366808 -296.766234) (xy 365.364776 -296.768774)
			(xy 365.360744 -296.774492) (xy 365.355608 -296.787501) (xy 365.354616 -296.794428) (xy 365.354362 -296.799254)
			(xy 365.354362 -296.866818) (xy 365.354616 -296.871644) (xy 365.355537 -296.878588) (xy 365.360698 -296.891603)
			(xy 365.364776 -296.897298) (xy 365.366808 -296.899838) (xy 365.367062 -296.900092) (xy 365.384659 -296.921015)
			(xy 365.414304 -296.966948) (xy 365.437086 -297.016643) (xy 365.452537 -297.069084) (xy 365.460341 -297.123193)
			(xy 365.460337 -297.177862) (xy 365.452525 -297.23197) (xy 365.437067 -297.284407) (xy 365.414278 -297.3341)
			(xy 365.384626 -297.380029) (xy 365.367062 -297.40098) (xy 365.366808 -297.401234) (xy 365.364776 -297.403774)
			(xy 365.360744 -297.409492) (xy 365.355608 -297.422501) (xy 365.354616 -297.429428) (xy 365.354362 -297.434254)
			(xy 365.354362 -297.501818) (xy 365.354616 -297.506644) (xy 365.355537 -297.513588) (xy 365.360698 -297.526603)
			(xy 365.364776 -297.532298) (xy 365.366808 -297.534838) (xy 365.367062 -297.535092) (xy 365.384659 -297.556015)
			(xy 365.414304 -297.601948) (xy 365.437086 -297.651643) (xy 365.452537 -297.704084) (xy 365.460341 -297.758193)
			(xy 365.460337 -297.812862) (xy 365.452525 -297.86697) (xy 365.437067 -297.919407) (xy 365.414278 -297.9691)
			(xy 365.384626 -298.015029) (xy 365.367062 -298.03598) (xy 365.366808 -298.036234) (xy 365.364776 -298.038774)
			(xy 365.360744 -298.044492) (xy 365.355608 -298.057501) (xy 365.354616 -298.064428) (xy 365.354362 -298.069254)
			(xy 365.354362 -298.136818) (xy 365.354616 -298.141644) (xy 365.355537 -298.148588) (xy 365.360698 -298.161603)
			(xy 365.364776 -298.167298) (xy 365.366808 -298.169838) (xy 365.367062 -298.170092) (xy 365.384653 -298.191019)
			(xy 365.414288 -298.236958) (xy 365.437065 -298.286655) (xy 365.452517 -298.339094) (xy 365.460327 -298.393202)
			(xy 365.460788 -298.420536) (xy 365.460299 -298.447785) (xy 365.452538 -298.501728) (xy 365.43718 -298.554017)
			(xy 365.414537 -298.603588) (xy 365.385069 -298.649433) (xy 365.349377 -298.690617) (xy 365.308188 -298.726303)
			(xy 365.262339 -298.755763) (xy 365.212764 -298.7784) (xy 365.160473 -298.79375) (xy 365.106529 -298.801503)
			(xy 365.07928 -298.802044) (xy 365.051947 -298.801573) (xy 364.99784 -298.793766) (xy 364.945402 -298.778315)
			(xy 364.895707 -298.755536) (xy 364.849773 -298.725897) (xy 364.828836 -298.708318) (xy 364.828582 -298.708064)
			(xy 364.826042 -298.706032) (xy 364.820326 -298.701995) (xy 364.807318 -298.696849) (xy 364.800388 -298.695872)
			(xy 364.795562 -298.695618) (xy 364.727998 -298.695618) (xy 364.723172 -298.695872) (xy 364.716227 -298.696789)
			(xy 364.703207 -298.701944) (xy 364.697518 -298.706032) (xy 364.694978 -298.708064) (xy 364.674047 -298.725706)
			(xy 364.628081 -298.755432) (xy 364.578334 -298.778275) (xy 364.52583 -298.793764) (xy 364.47165 -298.80158)
			(xy 364.44428 -298.802044) (xy 364.417029 -298.801557) (xy 364.363081 -298.793798) (xy 364.310787 -298.778442)
			(xy 364.26121 -298.7558) (xy 364.215359 -298.726334) (xy 364.174169 -298.690643) (xy 364.138476 -298.649453)
			(xy 364.109008 -298.603604) (xy 364.086364 -298.554028) (xy 364.071005 -298.501734) (xy 364.063244 -298.447787)
			(xy 364.062772 -298.420536) (xy 364.063239 -298.393201) (xy 364.071039 -298.339091) (xy 364.086484 -298.286649)
			(xy 364.109259 -298.236949) (xy 364.138896 -298.19101) (xy 364.156498 -298.170092) (xy 364.156752 -298.169838)
			(xy 364.158784 -298.167298) (xy 364.162827 -298.161584) (xy 364.167985 -298.148577) (xy 364.168944 -298.141644)
			(xy 364.169198 -298.136818) (xy 364.169198 -298.069254) (xy 364.168944 -298.064428) (xy 364.168022 -298.057485)
			(xy 364.162859 -298.044471) (xy 364.158784 -298.038774) (xy 364.156752 -298.036234) (xy 364.156498 -298.03598)
			(xy 364.138894 -298.015058) (xy 364.109234 -297.969125) (xy 364.086438 -297.919427) (xy 364.070975 -297.866982)
			(xy 364.063162 -297.812866) (xy 364.063158 -297.758189) (xy 364.070964 -297.704072) (xy 364.086419 -297.651624)
			(xy 364.109207 -297.601922) (xy 364.138861 -297.555985) (xy 364.156498 -297.535092) (xy 364.156752 -297.534838)
			(xy 364.158784 -297.532298) (xy 364.162827 -297.526584) (xy 364.167985 -297.513577) (xy 364.168944 -297.506644)
			(xy 364.169198 -297.501818) (xy 364.169198 -297.434254) (xy 364.168944 -297.429428) (xy 364.168022 -297.422485)
			(xy 364.162859 -297.409471) (xy 364.158784 -297.403774) (xy 364.156752 -297.401234) (xy 364.156498 -297.40098)
			(xy 364.138894 -297.380058) (xy 364.109234 -297.334125) (xy 364.086438 -297.284427) (xy 364.070975 -297.231982)
			(xy 364.063162 -297.177866) (xy 364.063158 -297.123189) (xy 364.070964 -297.069072) (xy 364.086419 -297.016624)
			(xy 364.109207 -296.966922) (xy 364.138861 -296.920985) (xy 364.156498 -296.900092) (xy 364.156752 -296.899838)
			(xy 364.158784 -296.897298) (xy 364.162827 -296.891584) (xy 364.167985 -296.878577) (xy 364.168944 -296.871644)
			(xy 364.169198 -296.866818) (xy 364.169198 -296.799254) (xy 364.168944 -296.794428) (xy 364.168022 -296.787485)
			(xy 364.162859 -296.774471) (xy 364.158784 -296.768774) (xy 364.156752 -296.766234) (xy 364.156498 -296.76598)
			(xy 364.138894 -296.745058) (xy 364.109234 -296.699125) (xy 364.086438 -296.649427) (xy 364.070975 -296.596982)
			(xy 364.063162 -296.542866) (xy 364.063158 -296.488189) (xy 364.070964 -296.434072) (xy 364.086419 -296.381624)
			(xy 364.109207 -296.331922) (xy 364.138861 -296.285985) (xy 364.156498 -296.265092) (xy 364.156752 -296.264838)
			(xy 364.158784 -296.262298) (xy 364.162827 -296.256584) (xy 364.167985 -296.243577) (xy 364.168944 -296.236644)
			(xy 364.169198 -296.231818) (xy 364.169198 -296.164254) (xy 364.168944 -296.159428) (xy 364.168022 -296.152485)
			(xy 364.162859 -296.139471) (xy 364.158784 -296.133774) (xy 364.156752 -296.131234) (xy 364.156498 -296.13098)
			(xy 364.138894 -296.110058) (xy 364.109234 -296.064125) (xy 364.086438 -296.014427) (xy 364.070975 -295.961982)
			(xy 364.063162 -295.907866) (xy 364.063158 -295.853189) (xy 364.070964 -295.799072) (xy 364.086419 -295.746624)
			(xy 364.109207 -295.696922) (xy 364.138861 -295.650985) (xy 364.156498 -295.630092) (xy 364.156752 -295.629838)
			(xy 364.158784 -295.627298) (xy 364.162827 -295.621584) (xy 364.167985 -295.608577) (xy 364.168944 -295.601644)
			(xy 364.169198 -295.596818) (xy 364.169198 -295.529254) (xy 364.168944 -295.524428) (xy 364.168022 -295.517485)
			(xy 364.162859 -295.504471) (xy 364.158784 -295.498774) (xy 364.156752 -295.496234) (xy 364.156498 -295.49598)
			(xy 364.138906 -295.475054) (xy 364.10927 -295.429116) (xy 364.086493 -295.379418) (xy 364.071042 -295.326978)
			(xy 364.063235 -295.27287) (xy 364.062772 -295.245536) (xy 364.063232 -295.218281) (xy 364.070985 -295.164325)
			(xy 364.086338 -295.112022) (xy 364.108978 -295.062436) (xy 364.138445 -295.016576) (xy 364.174138 -294.975378)
			(xy 364.215332 -294.939678) (xy 364.261186 -294.910205) (xy 364.310769 -294.887557) (xy 364.36307 -294.872197)
			(xy 364.417025 -294.864436) (xy 364.44428 -294.864028) (xy 364.473651 -294.864566) (xy 364.5317 -294.873564)
			(xy 364.587685 -294.891349) (xy 364.640285 -294.917501) (xy 364.688256 -294.951404) (xy 364.70971 -294.97147)
			(xy 364.710218 -294.971978) (xy 364.713947 -294.975501) (xy 364.72252 -294.981134) (xy 364.727236 -294.983154)
			(xy 364.735872 -294.98671) (xy 364.799118 -294.98671) (xy 364.809532 -294.975788) (xy 364.912656 -294.872918)
			(xy 365.058452 -294.726868) (xy 365.058706 -294.726868) (xy 365.14024 -294.64508) (xy 365.141256 -294.644064)
			(xy 365.145364 -294.639439) (xy 365.151408 -294.62865) (xy 365.153194 -294.622728) (xy 365.154972 -294.609266)
			(xy 365.154972 -284.525212) (xy 365.154519 -284.515428) (xy 365.147197 -284.49728) (xy 365.140748 -284.489906)
			(xy 365.119666 -284.468062) (xy 365.112899 -284.461726) (xy 365.096106 -284.453906) (xy 365.0869 -284.452822)
			(xy 365.060026 -284.450246) (xy 365.007336 -284.438488) (xy 364.956826 -284.41943) (xy 364.909501 -284.393452)
			(xy 364.866304 -284.361072) (xy 364.84687 -284.342332) (xy 364.500414 -283.995622) (xy 364.493012 -283.988787)
			(xy 364.474413 -283.98108) (xy 364.464346 -283.980636) (xy 362.77677 -283.980636) (xy 362.766703 -283.981065)
			(xy 362.74811 -283.988791) (xy 362.740702 -283.995622) (xy 361.752642 -284.983936) (xy 361.731027 -285.004714)
			(xy 361.68252 -285.039949) (xy 361.629101 -285.067167) (xy 361.572084 -285.085698) (xy 361.51287 -285.095086)
			(xy 361.482894 -285.095696) (xy 359.095802 -285.095696) (xy 359.065822 -285.095138) (xy 359.006601 -285.085754)
			(xy 358.949579 -285.067216) (xy 358.896161 -285.039983) (xy 358.847664 -285.004724) (xy 358.826054 -284.983936)
			(xy 358.18445 -284.342332) (xy 358.163656 -284.320738) (xy 358.12844 -284.272227) (xy 358.101256 -284.218799)
			(xy 358.082774 -284.161774) (xy 358.073451 -284.102557) (xy 358.072944 -284.072584) (xy 358.073401 -284.045225)
			(xy 358.081189 -283.991064) (xy 358.096632 -283.938571) (xy 358.119413 -283.888821) (xy 358.149066 -283.842834)
			(xy 358.16667 -283.821886) (xy 358.172766 -283.815028) (xy 358.17937 -283.797756) (xy 358.179116 -283.721556)
			(xy 358.178749 -283.712542) (xy 358.172493 -283.695635) (xy 358.166924 -283.688536) (xy 358.16667 -283.688282)
			(xy 358.14903 -283.66735) (xy 358.119309 -283.621382) (xy 358.09647 -283.571635) (xy 358.080983 -283.519132)
			(xy 358.073168 -283.464954) (xy 358.07269 -283.437584) (xy 358.073706 -283.410914) (xy 358.073706 -283.410406)
			(xy 358.074722 -283.394658) (xy 358.05872 -283.367734) (xy 357.957374 -283.321506) (xy 357.947816 -283.317673)
			(xy 357.927247 -283.31717) (xy 357.908127 -283.324769) (xy 357.900478 -283.331666) (xy 357.772208 -283.459936)
			(xy 357.765435 -283.467362) (xy 357.757854 -283.485959) (xy 357.757476 -283.496004) (xy 357.757476 -286.362648)
			(xy 357.758104 -286.37449) (xy 357.768708 -286.395668) (xy 357.777796 -286.403288) (xy 357.852218 -286.459422)
			(xy 357.875586 -286.463486) (xy 357.88727 -286.460184) (xy 357.913365 -286.453072) (xy 357.966907 -286.445418)
			(xy 357.99395 -286.444944) (xy 358.021209 -286.445404) (xy 358.075172 -286.453156) (xy 358.127482 -286.468509)
			(xy 358.177075 -286.491152) (xy 358.22294 -286.520622) (xy 358.264144 -286.55632) (xy 358.299848 -286.59752)
			(xy 358.329324 -286.643381) (xy 358.351973 -286.692971) (xy 358.365512 -286.739076) (xy 358.56494 -286.739076)
			(xy 358.569011 -286.683454) (xy 358.581137 -286.629017) (xy 358.60106 -286.576926) (xy 358.628356 -286.528291)
			(xy 358.662442 -286.484148) (xy 358.702591 -286.445439) (xy 358.747949 -286.412988) (xy 358.797549 -286.387487)
			(xy 358.850333 -286.36948) (xy 358.905176 -286.35935) (xy 358.96091 -286.357313) (xy 359.016347 -286.363413)
			(xy 359.070304 -286.377519) (xy 359.121633 -286.399331) (xy 359.169239 -286.428385) (xy 359.212107 -286.46406)
			(xy 359.249324 -286.505597) (xy 359.280097 -286.55211) (xy 359.303769 -286.602607) (xy 359.319837 -286.656014)
			(xy 359.327957 -286.71119) (xy 359.328466 -286.739076) (xy 359.327957 -286.766962) (xy 359.319837 -286.822138)
			(xy 359.303769 -286.875545) (xy 359.280097 -286.926042) (xy 359.249324 -286.972555) (xy 359.212107 -287.014092)
			(xy 359.169239 -287.049767) (xy 359.121633 -287.078821) (xy 359.070304 -287.100633) (xy 359.016347 -287.114739)
			(xy 358.96091 -287.120839) (xy 358.905176 -287.118802) (xy 358.850333 -287.108672) (xy 358.797549 -287.090665)
			(xy 358.747949 -287.065164) (xy 358.702591 -287.032713) (xy 358.662442 -286.994004) (xy 358.628356 -286.949861)
			(xy 358.60106 -286.901226) (xy 358.581137 -286.849135) (xy 358.569011 -286.794698) (xy 358.56494 -286.739076)
			(xy 358.365512 -286.739076) (xy 358.367334 -286.745279) (xy 358.375093 -286.799241) (xy 358.375093 -286.853759)
			(xy 358.367334 -286.907721) (xy 358.351973 -286.960029) (xy 358.329324 -287.009619) (xy 358.299848 -287.05548)
			(xy 358.264144 -287.09668) (xy 358.22294 -287.132378) (xy 358.177075 -287.161848) (xy 358.127482 -287.184491)
			(xy 358.075172 -287.199844) (xy 358.021209 -287.207596) (xy 357.99395 -287.20796) (xy 357.966907 -287.207488)
			(xy 357.913365 -287.199836) (xy 357.88727 -287.19272) (xy 357.875586 -287.189418) (xy 357.852218 -287.193482)
			(xy 357.777796 -287.249616) (xy 357.768687 -287.257218) (xy 357.758078 -287.278408) (xy 357.757476 -287.290256)
			(xy 357.757476 -294.1828) (xy 359.468926 -294.1828) (xy 359.472997 -294.127178) (xy 359.485123 -294.072741)
			(xy 359.505046 -294.02065) (xy 359.532342 -293.972015) (xy 359.566428 -293.927872) (xy 359.606577 -293.889163)
			(xy 359.651935 -293.856712) (xy 359.701535 -293.831211) (xy 359.754319 -293.813204) (xy 359.809162 -293.803074)
			(xy 359.864896 -293.801037) (xy 359.920333 -293.807137) (xy 359.97429 -293.821243) (xy 360.025619 -293.843055)
			(xy 360.073225 -293.872109) (xy 360.116093 -293.907784) (xy 360.15331 -293.949321) (xy 360.184083 -293.995834)
			(xy 360.207755 -294.046331) (xy 360.223823 -294.099738) (xy 360.231943 -294.154914) (xy 360.232452 -294.1828)
			(xy 360.231943 -294.210686) (xy 360.223823 -294.265862) (xy 360.207755 -294.319269) (xy 360.184083 -294.369766)
			(xy 360.15331 -294.416279) (xy 360.116093 -294.457816) (xy 360.073225 -294.493491) (xy 360.025619 -294.522545)
			(xy 359.97429 -294.544357) (xy 359.920333 -294.558463) (xy 359.864896 -294.564563) (xy 359.809162 -294.562526)
			(xy 359.754319 -294.552396) (xy 359.701535 -294.534389) (xy 359.651935 -294.508888) (xy 359.606577 -294.476437)
			(xy 359.566428 -294.437728) (xy 359.532342 -294.393585) (xy 359.505046 -294.34495) (xy 359.485123 -294.292859)
			(xy 359.472997 -294.238422) (xy 359.468926 -294.1828) (xy 357.757476 -294.1828) (xy 357.757476 -294.787066)
			(xy 357.758148 -294.799135) (xy 357.769155 -294.820617) (xy 357.778558 -294.828214) (xy 357.845106 -294.87622)
			(xy 357.855289 -294.882741) (xy 357.879148 -294.886462) (xy 357.890826 -294.883332) (xy 357.919912 -294.87433)
			(xy 357.980018 -294.864633) (xy 358.01046 -294.864028) (xy 358.010968 -294.864028) (xy 358.038221 -294.864489)
			(xy 358.092174 -294.872243) (xy 358.144474 -294.887596) (xy 358.194055 -294.910237) (xy 358.23991 -294.939705)
			(xy 358.281103 -294.975399) (xy 358.316797 -295.016593) (xy 358.346264 -295.062448) (xy 358.368905 -295.11203)
			(xy 358.384258 -295.16433) (xy 358.392011 -295.218283) (xy 358.392476 -295.245536) (xy 358.392002 -295.272905)
			(xy 358.384173 -295.32708) (xy 358.368681 -295.379581) (xy 358.345844 -295.429327) (xy 358.316132 -295.475299)
			(xy 358.298496 -295.496234) (xy 358.298496 -295.496488) (xy 358.298242 -295.496488) (xy 358.292651 -295.503573)
			(xy 358.2864 -295.52049) (xy 358.28605 -295.529508) (xy 358.28605 -295.596564) (xy 358.286402 -295.605584)
			(xy 358.292636 -295.622511) (xy 358.298242 -295.629584) (xy 358.298496 -295.629838) (xy 358.316133 -295.650771)
			(xy 358.345851 -295.696739) (xy 358.36869 -295.746484) (xy 358.384181 -295.798983) (xy 358.392004 -295.853158)
			(xy 358.392001 -295.907896) (xy 358.384169 -295.96207) (xy 358.368671 -296.014567) (xy 358.345825 -296.064309)
			(xy 358.3161 -296.110272) (xy 358.298496 -296.131234) (xy 358.298496 -296.131488) (xy 358.298242 -296.131488)
			(xy 358.292651 -296.138573) (xy 358.2864 -296.15549) (xy 358.28605 -296.164508) (xy 358.28605 -296.231564)
			(xy 358.286402 -296.240584) (xy 358.292636 -296.257511) (xy 358.298242 -296.264584) (xy 358.298496 -296.264838)
			(xy 358.316133 -296.285771) (xy 358.345851 -296.331739) (xy 358.36869 -296.381484) (xy 358.384181 -296.433983)
			(xy 358.392004 -296.488158) (xy 358.392001 -296.542896) (xy 358.384169 -296.59707) (xy 358.368671 -296.649567)
			(xy 358.345825 -296.699309) (xy 358.3161 -296.745272) (xy 358.298496 -296.766234) (xy 358.298496 -296.766488)
			(xy 358.298242 -296.766488) (xy 358.292651 -296.773573) (xy 358.2864 -296.79049) (xy 358.28605 -296.799508)
			(xy 358.28605 -296.866564) (xy 358.286402 -296.875584) (xy 358.292636 -296.892511) (xy 358.298242 -296.899584)
			(xy 358.298496 -296.899838) (xy 358.316133 -296.920771) (xy 358.345851 -296.966739) (xy 358.36869 -297.016484)
			(xy 358.384181 -297.068983) (xy 358.392004 -297.123158) (xy 358.392001 -297.177896) (xy 358.384169 -297.23207)
			(xy 358.368671 -297.284567) (xy 358.345825 -297.334309) (xy 358.3161 -297.380272) (xy 358.298496 -297.401234)
			(xy 358.298496 -297.401488) (xy 358.298242 -297.401488) (xy 358.292651 -297.408573) (xy 358.2864 -297.42549)
			(xy 358.28605 -297.434508) (xy 358.28605 -297.501564) (xy 358.286402 -297.510584) (xy 358.292636 -297.527511)
			(xy 358.298242 -297.534584) (xy 358.298496 -297.534838) (xy 358.316133 -297.555771) (xy 358.345851 -297.601739)
			(xy 358.36869 -297.651484) (xy 358.384181 -297.703983) (xy 358.392004 -297.758158) (xy 358.392001 -297.812896)
			(xy 358.384169 -297.86707) (xy 358.368671 -297.919567) (xy 358.345825 -297.969309) (xy 358.3161 -298.015272)
			(xy 358.298496 -298.036234) (xy 358.298496 -298.036488) (xy 358.298242 -298.036488) (xy 358.292651 -298.043573)
			(xy 358.2864 -298.06049) (xy 358.28605 -298.069508) (xy 358.28605 -298.136564) (xy 358.286402 -298.145584)
			(xy 358.292636 -298.162511) (xy 358.298242 -298.169584) (xy 358.298496 -298.169838) (xy 358.316136 -298.19077)
			(xy 358.345858 -298.236737) (xy 358.368696 -298.286484) (xy 358.384181 -298.338988) (xy 358.391995 -298.393166)
			(xy 358.392476 -298.420536) (xy 359.422192 -298.420536) (xy 359.422681 -298.393167) (xy 359.430494 -298.338989)
			(xy 359.445977 -298.286486) (xy 359.468814 -298.236739) (xy 359.498533 -298.190771) (xy 359.516172 -298.169838)
			(xy 359.516426 -298.169584) (xy 359.522028 -298.162508) (xy 359.528265 -298.145583) (xy 359.528618 -298.136564)
			(xy 359.528618 -298.069508) (xy 359.528253 -298.060492) (xy 359.522011 -298.043575) (xy 359.516426 -298.036488)
			(xy 359.516172 -298.036488) (xy 359.516172 -298.036234) (xy 359.498565 -298.015274) (xy 359.468835 -297.969312)
			(xy 359.445985 -297.91957) (xy 359.430484 -297.867072) (xy 359.422651 -297.812897) (xy 359.422647 -297.758158)
			(xy 359.430472 -297.703981) (xy 359.445966 -297.651481) (xy 359.468809 -297.601736) (xy 359.498532 -297.55577)
			(xy 359.516172 -297.534838) (xy 359.516426 -297.534584) (xy 359.522028 -297.527508) (xy 359.528265 -297.510583)
			(xy 359.528618 -297.501564) (xy 359.528618 -297.434508) (xy 359.528253 -297.425492) (xy 359.522011 -297.408575)
			(xy 359.516426 -297.401488) (xy 359.516172 -297.401488) (xy 359.516172 -297.401234) (xy 359.498565 -297.380274)
			(xy 359.468835 -297.334312) (xy 359.445985 -297.28457) (xy 359.430484 -297.232072) (xy 359.422651 -297.177897)
			(xy 359.422647 -297.123158) (xy 359.430472 -297.068981) (xy 359.445966 -297.016481) (xy 359.468809 -296.966736)
			(xy 359.498532 -296.92077) (xy 359.516172 -296.899838) (xy 359.516426 -296.899584) (xy 359.522028 -296.892508)
			(xy 359.528265 -296.875583) (xy 359.528618 -296.866564) (xy 359.528618 -296.799508) (xy 359.528253 -296.790492)
			(xy 359.522011 -296.773575) (xy 359.516426 -296.766488) (xy 359.516172 -296.766488) (xy 359.516172 -296.766234)
			(xy 359.498565 -296.745274) (xy 359.468835 -296.699312) (xy 359.445985 -296.64957) (xy 359.430484 -296.597072)
			(xy 359.422651 -296.542897) (xy 359.422647 -296.488158) (xy 359.430472 -296.433981) (xy 359.445966 -296.381481)
			(xy 359.468809 -296.331736) (xy 359.498532 -296.28577) (xy 359.516172 -296.264838) (xy 359.516426 -296.264584)
			(xy 359.522028 -296.257508) (xy 359.528265 -296.240583) (xy 359.528618 -296.231564) (xy 359.528618 -296.164508)
			(xy 359.528253 -296.155492) (xy 359.522011 -296.138575) (xy 359.516426 -296.131488) (xy 359.516172 -296.131488)
			(xy 359.516172 -296.131234) (xy 359.498565 -296.110274) (xy 359.468835 -296.064312) (xy 359.445985 -296.01457)
			(xy 359.430484 -295.962072) (xy 359.422651 -295.907897) (xy 359.422647 -295.853158) (xy 359.430472 -295.798981)
			(xy 359.445966 -295.746481) (xy 359.468809 -295.696736) (xy 359.498532 -295.65077) (xy 359.516172 -295.629838)
			(xy 359.516426 -295.629584) (xy 359.522028 -295.622508) (xy 359.528265 -295.605583) (xy 359.528618 -295.596564)
			(xy 359.528618 -295.529508) (xy 359.528253 -295.520492) (xy 359.522011 -295.503575) (xy 359.516426 -295.496488)
			(xy 359.516172 -295.496488) (xy 359.516172 -295.496234) (xy 359.498531 -295.475304) (xy 359.46882 -295.42933)
			(xy 359.445985 -295.379582) (xy 359.430495 -295.327081) (xy 359.422666 -295.272905) (xy 359.422192 -295.245536)
			(xy 359.422689 -295.218284) (xy 359.430441 -295.164334) (xy 359.445792 -295.112037) (xy 359.468431 -295.062457)
			(xy 359.497895 -295.016604) (xy 359.533585 -294.975411) (xy 359.574775 -294.939716) (xy 359.620625 -294.910248)
			(xy 359.670203 -294.887605) (xy 359.722499 -294.872249) (xy 359.776448 -294.864491) (xy 359.8037 -294.864028)
			(xy 359.831071 -294.864487) (xy 359.88525 -294.872306) (xy 359.937754 -294.887796) (xy 359.9875 -294.910639)
			(xy 360.033467 -294.940366) (xy 360.054398 -294.958008) (xy 360.054652 -294.958262) (xy 360.061743 -294.963842)
			(xy 360.078657 -294.970091) (xy 360.087672 -294.970454) (xy 360.154728 -294.970454) (xy 360.163747 -294.97012)
			(xy 360.180665 -294.963858) (xy 360.187748 -294.958262) (xy 360.187748 -294.958008) (xy 360.188002 -294.958008)
			(xy 360.208924 -294.940356) (xy 360.254899 -294.910646) (xy 360.304649 -294.887812) (xy 360.357152 -294.872324)
			(xy 360.41133 -294.8645) (xy 360.4387 -294.864028) (xy 360.465954 -294.864455) (xy 360.519909 -294.872213)
			(xy 360.572209 -294.887571) (xy 360.621792 -294.910216) (xy 360.667647 -294.939688) (xy 360.70884 -294.975385)
			(xy 360.744534 -295.016582) (xy 360.774001 -295.06244) (xy 360.796641 -295.112024) (xy 360.811994 -295.164327)
			(xy 360.819747 -295.218281) (xy 360.820208 -295.245536) (xy 360.819761 -295.272907) (xy 360.811938 -295.327087)
			(xy 360.796445 -295.37959) (xy 360.773599 -295.429336) (xy 360.743871 -295.475303) (xy 360.726228 -295.496234)
			(xy 360.725974 -295.496488) (xy 360.720383 -295.503572) (xy 360.71414 -295.520491) (xy 360.713782 -295.529508)
			(xy 360.713782 -295.596564) (xy 360.71416 -295.605579) (xy 360.720393 -295.622496) (xy 360.725974 -295.629584)
			(xy 360.726228 -295.629584) (xy 360.726228 -295.629838) (xy 360.743906 -295.650741) (xy 360.773633 -295.696713)
			(xy 360.796479 -295.746464) (xy 360.811974 -295.798971) (xy 360.8198 -295.853154) (xy 360.819796 -295.9079)
			(xy 360.811962 -295.962082) (xy 360.79646 -296.014587) (xy 360.773606 -296.064335) (xy 360.743873 -296.110302)
			(xy 360.726228 -296.131234) (xy 360.725974 -296.131488) (xy 360.720383 -296.138572) (xy 360.71414 -296.155491)
			(xy 360.713782 -296.164508) (xy 360.713782 -296.231564) (xy 360.71416 -296.240579) (xy 360.720393 -296.257496)
			(xy 360.725974 -296.264584) (xy 360.726228 -296.264584) (xy 360.726228 -296.264838) (xy 360.743906 -296.285741)
			(xy 360.773633 -296.331713) (xy 360.796479 -296.381464) (xy 360.811974 -296.433971) (xy 360.8198 -296.488154)
			(xy 360.819796 -296.5429) (xy 360.811962 -296.597082) (xy 360.79646 -296.649587) (xy 360.773606 -296.699335)
			(xy 360.743873 -296.745302) (xy 360.726228 -296.766234) (xy 360.725974 -296.766488) (xy 360.720383 -296.773572)
			(xy 360.71414 -296.790491) (xy 360.713782 -296.799508) (xy 360.713782 -296.866564) (xy 360.71416 -296.875579)
			(xy 360.720393 -296.892496) (xy 360.725974 -296.899584) (xy 360.726228 -296.899584) (xy 360.726228 -296.899838)
			(xy 360.743906 -296.920741) (xy 360.773633 -296.966713) (xy 360.796479 -297.016464) (xy 360.811974 -297.068971)
			(xy 360.8198 -297.123154) (xy 360.819796 -297.1779) (xy 360.811962 -297.232082) (xy 360.79646 -297.284587)
			(xy 360.773606 -297.334335) (xy 360.743873 -297.380302) (xy 360.726228 -297.401234) (xy 360.725974 -297.401488)
			(xy 360.720383 -297.408572) (xy 360.71414 -297.425491) (xy 360.713782 -297.434508) (xy 360.713782 -297.501564)
			(xy 360.71416 -297.510579) (xy 360.720393 -297.527496) (xy 360.725974 -297.534584) (xy 360.726228 -297.534584)
			(xy 360.726228 -297.534838) (xy 360.743906 -297.555741) (xy 360.773633 -297.601713) (xy 360.796479 -297.651464)
			(xy 360.811974 -297.703971) (xy 360.8198 -297.758154) (xy 360.819796 -297.8129) (xy 360.811962 -297.867082)
			(xy 360.79646 -297.919587) (xy 360.773606 -297.969335) (xy 360.743873 -298.015302) (xy 360.726228 -298.036234)
			(xy 360.725974 -298.036488) (xy 360.720383 -298.043572) (xy 360.71414 -298.060491) (xy 360.713782 -298.069508)
			(xy 360.713782 -298.136564) (xy 360.71416 -298.145579) (xy 360.720393 -298.162496) (xy 360.725974 -298.169584)
			(xy 360.726228 -298.169584) (xy 360.726228 -298.169838) (xy 360.743856 -298.190779) (xy 360.773568 -298.23675)
			(xy 360.796406 -298.286495) (xy 360.8119 -298.338994) (xy 360.819732 -298.393168) (xy 360.820208 -298.420536)
			(xy 360.819756 -298.447788) (xy 360.811994 -298.501737) (xy 360.796635 -298.554032) (xy 360.773989 -298.60361)
			(xy 360.744519 -298.64946) (xy 360.708824 -298.69065) (xy 360.667631 -298.726341) (xy 360.621778 -298.755807)
			(xy 360.572199 -298.778447) (xy 360.519902 -298.793802) (xy 360.465952 -298.801558) (xy 360.4387 -298.802044)
			(xy 360.411329 -298.801592) (xy 360.357149 -298.793773) (xy 360.304645 -298.778281) (xy 360.254898 -298.755436)
			(xy 360.208933 -298.725707) (xy 360.188002 -298.708064) (xy 360.187748 -298.70781) (xy 360.180651 -298.702238)
			(xy 360.163742 -298.695982) (xy 360.154728 -298.695618) (xy 360.087672 -298.695618) (xy 360.078653 -298.695958)
			(xy 360.061736 -298.702217) (xy 360.054652 -298.70781) (xy 360.054652 -298.708064) (xy 360.054398 -298.708064)
			(xy 360.033473 -298.725712) (xy 359.987499 -298.755424) (xy 359.93775 -298.778258) (xy 359.885247 -298.793747)
			(xy 359.83107 -298.801572) (xy 359.8037 -298.802044) (xy 359.77645 -298.801522) (xy 359.722506 -298.793767)
			(xy 359.670214 -298.778413) (xy 359.620639 -298.755775) (xy 359.57479 -298.726312) (xy 359.533601 -298.690624)
			(xy 359.49791 -298.649438) (xy 359.468442 -298.603593) (xy 359.445799 -298.55402) (xy 359.430441 -298.501729)
			(xy 359.42268 -298.447786) (xy 359.422192 -298.420536) (xy 358.392476 -298.420536) (xy 358.391987 -298.447785)
			(xy 358.384226 -298.501727) (xy 358.368868 -298.554015) (xy 358.346224 -298.603586) (xy 358.316757 -298.649429)
			(xy 358.281065 -298.690613) (xy 358.239875 -298.726297) (xy 358.194026 -298.755757) (xy 358.144452 -298.778392)
			(xy 358.09216 -298.793741) (xy 358.038217 -298.801492) (xy 358.010968 -298.802044) (xy 357.983599 -298.80157)
			(xy 357.929424 -298.793741) (xy 357.876924 -298.778249) (xy 357.827178 -298.755411) (xy 357.781207 -298.725697)
			(xy 357.76027 -298.708064) (xy 357.760016 -298.708064) (xy 357.760016 -298.70781) (xy 357.75293 -298.702221)
			(xy 357.736013 -298.695973) (xy 357.726996 -298.695618) (xy 357.65994 -298.695618) (xy 357.650921 -298.695971)
			(xy 357.633997 -298.70221) (xy 357.62692 -298.70781) (xy 357.626666 -298.708064) (xy 357.605735 -298.725706)
			(xy 357.559768 -298.75543) (xy 357.510021 -298.778271) (xy 357.457518 -298.793758) (xy 357.403338 -298.801573)
			(xy 357.375968 -298.802044) (xy 357.348717 -298.801556) (xy 357.294771 -298.793796) (xy 357.242478 -298.778439)
			(xy 357.192903 -298.755796) (xy 357.147054 -298.726329) (xy 357.105864 -298.690638) (xy 357.070173 -298.64945)
			(xy 357.040706 -298.603601) (xy 357.018063 -298.554026) (xy 357.002705 -298.501733) (xy 356.994944 -298.447787)
			(xy 356.99446 -298.420536) (xy 356.994936 -298.393168) (xy 357.002769 -298.338995) (xy 357.018265 -298.286498)
			(xy 357.041106 -298.236755) (xy 357.070823 -298.190788) (xy 357.08844 -298.169838) (xy 357.08844 -298.169584)
			(xy 357.088694 -298.169584) (xy 357.094277 -298.162497) (xy 357.100515 -298.145579) (xy 357.100886 -298.136564)
			(xy 357.100886 -298.069508) (xy 357.100528 -298.060491) (xy 357.094281 -298.043574) (xy 357.088694 -298.036488)
			(xy 357.08844 -298.036234) (xy 357.070796 -298.015301) (xy 357.041065 -297.969333) (xy 357.018214 -297.919586)
			(xy 357.002713 -297.867081) (xy 356.994879 -297.8129) (xy 356.994876 -297.758155) (xy 357.002701 -297.703972)
			(xy 357.018195 -297.651465) (xy 357.041039 -297.601714) (xy 357.070764 -297.555742) (xy 357.08844 -297.534838)
			(xy 357.08844 -297.534584) (xy 357.088694 -297.534584) (xy 357.094277 -297.527497) (xy 357.100515 -297.510579)
			(xy 357.100886 -297.501564) (xy 357.100886 -297.434508) (xy 357.100528 -297.425491) (xy 357.094281 -297.408574)
			(xy 357.088694 -297.401488) (xy 357.08844 -297.401234) (xy 357.070796 -297.380301) (xy 357.041065 -297.334333)
			(xy 357.018214 -297.284586) (xy 357.002713 -297.232081) (xy 356.994879 -297.1779) (xy 356.994876 -297.123155)
			(xy 357.002701 -297.068972) (xy 357.018195 -297.016465) (xy 357.041039 -296.966714) (xy 357.070764 -296.920742)
			(xy 357.08844 -296.899838) (xy 357.08844 -296.899584) (xy 357.088694 -296.899584) (xy 357.094277 -296.892497)
			(xy 357.100515 -296.875579) (xy 357.100886 -296.866564) (xy 357.100886 -296.799508) (xy 357.100528 -296.790491)
			(xy 357.094281 -296.773574) (xy 357.088694 -296.766488) (xy 357.08844 -296.766234) (xy 357.070796 -296.745301)
			(xy 357.041065 -296.699333) (xy 357.018214 -296.649586) (xy 357.002713 -296.597081) (xy 356.994879 -296.5429)
			(xy 356.994876 -296.488155) (xy 357.002701 -296.433972) (xy 357.018195 -296.381465) (xy 357.041039 -296.331714)
			(xy 357.070764 -296.285742) (xy 357.08844 -296.264838) (xy 357.08844 -296.264584) (xy 357.088694 -296.264584)
			(xy 357.094277 -296.257497) (xy 357.100515 -296.240579) (xy 357.100886 -296.231564) (xy 357.100886 -296.164508)
			(xy 357.100528 -296.155491) (xy 357.094281 -296.138574) (xy 357.088694 -296.131488) (xy 357.08844 -296.131234)
			(xy 357.070796 -296.110301) (xy 357.041065 -296.064333) (xy 357.018214 -296.014586) (xy 357.002713 -295.962081)
			(xy 356.994879 -295.9079) (xy 356.994876 -295.853155) (xy 357.002701 -295.798972) (xy 357.018195 -295.746465)
			(xy 357.041039 -295.696714) (xy 357.070764 -295.650742) (xy 357.08844 -295.629838) (xy 357.08844 -295.629584)
			(xy 357.088694 -295.629584) (xy 357.094277 -295.622497) (xy 357.100515 -295.605579) (xy 357.100886 -295.596564)
			(xy 357.10114 -295.520364) (xy 357.094536 -295.503092) (xy 357.08844 -295.496234) (xy 357.070794 -295.475304)
			(xy 357.041061 -295.429339) (xy 357.018211 -295.379593) (xy 357.002715 -295.327089) (xy 356.99489 -295.272908)
			(xy 356.99446 -295.245536) (xy 356.99446 -283.316934) (xy 356.995015 -283.286953) (xy 357.004394 -283.227729)
			(xy 357.022926 -283.170702) (xy 357.050155 -283.117278) (xy 357.085408 -283.068774) (xy 357.10622 -283.047186)
			(xy 357.63708 -282.516326) (xy 357.644108 -282.508651) (xy 357.651812 -282.489342) (xy 357.651167 -282.468563)
			(xy 357.64724 -282.458922) (xy 357.606854 -282.372562) (xy 357.602039 -282.363375) (xy 357.586582 -282.349572)
			(xy 357.56693 -282.343) (xy 357.556562 -282.343352) (xy 357.556308 -282.343352) (xy 357.523034 -282.344876)
			(xy 357.495782 -282.344415) (xy 357.441832 -282.336663) (xy 357.389534 -282.321311) (xy 357.339954 -282.298672)
			(xy 357.2941 -282.269208) (xy 357.252907 -282.233517) (xy 357.217213 -282.192327) (xy 357.187744 -282.146476)
			(xy 357.165101 -282.096898) (xy 357.149745 -282.044602) (xy 357.141987 -281.990652) (xy 357.141987 -281.936148)
			(xy 357.149745 -281.882199) (xy 357.165101 -281.829902) (xy 357.187744 -281.780324) (xy 357.217213 -281.734473)
			(xy 357.252907 -281.693283) (xy 357.2941 -281.657592) (xy 357.339954 -281.628128) (xy 357.389534 -281.605489)
			(xy 357.441832 -281.590137) (xy 357.495782 -281.582385) (xy 357.523034 -281.58186) (xy 357.551655 -281.582373)
			(xy 357.608255 -281.59092) (xy 357.662946 -281.607818) (xy 357.714503 -281.632689) (xy 357.738426 -281.648408)
			(xy 357.749856 -281.656282) (xy 357.778304 -281.65806) (xy 357.869998 -281.609546) (xy 357.877972 -281.604893)
			(xy 357.890188 -281.591067) (xy 357.896716 -281.573812) (xy 357.897176 -281.564588) (xy 357.897176 -280.999692)
			(xy 357.897662 -280.972441) (xy 357.905418 -280.918493) (xy 357.920773 -280.866198) (xy 357.943415 -280.816621)
			(xy 357.972881 -280.770771) (xy 358.008572 -280.72958) (xy 358.049763 -280.693889) (xy 358.095613 -280.664423)
			(xy 358.14519 -280.641781) (xy 358.197485 -280.626426) (xy 358.251433 -280.61867) (xy 358.305935 -280.61867)
			(xy 358.359883 -280.626426) (xy 358.412178 -280.641781) (xy 358.461755 -280.664423) (xy 358.507605 -280.693889)
			(xy 358.548796 -280.72958) (xy 358.584487 -280.770771) (xy 358.613953 -280.816621) (xy 358.636595 -280.866198)
			(xy 358.65195 -280.918493) (xy 358.659706 -280.972441) (xy 358.660192 -280.999692) (xy 358.660192 -282.414218)
			(xy 358.65964 -282.4442) (xy 358.650267 -282.503427) (xy 358.631738 -282.560457) (xy 358.604512 -282.613884)
			(xy 358.569258 -282.662391) (xy 358.548432 -282.683966) (xy 358.34828 -282.883864) (xy 358.341354 -282.891499)
			(xy 358.33373 -282.910629) (xy 358.33423 -282.931217) (xy 358.33812 -282.94076) (xy 358.377744 -283.027628)
			(xy 358.38246 -283.03675) (xy 358.397643 -283.050551) (xy 358.417009 -283.057329) (xy 358.427274 -283.057092)
			(xy 358.454198 -283.056076) (xy 358.48145 -283.056562) (xy 358.535399 -283.064318) (xy 358.587694 -283.079673)
			(xy 358.637273 -283.102313) (xy 358.683125 -283.131779) (xy 358.724317 -283.167471) (xy 358.76001 -283.208661)
			(xy 358.789478 -283.254511) (xy 358.812121 -283.304089) (xy 358.827478 -283.356384) (xy 358.835237 -283.410332)
			(xy 358.835706 -283.437584) (xy 358.835159 -283.467061) (xy 358.826092 -283.525315) (xy 358.808172 -283.58148)
			(xy 358.781825 -283.63422) (xy 358.747678 -283.682279) (xy 358.727502 -283.703776) (xy 358.720953 -283.711102)
			(xy 358.713504 -283.729267) (xy 358.713024 -283.739082) (xy 358.713024 -283.792422) (xy 358.723946 -283.802836)
			(xy 359.238804 -284.317694) (xy 359.246203 -284.32454) (xy 359.2648 -284.332274) (xy 359.274872 -284.33268)
			(xy 360.48442 -284.33268) (xy 360.495238 -284.332251) (xy 360.514991 -284.32344) (xy 360.52252 -284.315662)
			(xy 360.573066 -284.25902) (xy 360.579858 -284.25066) (xy 360.586328 -284.230134) (xy 360.585512 -284.219396)
			(xy 360.584322 -284.20845) (xy 360.583052 -284.186465) (xy 360.582972 -284.175454) (xy 360.583537 -284.145329)
			(xy 360.593003 -284.085827) (xy 360.611708 -284.028554) (xy 360.639187 -283.974935) (xy 360.674756 -283.926304)
			(xy 360.695748 -283.90469) (xy 360.702599 -283.897294) (xy 360.710338 -283.878695) (xy 360.710734 -283.868622)
			(xy 360.710734 -283.796486) (xy 360.710307 -283.786418) (xy 360.702581 -283.767824) (xy 360.695748 -283.760418)
			(xy 360.674771 -283.738793) (xy 360.639216 -283.690157) (xy 360.611745 -283.63654) (xy 360.59304 -283.579272)
			(xy 360.583566 -283.519777) (xy 360.582972 -283.489654) (xy 360.583569 -283.459817) (xy 360.59288 -283.400873)
			(xy 360.601514 -283.372306) (xy 360.604816 -283.361892) (xy 360.60253 -283.340302) (xy 360.552238 -283.25572)
			(xy 360.534966 -283.243274) (xy 360.524044 -283.241242) (xy 360.496195 -283.235368) (xy 360.442511 -283.216466)
			(xy 360.392234 -283.189793) (xy 360.346481 -283.155943) (xy 360.306268 -283.115667) (xy 360.272489 -283.069861)
			(xy 360.245895 -283.019543) (xy 360.227077 -282.96583) (xy 360.221276 -282.937966) (xy 360.218736 -282.92552)
			(xy 360.203496 -282.906216) (xy 360.102404 -282.862528) (xy 360.077766 -282.864306) (xy 360.067098 -282.871164)
			(xy 360.044105 -282.885157) (xy 359.995026 -282.907253) (xy 359.943333 -282.922247) (xy 359.890048 -282.929843)
			(xy 359.863136 -282.930346) (xy 359.845118 -282.93011) (xy 359.809244 -282.926673) (xy 359.791508 -282.923488)
			(xy 359.781856 -282.92171) (xy 359.762806 -282.925266) (xy 359.687876 -282.973272) (xy 359.676446 -282.98902)
			(xy 359.67416 -282.998418) (xy 359.666776 -283.025468) (xy 359.645162 -283.077204) (xy 359.616205 -283.125219)
			(xy 359.580532 -283.168477) (xy 359.538909 -283.206045) (xy 359.492234 -283.237115) (xy 359.441514 -283.261017)
			(xy 359.387841 -283.277235) (xy 359.332371 -283.28542) (xy 359.304336 -283.285946) (xy 359.277082 -283.285463)
			(xy 359.223128 -283.277711) (xy 359.170827 -283.262359) (xy 359.121243 -283.23972) (xy 359.075385 -283.210256)
			(xy 359.034188 -283.174565) (xy 358.998489 -283.133374) (xy 358.969015 -283.087522) (xy 358.946367 -283.037942)
			(xy 358.931005 -282.985644) (xy 358.923243 -282.931692) (xy 358.922828 -282.904438) (xy 358.923312 -282.876863)
			(xy 358.93125 -282.822288) (xy 358.946967 -282.769426) (xy 358.970133 -282.719378) (xy 359.000267 -282.673189)
			(xy 359.036739 -282.631822) (xy 359.057448 -282.613608) (xy 359.065534 -282.606065) (xy 359.074864 -282.586043)
			(xy 359.075482 -282.575) (xy 359.075482 -282.497276) (xy 359.074873 -282.486236) (xy 359.065517 -282.466229)
			(xy 359.057448 -282.458668) (xy 359.036743 -282.440452) (xy 359.00028 -282.39908) (xy 358.970153 -282.352889)
			(xy 358.946989 -282.302843) (xy 358.931271 -282.249983) (xy 358.923327 -282.195411) (xy 358.922828 -282.167838)
			(xy 358.923312 -282.140263) (xy 358.93125 -282.085688) (xy 358.946967 -282.032826) (xy 358.970133 -281.982778)
			(xy 359.000267 -281.936589) (xy 359.036739 -281.895222) (xy 359.057448 -281.877008) (xy 359.065534 -281.869465)
			(xy 359.074864 -281.849443) (xy 359.075482 -281.8384) (xy 359.075482 -281.760676) (xy 359.074873 -281.749636)
			(xy 359.065517 -281.729629) (xy 359.057448 -281.722068) (xy 359.036743 -281.703852) (xy 359.00028 -281.66248)
			(xy 358.970153 -281.616289) (xy 358.946989 -281.566243) (xy 358.931271 -281.513383) (xy 358.923327 -281.458811)
			(xy 358.922828 -281.431238) (xy 358.923289 -281.403984) (xy 358.931042 -281.350031) (xy 358.946395 -281.297731)
			(xy 358.969035 -281.248148) (xy 358.998503 -281.202293) (xy 359.034197 -281.161099) (xy 359.075391 -281.125404)
			(xy 359.121246 -281.095936) (xy 359.170829 -281.073295) (xy 359.223129 -281.057942) (xy 359.277082 -281.050189)
			(xy 359.304336 -281.04973) (xy 359.332196 -281.050232) (xy 359.387326 -281.058327) (xy 359.440692 -281.074354)
			(xy 359.491159 -281.097973) (xy 359.537654 -281.128681) (xy 359.579188 -281.165825) (xy 359.614879 -281.208615)
			(xy 359.643966 -281.256141) (xy 359.665831 -281.307392) (xy 359.673398 -281.33421) (xy 359.675684 -281.3431)
			(xy 359.686352 -281.35834) (xy 359.758234 -281.406092) (xy 359.776268 -281.410156) (xy 359.785412 -281.408886)
			(xy 359.798427 -281.407202) (xy 359.824613 -281.405422) (xy 359.837736 -281.40533) (xy 359.850859 -281.405436)
			(xy 359.877044 -281.407215) (xy 359.89006 -281.408886) (xy 359.899204 -281.410156) (xy 359.917238 -281.406092)
			(xy 359.98912 -281.35834) (xy 359.999788 -281.3431) (xy 360.002074 -281.33421) (xy 360.009667 -281.307405)
			(xy 360.031553 -281.256173) (xy 360.060651 -281.208665) (xy 360.096344 -281.165889) (xy 360.137874 -281.128755)
			(xy 360.184359 -281.098049) (xy 360.234813 -281.074425) (xy 360.288165 -281.058383) (xy 360.343281 -281.050263)
			(xy 360.371136 -281.04973) (xy 360.398386 -281.050196) (xy 360.452331 -281.057957) (xy 360.504623 -281.073317)
			(xy 360.554196 -281.095962) (xy 360.600042 -281.125431) (xy 360.641227 -281.161126) (xy 360.676913 -281.202318)
			(xy 360.706374 -281.248169) (xy 360.729009 -281.297747) (xy 360.744359 -281.350041) (xy 360.752109 -281.403988)
			(xy 360.752644 -281.431238) (xy 360.752176 -281.458536) (xy 360.74439 -281.512575) (xy 360.728983 -281.564953)
			(xy 360.70627 -281.614601) (xy 360.676714 -281.660506) (xy 360.659172 -281.681428) (xy 360.652822 -281.688794)
			(xy 360.646472 -281.706574) (xy 360.649774 -281.795728) (xy 360.657648 -281.813508) (xy 360.664506 -281.820112)
			(xy 360.685615 -281.84176) (xy 360.721407 -281.890489) (xy 360.749067 -281.944252) (xy 360.767905 -282.001704)
			(xy 360.777448 -282.061407) (xy 360.778044 -282.091638) (xy 360.777557 -282.119278) (xy 360.769582 -282.173979)
			(xy 360.75379 -282.226955) (xy 360.730514 -282.277095) (xy 360.70024 -282.323347) (xy 360.682286 -282.344368)
			(xy 360.673904 -282.353766) (xy 360.668062 -282.37815) (xy 360.692192 -282.47213) (xy 360.695862 -282.484095)
			(xy 360.712644 -282.502622) (xy 360.724196 -282.507436) (xy 360.751604 -282.517775) (xy 360.80312 -282.545651)
			(xy 360.849766 -282.581081) (xy 360.890443 -282.623229) (xy 360.924194 -282.671104) (xy 360.950224 -282.723578)
			(xy 360.96792 -282.779416) (xy 360.976867 -282.837304) (xy 360.977434 -282.866592) (xy 360.976833 -282.896428)
			(xy 360.967516 -282.955371) (xy 360.958892 -282.98394) (xy 360.95559 -282.994354) (xy 360.957876 -283.015944)
			(xy 361.008168 -283.100526) (xy 361.02544 -283.112972) (xy 361.036362 -283.115004) (xy 361.062166 -283.120405)
			(xy 361.11208 -283.137369) (xy 361.159184 -283.161043) (xy 361.202579 -283.190977) (xy 361.24144 -283.226601)
			(xy 361.275026 -283.267235) (xy 361.302698 -283.312107) (xy 361.323928 -283.360362) (xy 361.338313 -283.41108)
			(xy 361.345577 -283.463295) (xy 361.345988 -283.489654) (xy 361.345422 -283.519779) (xy 361.335956 -283.579282)
			(xy 361.317253 -283.636556) (xy 361.289776 -283.690177) (xy 361.254211 -283.738811) (xy 361.233212 -283.760418)
			(xy 361.226367 -283.767817) (xy 361.218637 -283.786415) (xy 361.218226 -283.796486) (xy 361.218226 -283.868622)
			(xy 361.218654 -283.87869) (xy 361.226377 -283.897286) (xy 361.233212 -283.90469) (xy 361.252607 -283.924648)
			(xy 361.285987 -283.969177) (xy 361.312533 -284.018088) (xy 361.331679 -284.070341) (xy 361.33786 -284.097476)
			(xy 361.33786 -284.09773) (xy 361.340138 -284.106564) (xy 361.349958 -284.121922) (xy 361.364537 -284.132867)
			(xy 361.373166 -284.13583) (xy 361.458764 -284.16123) (xy 361.467596 -284.163459) (xy 361.485755 -284.162203)
			(xy 361.502325 -284.154669) (xy 361.509056 -284.14853) (xy 362.256578 -283.401262) (xy 362.262475 -283.394802)
			(xy 362.269886 -283.378973) (xy 362.27154 -283.361573) (xy 362.269786 -283.353002) (xy 362.24845 -283.26842)
			(xy 362.245948 -283.260022) (xy 362.23621 -283.245468) (xy 362.222175 -283.234996) (xy 362.213906 -283.232098)
			(xy 362.213652 -283.232098) (xy 362.187872 -283.223842) (xy 362.138766 -283.201065) (xy 362.093374 -283.171573)
			(xy 362.072682 -283.15412) (xy 362.072174 -283.15412) (xy 362.072174 -283.153866) (xy 362.065085 -283.148288)
			(xy 362.048168 -283.142059) (xy 362.039154 -283.141674) (xy 361.972098 -283.141674) (xy 361.963081 -283.142034)
			(xy 361.946164 -283.148279) (xy 361.939078 -283.153866) (xy 361.938824 -283.15412) (xy 361.917893 -283.171763)
			(xy 361.871926 -283.20149) (xy 361.82218 -283.224335) (xy 361.769677 -283.239828) (xy 361.715497 -283.247649)
			(xy 361.688126 -283.2481) (xy 361.660873 -283.247638) (xy 361.60692 -283.239885) (xy 361.55462 -283.224531)
			(xy 361.505038 -283.201891) (xy 361.459182 -283.172424) (xy 361.417987 -283.136731) (xy 361.382292 -283.095539)
			(xy 361.352822 -283.049685) (xy 361.330178 -283.000104) (xy 361.314821 -282.947806) (xy 361.307063 -282.893853)
			(xy 361.307063 -282.839347) (xy 361.314821 -282.785394) (xy 361.330178 -282.733096) (xy 361.352822 -282.683515)
			(xy 361.382292 -282.637661) (xy 361.417987 -282.596469) (xy 361.459182 -282.560776) (xy 361.505038 -282.531309)
			(xy 361.55462 -282.508669) (xy 361.60692 -282.493315) (xy 361.660873 -282.485562) (xy 361.688126 -282.485084)
			(xy 361.715496 -282.485558) (xy 361.769672 -282.493384) (xy 361.822174 -282.508874) (xy 361.871923 -282.531708)
			(xy 361.917898 -282.561417) (xy 361.938824 -282.579064) (xy 361.939078 -282.579064) (xy 361.939078 -282.579318)
			(xy 361.946164 -282.584905) (xy 361.963081 -282.591152) (xy 361.972098 -282.59151) (xy 362.039154 -282.59151)
			(xy 362.048167 -282.591142) (xy 362.065072 -282.584882) (xy 362.072174 -282.579318) (xy 362.072428 -282.579064)
			(xy 362.093359 -282.561421) (xy 362.139324 -282.531693) (xy 362.189071 -282.50885) (xy 362.241575 -282.493361)
			(xy 362.295755 -282.485545) (xy 362.323126 -282.485084) (xy 362.350376 -282.485572) (xy 362.404322 -282.493331)
			(xy 362.456614 -282.508688) (xy 362.506188 -282.531331) (xy 362.552036 -282.560798) (xy 362.593224 -282.596489)
			(xy 362.628913 -282.637679) (xy 362.658378 -282.683528) (xy 362.681018 -282.733103) (xy 362.696373 -282.785396)
			(xy 362.70413 -282.839342) (xy 362.704634 -282.866592) (xy 362.704634 -282.8671) (xy 362.704189 -282.892971)
			(xy 362.697167 -282.944234) (xy 362.68328 -282.994078) (xy 362.662783 -283.041586) (xy 362.64977 -283.06395)
			(xy 362.642658 -283.075634) (xy 362.64215 -283.10332) (xy 362.692442 -283.19222) (xy 362.697165 -283.199856)
			(xy 362.710835 -283.211481) (xy 362.727667 -283.217701) (xy 362.736638 -283.218128) (xy 364.643924 -283.218128)
			(xy 364.67384 -283.218736) (xy 364.732931 -283.228125) (xy 364.789833 -283.246622) (xy 364.84315 -283.273774)
			(xy 364.891576 -283.308915) (xy 364.913164 -283.329634) (xy 365.068358 -283.484828) (xy 365.07568 -283.491631)
			(xy 365.0941 -283.499349) (xy 365.114072 -283.499394) (xy 365.123476 -283.496004) (xy 365.137954 -283.490162)
			(xy 365.154972 -283.464508) (xy 365.154972 -283.333952) (xy 365.155226 -283.32176) (xy 365.155226 -283.197046)
			(xy 365.155756 -283.187055) (xy 365.16346 -283.168614) (xy 365.170212 -283.161232) (xy 365.256826 -283.074364)
			(xy 365.258604 -283.072586) (xy 365.266732 -283.064204) (xy 365.289846 -283.04109) (xy 365.787432 -282.543758)
			(xy 366.03686 -282.294076) (xy 366.042956 -282.28671) (xy 366.048612 -282.277409) (xy 366.052236 -282.255966)
			(xy 366.046684 -282.234939) (xy 366.032947 -282.218079) (xy 366.013474 -282.208395) (xy 365.991741 -282.207614)
			(xy 365.981488 -282.211272) (xy 365.980472 -282.211526) (xy 365.979964 -282.212034) (xy 365.969804 -282.216352)
			(xy 365.962438 -282.224226) (xy 365.944304 -282.242949) (xy 365.903836 -282.275803) (xy 365.859276 -282.302845)
			(xy 365.811451 -282.323574) (xy 365.761251 -282.337605) (xy 365.709608 -282.344675) (xy 365.683546 -282.34513)
			(xy 365.656275 -282.34467) (xy 365.602288 -282.336914) (xy 365.549954 -282.321553) (xy 365.500339 -282.2989)
			(xy 365.454454 -282.269416) (xy 365.413231 -282.233701) (xy 365.377512 -282.192483) (xy 365.348023 -282.146601)
			(xy 365.325364 -282.096989) (xy 365.309996 -282.044657) (xy 365.302234 -281.990671) (xy 365.302234 -281.936129)
			(xy 365.309996 -281.882143) (xy 365.325364 -281.829811) (xy 365.348023 -281.780199) (xy 365.377512 -281.734317)
			(xy 365.413231 -281.693099) (xy 365.454454 -281.657384) (xy 365.500339 -281.6279) (xy 365.549954 -281.605247)
			(xy 365.602288 -281.589886) (xy 365.656275 -281.58213) (xy 365.683546 -281.581606) (xy 365.6838 -281.581606)
			(xy 365.711616 -281.582115) (xy 365.766657 -281.590199) (xy 365.819943 -281.606182) (xy 365.870347 -281.629724)
			(xy 365.893858 -281.644598) (xy 365.899192 -281.648154) (xy 365.924846 -281.657044) (xy 365.93907 -281.657806)
			(xy 366.02797 -281.61107) (xy 366.03813 -281.603958) (xy 366.039654 -281.602688) (xy 366.046812 -281.595212)
			(xy 366.054943 -281.576199) (xy 366.055402 -281.565858) (xy 366.055402 -280.700226) (xy 366.055839 -280.690162)
			(xy 366.063572 -280.671577) (xy 366.070388 -280.664158) (xy 366.256824 -280.477722) (xy 366.264223 -280.470877)
			(xy 366.282821 -280.463148) (xy 366.292892 -280.462736) (xy 366.740186 -280.462736) (xy 366.748314 -280.461974)
			(xy 366.748822 -280.461974) (xy 366.756341 -280.460373) (xy 366.770028 -280.453397) (xy 366.775746 -280.448258)
			(xy 366.882426 -280.341578) (xy 366.887617 -280.335898) (xy 366.894591 -280.322191) (xy 366.896142 -280.314654)
			(xy 366.896142 -280.314146) (xy 366.896904 -280.306018) (xy 366.896904 -279.040844) (xy 366.89665 -279.037288)
			(xy 366.896396 -279.03424) (xy 366.895568 -279.028787) (xy 366.89185 -279.018406) (xy 366.88903 -279.013666)
			(xy 366.882172 -279.002998) (xy 366.820347 -278.970201) (xy 366.699158 -278.900168) (xy 366.580969 -278.825182)
			(xy 366.52327 -278.785574) (xy 366.456656 -278.738739) (xy 366.327502 -278.639534) (xy 366.203278 -278.53422)
			(xy 366.084272 -278.423044) (xy 365.970761 -278.306263) (xy 365.863009 -278.184148) (xy 365.761265 -278.056984)
			(xy 365.665766 -277.925065) (xy 365.576734 -277.788699) (xy 365.494376 -277.648201) (xy 365.418883 -277.503898)
			(xy 365.35043 -277.356125) (xy 365.289177 -277.205226) (xy 365.235265 -277.05155) (xy 365.188821 -276.895456)
			(xy 365.149951 -276.737305) (xy 365.118745 -276.577465) (xy 365.095278 -276.416307) (xy 365.079602 -276.254206)
			(xy 365.071755 -276.091538) (xy 365.071755 -275.92868) (xy 365.079601 -275.766012) (xy 365.095276 -275.603911)
			(xy 365.118742 -275.442753) (xy 365.149947 -275.282913) (xy 365.188816 -275.124762) (xy 365.23526 -274.968667)
			(xy 365.289171 -274.814992) (xy 365.350423 -274.664092) (xy 365.418875 -274.516319) (xy 365.494367 -274.372015)
			(xy 365.576725 -274.231517) (xy 365.665756 -274.09515) (xy 365.761254 -273.96323) (xy 365.862997 -273.836066)
			(xy 365.970749 -273.71395) (xy 366.084259 -273.597169) (xy 366.203264 -273.485992) (xy 366.327488 -273.380678)
			(xy 366.456641 -273.281471) (xy 366.52327 -273.234658) (xy 366.607044 -273.17736) (xy 366.78039 -273.071752)
			(xy 366.869726 -273.023584) (xy 366.86998 -273.023584) (xy 366.875865 -273.020289) (xy 366.885778 -273.01115)
			(xy 366.889538 -273.00555) (xy 366.893094 -272.999962) (xy 366.895126 -272.99285) (xy 366.896904 -272.979388)
			(xy 366.896904 -262.373364) (xy 366.896574 -262.364759) (xy 366.89087 -262.348521) (xy 366.885728 -262.341614)
			(xy 366.88522 -262.341106) (xy 366.882172 -262.33755) (xy 366.559846 -262.01497) (xy 366.554004 -262.009128)
			(xy 366.536732 -261.99211) (xy 366.515323 -261.969748) (xy 366.480662 -261.918461) (xy 366.467898 -261.890256)
			(xy 366.46485 -261.883906) (xy 366.453544 -261.86442) (xy 366.435732 -261.823041) (xy 366.4237 -261.779627)
			(xy 366.417673 -261.734982) (xy 366.417352 -261.712456) (xy 366.417352 -256.8829) (xy 366.409986 -256.879344)
			(xy 366.319054 -256.8448) (xy 366.313057 -256.843052) (xy 366.300601 -256.842148) (xy 366.294416 -256.843022)
			(xy 366.283494 -256.845562) (xy 366.270794 -256.852928) (xy 366.265206 -256.859278) (xy 366.247036 -256.878938)
			(xy 366.206137 -256.913481) (xy 366.16081 -256.941965) (xy 366.111945 -256.963829) (xy 366.060502 -256.978646)
			(xy 366.007493 -256.986122) (xy 365.980726 -256.986532) (xy 365.95347 -256.986071) (xy 365.899513 -256.978316)
			(xy 365.847209 -256.962962) (xy 365.797622 -256.940319) (xy 365.751763 -256.91085) (xy 365.710564 -256.875154)
			(xy 365.674866 -256.833958) (xy 365.645393 -256.788101) (xy 365.622747 -256.738516) (xy 365.607389 -256.686212)
			(xy 365.599631 -256.632256) (xy 365.599631 -256.577744) (xy 365.607389 -256.523788) (xy 365.622747 -256.471484)
			(xy 365.645393 -256.421899) (xy 365.674866 -256.376042) (xy 365.710564 -256.334846) (xy 365.751763 -256.29915)
			(xy 365.797622 -256.269681) (xy 365.847209 -256.247038) (xy 365.899513 -256.231684) (xy 365.95347 -256.223929)
			(xy 365.980726 -256.223516) (xy 366.00749 -256.223969) (xy 366.060494 -256.231451) (xy 366.111932 -256.246266)
			(xy 366.160795 -256.268123) (xy 366.206125 -256.296592) (xy 366.247033 -256.331116) (xy 366.265206 -256.35077)
			(xy 366.272372 -256.358098) (xy 366.290889 -256.366843) (xy 366.311351 -256.367687) (xy 366.321086 -256.364486)
			(xy 366.409986 -256.330704) (xy 366.417352 -256.327148) (xy 366.417352 -254.39243) (xy 366.416915 -254.382367)
			(xy 366.409177 -254.363785) (xy 366.402366 -254.356362) (xy 366.317022 -254.271018) (xy 366.310186 -254.263616)
			(xy 366.302478 -254.245018) (xy 366.302036 -254.23495) (xy 366.302036 -252.642878) (xy 366.301972 -252.639272)
			(xy 366.300949 -252.632134) (xy 366.300004 -252.628654) (xy 366.29848 -252.624082) (xy 366.29467 -252.614938)
			(xy 362.168948 -248.489216) (xy 362.162109 -248.481815) (xy 362.154398 -248.463216) (xy 362.153962 -248.453148)
			(xy 362.153962 -244.70233) (xy 362.153901 -244.698724) (xy 362.152887 -244.691583) (xy 362.15193 -244.688106)
			(xy 362.150406 -244.683534) (xy 362.146596 -244.67439) (xy 361.208574 -243.736368) (xy 361.201245 -243.729648)
			(xy 361.182942 -243.721927) (xy 361.173014 -243.721382) (xy 361.142788 -243.721382) (xy 361.13355 -243.721678)
			(xy 361.116215 -243.728047) (xy 361.109006 -243.733828) (xy 361.088028 -243.751561) (xy 361.041941 -243.781447)
			(xy 360.992046 -243.804417) (xy 360.939373 -243.819997) (xy 360.88501 -243.827864) (xy 360.857546 -243.828316)
			(xy 360.830291 -243.827856) (xy 360.776334 -243.820104) (xy 360.724031 -243.804752) (xy 360.674444 -243.782112)
			(xy 360.628585 -243.752646) (xy 360.587386 -243.716952) (xy 360.551687 -243.675759) (xy 360.522213 -243.629903)
			(xy 360.499567 -243.58032) (xy 360.484207 -243.528018) (xy 360.476448 -243.474063) (xy 360.476038 -243.446808)
			(xy 360.476575 -243.417473) (xy 360.485552 -243.359494) (xy 360.503296 -243.303572) (xy 360.529388 -243.251024)
			(xy 360.563215 -243.203088) (xy 360.583226 -243.181632) (xy 360.597704 -243.166646) (xy 360.59745 -243.125244)
			(xy 359.477564 -242.005358) (xy 359.473832 -242.001839) (xy 359.465255 -241.996216) (xy 359.460546 -241.994182)
			(xy 359.45191 -241.990626) (xy 332.225904 -241.990626) (xy 332.222298 -241.990689) (xy 332.215159 -241.991706)
			(xy 332.21168 -241.992658) (xy 332.207108 -241.994182) (xy 332.197964 -241.997992) (xy 331.11059 -243.085366)
			(xy 331.107065 -243.089094) (xy 331.101427 -243.097665) (xy 331.099414 -243.102384) (xy 331.095858 -243.11102)
			(xy 331.095858 -243.967) (xy 331.595982 -243.967) (xy 331.600053 -243.911378) (xy 331.612179 -243.856941)
			(xy 331.632102 -243.80485) (xy 331.659398 -243.756215) (xy 331.693484 -243.712072) (xy 331.733633 -243.673363)
			(xy 331.778991 -243.640912) (xy 331.828591 -243.615411) (xy 331.881375 -243.597404) (xy 331.936218 -243.587274)
			(xy 331.991952 -243.585237) (xy 332.047389 -243.591337) (xy 332.101346 -243.605443) (xy 332.152675 -243.627255)
			(xy 332.200281 -243.656309) (xy 332.243149 -243.691984) (xy 332.280366 -243.733521) (xy 332.311139 -243.780034)
			(xy 332.334811 -243.830531) (xy 332.350879 -243.883938) (xy 332.358999 -243.939114) (xy 332.359508 -243.967)
			(xy 332.358999 -243.994886) (xy 332.350879 -244.050062) (xy 332.334811 -244.103469) (xy 332.311139 -244.153966)
			(xy 332.280366 -244.200479) (xy 332.261979 -244.221) (xy 332.611982 -244.221) (xy 332.616053 -244.165378)
			(xy 332.628179 -244.110941) (xy 332.648102 -244.05885) (xy 332.675398 -244.010215) (xy 332.709484 -243.966072)
			(xy 332.749633 -243.927363) (xy 332.794991 -243.894912) (xy 332.844591 -243.869411) (xy 332.897375 -243.851404)
			(xy 332.952218 -243.841274) (xy 333.007952 -243.839237) (xy 333.014886 -243.84) (xy 333.739996 -243.84)
			(xy 333.744067 -243.784378) (xy 333.756193 -243.729941) (xy 333.776116 -243.67785) (xy 333.803412 -243.629215)
			(xy 333.837498 -243.585072) (xy 333.877647 -243.546363) (xy 333.923005 -243.513912) (xy 333.972605 -243.488411)
			(xy 334.025389 -243.470404) (xy 334.080232 -243.460274) (xy 334.135966 -243.458237) (xy 334.191403 -243.464337)
			(xy 334.24536 -243.478443) (xy 334.296689 -243.500255) (xy 334.315242 -243.511578) (xy 354.422708 -243.511578)
			(xy 354.426779 -243.455956) (xy 354.438905 -243.401519) (xy 354.458828 -243.349428) (xy 354.486124 -243.300793)
			(xy 354.52021 -243.25665) (xy 354.560359 -243.217941) (xy 354.605717 -243.18549) (xy 354.655317 -243.159989)
			(xy 354.708101 -243.141982) (xy 354.762944 -243.131852) (xy 354.818678 -243.129815) (xy 354.874115 -243.135915)
			(xy 354.928072 -243.150021) (xy 354.979401 -243.171833) (xy 355.027007 -243.200887) (xy 355.069875 -243.236562)
			(xy 355.107092 -243.278099) (xy 355.137865 -243.324612) (xy 355.161537 -243.375109) (xy 355.177605 -243.428516)
			(xy 355.185725 -243.483692) (xy 355.186234 -243.511578) (xy 355.185725 -243.539464) (xy 355.177605 -243.59464)
			(xy 355.161537 -243.648047) (xy 355.137865 -243.698544) (xy 355.107092 -243.745057) (xy 355.069875 -243.786594)
			(xy 355.027007 -243.822269) (xy 354.979401 -243.851323) (xy 354.928072 -243.873135) (xy 354.874115 -243.887241)
			(xy 354.818678 -243.893341) (xy 354.762944 -243.891304) (xy 354.708101 -243.881174) (xy 354.655317 -243.863167)
			(xy 354.605717 -243.837666) (xy 354.560359 -243.805215) (xy 354.52021 -243.766506) (xy 354.486124 -243.722363)
			(xy 354.458828 -243.673728) (xy 354.438905 -243.621637) (xy 354.426779 -243.5672) (xy 354.422708 -243.511578)
			(xy 334.315242 -243.511578) (xy 334.344295 -243.529309) (xy 334.387163 -243.564984) (xy 334.42438 -243.606521)
			(xy 334.455153 -243.653034) (xy 334.478825 -243.703531) (xy 334.494893 -243.756938) (xy 334.503013 -243.812114)
			(xy 334.503522 -243.84) (xy 334.503013 -243.867886) (xy 334.494893 -243.923062) (xy 334.478825 -243.976469)
			(xy 334.455153 -244.026966) (xy 334.42438 -244.073479) (xy 334.387163 -244.115016) (xy 334.344295 -244.150691)
			(xy 334.296689 -244.179745) (xy 334.24536 -244.201557) (xy 334.191403 -244.215663) (xy 334.135966 -244.221763)
			(xy 334.080232 -244.219726) (xy 334.025389 -244.209596) (xy 333.972605 -244.191589) (xy 333.923005 -244.166088)
			(xy 333.877647 -244.133637) (xy 333.837498 -244.094928) (xy 333.803412 -244.050785) (xy 333.776116 -244.00215)
			(xy 333.756193 -243.950059) (xy 333.744067 -243.895622) (xy 333.739996 -243.84) (xy 333.014886 -243.84)
			(xy 333.063389 -243.845337) (xy 333.117346 -243.859443) (xy 333.168675 -243.881255) (xy 333.216281 -243.910309)
			(xy 333.259149 -243.945984) (xy 333.296366 -243.987521) (xy 333.327139 -244.034034) (xy 333.350811 -244.084531)
			(xy 333.366879 -244.137938) (xy 333.374999 -244.193114) (xy 333.375508 -244.221) (xy 333.374999 -244.248886)
			(xy 333.369795 -244.284246) (xy 335.159094 -244.284246) (xy 335.163165 -244.228624) (xy 335.175291 -244.174187)
			(xy 335.195214 -244.122096) (xy 335.22251 -244.073461) (xy 335.256596 -244.029318) (xy 335.296745 -243.990609)
			(xy 335.342103 -243.958158) (xy 335.391703 -243.932657) (xy 335.444487 -243.91465) (xy 335.49933 -243.90452)
			(xy 335.555064 -243.902483) (xy 335.610501 -243.908583) (xy 335.664458 -243.922689) (xy 335.715787 -243.944501)
			(xy 335.729762 -243.95303) (xy 336.307682 -243.95303) (xy 336.311753 -243.897408) (xy 336.323879 -243.842971)
			(xy 336.343802 -243.79088) (xy 336.371098 -243.742245) (xy 336.405184 -243.698102) (xy 336.445333 -243.659393)
			(xy 336.490691 -243.626942) (xy 336.540291 -243.601441) (xy 336.593075 -243.583434) (xy 336.647918 -243.573304)
			(xy 336.703652 -243.571267) (xy 336.759089 -243.577367) (xy 336.813046 -243.591473) (xy 336.864375 -243.613285)
			(xy 336.911981 -243.642339) (xy 336.954849 -243.678014) (xy 336.992066 -243.719551) (xy 337.022839 -243.766064)
			(xy 337.046511 -243.816561) (xy 337.062579 -243.869968) (xy 337.070699 -243.925144) (xy 337.071208 -243.95303)
			(xy 337.070699 -243.980916) (xy 337.062579 -244.036092) (xy 337.046511 -244.089499) (xy 337.022839 -244.139996)
			(xy 336.992066 -244.186509) (xy 336.954849 -244.228046) (xy 336.93057 -244.248251) (xy 338.073978 -244.248251)
			(xy 338.073978 -244.193749) (xy 338.081734 -244.139801) (xy 338.097089 -244.087506) (xy 338.119731 -244.037929)
			(xy 338.149197 -243.992079) (xy 338.184888 -243.950888) (xy 338.226079 -243.915197) (xy 338.271929 -243.885731)
			(xy 338.321506 -243.863089) (xy 338.373801 -243.847734) (xy 338.427749 -243.839978) (xy 338.455 -243.839492)
			(xy 338.484507 -243.840006) (xy 338.542814 -243.849113) (xy 338.599027 -243.86708) (xy 338.651807 -243.893479)
			(xy 338.699899 -243.927682) (xy 338.742158 -243.968875) (xy 338.760308 -243.992146) (xy 338.766912 -244.000782)
			(xy 338.785962 -244.01145) (xy 338.884006 -244.01907) (xy 338.904072 -244.011958) (xy 338.9122 -244.004338)
			(xy 338.933637 -243.984344) (xy 338.981528 -243.950543) (xy 339.034024 -243.924461) (xy 339.08989 -243.906709)
			(xy 339.147813 -243.897706) (xy 339.177122 -243.89715) (xy 339.204369 -243.897722) (xy 339.258309 -243.90548)
			(xy 339.310595 -243.920835) (xy 339.360164 -243.943475) (xy 339.406006 -243.972939) (xy 339.447189 -244.008626)
			(xy 339.482875 -244.049811) (xy 339.512335 -244.095656) (xy 339.534973 -244.145226) (xy 339.550325 -244.197513)
			(xy 339.55808 -244.251453) (xy 339.55808 -244.305947) (xy 339.550325 -244.359887) (xy 339.534973 -244.412174)
			(xy 339.512335 -244.461744) (xy 339.482875 -244.507589) (xy 339.447189 -244.548774) (xy 339.406006 -244.584461)
			(xy 339.360164 -244.613925) (xy 339.310595 -244.636565) (xy 339.258309 -244.65192) (xy 339.204369 -244.659678)
			(xy 339.177122 -244.660166) (xy 339.147613 -244.659633) (xy 339.089297 -244.65056) (xy 339.033075 -244.632612)
			(xy 338.980288 -244.606217) (xy 338.932198 -244.572006) (xy 338.889952 -244.530795) (xy 338.871814 -244.507512)
			(xy 338.86521 -244.498876) (xy 338.84616 -244.488208) (xy 338.748116 -244.480588) (xy 338.72805 -244.4877)
			(xy 338.719922 -244.49532) (xy 338.69847 -244.515297) (xy 338.650583 -244.549101) (xy 338.598091 -244.575188)
			(xy 338.542228 -244.592943) (xy 338.484308 -244.60195) (xy 338.455 -244.602508) (xy 338.427749 -244.602022)
			(xy 338.373801 -244.594266) (xy 338.321506 -244.578911) (xy 338.271929 -244.556269) (xy 338.226079 -244.526803)
			(xy 338.184888 -244.491112) (xy 338.149197 -244.449921) (xy 338.119731 -244.404071) (xy 338.097089 -244.354494)
			(xy 338.081734 -244.302199) (xy 338.073978 -244.248251) (xy 336.93057 -244.248251) (xy 336.911981 -244.263721)
			(xy 336.864375 -244.292775) (xy 336.813046 -244.314587) (xy 336.759089 -244.328693) (xy 336.703652 -244.334793)
			(xy 336.647918 -244.332756) (xy 336.593075 -244.322626) (xy 336.540291 -244.304619) (xy 336.490691 -244.279118)
			(xy 336.445333 -244.246667) (xy 336.405184 -244.207958) (xy 336.371098 -244.163815) (xy 336.343802 -244.11518)
			(xy 336.323879 -244.063089) (xy 336.311753 -244.008652) (xy 336.307682 -243.95303) (xy 335.729762 -243.95303)
			(xy 335.763393 -243.973555) (xy 335.806261 -244.00923) (xy 335.843478 -244.050767) (xy 335.874251 -244.09728)
			(xy 335.897923 -244.147777) (xy 335.913991 -244.201184) (xy 335.922111 -244.25636) (xy 335.92262 -244.284246)
			(xy 335.922111 -244.312132) (xy 335.913991 -244.367308) (xy 335.897923 -244.420715) (xy 335.874251 -244.471212)
			(xy 335.843478 -244.517725) (xy 335.806261 -244.559262) (xy 335.763393 -244.594937) (xy 335.715787 -244.623991)
			(xy 335.664458 -244.645803) (xy 335.610501 -244.659909) (xy 335.555064 -244.666009) (xy 335.49933 -244.663972)
			(xy 335.444487 -244.653842) (xy 335.391703 -244.635835) (xy 335.342103 -244.610334) (xy 335.296745 -244.577883)
			(xy 335.256596 -244.539174) (xy 335.22251 -244.495031) (xy 335.195214 -244.446396) (xy 335.175291 -244.394305)
			(xy 335.163165 -244.339868) (xy 335.159094 -244.284246) (xy 333.369795 -244.284246) (xy 333.366879 -244.304062)
			(xy 333.350811 -244.357469) (xy 333.327139 -244.407966) (xy 333.296366 -244.454479) (xy 333.259149 -244.496016)
			(xy 333.216281 -244.531691) (xy 333.168675 -244.560745) (xy 333.117346 -244.582557) (xy 333.063389 -244.596663)
			(xy 333.007952 -244.602763) (xy 332.952218 -244.600726) (xy 332.897375 -244.590596) (xy 332.844591 -244.572589)
			(xy 332.794991 -244.547088) (xy 332.749633 -244.514637) (xy 332.709484 -244.475928) (xy 332.675398 -244.431785)
			(xy 332.648102 -244.38315) (xy 332.628179 -244.331059) (xy 332.616053 -244.276622) (xy 332.611982 -244.221)
			(xy 332.261979 -244.221) (xy 332.243149 -244.242016) (xy 332.200281 -244.277691) (xy 332.152675 -244.306745)
			(xy 332.101346 -244.328557) (xy 332.047389 -244.342663) (xy 331.991952 -244.348763) (xy 331.936218 -244.346726)
			(xy 331.881375 -244.336596) (xy 331.828591 -244.318589) (xy 331.778991 -244.293088) (xy 331.733633 -244.260637)
			(xy 331.693484 -244.221928) (xy 331.659398 -244.177785) (xy 331.632102 -244.12915) (xy 331.612179 -244.077059)
			(xy 331.600053 -244.022622) (xy 331.595982 -243.967) (xy 331.095858 -243.967) (xy 331.095858 -245.369149)
			(xy 355.74328 -245.369149) (xy 355.74328 -245.314651) (xy 355.751035 -245.260707) (xy 355.766388 -245.208416)
			(xy 355.789026 -245.158842) (xy 355.818488 -245.112994) (xy 355.854174 -245.071805) (xy 355.895359 -245.036114)
			(xy 355.941204 -245.006647) (xy 355.990775 -244.984003) (xy 356.043064 -244.968644) (xy 356.097007 -244.960883)
			(xy 356.124256 -244.960394) (xy 356.153627 -244.960912) (xy 356.211677 -244.969911) (xy 356.26766 -244.987704)
			(xy 356.320253 -245.013869) (xy 356.368213 -245.047789) (xy 356.389686 -245.067836) (xy 356.400835 -245.077816)
			(xy 356.42746 -245.091436) (xy 356.456887 -245.096767) (xy 356.486598 -245.093353) (xy 356.514049 -245.081487)
			(xy 356.536892 -245.062183) (xy 356.553169 -245.037095) (xy 356.557834 -245.022878) (xy 356.565924 -244.996755)
			(xy 356.588449 -244.946926) (xy 356.617858 -244.900824) (xy 356.653548 -244.859393) (xy 356.694788 -244.823482)
			(xy 356.740732 -244.793827) (xy 356.790439 -244.771036) (xy 356.842892 -244.755575) (xy 356.897014 -244.747761)
			(xy 356.924356 -244.747288) (xy 356.951611 -244.747756) (xy 357.005566 -244.755508) (xy 357.057868 -244.77086)
			(xy 357.107453 -244.7935) (xy 357.153312 -244.822966) (xy 357.194509 -244.85866) (xy 357.230207 -244.899853)
			(xy 357.259679 -244.945708) (xy 357.282324 -244.99529) (xy 357.297683 -245.047591) (xy 357.305441 -245.101545)
			(xy 357.305441 -245.156055) (xy 357.297683 -245.210009) (xy 357.282324 -245.26231) (xy 357.259679 -245.311892)
			(xy 357.230207 -245.357747) (xy 357.194509 -245.39894) (xy 357.153312 -245.434634) (xy 357.107453 -245.4641)
			(xy 357.057868 -245.48674) (xy 357.005566 -245.502092) (xy 356.951611 -245.509844) (xy 356.924356 -245.510304)
			(xy 356.894985 -245.50978) (xy 356.836936 -245.500782) (xy 356.780953 -245.482991) (xy 356.728359 -245.456827)
			(xy 356.680399 -245.422908) (xy 356.658926 -245.402862) (xy 356.647765 -245.392897) (xy 356.621143 -245.379277)
			(xy 356.591719 -245.373944) (xy 356.562011 -245.377356) (xy 356.534561 -245.389219) (xy 356.51172 -245.40852)
			(xy 356.495443 -245.433605) (xy 356.490778 -245.44782) (xy 356.482676 -245.473939) (xy 356.460152 -245.523767)
			(xy 356.430744 -245.569869) (xy 356.395056 -245.6113) (xy 356.353818 -245.647211) (xy 356.307875 -245.676867)
			(xy 356.258169 -245.699659) (xy 356.205718 -245.715121) (xy 356.151597 -245.722936) (xy 356.124256 -245.72341)
			(xy 356.097007 -245.722917) (xy 356.043064 -245.715156) (xy 355.990775 -245.699797) (xy 355.941204 -245.677153)
			(xy 355.895359 -245.647686) (xy 355.854174 -245.611995) (xy 355.818488 -245.570806) (xy 355.789026 -245.524958)
			(xy 355.766388 -245.475384) (xy 355.751035 -245.423093) (xy 355.74328 -245.369149) (xy 331.095858 -245.369149)
			(xy 331.095858 -245.927118) (xy 331.096332 -245.935996) (xy 331.102568 -245.95263) (xy 331.10805 -245.95963)
			(xy 331.13726 -245.990872) (xy 331.13726 -245.99138) (xy 331.15123 -246.005858) (xy 331.16139 -246.01424)
			(xy 331.161898 -246.01424) (xy 331.167232 -246.017288) (xy 331.167486 -246.017288) (xy 331.1906 -246.027956)
			(xy 331.19949 -246.028718) (xy 331.226802 -246.031609) (xy 331.280253 -246.044231) (xy 331.331343 -246.064382)
			(xy 331.379018 -246.091646) (xy 331.422295 -246.125461) (xy 331.460279 -246.165128) (xy 331.476604 -246.187214)
			(xy 331.482954 -246.196104) (xy 331.48905 -246.201184) (xy 331.495423 -246.206014) (xy 331.510301 -246.211846)
			(xy 331.51826 -246.212614) (xy 331.518768 -246.212614) (xy 331.522832 -246.21236) (xy 331.611224 -246.209566)
			(xy 331.616777 -246.208883) (xy 331.627411 -246.205417) (xy 331.632306 -246.202708) (xy 331.637894 -246.199406)
			(xy 331.646784 -246.190516) (xy 331.650086 -246.184928) (xy 331.664936 -246.160953) (xy 331.700587 -246.117256)
			(xy 331.742284 -246.079285) (xy 331.789117 -246.047868) (xy 331.840066 -246.023689) (xy 331.89402 -246.007277)
			(xy 331.949802 -245.998987) (xy 331.978 -245.998492) (xy 332.005251 -245.998978) (xy 332.059199 -246.006734)
			(xy 332.111494 -246.022089) (xy 332.161071 -246.044731) (xy 332.206921 -246.074197) (xy 332.248112 -246.109888)
			(xy 332.283803 -246.151079) (xy 332.313269 -246.196929) (xy 332.335911 -246.246506) (xy 332.351266 -246.298801)
			(xy 332.359022 -246.352749) (xy 332.359022 -246.407251) (xy 332.358412 -246.411496) (xy 332.611982 -246.411496)
			(xy 332.616053 -246.355874) (xy 332.628179 -246.301437) (xy 332.648102 -246.249346) (xy 332.675398 -246.200711)
			(xy 332.709484 -246.156568) (xy 332.749633 -246.117859) (xy 332.794991 -246.085408) (xy 332.844591 -246.059907)
			(xy 332.897375 -246.0419) (xy 332.952218 -246.03177) (xy 333.007952 -246.029733) (xy 333.063389 -246.035833)
			(xy 333.117346 -246.049939) (xy 333.168675 -246.071751) (xy 333.216281 -246.100805) (xy 333.259149 -246.13648)
			(xy 333.296366 -246.178017) (xy 333.327139 -246.22453) (xy 333.340485 -246.253) (xy 336.675982 -246.253)
			(xy 336.680053 -246.197378) (xy 336.692179 -246.142941) (xy 336.712102 -246.09085) (xy 336.739398 -246.042215)
			(xy 336.773484 -245.998072) (xy 336.813633 -245.959363) (xy 336.858991 -245.926912) (xy 336.908591 -245.901411)
			(xy 336.961375 -245.883404) (xy 337.016218 -245.873274) (xy 337.071952 -245.871237) (xy 337.127389 -245.877337)
			(xy 337.181346 -245.891443) (xy 337.232675 -245.913255) (xy 337.280281 -245.942309) (xy 337.323149 -245.977984)
			(xy 337.360366 -246.019521) (xy 337.391139 -246.066034) (xy 337.414811 -246.116531) (xy 337.430879 -246.169938)
			(xy 337.438999 -246.225114) (xy 337.439508 -246.253) (xy 337.945982 -246.253) (xy 337.950053 -246.197378)
			(xy 337.962179 -246.142941) (xy 337.982102 -246.09085) (xy 338.009398 -246.042215) (xy 338.043484 -245.998072)
			(xy 338.083633 -245.959363) (xy 338.128991 -245.926912) (xy 338.178591 -245.901411) (xy 338.231375 -245.883404)
			(xy 338.286218 -245.873274) (xy 338.341952 -245.871237) (xy 338.397389 -245.877337) (xy 338.451346 -245.891443)
			(xy 338.502675 -245.913255) (xy 338.550281 -245.942309) (xy 338.593149 -245.977984) (xy 338.630366 -246.019521)
			(xy 338.661139 -246.066034) (xy 338.684811 -246.116531) (xy 338.700879 -246.169938) (xy 338.708999 -246.225114)
			(xy 338.709508 -246.253) (xy 338.708999 -246.280886) (xy 338.700879 -246.336062) (xy 338.684811 -246.389469)
			(xy 338.661139 -246.439966) (xy 338.630366 -246.486479) (xy 338.593149 -246.528016) (xy 338.550281 -246.563691)
			(xy 338.502675 -246.592745) (xy 338.451346 -246.614557) (xy 338.397389 -246.628663) (xy 338.341952 -246.634763)
			(xy 338.286218 -246.632726) (xy 338.231375 -246.622596) (xy 338.178591 -246.604589) (xy 338.128991 -246.579088)
			(xy 338.083633 -246.546637) (xy 338.043484 -246.507928) (xy 338.009398 -246.463785) (xy 337.982102 -246.41515)
			(xy 337.962179 -246.363059) (xy 337.950053 -246.308622) (xy 337.945982 -246.253) (xy 337.439508 -246.253)
			(xy 337.438999 -246.280886) (xy 337.430879 -246.336062) (xy 337.414811 -246.389469) (xy 337.391139 -246.439966)
			(xy 337.360366 -246.486479) (xy 337.323149 -246.528016) (xy 337.280281 -246.563691) (xy 337.232675 -246.592745)
			(xy 337.181346 -246.614557) (xy 337.127389 -246.628663) (xy 337.071952 -246.634763) (xy 337.016218 -246.632726)
			(xy 336.961375 -246.622596) (xy 336.908591 -246.604589) (xy 336.858991 -246.579088) (xy 336.813633 -246.546637)
			(xy 336.773484 -246.507928) (xy 336.739398 -246.463785) (xy 336.712102 -246.41515) (xy 336.692179 -246.363059)
			(xy 336.680053 -246.308622) (xy 336.675982 -246.253) (xy 333.340485 -246.253) (xy 333.350811 -246.275027)
			(xy 333.366879 -246.328434) (xy 333.374999 -246.38361) (xy 333.375508 -246.411496) (xy 333.374999 -246.439382)
			(xy 333.366879 -246.494558) (xy 333.350811 -246.547965) (xy 333.327139 -246.598462) (xy 333.296366 -246.644975)
			(xy 333.259149 -246.686512) (xy 333.216281 -246.722187) (xy 333.168675 -246.751241) (xy 333.117346 -246.773053)
			(xy 333.063389 -246.787159) (xy 333.007952 -246.793259) (xy 332.952218 -246.791222) (xy 332.897375 -246.781092)
			(xy 332.844591 -246.763085) (xy 332.794991 -246.737584) (xy 332.749633 -246.705133) (xy 332.709484 -246.666424)
			(xy 332.675398 -246.622281) (xy 332.648102 -246.573646) (xy 332.628179 -246.521555) (xy 332.616053 -246.467118)
			(xy 332.611982 -246.411496) (xy 332.358412 -246.411496) (xy 332.351266 -246.461199) (xy 332.335911 -246.513494)
			(xy 332.313269 -246.563071) (xy 332.283803 -246.608921) (xy 332.248112 -246.650112) (xy 332.206921 -246.685803)
			(xy 332.161071 -246.715269) (xy 332.111494 -246.737911) (xy 332.059199 -246.753266) (xy 332.005251 -246.761022)
			(xy 331.978 -246.761508) (xy 331.951748 -246.761071) (xy 331.899741 -246.753875) (xy 331.84921 -246.739619)
			(xy 331.80111 -246.718572) (xy 331.756348 -246.691132) (xy 331.71577 -246.657815) (xy 331.680141 -246.619251)
			(xy 331.664818 -246.597932) (xy 331.661008 -246.592344) (xy 331.656182 -246.58828) (xy 331.648732 -246.582428)
			(xy 331.630859 -246.576184) (xy 331.621384 -246.576088) (xy 331.526896 -246.579136) (xy 331.523086 -246.57939)
			(xy 331.51191 -246.585994) (xy 331.50175 -246.593868) (xy 331.497432 -246.598186) (xy 331.49413 -246.603774)
			(xy 331.480239 -246.626248) (xy 331.447223 -246.667494) (xy 331.408831 -246.70379) (xy 331.365799 -246.734442)
			(xy 331.31895 -246.758865) (xy 331.269179 -246.77659) (xy 331.217439 -246.787279) (xy 331.191108 -246.789448)
			(xy 331.190854 -246.789448) (xy 331.180948 -246.79021) (xy 331.17282 -246.79402) (xy 331.168448 -246.796145)
			(xy 331.160522 -246.801771) (xy 331.157072 -246.805196) (xy 331.141324 -246.822214) (xy 331.10805 -246.857774)
			(xy 331.102489 -246.864803) (xy 331.096234 -246.881586) (xy 331.095858 -246.89054) (xy 331.095858 -248.206768)
			(xy 360.157266 -248.206768) (xy 360.161337 -248.151146) (xy 360.173463 -248.096709) (xy 360.193386 -248.044618)
			(xy 360.220682 -247.995983) (xy 360.254768 -247.95184) (xy 360.294917 -247.913131) (xy 360.340275 -247.88068)
			(xy 360.389875 -247.855179) (xy 360.442659 -247.837172) (xy 360.497502 -247.827042) (xy 360.553236 -247.825005)
			(xy 360.608673 -247.831105) (xy 360.66263 -247.845211) (xy 360.713959 -247.867023) (xy 360.761565 -247.896077)
			(xy 360.804433 -247.931752) (xy 360.84165 -247.973289) (xy 360.872423 -248.019802) (xy 360.896095 -248.070299)
			(xy 360.912163 -248.123706) (xy 360.920283 -248.178882) (xy 360.920792 -248.206768) (xy 360.920283 -248.234654)
			(xy 360.912163 -248.28983) (xy 360.896095 -248.343237) (xy 360.872423 -248.393734) (xy 360.84165 -248.440247)
			(xy 360.804433 -248.481784) (xy 360.761565 -248.517459) (xy 360.713959 -248.546513) (xy 360.66263 -248.568325)
			(xy 360.608673 -248.582431) (xy 360.553236 -248.588531) (xy 360.497502 -248.586494) (xy 360.442659 -248.576364)
			(xy 360.389875 -248.558357) (xy 360.340275 -248.532856) (xy 360.294917 -248.500405) (xy 360.254768 -248.461696)
			(xy 360.220682 -248.417553) (xy 360.193386 -248.368918) (xy 360.173463 -248.316827) (xy 360.161337 -248.26239)
			(xy 360.157266 -248.206768) (xy 331.095858 -248.206768) (xy 331.095858 -248.88698) (xy 331.77556 -248.88698)
			(xy 331.779631 -248.831358) (xy 331.791757 -248.776921) (xy 331.81168 -248.72483) (xy 331.838976 -248.676195)
			(xy 331.873062 -248.632052) (xy 331.913211 -248.593343) (xy 331.958569 -248.560892) (xy 332.008169 -248.535391)
			(xy 332.060953 -248.517384) (xy 332.115796 -248.507254) (xy 332.17153 -248.505217) (xy 332.226967 -248.511317)
			(xy 332.280924 -248.525423) (xy 332.332253 -248.547235) (xy 332.379859 -248.576289) (xy 332.422727 -248.611964)
			(xy 332.459944 -248.653501) (xy 332.490717 -248.700014) (xy 332.514389 -248.750511) (xy 332.530457 -248.803918)
			(xy 332.538577 -248.859094) (xy 332.539086 -248.88698) (xy 332.538577 -248.914866) (xy 332.530457 -248.970042)
			(xy 332.514389 -249.023449) (xy 332.490717 -249.073946) (xy 332.459944 -249.120459) (xy 332.422727 -249.161996)
			(xy 332.379859 -249.197671) (xy 332.332253 -249.226725) (xy 332.280924 -249.248537) (xy 332.226967 -249.262643)
			(xy 332.17153 -249.268743) (xy 332.115796 -249.266706) (xy 332.060953 -249.256576) (xy 332.008169 -249.238569)
			(xy 331.958569 -249.213068) (xy 331.913211 -249.180617) (xy 331.873062 -249.141908) (xy 331.838976 -249.097765)
			(xy 331.81168 -249.04913) (xy 331.791757 -248.997039) (xy 331.779631 -248.942602) (xy 331.77556 -248.88698)
			(xy 331.095858 -248.88698) (xy 331.095858 -250.685554) (xy 331.738476 -250.685554) (xy 331.742547 -250.629932)
			(xy 331.754673 -250.575495) (xy 331.774596 -250.523404) (xy 331.801892 -250.474769) (xy 331.835978 -250.430626)
			(xy 331.876127 -250.391917) (xy 331.921485 -250.359466) (xy 331.971085 -250.333965) (xy 332.023869 -250.315958)
			(xy 332.078712 -250.305828) (xy 332.134446 -250.303791) (xy 332.189883 -250.309891) (xy 332.24384 -250.323997)
			(xy 332.295169 -250.345809) (xy 332.342775 -250.374863) (xy 332.385643 -250.410538) (xy 332.42286 -250.452075)
			(xy 332.453633 -250.498588) (xy 332.477305 -250.549085) (xy 332.493373 -250.602492) (xy 332.501493 -250.657668)
			(xy 332.502002 -250.685554) (xy 332.501493 -250.71344) (xy 332.493373 -250.768616) (xy 332.477305 -250.822023)
			(xy 332.453633 -250.87252) (xy 332.42286 -250.919033) (xy 332.385643 -250.96057) (xy 332.342775 -250.996245)
			(xy 332.295169 -251.025299) (xy 332.24384 -251.047111) (xy 332.189883 -251.061217) (xy 332.134446 -251.067317)
			(xy 332.078712 -251.06528) (xy 332.023869 -251.05515) (xy 331.971085 -251.037143) (xy 331.921485 -251.011642)
			(xy 331.876127 -250.979191) (xy 331.835978 -250.940482) (xy 331.801892 -250.896339) (xy 331.774596 -250.847704)
			(xy 331.754673 -250.795613) (xy 331.742547 -250.741176) (xy 331.738476 -250.685554) (xy 331.095858 -250.685554)
			(xy 331.095858 -253.207012) (xy 333.137764 -253.207012) (xy 333.137764 -250.854718) (xy 333.138182 -250.844648)
			(xy 333.145906 -250.826049) (xy 333.15275 -250.81865) (xy 333.490824 -250.48083) (xy 333.498225 -250.473991)
			(xy 333.516823 -250.46627) (xy 333.526892 -250.465844) (xy 334.824578 -250.465844) (xy 334.834647 -250.466269)
			(xy 334.853246 -250.473989) (xy 334.860646 -250.48083) (xy 335.068418 -250.688602) (xy 335.075254 -250.696005)
			(xy 335.082975 -250.714602) (xy 335.083404 -250.72467) (xy 335.083404 -250.94438) (xy 335.0839 -250.955276)
			(xy 335.092841 -250.975147) (xy 335.100676 -250.982734) (xy 335.158334 -251.033026) (xy 335.166847 -251.039793)
			(xy 335.18763 -251.04612) (xy 335.198466 -251.045218) (xy 335.210791 -251.043681) (xy 335.235576 -251.042031)
			(xy 335.247996 -251.041916) (xy 335.248758 -251.041916) (xy 335.282236 -251.042651) (xy 335.348156 -251.054396)
			(xy 335.379822 -251.065284) (xy 335.390998 -251.069602) (xy 335.41462 -251.067062) (xy 335.503012 -251.01042)
			(xy 335.515204 -250.9901) (xy 335.51622 -250.978162) (xy 335.51895 -250.949813) (xy 335.5318 -250.89433)
			(xy 335.552758 -250.841374) (xy 335.581357 -250.792124) (xy 335.616963 -250.747675) (xy 335.658783 -250.709015)
			(xy 335.705886 -250.677003) (xy 335.757227 -250.652353) (xy 335.811662 -250.635611) (xy 335.867982 -250.62715)
			(xy 335.896458 -250.626626) (xy 335.9253 -250.627162) (xy 335.982323 -250.635868) (xy 336.037386 -250.653058)
			(xy 336.089234 -250.67834) (xy 336.136686 -250.711139) (xy 336.17866 -250.750706) (xy 336.214201 -250.79614)
			(xy 336.242498 -250.846406) (xy 336.262907 -250.900359) (xy 336.274963 -250.956768) (xy 336.277204 -250.985528)
			(xy 336.277204 -250.985782) (xy 336.278455 -250.996649) (xy 336.288862 -251.015867) (xy 336.29727 -251.022866)
			(xy 336.368136 -251.07646) (xy 336.389726 -251.081286) (xy 336.400648 -251.078746) (xy 336.420836 -251.074569)
			(xy 336.461822 -251.070119) (xy 336.482436 -251.069856) (xy 336.48269 -251.069856) (xy 336.51508 -251.070566)
			(xy 336.578925 -251.081543) (xy 336.60969 -251.0917) (xy 336.62112 -251.095764) (xy 336.644488 -251.092716)
			(xy 336.732372 -251.033788) (xy 336.74431 -251.01296) (xy 336.744818 -251.001022) (xy 336.746881 -250.972103)
			(xy 336.758612 -250.915328) (xy 336.7788 -250.860981) (xy 336.806978 -250.810316) (xy 336.842498 -250.764497)
			(xy 336.884543 -250.72458) (xy 336.932143 -250.691485) (xy 336.984203 -250.665974) (xy 337.039523 -250.648634)
			(xy 337.096831 -250.639864) (xy 337.125818 -250.639326) (xy 337.152086 -250.639759) (xy 337.204123 -250.646981)
			(xy 337.254679 -250.661271) (xy 337.302796 -250.682359) (xy 337.347567 -250.709848) (xy 337.368134 -250.726194)
			(xy 337.375676 -250.73181) (xy 337.393528 -250.737669) (xy 337.402932 -250.737624) (xy 337.471766 -250.733814)
			(xy 337.481079 -250.732833) (xy 337.498144 -250.725162) (xy 337.50504 -250.718828) (xy 337.505294 -250.718574)
			(xy 337.526954 -250.697269) (xy 337.575808 -250.661154) (xy 337.629769 -250.633239) (xy 337.687472 -250.61423)
			(xy 337.747459 -250.604606) (xy 337.777836 -250.60402) (xy 337.778344 -250.60402) (xy 337.807867 -250.604593)
			(xy 337.866202 -250.613728) (xy 337.922434 -250.631743) (xy 337.975218 -250.658207) (xy 338.023294 -250.692487)
			(xy 338.04479 -250.712732) (xy 338.051648 -250.71959) (xy 338.06892 -250.726956) (xy 338.156804 -250.730004)
			(xy 338.174584 -250.723654) (xy 338.18195 -250.717304) (xy 338.202818 -250.70001) (xy 338.248496 -250.670844)
			(xy 338.297844 -250.648439) (xy 338.349868 -250.633248) (xy 338.403518 -250.625577) (xy 338.430616 -250.625102)
			(xy 338.457868 -250.625563) (xy 338.511817 -250.633322) (xy 338.564113 -250.64868) (xy 338.613691 -250.671323)
			(xy 338.659542 -250.700792) (xy 338.700732 -250.736486) (xy 338.736423 -250.777679) (xy 338.765889 -250.823532)
			(xy 338.78853 -250.873111) (xy 338.803884 -250.925408) (xy 338.811639 -250.979358) (xy 338.812124 -251.00661)
			(xy 338.811938 -251.023272) (xy 338.809014 -251.056467) (xy 338.806282 -251.072904) (xy 338.806282 -251.073158)
			(xy 338.805101 -251.081932) (xy 338.80818 -251.099353) (xy 338.817026 -251.114674) (xy 338.823554 -251.120656)
			(xy 338.90077 -251.186188) (xy 338.92744 -251.191014) (xy 338.94014 -251.186442) (xy 338.970851 -251.176359)
			(xy 339.034568 -251.165508) (xy 339.066886 -251.164852) (xy 339.091965 -251.165232) (xy 339.14169 -251.1718)
			(xy 339.190131 -251.18481) (xy 339.213444 -251.194062) (xy 339.222011 -251.197267) (xy 339.240269 -251.198052)
			(xy 339.257636 -251.192366) (xy 339.265006 -251.18695) (xy 339.34527 -251.122434) (xy 339.354922 -251.09678)
			(xy 339.352636 -251.083064) (xy 339.350023 -251.066999) (xy 339.347228 -251.034569) (xy 339.347048 -251.018294)
			(xy 339.347048 -251.017786) (xy 339.34757 -250.990534) (xy 339.355329 -250.936584) (xy 339.370687 -250.884288)
			(xy 339.393331 -250.83471) (xy 339.422801 -250.788859) (xy 339.458496 -250.747669) (xy 339.499689 -250.711978)
			(xy 339.545543 -250.682513) (xy 339.595124 -250.659874) (xy 339.647421 -250.644521) (xy 339.701372 -250.636768)
			(xy 339.755876 -250.636771) (xy 339.809826 -250.644531) (xy 339.862121 -250.659891) (xy 339.911699 -250.682536)
			(xy 339.957549 -250.712007) (xy 339.998738 -250.747703) (xy 340.034428 -250.788898) (xy 340.063892 -250.834752)
			(xy 340.08653 -250.884333) (xy 340.101881 -250.936631) (xy 340.109633 -250.990582) (xy 340.109628 -251.045086)
			(xy 340.101866 -251.099035) (xy 340.086506 -251.151331) (xy 340.063859 -251.200908) (xy 340.034387 -251.246757)
			(xy 339.99869 -251.287945) (xy 339.957494 -251.323634) (xy 339.911639 -251.353096) (xy 339.862058 -251.375733)
			(xy 339.809759 -251.391083) (xy 339.755808 -251.398834) (xy 339.728556 -251.399294) (xy 339.728302 -251.399294)
			(xy 339.703268 -251.398866) (xy 339.653632 -251.392294) (xy 339.605277 -251.379302) (xy 339.581998 -251.370084)
			(xy 339.573444 -251.366842) (xy 339.555178 -251.366076) (xy 339.537807 -251.371775) (xy 339.530436 -251.377196)
			(xy 339.450172 -251.441712) (xy 339.44052 -251.467366) (xy 339.442806 -251.481082) (xy 339.445412 -251.497148)
			(xy 339.448212 -251.529577) (xy 339.448394 -251.545852) (xy 339.448394 -251.54636) (xy 339.447908 -251.573611)
			(xy 339.440152 -251.627559) (xy 339.424797 -251.679854) (xy 339.402155 -251.729431) (xy 339.372689 -251.775281)
			(xy 339.336998 -251.816472) (xy 339.295807 -251.852163) (xy 339.249957 -251.881629) (xy 339.20038 -251.904271)
			(xy 339.148085 -251.919626) (xy 339.094137 -251.927382) (xy 339.039635 -251.927382) (xy 338.985687 -251.919626)
			(xy 338.933392 -251.904271) (xy 338.883815 -251.881629) (xy 338.837965 -251.852163) (xy 338.796774 -251.816472)
			(xy 338.761083 -251.775281) (xy 338.731617 -251.729431) (xy 338.708975 -251.679854) (xy 338.69362 -251.627559)
			(xy 338.685864 -251.573611) (xy 338.685378 -251.54636) (xy 338.68556 -251.529698) (xy 338.688487 -251.496503)
			(xy 338.69122 -251.480066) (xy 338.69122 -251.479812) (xy 338.692424 -251.47104) (xy 338.689335 -251.453616)
			(xy 338.68048 -251.438295) (xy 338.673948 -251.432314) (xy 338.596732 -251.366782) (xy 338.570062 -251.361956)
			(xy 338.557362 -251.366528) (xy 338.52665 -251.376609) (xy 338.462934 -251.387461) (xy 338.430616 -251.388118)
			(xy 338.401041 -251.3876) (xy 338.342595 -251.378505) (xy 338.286253 -251.360499) (xy 338.233365 -251.334014)
			(xy 338.185197 -251.299684) (xy 338.163662 -251.279406) (xy 338.156804 -251.272548) (xy 338.139532 -251.265182)
			(xy 338.051648 -251.262134) (xy 338.033868 -251.268484) (xy 338.026502 -251.274834) (xy 338.015692 -251.283947)
			(xy 337.992936 -251.300729) (xy 337.981036 -251.308362) (xy 337.980782 -251.308616) (xy 337.971388 -251.315113)
			(xy 337.959228 -251.334423) (xy 337.957414 -251.3457) (xy 337.947508 -251.436378) (xy 337.954874 -251.457968)
			(xy 337.963256 -251.46635) (xy 337.984125 -251.487933) (xy 338.019455 -251.536473) (xy 338.046743 -251.589948)
			(xy 338.065315 -251.647039) (xy 338.074713 -251.706334) (xy 338.07527 -251.736352) (xy 338.074784 -251.763603)
			(xy 338.067028 -251.817551) (xy 338.051673 -251.869846) (xy 338.029031 -251.919423) (xy 337.999565 -251.965273)
			(xy 337.963874 -252.006464) (xy 337.922683 -252.042155) (xy 337.876833 -252.071621) (xy 337.827256 -252.094263)
			(xy 337.774961 -252.109618) (xy 337.721013 -252.117374) (xy 337.666511 -252.117374) (xy 337.612563 -252.109618)
			(xy 337.560268 -252.094263) (xy 337.510691 -252.071621) (xy 337.464841 -252.042155) (xy 337.42365 -252.006464)
			(xy 337.387959 -251.965273) (xy 337.358493 -251.919423) (xy 337.335851 -251.869846) (xy 337.320496 -251.817551)
			(xy 337.31274 -251.763603) (xy 337.312254 -251.736352) (xy 337.312707 -251.710009) (xy 337.319946 -251.657821)
			(xy 337.334292 -251.607126) (xy 337.355475 -251.558884) (xy 337.38309 -251.514015) (xy 337.416614 -251.473369)
			(xy 337.455409 -251.43772) (xy 337.498738 -251.407745) (xy 337.522058 -251.395484) (xy 337.533074 -251.389163)
			(xy 337.547609 -251.368379) (xy 337.549744 -251.35586) (xy 337.556348 -251.29617) (xy 337.53552 -251.280168)
			(xy 337.527965 -251.274571) (xy 337.510123 -251.268702) (xy 337.500722 -251.268738) (xy 337.431888 -251.272548)
			(xy 337.422568 -251.273491) (xy 337.405505 -251.281187) (xy 337.398614 -251.287534) (xy 337.39836 -251.287788)
			(xy 337.376669 -251.30906) (xy 337.327824 -251.345181) (xy 337.273871 -251.373103) (xy 337.216174 -251.39212)
			(xy 337.156193 -251.401752) (xy 337.125818 -251.402342) (xy 337.093428 -251.40163) (xy 337.029583 -251.390654)
			(xy 336.998818 -251.380498) (xy 336.987388 -251.376434) (xy 336.96402 -251.379482) (xy 336.876136 -251.43841)
			(xy 336.864198 -251.459238) (xy 336.86369 -251.471176) (xy 336.861617 -251.500094) (xy 336.849887 -251.556869)
			(xy 336.8297 -251.611214) (xy 336.801523 -251.66188) (xy 336.766003 -251.707698) (xy 336.72396 -251.747615)
			(xy 336.676361 -251.78071) (xy 336.624303 -251.806221) (xy 336.568983 -251.823562) (xy 336.511677 -251.832333)
			(xy 336.48269 -251.832872) (xy 336.453847 -251.832386) (xy 336.396822 -251.823672) (xy 336.341758 -251.806475)
			(xy 336.289909 -251.781186) (xy 336.242458 -251.748382) (xy 336.200484 -251.70881) (xy 336.164944 -251.663371)
			(xy 336.136648 -251.613101) (xy 336.11624 -251.559144) (xy 336.104185 -251.502731) (xy 336.101944 -251.47397)
			(xy 336.101944 -251.473716) (xy 336.100711 -251.462845) (xy 336.090293 -251.443627) (xy 336.081878 -251.436632)
			(xy 336.011012 -251.383038) (xy 335.989422 -251.378212) (xy 335.9785 -251.380752) (xy 335.958311 -251.384921)
			(xy 335.917325 -251.389376) (xy 335.896712 -251.389642) (xy 335.896458 -251.389642) (xy 335.862788 -251.388966)
			(xy 335.796482 -251.377215) (xy 335.764632 -251.366274) (xy 335.753456 -251.361956) (xy 335.729834 -251.364496)
			(xy 335.641442 -251.421138) (xy 335.62925 -251.441458) (xy 335.628234 -251.453396) (xy 335.625838 -251.478911)
			(xy 335.615021 -251.529006) (xy 335.597598 -251.577202) (xy 335.573881 -251.622633) (xy 335.544298 -251.664481)
			(xy 335.527142 -251.68352) (xy 335.521008 -251.690752) (xy 335.513969 -251.708342) (xy 335.513426 -251.71781)
			(xy 335.513426 -251.74829) (xy 335.513755 -251.758401) (xy 335.521348 -251.777133) (xy 335.528158 -251.784612)
			(xy 340.454996 -256.71145) (xy 340.462409 -256.718274) (xy 340.480998 -256.726005) (xy 340.491064 -256.726436)
			(xy 345.977972 -256.726436) (xy 345.988041 -256.726867) (xy 346.006639 -256.734583) (xy 346.01404 -256.741422)
			(xy 346.598494 -257.325876) (xy 346.605315 -257.333291) (xy 346.613046 -257.351879) (xy 346.61348 -257.361944)
			(xy 346.61348 -259.025136) (xy 346.613079 -259.035208) (xy 346.605342 -259.053806) (xy 346.598494 -259.061204)
			(xy 346.561664 -259.098034) (xy 346.555356 -259.104813) (xy 346.547695 -259.121656) (xy 346.546516 -259.140121)
			(xy 346.551973 -259.157802) (xy 346.557346 -259.165344) (xy 346.565474 -259.175758) (xy 346.573012 -259.184441)
			(xy 346.593631 -259.194557) (xy 346.616597 -259.194688) (xy 346.627196 -259.190236) (xy 346.652738 -259.178747)
			(xy 346.706347 -259.162548) (xy 346.761754 -259.154386) (xy 346.789756 -259.153914) (xy 346.817009 -259.154396)
			(xy 346.87096 -259.162148) (xy 346.923259 -259.177499) (xy 346.97284 -259.200138) (xy 347.018695 -259.229604)
			(xy 347.059889 -259.265296) (xy 347.095583 -259.306488) (xy 347.125051 -259.35234) (xy 347.147693 -259.40192)
			(xy 347.163047 -259.454218) (xy 347.170802 -259.508169) (xy 347.171264 -259.535422) (xy 347.171264 -259.55244)
			(xy 347.188028 -259.578094) (xy 347.28912 -259.620258) (xy 347.298599 -259.623693) (xy 347.318743 -259.623665)
			(xy 347.33734 -259.615921) (xy 347.344746 -259.609082) (xy 347.693234 -259.26034) (xy 347.700054 -259.252924)
			(xy 347.707784 -259.234337) (xy 347.70822 -259.224272) (xy 347.70822 -258.156456) (xy 347.707839 -258.146381)
			(xy 347.70009 -258.127783) (xy 347.693234 -258.120388) (xy 346.989146 -257.4163) (xy 346.96716 -257.393554)
			(xy 346.928657 -257.34336) (xy 346.897032 -257.288571) (xy 346.872826 -257.230124) (xy 346.856451 -257.169019)
			(xy 346.848189 -257.1063) (xy 346.847668 -257.07467) (xy 346.847668 -255.68402) (xy 346.847128 -255.672715)
			(xy 346.837495 -255.652269) (xy 346.829126 -255.64465) (xy 346.759276 -255.5875) (xy 346.737432 -255.582166)
			(xy 346.726002 -255.584452) (xy 346.707281 -255.588005) (xy 346.669364 -255.591821) (xy 346.65031 -255.592072)
			(xy 346.623054 -255.591682) (xy 346.569097 -255.583925) (xy 346.516793 -255.568569) (xy 346.467207 -255.545924)
			(xy 346.421348 -255.516454) (xy 346.38015 -255.480757) (xy 346.344452 -255.43956) (xy 346.31498 -255.393702)
			(xy 346.292335 -255.344116) (xy 346.276977 -255.291813) (xy 346.269219 -255.237856) (xy 346.269219 -255.183344)
			(xy 346.276977 -255.129387) (xy 346.292335 -255.077084) (xy 346.31498 -255.027498) (xy 346.344452 -254.98164)
			(xy 346.38015 -254.940443) (xy 346.421348 -254.904746) (xy 346.467207 -254.875276) (xy 346.516793 -254.852631)
			(xy 346.569097 -254.837275) (xy 346.623054 -254.829518) (xy 346.65031 -254.829056) (xy 346.677282 -254.829472)
			(xy 346.730697 -254.836999) (xy 346.756736 -254.844042) (xy 346.76588 -254.846836) (xy 346.784676 -254.845058)
			(xy 346.863416 -254.805942) (xy 346.87637 -254.791718) (xy 346.879672 -254.782828) (xy 346.892296 -254.751497)
			(xy 346.925023 -254.692407) (xy 346.965664 -254.638453) (xy 346.989146 -254.614172) (xy 348.058486 -253.544832)
			(xy 348.065303 -253.537413) (xy 348.073037 -253.518828) (xy 348.073472 -253.508764) (xy 348.073472 -252.210316)
			(xy 348.073959 -252.178682) (xy 348.082206 -252.115954) (xy 348.098573 -252.05484) (xy 348.12278 -251.996387)
			(xy 348.154413 -251.941595) (xy 348.19293 -251.891403) (xy 348.21495 -251.868686) (xy 350.638872 -249.444764)
			(xy 350.661584 -249.422847) (xy 350.711679 -249.384451) (xy 350.766346 -249.352904) (xy 350.824655 -249.328743)
			(xy 350.885613 -249.312378) (xy 350.948182 -249.304088) (xy 350.97974 -249.30354) (xy 356.876858 -249.30354)
			(xy 356.908417 -249.30411) (xy 356.970991 -249.312379) (xy 357.031954 -249.32873) (xy 357.090267 -249.352884)
			(xy 357.144937 -249.384429) (xy 357.195031 -249.422828) (xy 357.217726 -249.444764) (xy 358.086301 -250.313444)
			(xy 358.810304 -250.313444) (xy 358.814375 -250.257822) (xy 358.826501 -250.203385) (xy 358.846424 -250.151294)
			(xy 358.87372 -250.102659) (xy 358.907806 -250.058516) (xy 358.947955 -250.019807) (xy 358.993313 -249.987356)
			(xy 359.042913 -249.961855) (xy 359.095697 -249.943848) (xy 359.15054 -249.933718) (xy 359.206274 -249.931681)
			(xy 359.261711 -249.937781) (xy 359.315668 -249.951887) (xy 359.366997 -249.973699) (xy 359.414603 -250.002753)
			(xy 359.457471 -250.038428) (xy 359.494688 -250.079965) (xy 359.525461 -250.126478) (xy 359.549133 -250.176975)
			(xy 359.565201 -250.230382) (xy 359.573321 -250.285558) (xy 359.57383 -250.313444) (xy 359.573321 -250.34133)
			(xy 359.565201 -250.396506) (xy 359.549133 -250.449913) (xy 359.525461 -250.50041) (xy 359.494688 -250.546923)
			(xy 359.457471 -250.58846) (xy 359.414603 -250.624135) (xy 359.366997 -250.653189) (xy 359.315668 -250.675001)
			(xy 359.261711 -250.689107) (xy 359.206274 -250.695207) (xy 359.15054 -250.69317) (xy 359.095697 -250.68304)
			(xy 359.042913 -250.665033) (xy 358.993313 -250.639532) (xy 358.947955 -250.607081) (xy 358.907806 -250.568372)
			(xy 358.87372 -250.524229) (xy 358.846424 -250.475594) (xy 358.826501 -250.423503) (xy 358.814375 -250.369066)
			(xy 358.810304 -250.313444) (xy 358.086301 -250.313444) (xy 359.320846 -251.548138) (xy 359.328305 -251.554894)
			(xy 359.346864 -251.562617) (xy 359.356914 -251.563124) (xy 359.820972 -251.563124) (xy 359.852587 -251.563661)
			(xy 359.915277 -251.571911) (xy 359.976354 -251.588273) (xy 360.034772 -251.612468) (xy 360.089533 -251.644081)
			(xy 360.139698 -251.682571) (xy 360.18441 -251.727281) (xy 360.222904 -251.777444) (xy 360.25452 -251.832202)
			(xy 360.278718 -251.890619) (xy 360.295084 -251.951695) (xy 360.303337 -252.014385) (xy 360.303337 -252.077615)
			(xy 360.295084 -252.140305) (xy 360.278718 -252.201381) (xy 360.25452 -252.259798) (xy 360.222904 -252.314556)
			(xy 360.18441 -252.364719) (xy 360.139698 -252.409429) (xy 360.089533 -252.447919) (xy 360.034772 -252.479532)
			(xy 359.976354 -252.503727) (xy 359.915277 -252.520089) (xy 359.852587 -252.528339) (xy 359.820972 -252.528832)
			(xy 359.134918 -252.528832) (xy 359.103359 -252.528286) (xy 359.040783 -252.520013) (xy 358.979819 -252.503658)
			(xy 358.921506 -252.479499) (xy 358.866837 -252.44795) (xy 358.816744 -252.409546) (xy 358.79405 -252.387608)
			(xy 357.922322 -251.515626) (xy 357.913849 -251.507953) (xy 357.892337 -251.500311) (xy 357.88092 -251.500894)
			(xy 357.802434 -251.509276) (xy 357.791195 -251.511082) (xy 357.771802 -251.52294) (xy 357.765096 -251.532136)
			(xy 357.749895 -251.554576) (xy 357.714216 -251.595374) (xy 357.673122 -251.630711) (xy 357.627439 -251.659874)
			(xy 357.578087 -251.682277) (xy 357.526061 -251.697468) (xy 357.472409 -251.705142) (xy 357.44531 -251.705618)
			(xy 357.418059 -251.705112) (xy 357.364113 -251.697358) (xy 357.311819 -251.682004) (xy 357.262243 -251.659365)
			(xy 357.216393 -251.629901) (xy 357.175203 -251.594211) (xy 357.139511 -251.553023) (xy 357.110045 -251.507175)
			(xy 357.087403 -251.457599) (xy 357.072047 -251.405307) (xy 357.064289 -251.35136) (xy 357.063802 -251.32411)
			(xy 357.064294 -251.297011) (xy 357.071964 -251.243357) (xy 357.08715 -251.191329) (xy 357.109548 -251.141975)
			(xy 357.138705 -251.096287) (xy 357.174035 -251.055186) (xy 357.214827 -251.0195) (xy 357.237284 -251.004324)
			(xy 357.246474 -250.997611) (xy 357.258339 -250.978223) (xy 357.260144 -250.966986) (xy 357.268526 -250.8885)
			(xy 357.269128 -250.877085) (xy 357.261458 -250.855581) (xy 357.253794 -250.847098) (xy 356.69093 -250.284234)
			(xy 356.68351 -250.277419) (xy 356.664926 -250.269684) (xy 356.654862 -250.269248) (xy 351.201736 -250.269248)
			(xy 351.191667 -250.26968) (xy 351.173069 -250.277395) (xy 351.165668 -250.284234) (xy 350.708784 -250.741173)
			(xy 354.92786 -250.741173) (xy 354.935613 -250.687223) (xy 354.950965 -250.634926) (xy 354.973603 -250.585345)
			(xy 355.003067 -250.539492) (xy 355.038757 -250.498298) (xy 355.079945 -250.462602) (xy 355.125795 -250.433131)
			(xy 355.175371 -250.410485) (xy 355.227666 -250.395126) (xy 355.281615 -250.387364) (xy 355.336119 -250.387359)
			(xy 355.390069 -250.395111) (xy 355.442366 -250.410462) (xy 355.491947 -250.433099) (xy 355.537801 -250.462562)
			(xy 355.578996 -250.49825) (xy 355.614693 -250.539438) (xy 355.644165 -250.585287) (xy 355.666812 -250.634863)
			(xy 355.682173 -250.687158) (xy 355.689935 -250.741106) (xy 355.690424 -250.768358) (xy 355.690424 -250.768612)
			(xy 355.690209 -250.787019) (xy 355.686646 -250.82366) (xy 355.683312 -250.841764) (xy 355.681034 -250.856522)
			(xy 355.684063 -250.886212) (xy 355.695534 -250.913764) (xy 355.71447 -250.93683) (xy 355.73926 -250.953448)
			(xy 355.767791 -250.962201) (xy 355.797635 -250.962345) (xy 355.81209 -250.958604) (xy 355.838774 -250.951129)
			(xy 355.893603 -250.943096) (xy 355.92131 -250.942602) (xy 355.94856 -250.943089) (xy 356.002506 -250.950846)
			(xy 356.054798 -250.966202) (xy 356.104373 -250.988844) (xy 356.150221 -251.01831) (xy 356.191409 -251.054001)
			(xy 356.227098 -251.09519) (xy 356.256563 -251.141039) (xy 356.279202 -251.190614) (xy 356.294556 -251.242907)
			(xy 356.302312 -251.296853) (xy 356.302312 -251.351354) (xy 356.294555 -251.405299) (xy 356.2792 -251.457592)
			(xy 356.25656 -251.507167) (xy 356.227094 -251.553016) (xy 356.191404 -251.594204) (xy 356.150216 -251.629894)
			(xy 356.104367 -251.65936) (xy 356.054792 -251.682) (xy 356.002499 -251.697355) (xy 355.948554 -251.705112)
			(xy 355.894053 -251.705112) (xy 355.840107 -251.697356) (xy 355.787814 -251.682002) (xy 355.738239 -251.659363)
			(xy 355.69239 -251.629898) (xy 355.651201 -251.594209) (xy 355.61551 -251.553021) (xy 355.586044 -251.507173)
			(xy 355.563402 -251.457598) (xy 355.548046 -251.405306) (xy 355.540289 -251.35136) (xy 355.539802 -251.32411)
			(xy 355.539802 -251.323856) (xy 355.540012 -251.305449) (xy 355.543579 -251.268808) (xy 355.546914 -251.250704)
			(xy 355.549191 -251.235948) (xy 355.546155 -251.206261) (xy 355.534681 -251.178715) (xy 355.515745 -251.155652)
			(xy 355.490958 -251.139035) (xy 355.462431 -251.130279) (xy 355.432591 -251.130128) (xy 355.418136 -251.133864)
			(xy 355.39145 -251.141333) (xy 355.336623 -251.14937) (xy 355.308916 -251.149866) (xy 355.281664 -251.149439)
			(xy 355.227714 -251.141685) (xy 355.175418 -251.126332) (xy 355.125838 -251.103692) (xy 355.079985 -251.074228)
			(xy 355.038791 -251.038537) (xy 355.003097 -250.997348) (xy 354.973627 -250.951498) (xy 354.950982 -250.901921)
			(xy 354.935624 -250.849625) (xy 354.927864 -250.795677) (xy 354.92786 -250.741173) (xy 350.708784 -250.741173)
			(xy 349.525533 -251.924566) (xy 350.94113 -251.924566) (xy 350.945201 -251.868944) (xy 350.957327 -251.814507)
			(xy 350.97725 -251.762416) (xy 351.004546 -251.713781) (xy 351.038632 -251.669638) (xy 351.078781 -251.630929)
			(xy 351.124139 -251.598478) (xy 351.173739 -251.572977) (xy 351.226523 -251.55497) (xy 351.281366 -251.54484)
			(xy 351.3371 -251.542803) (xy 351.392537 -251.548903) (xy 351.446494 -251.563009) (xy 351.497823 -251.584821)
			(xy 351.545429 -251.613875) (xy 351.588297 -251.64955) (xy 351.625514 -251.691087) (xy 351.656287 -251.7376)
			(xy 351.679959 -251.788097) (xy 351.696027 -251.841504) (xy 351.704147 -251.89668) (xy 351.704656 -251.924566)
			(xy 351.704147 -251.952452) (xy 351.696027 -252.007628) (xy 351.679959 -252.061035) (xy 351.656287 -252.111532)
			(xy 351.637749 -252.139552) (xy 352.47375 -252.139552) (xy 352.47375 -252.085048) (xy 352.481506 -252.031099)
			(xy 352.496861 -251.978803) (xy 352.519501 -251.929225) (xy 352.548967 -251.883372) (xy 352.584657 -251.84218)
			(xy 352.625847 -251.806486) (xy 352.671696 -251.777016) (xy 352.721273 -251.754372) (xy 352.773568 -251.739013)
			(xy 352.827516 -251.731252) (xy 352.854768 -251.730764) (xy 352.8877 -251.731504) (xy 352.95258 -251.742865)
			(xy 352.9838 -251.75337) (xy 352.992182 -251.756164) (xy 355.422454 -251.756164) (xy 355.450435 -251.756702)
			(xy 355.505705 -251.76547) (xy 355.558921 -251.782782) (xy 355.608771 -251.80821) (xy 355.654027 -251.841128)
			(xy 355.674168 -251.860558) (xy 357.157274 -253.343664) (xy 357.176674 -253.363829) (xy 357.194138 -253.38786)
			(xy 358.443274 -253.38786) (xy 358.447345 -253.332238) (xy 358.459471 -253.277801) (xy 358.479394 -253.22571)
			(xy 358.50669 -253.177075) (xy 358.540776 -253.132932) (xy 358.580925 -253.094223) (xy 358.626283 -253.061772)
			(xy 358.675883 -253.036271) (xy 358.728667 -253.018264) (xy 358.78351 -253.008134) (xy 358.839244 -253.006097)
			(xy 358.894681 -253.012197) (xy 358.948638 -253.026303) (xy 358.999967 -253.048115) (xy 359.047573 -253.077169)
			(xy 359.090441 -253.112844) (xy 359.127658 -253.154381) (xy 359.143657 -253.178564) (xy 360.485942 -253.178564)
			(xy 360.490013 -253.122942) (xy 360.502139 -253.068505) (xy 360.522062 -253.016414) (xy 360.549358 -252.967779)
			(xy 360.583444 -252.923636) (xy 360.623593 -252.884927) (xy 360.668951 -252.852476) (xy 360.718551 -252.826975)
			(xy 360.771335 -252.808968) (xy 360.826178 -252.798838) (xy 360.881912 -252.796801) (xy 360.937349 -252.802901)
			(xy 360.991306 -252.817007) (xy 361.042635 -252.838819) (xy 361.090241 -252.867873) (xy 361.133109 -252.903548)
			(xy 361.170326 -252.945085) (xy 361.201099 -252.991598) (xy 361.224771 -253.042095) (xy 361.240839 -253.095502)
			(xy 361.248959 -253.150678) (xy 361.249468 -253.178564) (xy 362.549438 -253.178564) (xy 362.553509 -253.122942)
			(xy 362.565635 -253.068505) (xy 362.585558 -253.016414) (xy 362.612854 -252.967779) (xy 362.64694 -252.923636)
			(xy 362.687089 -252.884927) (xy 362.732447 -252.852476) (xy 362.782047 -252.826975) (xy 362.834831 -252.808968)
			(xy 362.889674 -252.798838) (xy 362.945408 -252.796801) (xy 363.000845 -252.802901) (xy 363.054802 -252.817007)
			(xy 363.106131 -252.838819) (xy 363.153737 -252.867873) (xy 363.196605 -252.903548) (xy 363.233822 -252.945085)
			(xy 363.264595 -252.991598) (xy 363.288267 -253.042095) (xy 363.304335 -253.095502) (xy 363.312455 -253.150678)
			(xy 363.312964 -253.178564) (xy 363.312455 -253.20645) (xy 363.304335 -253.261626) (xy 363.288267 -253.315033)
			(xy 363.264595 -253.36553) (xy 363.233822 -253.412043) (xy 363.196605 -253.45358) (xy 363.153737 -253.489255)
			(xy 363.106131 -253.518309) (xy 363.054802 -253.540121) (xy 363.000845 -253.554227) (xy 362.945408 -253.560327)
			(xy 362.889674 -253.55829) (xy 362.834831 -253.54816) (xy 362.782047 -253.530153) (xy 362.732447 -253.504652)
			(xy 362.687089 -253.472201) (xy 362.64694 -253.433492) (xy 362.612854 -253.389349) (xy 362.585558 -253.340714)
			(xy 362.565635 -253.288623) (xy 362.553509 -253.234186) (xy 362.549438 -253.178564) (xy 361.249468 -253.178564)
			(xy 361.248959 -253.20645) (xy 361.240839 -253.261626) (xy 361.224771 -253.315033) (xy 361.201099 -253.36553)
			(xy 361.170326 -253.412043) (xy 361.133109 -253.45358) (xy 361.090241 -253.489255) (xy 361.042635 -253.518309)
			(xy 360.991306 -253.540121) (xy 360.937349 -253.554227) (xy 360.881912 -253.560327) (xy 360.826178 -253.55829)
			(xy 360.771335 -253.54816) (xy 360.718551 -253.530153) (xy 360.668951 -253.504652) (xy 360.623593 -253.472201)
			(xy 360.583444 -253.433492) (xy 360.549358 -253.389349) (xy 360.522062 -253.340714) (xy 360.502139 -253.288623)
			(xy 360.490013 -253.234186) (xy 360.485942 -253.178564) (xy 359.143657 -253.178564) (xy 359.158431 -253.200894)
			(xy 359.182103 -253.251391) (xy 359.198171 -253.304798) (xy 359.206291 -253.359974) (xy 359.2068 -253.38786)
			(xy 359.206291 -253.415746) (xy 359.198171 -253.470922) (xy 359.182103 -253.524329) (xy 359.158431 -253.574826)
			(xy 359.127658 -253.621339) (xy 359.090441 -253.662876) (xy 359.047573 -253.698551) (xy 358.999967 -253.727605)
			(xy 358.948638 -253.749417) (xy 358.894681 -253.763523) (xy 358.839244 -253.769623) (xy 358.78351 -253.767586)
			(xy 358.728667 -253.757456) (xy 358.675883 -253.739449) (xy 358.626283 -253.713948) (xy 358.580925 -253.681497)
			(xy 358.540776 -253.642788) (xy 358.50669 -253.598645) (xy 358.479394 -253.55001) (xy 358.459471 -253.497919)
			(xy 358.447345 -253.443482) (xy 358.443274 -253.38786) (xy 357.194138 -253.38786) (xy 357.209568 -253.409092)
			(xy 357.234986 -253.458938) (xy 357.252304 -253.512144) (xy 357.261096 -253.567402) (xy 357.261668 -253.595378)
			(xy 357.261668 -254.194564) (xy 362.517942 -254.194564) (xy 362.522013 -254.138942) (xy 362.534139 -254.084505)
			(xy 362.554062 -254.032414) (xy 362.581358 -253.983779) (xy 362.615444 -253.939636) (xy 362.655593 -253.900927)
			(xy 362.700951 -253.868476) (xy 362.750551 -253.842975) (xy 362.803335 -253.824968) (xy 362.858178 -253.814838)
			(xy 362.913912 -253.812801) (xy 362.969349 -253.818901) (xy 363.023306 -253.833007) (xy 363.074635 -253.854819)
			(xy 363.122241 -253.883873) (xy 363.165109 -253.919548) (xy 363.202326 -253.961085) (xy 363.233099 -254.007598)
			(xy 363.256771 -254.058095) (xy 363.272839 -254.111502) (xy 363.280959 -254.166678) (xy 363.281468 -254.194564)
			(xy 363.280959 -254.22245) (xy 363.272839 -254.277626) (xy 363.256771 -254.331033) (xy 363.233099 -254.38153)
			(xy 363.202326 -254.428043) (xy 363.165109 -254.46958) (xy 363.122241 -254.505255) (xy 363.074635 -254.534309)
			(xy 363.023306 -254.556121) (xy 362.969349 -254.570227) (xy 362.913912 -254.576327) (xy 362.858178 -254.57429)
			(xy 362.803335 -254.56416) (xy 362.750551 -254.546153) (xy 362.700951 -254.520652) (xy 362.655593 -254.488201)
			(xy 362.615444 -254.449492) (xy 362.581358 -254.405349) (xy 362.554062 -254.356714) (xy 362.534139 -254.304623)
			(xy 362.522013 -254.250186) (xy 362.517942 -254.194564) (xy 357.261668 -254.194564) (xy 357.261668 -255.362964)
			(xy 364.277908 -255.362964) (xy 364.281979 -255.307342) (xy 364.294105 -255.252905) (xy 364.314028 -255.200814)
			(xy 364.341324 -255.152179) (xy 364.37541 -255.108036) (xy 364.415559 -255.069327) (xy 364.460917 -255.036876)
			(xy 364.510517 -255.011375) (xy 364.563301 -254.993368) (xy 364.618144 -254.983238) (xy 364.673878 -254.981201)
			(xy 364.729315 -254.987301) (xy 364.783272 -255.001407) (xy 364.834601 -255.023219) (xy 364.882207 -255.052273)
			(xy 364.925075 -255.087948) (xy 364.962292 -255.129485) (xy 364.993065 -255.175998) (xy 365.016737 -255.226495)
			(xy 365.032805 -255.279902) (xy 365.040925 -255.335078) (xy 365.041434 -255.362964) (xy 365.040925 -255.39085)
			(xy 365.032805 -255.446026) (xy 365.016737 -255.499433) (xy 364.993065 -255.54993) (xy 364.962292 -255.596443)
			(xy 364.925075 -255.63798) (xy 364.882207 -255.673655) (xy 364.834601 -255.702709) (xy 364.783272 -255.724521)
			(xy 364.729315 -255.738627) (xy 364.673878 -255.744727) (xy 364.618144 -255.74269) (xy 364.563301 -255.73256)
			(xy 364.510517 -255.714553) (xy 364.460917 -255.689052) (xy 364.415559 -255.656601) (xy 364.37541 -255.617892)
			(xy 364.341324 -255.573749) (xy 364.314028 -255.525114) (xy 364.294105 -255.473023) (xy 364.281979 -255.418586)
			(xy 364.277908 -255.362964) (xy 357.261668 -255.362964) (xy 357.261668 -256.226564) (xy 358.420668 -256.226564)
			(xy 358.424739 -256.170942) (xy 358.436865 -256.116505) (xy 358.456788 -256.064414) (xy 358.484084 -256.015779)
			(xy 358.51817 -255.971636) (xy 358.558319 -255.932927) (xy 358.603677 -255.900476) (xy 358.653277 -255.874975)
			(xy 358.706061 -255.856968) (xy 358.760904 -255.846838) (xy 358.816638 -255.844801) (xy 358.872075 -255.850901)
			(xy 358.926032 -255.865007) (xy 358.977361 -255.886819) (xy 359.024967 -255.915873) (xy 359.067835 -255.951548)
			(xy 359.105052 -255.993085) (xy 359.135825 -256.039598) (xy 359.159497 -256.090095) (xy 359.175565 -256.143502)
			(xy 359.183685 -256.198678) (xy 359.184194 -256.226564) (xy 360.485942 -256.226564) (xy 360.490013 -256.170942)
			(xy 360.502139 -256.116505) (xy 360.522062 -256.064414) (xy 360.549358 -256.015779) (xy 360.583444 -255.971636)
			(xy 360.623593 -255.932927) (xy 360.668951 -255.900476) (xy 360.718551 -255.874975) (xy 360.771335 -255.856968)
			(xy 360.826178 -255.846838) (xy 360.881912 -255.844801) (xy 360.937349 -255.850901) (xy 360.991306 -255.865007)
			(xy 361.042635 -255.886819) (xy 361.090241 -255.915873) (xy 361.133109 -255.951548) (xy 361.170326 -255.993085)
			(xy 361.201099 -256.039598) (xy 361.224771 -256.090095) (xy 361.240839 -256.143502) (xy 361.248959 -256.198678)
			(xy 361.249468 -256.226564) (xy 361.248959 -256.25445) (xy 361.240839 -256.309626) (xy 361.224771 -256.363033)
			(xy 361.201099 -256.41353) (xy 361.170326 -256.460043) (xy 361.133109 -256.50158) (xy 361.090241 -256.537255)
			(xy 361.042635 -256.566309) (xy 360.991306 -256.588121) (xy 360.937349 -256.602227) (xy 360.881912 -256.608327)
			(xy 360.826178 -256.60629) (xy 360.771335 -256.59616) (xy 360.718551 -256.578153) (xy 360.668951 -256.552652)
			(xy 360.623593 -256.520201) (xy 360.583444 -256.481492) (xy 360.549358 -256.437349) (xy 360.522062 -256.388714)
			(xy 360.502139 -256.336623) (xy 360.490013 -256.282186) (xy 360.485942 -256.226564) (xy 359.184194 -256.226564)
			(xy 359.183685 -256.25445) (xy 359.175565 -256.309626) (xy 359.159497 -256.363033) (xy 359.135825 -256.41353)
			(xy 359.105052 -256.460043) (xy 359.067835 -256.50158) (xy 359.024967 -256.537255) (xy 358.977361 -256.566309)
			(xy 358.926032 -256.588121) (xy 358.872075 -256.602227) (xy 358.816638 -256.608327) (xy 358.760904 -256.60629)
			(xy 358.706061 -256.59616) (xy 358.653277 -256.578153) (xy 358.603677 -256.552652) (xy 358.558319 -256.520201)
			(xy 358.51817 -256.481492) (xy 358.484084 -256.437349) (xy 358.456788 -256.388714) (xy 358.436865 -256.336623)
			(xy 358.424739 -256.282186) (xy 358.420668 -256.226564) (xy 357.261668 -256.226564) (xy 357.261668 -256.54254)
			(xy 357.262055 -256.552614) (xy 357.2698 -256.571213) (xy 357.276654 -256.578608) (xy 357.813458 -257.115564)
			(xy 360.485942 -257.115564) (xy 360.490013 -257.059942) (xy 360.502139 -257.005505) (xy 360.522062 -256.953414)
			(xy 360.549358 -256.904779) (xy 360.583444 -256.860636) (xy 360.623593 -256.821927) (xy 360.668951 -256.789476)
			(xy 360.718551 -256.763975) (xy 360.771335 -256.745968) (xy 360.826178 -256.735838) (xy 360.881912 -256.733801)
			(xy 360.937349 -256.739901) (xy 360.991306 -256.754007) (xy 361.042635 -256.775819) (xy 361.090241 -256.804873)
			(xy 361.133109 -256.840548) (xy 361.170326 -256.882085) (xy 361.201099 -256.928598) (xy 361.224771 -256.979095)
			(xy 361.240839 -257.032502) (xy 361.248959 -257.087678) (xy 361.249468 -257.115564) (xy 361.248959 -257.14345)
			(xy 361.240839 -257.198626) (xy 361.224771 -257.252033) (xy 361.201099 -257.30253) (xy 361.170326 -257.349043)
			(xy 361.133109 -257.39058) (xy 361.090241 -257.426255) (xy 361.042635 -257.455309) (xy 360.991306 -257.477121)
			(xy 360.937349 -257.491227) (xy 360.881912 -257.497327) (xy 360.826178 -257.49529) (xy 360.771335 -257.48516)
			(xy 360.718551 -257.467153) (xy 360.668951 -257.441652) (xy 360.623593 -257.409201) (xy 360.583444 -257.370492)
			(xy 360.549358 -257.326349) (xy 360.522062 -257.277714) (xy 360.502139 -257.225623) (xy 360.490013 -257.171186)
			(xy 360.485942 -257.115564) (xy 357.813458 -257.115564) (xy 358.172258 -257.474466) (xy 358.191656 -257.494632)
			(xy 358.224551 -257.539895) (xy 358.24997 -257.589741) (xy 358.267288 -257.642946) (xy 358.27608 -257.698204)
			(xy 358.276652 -257.72618) (xy 358.276652 -258.131564) (xy 358.458768 -258.131564) (xy 358.462839 -258.075942)
			(xy 358.474965 -258.021505) (xy 358.494888 -257.969414) (xy 358.522184 -257.920779) (xy 358.55627 -257.876636)
			(xy 358.596419 -257.837927) (xy 358.641777 -257.805476) (xy 358.691377 -257.779975) (xy 358.744161 -257.761968)
			(xy 358.799004 -257.751838) (xy 358.854738 -257.749801) (xy 358.910175 -257.755901) (xy 358.964132 -257.770007)
			(xy 359.015461 -257.791819) (xy 359.063067 -257.820873) (xy 359.105935 -257.856548) (xy 359.143152 -257.898085)
			(xy 359.173925 -257.944598) (xy 359.197597 -257.995095) (xy 359.213665 -258.048502) (xy 359.221785 -258.103678)
			(xy 359.222294 -258.131564) (xy 362.517942 -258.131564) (xy 362.522013 -258.075942) (xy 362.534139 -258.021505)
			(xy 362.554062 -257.969414) (xy 362.581358 -257.920779) (xy 362.615444 -257.876636) (xy 362.655593 -257.837927)
			(xy 362.700951 -257.805476) (xy 362.750551 -257.779975) (xy 362.803335 -257.761968) (xy 362.858178 -257.751838)
			(xy 362.913912 -257.749801) (xy 362.969349 -257.755901) (xy 363.023306 -257.770007) (xy 363.074635 -257.791819)
			(xy 363.122241 -257.820873) (xy 363.165109 -257.856548) (xy 363.202326 -257.898085) (xy 363.233099 -257.944598)
			(xy 363.256771 -257.995095) (xy 363.272839 -258.048502) (xy 363.280959 -258.103678) (xy 363.281468 -258.131564)
			(xy 363.280959 -258.15945) (xy 363.272839 -258.214626) (xy 363.256771 -258.268033) (xy 363.233099 -258.31853)
			(xy 363.202326 -258.365043) (xy 363.165109 -258.40658) (xy 363.122241 -258.442255) (xy 363.074635 -258.471309)
			(xy 363.023306 -258.493121) (xy 362.969349 -258.507227) (xy 362.913912 -258.513327) (xy 362.858178 -258.51129)
			(xy 362.803335 -258.50116) (xy 362.750551 -258.483153) (xy 362.700951 -258.457652) (xy 362.655593 -258.425201)
			(xy 362.615444 -258.386492) (xy 362.581358 -258.342349) (xy 362.554062 -258.293714) (xy 362.534139 -258.241623)
			(xy 362.522013 -258.187186) (xy 362.517942 -258.131564) (xy 359.222294 -258.131564) (xy 359.221785 -258.15945)
			(xy 359.213665 -258.214626) (xy 359.197597 -258.268033) (xy 359.173925 -258.31853) (xy 359.143152 -258.365043)
			(xy 359.105935 -258.40658) (xy 359.063067 -258.442255) (xy 359.015461 -258.471309) (xy 358.964132 -258.493121)
			(xy 358.910175 -258.507227) (xy 358.854738 -258.513327) (xy 358.799004 -258.51129) (xy 358.744161 -258.50116)
			(xy 358.691377 -258.483153) (xy 358.641777 -258.457652) (xy 358.596419 -258.425201) (xy 358.55627 -258.386492)
			(xy 358.522184 -258.342349) (xy 358.494888 -258.293714) (xy 358.474965 -258.241623) (xy 358.462839 -258.187186)
			(xy 358.458768 -258.131564) (xy 358.276652 -258.131564) (xy 358.276652 -259.147564) (xy 362.539024 -259.147564)
			(xy 362.543095 -259.091942) (xy 362.555221 -259.037505) (xy 362.575144 -258.985414) (xy 362.60244 -258.936779)
			(xy 362.636526 -258.892636) (xy 362.676675 -258.853927) (xy 362.722033 -258.821476) (xy 362.771633 -258.795975)
			(xy 362.824417 -258.777968) (xy 362.87926 -258.767838) (xy 362.934994 -258.765801) (xy 362.990431 -258.771901)
			(xy 363.044388 -258.786007) (xy 363.095717 -258.807819) (xy 363.143323 -258.836873) (xy 363.186191 -258.872548)
			(xy 363.223408 -258.914085) (xy 363.254181 -258.960598) (xy 363.277853 -259.011095) (xy 363.293921 -259.064502)
			(xy 363.302041 -259.119678) (xy 363.30255 -259.147564) (xy 363.302041 -259.17545) (xy 363.293921 -259.230626)
			(xy 363.277853 -259.284033) (xy 363.254181 -259.33453) (xy 363.223408 -259.381043) (xy 363.186191 -259.42258)
			(xy 363.143323 -259.458255) (xy 363.095717 -259.487309) (xy 363.044388 -259.509121) (xy 362.990431 -259.523227)
			(xy 362.934994 -259.529327) (xy 362.87926 -259.52729) (xy 362.824417 -259.51716) (xy 362.771633 -259.499153)
			(xy 362.722033 -259.473652) (xy 362.676675 -259.441201) (xy 362.636526 -259.402492) (xy 362.60244 -259.358349)
			(xy 362.575144 -259.309714) (xy 362.555221 -259.257623) (xy 362.543095 -259.203186) (xy 362.539024 -259.147564)
			(xy 358.276652 -259.147564) (xy 358.276652 -260.677406) (xy 358.27706 -260.687477) (xy 358.284791 -260.706076)
			(xy 358.291638 -260.713474) (xy 358.784631 -261.206488) (xy 364.15802 -261.206488) (xy 364.162091 -261.150866)
			(xy 364.174217 -261.096429) (xy 364.19414 -261.044338) (xy 364.221436 -260.995703) (xy 364.255522 -260.95156)
			(xy 364.295671 -260.912851) (xy 364.341029 -260.8804) (xy 364.390629 -260.854899) (xy 364.443413 -260.836892)
			(xy 364.498256 -260.826762) (xy 364.55399 -260.824725) (xy 364.609427 -260.830825) (xy 364.663384 -260.844931)
			(xy 364.714713 -260.866743) (xy 364.762319 -260.895797) (xy 364.805187 -260.931472) (xy 364.842404 -260.973009)
			(xy 364.873177 -261.019522) (xy 364.896849 -261.070019) (xy 364.912917 -261.123426) (xy 364.921037 -261.178602)
			(xy 364.921546 -261.206488) (xy 364.921037 -261.234374) (xy 364.912917 -261.28955) (xy 364.896849 -261.342957)
			(xy 364.873177 -261.393454) (xy 364.842404 -261.439967) (xy 364.805187 -261.481504) (xy 364.762319 -261.517179)
			(xy 364.714713 -261.546233) (xy 364.663384 -261.568045) (xy 364.609427 -261.582151) (xy 364.55399 -261.588251)
			(xy 364.498256 -261.586214) (xy 364.443413 -261.576084) (xy 364.390629 -261.558077) (xy 364.341029 -261.532576)
			(xy 364.295671 -261.500125) (xy 364.255522 -261.461416) (xy 364.221436 -261.417273) (xy 364.19414 -261.368638)
			(xy 364.174217 -261.316547) (xy 364.162091 -261.26211) (xy 364.15802 -261.206488) (xy 358.784631 -261.206488)
			(xy 364.157006 -266.579096) (xy 364.17641 -266.599258) (xy 364.209306 -266.64452) (xy 364.234725 -266.694367)
			(xy 364.252041 -266.747574) (xy 364.26083 -266.802833) (xy 364.2614 -266.83081) (xy 364.2614 -277.827232)
			(xy 364.260858 -277.855213) (xy 364.252092 -277.910483) (xy 364.234782 -277.963699) (xy 364.209354 -278.01355)
			(xy 364.176436 -278.058805) (xy 364.157006 -278.078946) (xy 363.305598 -278.930354) (xy 363.298785 -278.937776)
			(xy 363.29105 -278.956358) (xy 363.290612 -278.966422) (xy 363.290612 -280.479754) (xy 363.29366 -280.488136)
			(xy 363.304197 -280.519348) (xy 363.315556 -280.584233) (xy 363.316266 -280.617168) (xy 363.316208 -280.627794)
			(xy 363.315065 -280.649015) (xy 363.31398 -280.659586) (xy 363.312964 -280.668984) (xy 363.31779 -280.687272)
			(xy 363.363764 -280.750772) (xy 363.369595 -280.758056) (xy 363.385218 -280.768224) (xy 363.394244 -280.770584)
			(xy 363.394498 -280.770584) (xy 363.409992 -280.77414) (xy 363.419518 -280.776007) (xy 363.438718 -280.773282)
			(xy 363.44733 -280.768806) (xy 363.508544 -280.733754) (xy 363.516818 -280.728554) (xy 363.528967 -280.71327)
			(xy 363.532166 -280.704036) (xy 363.532166 -280.703782) (xy 363.540248 -280.67769) (xy 363.562792 -280.62794)
			(xy 363.592204 -280.581915) (xy 363.627882 -280.540558) (xy 363.669097 -280.504715) (xy 363.715004 -280.47512)
			(xy 363.764665 -280.452378) (xy 363.817062 -280.436954) (xy 363.871124 -280.429166) (xy 363.898434 -280.4287)
			(xy 363.923606 -280.429087) (xy 363.973513 -280.43571) (xy 364.022117 -280.448835) (xy 364.0455 -280.458164)
			(xy 364.055643 -280.461865) (xy 364.077208 -280.461344) (xy 364.087156 -280.457148) (xy 364.165134 -280.420064)
			(xy 364.179104 -280.403808) (xy 364.182152 -280.39314) (xy 364.190912 -280.365226) (xy 364.215849 -280.312304)
			(xy 364.248575 -280.26381) (xy 364.288323 -280.220883) (xy 364.33416 -280.184529) (xy 364.385012 -280.155602)
			(xy 364.439684 -280.134779) (xy 364.496895 -280.12255) (xy 364.526068 -280.120344) (xy 364.526322 -280.120344)
			(xy 364.537598 -280.118999) (xy 364.557384 -280.10792) (xy 364.564422 -280.099008) (xy 364.617254 -280.02484)
			(xy 364.621064 -280.002234) (xy 364.618016 -279.991058) (xy 364.611252 -279.965556) (xy 364.603985 -279.913298)
			(xy 364.603538 -279.886918) (xy 364.604024 -279.859667) (xy 364.61178 -279.805719) (xy 364.627135 -279.753424)
			(xy 364.649777 -279.703847) (xy 364.679243 -279.657997) (xy 364.714934 -279.616806) (xy 364.756125 -279.581115)
			(xy 364.801975 -279.551649) (xy 364.851552 -279.529007) (xy 364.903847 -279.513652) (xy 364.957795 -279.505896)
			(xy 365.012297 -279.505896) (xy 365.066245 -279.513652) (xy 365.11854 -279.529007) (xy 365.168117 -279.551649)
			(xy 365.213967 -279.581115) (xy 365.255158 -279.616806) (xy 365.290849 -279.657997) (xy 365.320315 -279.703847)
			(xy 365.342957 -279.753424) (xy 365.358312 -279.805719) (xy 365.366068 -279.859667) (xy 365.366554 -279.886918)
			(xy 365.366066 -279.915793) (xy 365.357382 -279.972885) (xy 365.340186 -280.028014) (xy 365.314871 -280.079918)
			(xy 365.282016 -280.12741) (xy 365.242373 -280.169402) (xy 365.19685 -280.204934) (xy 365.146488 -280.233193)
			(xy 365.092439 -280.253532) (xy 365.035941 -280.265485) (xy 365.007144 -280.267664) (xy 365.00689 -280.267664)
			(xy 364.995623 -280.269049) (xy 364.975836 -280.280103) (xy 364.96879 -280.289) (xy 364.915958 -280.363168)
			(xy 364.912148 -280.385774) (xy 364.915196 -280.39695) (xy 364.921961 -280.422452) (xy 364.929228 -280.47471)
			(xy 364.929674 -280.50109) (xy 364.928906 -280.535173) (xy 364.916774 -280.602251) (xy 364.905544 -280.63444)
			(xy 364.901226 -280.64587) (xy 364.903766 -280.669492) (xy 364.96117 -280.758138) (xy 364.981998 -280.77033)
			(xy 364.993936 -280.771092) (xy 365.022544 -280.773549) (xy 365.078611 -280.785929) (xy 365.13219 -280.806569)
			(xy 365.182073 -280.835001) (xy 365.227134 -280.870586) (xy 365.266356 -280.912519) (xy 365.298854 -280.959855)
			(xy 365.323894 -281.011524) (xy 365.340911 -281.066362) (xy 365.349521 -281.123129) (xy 365.350044 -281.151838)
			(xy 365.349558 -281.179089) (xy 365.341802 -281.233037) (xy 365.326447 -281.285332) (xy 365.303805 -281.334909)
			(xy 365.274339 -281.380759) (xy 365.238648 -281.42195) (xy 365.197457 -281.457641) (xy 365.151607 -281.487107)
			(xy 365.10203 -281.509749) (xy 365.049735 -281.525104) (xy 364.995787 -281.53286) (xy 364.941285 -281.53286)
			(xy 364.887337 -281.525104) (xy 364.835042 -281.509749) (xy 364.785465 -281.487107) (xy 364.739615 -281.457641)
			(xy 364.698424 -281.42195) (xy 364.662733 -281.380759) (xy 364.633267 -281.334909) (xy 364.610625 -281.285332)
			(xy 364.59527 -281.233037) (xy 364.587514 -281.179089) (xy 364.587028 -281.151838) (xy 364.587777 -281.117754)
			(xy 364.599921 -281.050676) (xy 364.611158 -281.018488) (xy 364.615476 -281.007058) (xy 364.612936 -280.983436)
			(xy 364.555532 -280.89479) (xy 364.534704 -280.882598) (xy 364.522766 -280.881836) (xy 364.491468 -280.879091)
			(xy 364.430323 -280.86467) (xy 364.4011 -280.853134) (xy 364.390957 -280.849433) (xy 364.369392 -280.849954)
			(xy 364.359444 -280.85415) (xy 364.281466 -280.891234) (xy 364.267496 -280.90749) (xy 364.264448 -280.918158)
			(xy 364.256256 -280.94413) (xy 364.233577 -280.99364) (xy 364.204088 -281.039422) (xy 364.168389 -281.080545)
			(xy 364.127205 -281.116175) (xy 364.081373 -281.145586) (xy 364.031825 -281.168182) (xy 363.979568 -281.183502)
			(xy 363.925663 -281.191237) (xy 363.898434 -281.191716) (xy 363.875078 -281.191348) (xy 363.828719 -281.185619)
			(xy 363.805978 -281.180286) (xy 363.796454 -281.178399) (xy 363.777251 -281.181137) (xy 363.76864 -281.18562)
			(xy 363.707426 -281.220672) (xy 363.699158 -281.22588) (xy 363.687004 -281.241158) (xy 363.683804 -281.25039)
			(xy 363.683804 -281.250644) (xy 363.675765 -281.27675) (xy 363.653216 -281.326501) (xy 363.623798 -281.372527)
			(xy 363.588113 -281.413883) (xy 363.546893 -281.449725) (xy 363.500981 -281.479318) (xy 363.451315 -281.502058)
			(xy 363.398914 -281.517477) (xy 363.344848 -281.525263) (xy 363.317536 -281.525726) (xy 363.290285 -281.525211)
			(xy 363.236337 -281.51746) (xy 363.184041 -281.502109) (xy 363.134462 -281.479472) (xy 363.08861 -281.45001)
			(xy 363.047417 -281.414321) (xy 363.011723 -281.373134) (xy 362.982254 -281.327285) (xy 362.95961 -281.27771)
			(xy 362.944252 -281.225416) (xy 362.936493 -281.171469) (xy 362.936028 -281.144218) (xy 362.936085 -281.133592)
			(xy 362.937228 -281.112371) (xy 362.938314 -281.1018) (xy 362.93933 -281.092402) (xy 362.934504 -281.074114)
			(xy 362.88853 -281.010614) (xy 362.882703 -281.003326) (xy 362.867077 -280.99316) (xy 362.85805 -280.990802)
			(xy 362.857796 -280.990802) (xy 362.829495 -280.984439) (xy 362.775108 -280.964278) (xy 362.724399 -280.936114)
			(xy 362.67854 -280.900598) (xy 362.638586 -280.858548) (xy 362.605459 -280.810934) (xy 362.579922 -280.758853)
			(xy 362.562566 -280.703507) (xy 362.553789 -280.64617) (xy 362.55325 -280.617168) (xy 362.553975 -280.584235)
			(xy 362.565346 -280.519356) (xy 362.575856 -280.488136) (xy 362.578904 -280.479754) (xy 362.578904 -278.797512)
			(xy 362.579488 -278.769572) (xy 362.588244 -278.714381) (xy 362.605512 -278.661234) (xy 362.630867 -278.611437)
			(xy 362.663689 -278.56621) (xy 362.683044 -278.546052) (xy 363.534198 -277.694644) (xy 363.541011 -277.687223)
			(xy 363.548747 -277.66864) (xy 363.549184 -277.658576) (xy 363.549184 -266.999466) (xy 363.548781 -266.989394)
			(xy 363.541045 -266.970796) (xy 363.534198 -266.963398) (xy 357.66883 -261.097776) (xy 357.64945 -261.077593)
			(xy 357.616553 -261.032335) (xy 357.591131 -260.982493) (xy 357.573809 -260.929292) (xy 357.565011 -260.874037)
			(xy 357.564436 -260.846062) (xy 357.564436 -257.894836) (xy 357.564009 -257.884767) (xy 357.556291 -257.866168)
			(xy 357.54945 -257.858768) (xy 356.653846 -256.96291) (xy 356.634437 -256.942754) (xy 356.601543 -256.897489)
			(xy 356.576127 -256.84764) (xy 356.558811 -256.794432) (xy 356.550022 -256.739173) (xy 356.549452 -256.711196)
			(xy 356.549452 -253.764034) (xy 356.549021 -253.753965) (xy 356.541306 -253.735366) (xy 356.534466 -253.727966)
			(xy 355.289866 -252.483366) (xy 355.282476 -252.476514) (xy 355.263869 -252.468802) (xy 355.253798 -252.46838)
			(xy 352.992182 -252.46838) (xy 352.9838 -252.471174) (xy 352.952584 -252.481699) (xy 352.887703 -252.493067)
			(xy 352.854768 -252.49378) (xy 352.827516 -252.493348) (xy 352.773568 -252.485587) (xy 352.721273 -252.470228)
			(xy 352.671696 -252.447584) (xy 352.625847 -252.418114) (xy 352.584657 -252.38242) (xy 352.548967 -252.341228)
			(xy 352.519501 -252.295375) (xy 352.496861 -252.245797) (xy 352.481506 -252.193501) (xy 352.47375 -252.139552)
			(xy 351.637749 -252.139552) (xy 351.625514 -252.158045) (xy 351.588297 -252.199582) (xy 351.545429 -252.235257)
			(xy 351.497823 -252.264311) (xy 351.446494 -252.286123) (xy 351.392537 -252.300229) (xy 351.3371 -252.306329)
			(xy 351.281366 -252.304292) (xy 351.226523 -252.294162) (xy 351.173739 -252.276155) (xy 351.124139 -252.250654)
			(xy 351.078781 -252.218203) (xy 351.038632 -252.179494) (xy 351.004546 -252.135351) (xy 350.97725 -252.086716)
			(xy 350.957327 -252.034625) (xy 350.945201 -251.980188) (xy 350.94113 -251.924566) (xy 349.525533 -251.924566)
			(xy 349.054674 -252.395482) (xy 349.047846 -252.402891) (xy 349.04012 -252.421484) (xy 349.039688 -252.43155)
			(xy 349.039688 -253.729998) (xy 349.039192 -253.761631) (xy 349.030945 -253.824358) (xy 349.014578 -253.885471)
			(xy 348.990373 -253.943925) (xy 348.958742 -253.998717) (xy 348.920228 -254.04891) (xy 348.89821 -254.071628)
			(xy 348.820994 -254.148844) (xy 349.868234 -254.148844) (xy 349.872305 -254.093222) (xy 349.884431 -254.038785)
			(xy 349.904354 -253.986694) (xy 349.93165 -253.938059) (xy 349.965736 -253.893916) (xy 350.005885 -253.855207)
			(xy 350.051243 -253.822756) (xy 350.100843 -253.797255) (xy 350.153627 -253.779248) (xy 350.20847 -253.769118)
			(xy 350.264204 -253.767081) (xy 350.319641 -253.773181) (xy 350.373598 -253.787287) (xy 350.424927 -253.809099)
			(xy 350.472533 -253.838153) (xy 350.515401 -253.873828) (xy 350.552618 -253.915365) (xy 350.583391 -253.961878)
			(xy 350.607063 -254.012375) (xy 350.623131 -254.065782) (xy 350.631251 -254.120958) (xy 350.63176 -254.148844)
			(xy 350.631251 -254.17673) (xy 350.623131 -254.231906) (xy 350.607063 -254.285313) (xy 350.583391 -254.33581)
			(xy 350.552618 -254.382323) (xy 350.515401 -254.42386) (xy 350.472533 -254.459535) (xy 350.424927 -254.488589)
			(xy 350.373598 -254.510401) (xy 350.319641 -254.524507) (xy 350.264204 -254.530607) (xy 350.20847 -254.52857)
			(xy 350.153627 -254.51844) (xy 350.100843 -254.500433) (xy 350.051243 -254.474932) (xy 350.005885 -254.442481)
			(xy 349.965736 -254.403772) (xy 349.93165 -254.359629) (xy 349.904354 -254.310994) (xy 349.884431 -254.258903)
			(xy 349.872305 -254.204466) (xy 349.868234 -254.148844) (xy 348.820994 -254.148844) (xy 347.82887 -255.140968)
			(xy 347.822047 -255.148381) (xy 347.814318 -255.166971) (xy 347.813884 -255.177036) (xy 347.813884 -255.18872)
			(xy 348.495618 -255.18872) (xy 348.499689 -255.133098) (xy 348.511815 -255.078661) (xy 348.531738 -255.02657)
			(xy 348.559034 -254.977935) (xy 348.59312 -254.933792) (xy 348.633269 -254.895083) (xy 348.678627 -254.862632)
			(xy 348.728227 -254.837131) (xy 348.781011 -254.819124) (xy 348.835854 -254.808994) (xy 348.891588 -254.806957)
			(xy 348.947025 -254.813057) (xy 349.000982 -254.827163) (xy 349.052311 -254.848975) (xy 349.099917 -254.878029)
			(xy 349.142785 -254.913704) (xy 349.180002 -254.955241) (xy 349.210775 -255.001754) (xy 349.234447 -255.052251)
			(xy 349.250515 -255.105658) (xy 349.258635 -255.160834) (xy 349.259144 -255.18872) (xy 349.258635 -255.216606)
			(xy 349.250515 -255.271782) (xy 349.234447 -255.325189) (xy 349.210775 -255.375686) (xy 349.180002 -255.422199)
			(xy 349.142785 -255.463736) (xy 349.099917 -255.499411) (xy 349.052311 -255.528465) (xy 349.000982 -255.550277)
			(xy 348.947025 -255.564383) (xy 348.891588 -255.570483) (xy 348.835854 -255.568446) (xy 348.781011 -255.558316)
			(xy 348.728227 -255.540309) (xy 348.678627 -255.514808) (xy 348.633269 -255.482357) (xy 348.59312 -255.443648)
			(xy 348.559034 -255.399505) (xy 348.531738 -255.35087) (xy 348.511815 -255.298779) (xy 348.499689 -255.244342)
			(xy 348.495618 -255.18872) (xy 347.813884 -255.18872) (xy 347.813884 -256.853436) (xy 347.814268 -256.86351)
			(xy 347.822015 -256.882109) (xy 347.82887 -256.889504) (xy 348.069916 -257.13055) (xy 348.495618 -257.13055)
			(xy 348.499689 -257.074928) (xy 348.511815 -257.020491) (xy 348.531738 -256.9684) (xy 348.559034 -256.919765)
			(xy 348.59312 -256.875622) (xy 348.633269 -256.836913) (xy 348.678627 -256.804462) (xy 348.728227 -256.778961)
			(xy 348.781011 -256.760954) (xy 348.835854 -256.750824) (xy 348.891588 -256.748787) (xy 348.947025 -256.754887)
			(xy 349.000982 -256.768993) (xy 349.052311 -256.790805) (xy 349.099917 -256.819859) (xy 349.142785 -256.855534)
			(xy 349.180002 -256.897071) (xy 349.210775 -256.943584) (xy 349.234447 -256.994081) (xy 349.250515 -257.047488)
			(xy 349.258635 -257.102664) (xy 349.259144 -257.13055) (xy 349.258635 -257.158436) (xy 349.250515 -257.213612)
			(xy 349.234447 -257.267019) (xy 349.210775 -257.317516) (xy 349.180002 -257.364029) (xy 349.142785 -257.405566)
			(xy 349.099917 -257.441241) (xy 349.052311 -257.470295) (xy 349.000982 -257.492107) (xy 348.947025 -257.506213)
			(xy 348.891588 -257.512313) (xy 348.835854 -257.510276) (xy 348.781011 -257.500146) (xy 348.728227 -257.482139)
			(xy 348.678627 -257.456638) (xy 348.633269 -257.424187) (xy 348.59312 -257.385478) (xy 348.559034 -257.341335)
			(xy 348.531738 -257.2927) (xy 348.511815 -257.240609) (xy 348.499689 -257.186172) (xy 348.495618 -257.13055)
			(xy 348.069916 -257.13055) (xy 348.532958 -257.593592) (xy 348.555299 -257.616771) (xy 348.594294 -257.667992)
			(xy 348.610682 -257.6957) (xy 348.61627 -257.705606) (xy 348.634304 -257.71856) (xy 348.73311 -257.736594)
			(xy 348.754446 -257.73126) (xy 348.763082 -257.724148) (xy 348.76359 -257.724148) (xy 348.784058 -257.707923)
			(xy 348.828633 -257.680698) (xy 348.876506 -257.659811) (xy 348.926783 -257.645653) (xy 348.978521 -257.638489)
			(xy 349.004636 -257.638042) (xy 349.031693 -257.638468) (xy 349.085261 -257.646131) (xy 349.13721 -257.661285)
			(xy 349.186497 -257.683626) (xy 349.232134 -257.712706) (xy 349.273205 -257.74794) (xy 349.308887 -257.788624)
			(xy 349.338463 -257.83394) (xy 349.35033 -257.85826) (xy 349.354394 -257.866896) (xy 349.367602 -257.879596)
			(xy 349.447104 -257.913886) (xy 349.465646 -257.914648) (xy 349.474536 -257.9116) (xy 349.503804 -257.90251)
			(xy 349.564292 -257.892677) (xy 349.594932 -257.892042) (xy 349.595186 -257.892042) (xy 349.622443 -257.892404)
			(xy 349.676403 -257.90016) (xy 349.728709 -257.915517) (xy 349.778298 -257.938162) (xy 349.824158 -257.967633)
			(xy 349.865358 -258.003332) (xy 349.901058 -258.04453) (xy 349.930531 -258.09039) (xy 349.953178 -258.139978)
			(xy 349.968537 -258.192284) (xy 349.976295 -258.246243) (xy 349.976295 -258.300757) (xy 349.968537 -258.354716)
			(xy 349.953178 -258.407022) (xy 349.930531 -258.45661) (xy 349.901058 -258.50247) (xy 349.865358 -258.543668)
			(xy 349.824158 -258.579367) (xy 349.778298 -258.608838) (xy 349.728709 -258.631483) (xy 349.676403 -258.64684)
			(xy 349.622443 -258.654596) (xy 349.595186 -258.655058) (xy 349.574638 -258.654758) (xy 349.533782 -258.650305)
			(xy 349.513652 -258.646168) (xy 349.513398 -258.646168) (xy 349.501664 -258.644425) (xy 349.478765 -258.650502)
			(xy 349.469456 -258.657852) (xy 349.39859 -258.720336) (xy 349.3897 -258.742688) (xy 349.390716 -258.754626)
			(xy 349.390716 -258.755134) (xy 349.392494 -258.79044) (xy 349.392059 -258.817693) (xy 349.384297 -258.871643)
			(xy 349.368936 -258.92394) (xy 349.346289 -258.973518) (xy 349.316818 -259.019369) (xy 349.281121 -259.060559)
			(xy 349.239926 -259.09625) (xy 349.194071 -259.125715) (xy 349.144489 -259.148355) (xy 349.09219 -259.163709)
			(xy 349.038239 -259.171463) (xy 349.010986 -259.171948) (xy 348.986737 -259.171553) (xy 348.938629 -259.165411)
			(xy 348.89169 -259.153216) (xy 348.846676 -259.135165) (xy 348.825312 -259.123688) (xy 348.813374 -259.117084)
			(xy 348.78645 -259.117338) (xy 348.699328 -259.168646) (xy 348.691943 -259.173431) (xy 348.680744 -259.18699)
			(xy 348.6748 -259.203541) (xy 348.674436 -259.212334) (xy 348.674436 -259.445506) (xy 348.67396 -259.47714)
			(xy 348.665711 -259.539869) (xy 348.649342 -259.600983) (xy 348.625132 -259.659436) (xy 348.593497 -259.714228)
			(xy 348.554979 -259.764419) (xy 348.532958 -259.787136) (xy 347.61932 -260.700774) (xy 347.596596 -260.722784)
			(xy 347.546398 -260.761287) (xy 347.491605 -260.792911) (xy 347.433154 -260.817113) (xy 347.372045 -260.833482)
			(xy 347.309322 -260.841736) (xy 347.27769 -260.842252) (xy 347.120464 -260.842252) (xy 347.111235 -260.842663)
			(xy 347.093976 -260.849212) (xy 347.080154 -260.861447) (xy 347.075506 -260.86943) (xy 347.026992 -260.961378)
			(xy 347.02877 -260.989826) (xy 347.036644 -261.001256) (xy 347.052522 -261.025263) (xy 347.07768 -261.077028)
			(xy 347.094778 -261.131985) (xy 347.103428 -261.188887) (xy 347.103954 -261.217664) (xy 347.103388 -261.244912)
			(xy 347.095638 -261.298855) (xy 347.08029 -261.351145) (xy 347.057656 -261.400719) (xy 347.028198 -261.446567)
			(xy 346.992515 -261.487757) (xy 346.951333 -261.523449) (xy 346.905491 -261.552917) (xy 346.855922 -261.575561)
			(xy 346.803635 -261.590921) (xy 346.749694 -261.598683) (xy 346.722446 -261.599172) (xy 346.694645 -261.59865)
			(xy 346.639631 -261.590596) (xy 346.586369 -261.574639) (xy 346.535989 -261.551116) (xy 346.48956 -261.520526)
			(xy 346.448064 -261.483518) (xy 346.429838 -261.46252) (xy 346.422788 -261.454927) (xy 346.404269 -261.445676)
			(xy 346.383603 -261.444471) (xy 346.373704 -261.447534) (xy 346.283788 -261.480046) (xy 346.274179 -261.484061)
			(xy 346.259018 -261.498305) (xy 346.250759 -261.517397) (xy 346.25026 -261.527798) (xy 346.25026 -262.101584)
			(xy 346.249707 -262.133143) (xy 346.241434 -262.195718) (xy 346.22508 -262.256681) (xy 346.200923 -262.314995)
			(xy 346.169375 -262.369664) (xy 346.130973 -262.419758) (xy 346.109036 -262.442452) (xy 345.506294 -263.045194)
			(xy 345.48354 -263.067172) (xy 345.433349 -263.105678) (xy 345.378562 -263.137305) (xy 345.320117 -263.161513)
			(xy 345.259013 -263.177889) (xy 345.196294 -263.186151) (xy 345.164664 -263.186672) (xy 344.74531 -263.186672)
			(xy 344.713675 -263.18625) (xy 344.650946 -263.177992) (xy 344.589832 -263.161618) (xy 344.531378 -263.137407)
			(xy 344.476584 -263.105772) (xy 344.426389 -263.067257) (xy 344.38165 -263.022519) (xy 344.343133 -262.972324)
			(xy 344.311498 -262.917531) (xy 344.287285 -262.859077) (xy 344.27091 -262.797963) (xy 344.262651 -262.735235)
			(xy 344.262651 -262.671965) (xy 344.27091 -262.609237) (xy 344.287285 -262.548123) (xy 344.311498 -262.489669)
			(xy 344.343133 -262.434876) (xy 344.38165 -262.384681) (xy 344.426389 -262.339943) (xy 344.476584 -262.301428)
			(xy 344.531378 -262.269793) (xy 344.589832 -262.245582) (xy 344.650946 -262.229208) (xy 344.713675 -262.22095)
			(xy 344.74531 -262.220456) (xy 344.94343 -262.220456) (xy 344.953503 -262.220058) (xy 344.972101 -262.212319)
			(xy 344.979498 -262.20547) (xy 345.269566 -261.915656) (xy 345.276413 -261.908261) (xy 345.28413 -261.889658)
			(xy 345.284552 -261.879588) (xy 345.284552 -260.589776) (xy 345.285076 -260.558216) (xy 345.293354 -260.49564)
			(xy 345.309714 -260.434676) (xy 345.333876 -260.376362) (xy 345.36543 -260.321694) (xy 345.403837 -260.271601)
			(xy 345.425776 -260.248908) (xy 345.65717 -260.017514) (xy 345.679896 -259.995506) (xy 345.730094 -259.957004)
			(xy 345.784886 -259.92538) (xy 345.843337 -259.901177) (xy 345.904446 -259.884808) (xy 345.967168 -259.876553)
			(xy 345.9988 -259.876036) (xy 346.370148 -259.876036) (xy 346.379018 -259.875735) (xy 346.395712 -259.86974)
			(xy 346.40934 -259.858387) (xy 346.41409 -259.85089) (xy 346.46489 -259.76326) (xy 346.465144 -259.736336)
			(xy 346.458286 -259.724398) (xy 346.446393 -259.702723) (xy 346.427677 -259.656962) (xy 346.415022 -259.609169)
			(xy 346.408639 -259.560142) (xy 346.408248 -259.535422) (xy 346.409518 -259.503418) (xy 346.410788 -259.48767)
			(xy 346.394786 -259.459984) (xy 346.293948 -259.412994) (xy 346.284319 -259.409031) (xy 346.26353 -259.408396)
			(xy 346.244217 -259.416116) (xy 346.236544 -259.423154) (xy 346.086938 -259.57276) (xy 346.079471 -259.579471)
			(xy 346.060901 -259.587051) (xy 346.05087 -259.587492) (xy 345.389454 -259.587492) (xy 345.379388 -259.58704)
			(xy 345.36079 -259.579338) (xy 345.353386 -259.572506) (xy 345.13393 -259.353304) (xy 345.125478 -259.345773)
			(xy 345.104159 -259.338252) (xy 345.081673 -259.340584) (xy 345.0717 -259.345938) (xy 345.049086 -259.359238)
			(xy 345.001009 -259.380236) (xy 344.95051 -259.394458) (xy 344.898541 -259.401637) (xy 344.87231 -259.402072)
			(xy 344.845056 -259.401635) (xy 344.791102 -259.393879) (xy 344.738801 -259.378522) (xy 344.689219 -259.355878)
			(xy 344.643364 -259.326408) (xy 344.60217 -259.290711) (xy 344.566477 -259.249515) (xy 344.537009 -259.203658)
			(xy 344.514369 -259.154074) (xy 344.499016 -259.101773) (xy 344.491263 -259.047818) (xy 344.490802 -259.020564)
			(xy 344.492326 -258.986782) (xy 344.493342 -258.976114) (xy 344.486484 -258.955794) (xy 344.428572 -258.892802)
			(xy 344.421062 -258.885386) (xy 344.401773 -258.87687) (xy 344.391234 -258.876292) (xy 343.369392 -258.876292)
			(xy 343.359319 -258.876689) (xy 343.34072 -258.884427) (xy 343.333324 -258.891278) (xy 342.773762 -259.45084)
			(xy 342.766907 -259.458228) (xy 342.759197 -259.476837) (xy 342.758776 -259.486908) (xy 342.758776 -260.671564)
			(xy 344.363292 -260.671564) (xy 344.367363 -260.615942) (xy 344.379489 -260.561505) (xy 344.399412 -260.509414)
			(xy 344.426708 -260.460779) (xy 344.460794 -260.416636) (xy 344.500943 -260.377927) (xy 344.546301 -260.345476)
			(xy 344.595901 -260.319975) (xy 344.648685 -260.301968) (xy 344.703528 -260.291838) (xy 344.759262 -260.289801)
			(xy 344.814699 -260.295901) (xy 344.868656 -260.310007) (xy 344.919985 -260.331819) (xy 344.967591 -260.360873)
			(xy 345.010459 -260.396548) (xy 345.047676 -260.438085) (xy 345.078449 -260.484598) (xy 345.102121 -260.535095)
			(xy 345.118189 -260.588502) (xy 345.126309 -260.643678) (xy 345.126818 -260.671564) (xy 345.126309 -260.69945)
			(xy 345.118189 -260.754626) (xy 345.102121 -260.808033) (xy 345.078449 -260.85853) (xy 345.047676 -260.905043)
			(xy 345.010459 -260.94658) (xy 344.967591 -260.982255) (xy 344.919985 -261.011309) (xy 344.868656 -261.033121)
			(xy 344.814699 -261.047227) (xy 344.759262 -261.053327) (xy 344.703528 -261.05129) (xy 344.648685 -261.04116)
			(xy 344.595901 -261.023153) (xy 344.546301 -260.997652) (xy 344.500943 -260.965201) (xy 344.460794 -260.926492)
			(xy 344.426708 -260.882349) (xy 344.399412 -260.833714) (xy 344.379489 -260.781623) (xy 344.367363 -260.727186)
			(xy 344.363292 -260.671564) (xy 342.758776 -260.671564) (xy 342.758776 -261.881112) (xy 342.758363 -261.891183)
			(xy 342.750634 -261.909781) (xy 342.74379 -261.91718) (xy 342.392 -262.26897) (xy 342.38459 -262.275798)
			(xy 342.365999 -262.283526) (xy 342.355932 -262.283956) (xy 340.120732 -262.283956) (xy 340.110663 -262.283525)
			(xy 340.092065 -262.27581) (xy 340.084664 -262.26897) (xy 339.651086 -261.835138) (xy 339.644268 -261.82772)
			(xy 339.636536 -261.809135) (xy 339.6361 -261.79907) (xy 339.6361 -259.747258) (xy 339.635723 -259.737183)
			(xy 339.627971 -259.718584) (xy 339.621114 -259.71119) (xy 333.15275 -253.24308) (xy 333.145916 -253.235675)
			(xy 333.138191 -253.21708) (xy 333.137764 -253.207012) (xy 331.095858 -253.207012) (xy 331.095858 -254.030988)
			(xy 331.096874 -254.040386) (xy 331.096874 -254.040894) (xy 331.098579 -254.048053) (xy 331.105411 -254.06108)
			(xy 331.110336 -254.066548) (xy 339.188806 -262.145018) (xy 339.212009 -262.168923) (xy 339.252599 -262.221751)
			(xy 339.285937 -262.279431) (xy 339.311452 -262.340972) (xy 339.328705 -262.40532) (xy 339.337401 -262.471371)
			(xy 339.337904 -262.504682) (xy 339.337442 -262.535388) (xy 339.330044 -262.596351) (xy 339.315352 -262.655979)
			(xy 339.293583 -262.713402) (xy 339.265052 -262.767783) (xy 339.230175 -262.818329) (xy 339.189461 -262.864304)
			(xy 339.143504 -262.905038) (xy 339.092973 -262.939937) (xy 339.038605 -262.968491) (xy 338.981191 -262.990286)
			(xy 338.92157 -263.005003) (xy 338.860609 -263.012429) (xy 338.829904 -263.012936) (xy 338.829396 -263.012936)
			(xy 338.796118 -263.012392) (xy 338.730131 -263.003707) (xy 338.665841 -262.986486) (xy 338.604348 -262.961023)
			(xy 338.546703 -262.927755) (xy 338.493892 -262.887248) (xy 338.469986 -262.864092) (xy 331.26934 -255.6637)
			(xy 331.258376 -255.653481) (xy 331.231963 -255.639347) (xy 331.202585 -255.633484) (xy 331.17277 -255.636397)
			(xy 331.145082 -255.647833) (xy 331.121903 -255.666811) (xy 331.105227 -255.691697) (xy 331.096487 -255.720351)
			(xy 331.095858 -255.735328) (xy 331.095858 -262.87603) (xy 331.095923 -262.879635) (xy 331.096946 -262.886774)
			(xy 331.09789 -262.890254) (xy 331.219543 -263.308084) (xy 331.439772 -263.308084) (xy 331.443843 -263.252462)
			(xy 331.455969 -263.198025) (xy 331.475892 -263.145934) (xy 331.503188 -263.097299) (xy 331.537274 -263.053156)
			(xy 331.577423 -263.014447) (xy 331.622781 -262.981996) (xy 331.672381 -262.956495) (xy 331.725165 -262.938488)
			(xy 331.780008 -262.928358) (xy 331.835742 -262.926321) (xy 331.891179 -262.932421) (xy 331.945136 -262.946527)
			(xy 331.996465 -262.968339) (xy 332.044071 -262.997393) (xy 332.086939 -263.033068) (xy 332.124156 -263.074605)
			(xy 332.154929 -263.121118) (xy 332.178601 -263.171615) (xy 332.194669 -263.225022) (xy 332.202789 -263.280198)
			(xy 332.20282 -263.281922) (xy 333.087724 -263.281922) (xy 333.091795 -263.2263) (xy 333.103921 -263.171863)
			(xy 333.123844 -263.119772) (xy 333.15114 -263.071137) (xy 333.185226 -263.026994) (xy 333.225375 -262.988285)
			(xy 333.270733 -262.955834) (xy 333.320333 -262.930333) (xy 333.373117 -262.912326) (xy 333.42796 -262.902196)
			(xy 333.483694 -262.900159) (xy 333.539131 -262.906259) (xy 333.593088 -262.920365) (xy 333.644417 -262.942177)
			(xy 333.692023 -262.971231) (xy 333.734891 -263.006906) (xy 333.772108 -263.048443) (xy 333.802881 -263.094956)
			(xy 333.826553 -263.145453) (xy 333.842621 -263.19886) (xy 333.850741 -263.254036) (xy 333.85125 -263.281922)
			(xy 333.850741 -263.309808) (xy 333.842621 -263.364984) (xy 333.826553 -263.418391) (xy 333.802881 -263.468888)
			(xy 333.772108 -263.515401) (xy 333.734891 -263.556938) (xy 333.692023 -263.592613) (xy 333.644417 -263.621667)
			(xy 333.593088 -263.643479) (xy 333.539131 -263.657585) (xy 333.483694 -263.663685) (xy 333.42796 -263.661648)
			(xy 333.373117 -263.651518) (xy 333.320333 -263.633511) (xy 333.270733 -263.60801) (xy 333.225375 -263.575559)
			(xy 333.185226 -263.53685) (xy 333.15114 -263.492707) (xy 333.123844 -263.444072) (xy 333.103921 -263.391981)
			(xy 333.091795 -263.337544) (xy 333.087724 -263.281922) (xy 332.20282 -263.281922) (xy 332.203298 -263.308084)
			(xy 332.202789 -263.33597) (xy 332.194669 -263.391146) (xy 332.178601 -263.444553) (xy 332.154929 -263.49505)
			(xy 332.124156 -263.541563) (xy 332.086939 -263.5831) (xy 332.044071 -263.618775) (xy 331.996465 -263.647829)
			(xy 331.945136 -263.669641) (xy 331.891179 -263.683747) (xy 331.835742 -263.689847) (xy 331.780008 -263.68781)
			(xy 331.725165 -263.67768) (xy 331.672381 -263.659673) (xy 331.622781 -263.634172) (xy 331.577423 -263.601721)
			(xy 331.537274 -263.563012) (xy 331.503188 -263.518869) (xy 331.475892 -263.470234) (xy 331.455969 -263.418143)
			(xy 331.443843 -263.363706) (xy 331.439772 -263.308084) (xy 331.219543 -263.308084) (xy 331.419069 -263.993376)
			(xy 333.820006 -263.993376) (xy 333.824077 -263.937754) (xy 333.836203 -263.883317) (xy 333.856126 -263.831226)
			(xy 333.883422 -263.782591) (xy 333.917508 -263.738448) (xy 333.957657 -263.699739) (xy 334.003015 -263.667288)
			(xy 334.052615 -263.641787) (xy 334.105399 -263.62378) (xy 334.160242 -263.61365) (xy 334.215976 -263.611613)
			(xy 334.271413 -263.617713) (xy 334.282089 -263.620504) (xy 335.037428 -263.620504) (xy 335.041499 -263.564882)
			(xy 335.053625 -263.510445) (xy 335.073548 -263.458354) (xy 335.100844 -263.409719) (xy 335.13493 -263.365576)
			(xy 335.175079 -263.326867) (xy 335.220437 -263.294416) (xy 335.270037 -263.268915) (xy 335.322821 -263.250908)
			(xy 335.377664 -263.240778) (xy 335.433398 -263.238741) (xy 335.488835 -263.244841) (xy 335.542792 -263.258947)
			(xy 335.594121 -263.280759) (xy 335.641727 -263.309813) (xy 335.684595 -263.345488) (xy 335.721812 -263.387025)
			(xy 335.752585 -263.433538) (xy 335.776257 -263.484035) (xy 335.792325 -263.537442) (xy 335.800445 -263.592618)
			(xy 335.800954 -263.620504) (xy 335.800445 -263.64839) (xy 335.792325 -263.703566) (xy 335.776257 -263.756973)
			(xy 335.752585 -263.80747) (xy 335.721812 -263.853983) (xy 335.684595 -263.89552) (xy 335.641727 -263.931195)
			(xy 335.594121 -263.960249) (xy 335.542792 -263.982061) (xy 335.488835 -263.996167) (xy 335.433398 -264.002267)
			(xy 335.377664 -264.00023) (xy 335.322821 -263.9901) (xy 335.270037 -263.972093) (xy 335.220437 -263.946592)
			(xy 335.175079 -263.914141) (xy 335.13493 -263.875432) (xy 335.100844 -263.831289) (xy 335.073548 -263.782654)
			(xy 335.053625 -263.730563) (xy 335.041499 -263.676126) (xy 335.037428 -263.620504) (xy 334.282089 -263.620504)
			(xy 334.32537 -263.631819) (xy 334.376699 -263.653631) (xy 334.424305 -263.682685) (xy 334.467173 -263.71836)
			(xy 334.50439 -263.759897) (xy 334.535163 -263.80641) (xy 334.558835 -263.856907) (xy 334.574903 -263.910314)
			(xy 334.583023 -263.96549) (xy 334.583532 -263.993376) (xy 334.583023 -264.021262) (xy 334.574903 -264.076438)
			(xy 334.558835 -264.129845) (xy 334.535163 -264.180342) (xy 334.50439 -264.226855) (xy 334.467173 -264.268392)
			(xy 334.424305 -264.304067) (xy 334.411067 -264.312146) (xy 335.602324 -264.312146) (xy 335.606395 -264.256524)
			(xy 335.618521 -264.202087) (xy 335.638444 -264.149996) (xy 335.66574 -264.101361) (xy 335.699826 -264.057218)
			(xy 335.739975 -264.018509) (xy 335.785333 -263.986058) (xy 335.834933 -263.960557) (xy 335.887717 -263.94255)
			(xy 335.94256 -263.93242) (xy 335.998294 -263.930383) (xy 336.053731 -263.936483) (xy 336.107688 -263.950589)
			(xy 336.159017 -263.972401) (xy 336.206623 -264.001455) (xy 336.249491 -264.03713) (xy 336.286708 -264.078667)
			(xy 336.317481 -264.12518) (xy 336.341153 -264.175677) (xy 336.357221 -264.229084) (xy 336.365341 -264.28426)
			(xy 336.36585 -264.312146) (xy 336.365341 -264.340032) (xy 336.357221 -264.395208) (xy 336.341153 -264.448615)
			(xy 336.317481 -264.499112) (xy 336.286708 -264.545625) (xy 336.249491 -264.587162) (xy 336.206623 -264.622837)
			(xy 336.159017 -264.651891) (xy 336.107688 -264.673703) (xy 336.053731 -264.687809) (xy 335.998294 -264.693909)
			(xy 335.94256 -264.691872) (xy 335.887717 -264.681742) (xy 335.834933 -264.663735) (xy 335.785333 -264.638234)
			(xy 335.739975 -264.605783) (xy 335.699826 -264.567074) (xy 335.66574 -264.522931) (xy 335.638444 -264.474296)
			(xy 335.618521 -264.422205) (xy 335.606395 -264.367768) (xy 335.602324 -264.312146) (xy 334.411067 -264.312146)
			(xy 334.376699 -264.333121) (xy 334.32537 -264.354933) (xy 334.271413 -264.369039) (xy 334.215976 -264.375139)
			(xy 334.160242 -264.373102) (xy 334.105399 -264.362972) (xy 334.052615 -264.344965) (xy 334.003015 -264.319464)
			(xy 333.957657 -264.287013) (xy 333.917508 -264.248304) (xy 333.883422 -264.204161) (xy 333.856126 -264.155526)
			(xy 333.836203 -264.103435) (xy 333.824077 -264.048998) (xy 333.820006 -263.993376) (xy 331.419069 -263.993376)
			(xy 331.676501 -264.87755) (xy 333.781906 -264.87755) (xy 333.785977 -264.821928) (xy 333.798103 -264.767491)
			(xy 333.818026 -264.7154) (xy 333.845322 -264.666765) (xy 333.879408 -264.622622) (xy 333.919557 -264.583913)
			(xy 333.964915 -264.551462) (xy 334.014515 -264.525961) (xy 334.067299 -264.507954) (xy 334.122142 -264.497824)
			(xy 334.177876 -264.495787) (xy 334.233313 -264.501887) (xy 334.28727 -264.515993) (xy 334.338599 -264.537805)
			(xy 334.386205 -264.566859) (xy 334.429073 -264.602534) (xy 334.46629 -264.644071) (xy 334.497063 -264.690584)
			(xy 334.520735 -264.741081) (xy 334.536803 -264.794488) (xy 334.544923 -264.849664) (xy 334.545432 -264.87755)
			(xy 334.544923 -264.905436) (xy 334.536803 -264.960612) (xy 334.520735 -265.014019) (xy 334.497063 -265.064516)
			(xy 334.46629 -265.111029) (xy 334.429073 -265.152566) (xy 334.386205 -265.188241) (xy 334.338599 -265.217295)
			(xy 334.28727 -265.239107) (xy 334.233313 -265.253213) (xy 334.177876 -265.259313) (xy 334.122142 -265.257276)
			(xy 334.067299 -265.247146) (xy 334.014515 -265.229139) (xy 333.964915 -265.203638) (xy 333.919557 -265.171187)
			(xy 333.879408 -265.132478) (xy 333.845322 -265.088335) (xy 333.818026 -265.0397) (xy 333.798103 -264.987609)
			(xy 333.785977 -264.933172) (xy 333.781906 -264.87755) (xy 331.676501 -264.87755) (xy 332.831948 -268.846046)
			(xy 332.83713 -268.86424) (xy 332.846277 -268.900953) (xy 332.850236 -268.919452) (xy 332.850744 -268.921484)
			(xy 332.995249 -269.417038) (xy 334.700626 -269.417038) (xy 334.701132 -269.388299) (xy 334.709762 -269.331471)
			(xy 334.726817 -269.276581) (xy 334.751912 -269.22487) (xy 334.784479 -269.177507) (xy 334.80375 -269.15618)
			(xy 334.810354 -269.149322) (xy 334.817466 -269.131288) (xy 334.817466 -269.042388) (xy 334.810354 -269.024354)
			(xy 334.80375 -269.017496) (xy 334.784499 -268.996152) (xy 334.75193 -268.948795) (xy 334.726833 -268.897087)
			(xy 334.709778 -268.8422) (xy 334.70115 -268.785376) (xy 334.700626 -268.756638) (xy 334.701091 -268.729385)
			(xy 334.708843 -268.675432) (xy 334.724196 -268.623132) (xy 334.746837 -268.57355) (xy 334.776304 -268.527695)
			(xy 334.811998 -268.486501) (xy 334.853192 -268.450807) (xy 334.899046 -268.421339) (xy 334.948628 -268.398698)
			(xy 335.000928 -268.383344) (xy 335.054881 -268.375591) (xy 335.082134 -268.37513) (xy 335.109505 -268.375569)
			(xy 335.163686 -268.383392) (xy 335.21619 -268.398887) (xy 335.265936 -268.421735) (xy 335.311901 -268.451466)
			(xy 335.332832 -268.46911) (xy 335.333086 -268.469364) (xy 335.340167 -268.474958) (xy 335.357088 -268.481199)
			(xy 335.366106 -268.481556) (xy 335.433162 -268.481556) (xy 335.442178 -268.48119) (xy 335.459096 -268.47495)
			(xy 335.466182 -268.469364) (xy 335.466182 -268.46911) (xy 335.466436 -268.46911) (xy 335.487369 -268.451469)
			(xy 335.533337 -268.421745) (xy 335.583083 -268.398899) (xy 335.635585 -268.383403) (xy 335.689763 -268.375574)
			(xy 335.744505 -268.375574) (xy 335.798683 -268.383403) (xy 335.851185 -268.398899) (xy 335.900931 -268.421745)
			(xy 335.946899 -268.451469) (xy 335.967832 -268.46911) (xy 335.968086 -268.469364) (xy 335.975167 -268.474958)
			(xy 335.992088 -268.481199) (xy 336.001106 -268.481556) (xy 336.068162 -268.481556) (xy 336.077178 -268.48119)
			(xy 336.094096 -268.47495) (xy 336.101182 -268.469364) (xy 336.101182 -268.46911) (xy 336.101436 -268.46911)
			(xy 336.122369 -268.451469) (xy 336.168337 -268.421745) (xy 336.218083 -268.398899) (xy 336.270585 -268.383403)
			(xy 336.324763 -268.375574) (xy 336.379505 -268.375574) (xy 336.433683 -268.383403) (xy 336.486185 -268.398899)
			(xy 336.535931 -268.421745) (xy 336.581899 -268.451469) (xy 336.602832 -268.46911) (xy 336.603086 -268.469364)
			(xy 336.610167 -268.474958) (xy 336.627088 -268.481199) (xy 336.636106 -268.481556) (xy 336.703162 -268.481556)
			(xy 336.712178 -268.48119) (xy 336.729096 -268.47495) (xy 336.736182 -268.469364) (xy 336.736182 -268.46911)
			(xy 336.736436 -268.46911) (xy 336.757369 -268.451469) (xy 336.803337 -268.421745) (xy 336.853083 -268.398899)
			(xy 336.905585 -268.383403) (xy 336.959763 -268.375574) (xy 337.014505 -268.375574) (xy 337.068683 -268.383403)
			(xy 337.121185 -268.398899) (xy 337.170931 -268.421745) (xy 337.216899 -268.451469) (xy 337.237832 -268.46911)
			(xy 337.238086 -268.469364) (xy 337.245167 -268.474958) (xy 337.262088 -268.481199) (xy 337.271106 -268.481556)
			(xy 337.338162 -268.481556) (xy 337.347178 -268.48119) (xy 337.364096 -268.47495) (xy 337.371182 -268.469364)
			(xy 337.371182 -268.46911) (xy 337.371436 -268.46911) (xy 337.392383 -268.451489) (xy 337.438351 -268.421774)
			(xy 337.488095 -268.398935) (xy 337.540593 -268.383439) (xy 337.594766 -268.375606) (xy 337.622134 -268.37513)
			(xy 337.649389 -268.375523) (xy 337.703345 -268.383286) (xy 337.755646 -268.398648) (xy 337.805229 -268.421297)
			(xy 337.851084 -268.450773) (xy 337.892277 -268.486474) (xy 337.927971 -268.527674) (xy 337.957437 -268.573534)
			(xy 337.980077 -268.623121) (xy 337.995429 -268.675426) (xy 338.003182 -268.729382) (xy 338.003642 -268.756638)
			(xy 338.00313 -268.785377) (xy 337.994503 -268.842205) (xy 337.977449 -268.897095) (xy 337.952356 -268.948807)
			(xy 337.919789 -268.996169) (xy 337.900518 -269.017496) (xy 337.893914 -269.024354) (xy 337.886802 -269.042388)
			(xy 337.886802 -269.131288) (xy 337.893914 -269.149322) (xy 337.900518 -269.15618) (xy 337.919799 -269.177498)
			(xy 337.952366 -269.224862) (xy 337.977457 -269.276575) (xy 337.994505 -269.331469) (xy 338.003124 -269.388298)
			(xy 338.003642 -269.417038) (xy 338.003158 -269.444289) (xy 337.995397 -269.498235) (xy 337.980039 -269.550527)
			(xy 337.957396 -269.600102) (xy 337.927928 -269.645951) (xy 337.892237 -269.68714) (xy 337.851048 -269.722831)
			(xy 337.805199 -269.752297) (xy 337.755624 -269.77494) (xy 337.703331 -269.790298) (xy 337.649385 -269.798058)
			(xy 337.622134 -269.798546) (xy 337.594764 -269.798073) (xy 337.540585 -269.790259) (xy 337.488081 -269.774772)
			(xy 337.438334 -269.751932) (xy 337.392367 -269.722207) (xy 337.371436 -269.704566) (xy 337.371182 -269.704312)
			(xy 337.364104 -269.698713) (xy 337.347181 -269.692473) (xy 337.338162 -269.69212) (xy 337.271106 -269.69212)
			(xy 337.262089 -269.692475) (xy 337.245172 -269.698724) (xy 337.238086 -269.704312) (xy 337.237832 -269.704566)
			(xy 337.216899 -269.722207) (xy 337.170931 -269.751931) (xy 337.121185 -269.774777) (xy 337.068683 -269.790273)
			(xy 337.014505 -269.798102) (xy 336.959763 -269.798102) (xy 336.905585 -269.790273) (xy 336.853083 -269.774777)
			(xy 336.803337 -269.751931) (xy 336.757369 -269.722207) (xy 336.736436 -269.704566) (xy 336.736182 -269.704312)
			(xy 336.729104 -269.698713) (xy 336.712181 -269.692473) (xy 336.703162 -269.69212) (xy 336.636106 -269.69212)
			(xy 336.627089 -269.692475) (xy 336.610172 -269.698724) (xy 336.603086 -269.704312) (xy 336.603086 -269.704566)
			(xy 336.602832 -269.704566) (xy 336.581899 -269.722207) (xy 336.535931 -269.751931) (xy 336.486185 -269.774777)
			(xy 336.433683 -269.790273) (xy 336.379505 -269.798102) (xy 336.324763 -269.798102) (xy 336.270585 -269.790273)
			(xy 336.218083 -269.774777) (xy 336.168337 -269.751931) (xy 336.122369 -269.722207) (xy 336.101436 -269.704566)
			(xy 336.101182 -269.704312) (xy 336.094104 -269.698713) (xy 336.077181 -269.692473) (xy 336.068162 -269.69212)
			(xy 336.001106 -269.69212) (xy 335.992089 -269.692475) (xy 335.975172 -269.698724) (xy 335.968086 -269.704312)
			(xy 335.968086 -269.704566) (xy 335.967832 -269.704566) (xy 335.946899 -269.722207) (xy 335.900931 -269.751931)
			(xy 335.851185 -269.774777) (xy 335.798683 -269.790273) (xy 335.744505 -269.798102) (xy 335.689763 -269.798102)
			(xy 335.635585 -269.790273) (xy 335.583083 -269.774777) (xy 335.533337 -269.751931) (xy 335.487369 -269.722207)
			(xy 335.466436 -269.704566) (xy 335.466182 -269.704312) (xy 335.459104 -269.698713) (xy 335.442181 -269.692473)
			(xy 335.433162 -269.69212) (xy 335.366106 -269.69212) (xy 335.357089 -269.692475) (xy 335.340172 -269.698724)
			(xy 335.333086 -269.704312) (xy 335.333086 -269.704566) (xy 335.332832 -269.704566) (xy 335.311894 -269.722198)
			(xy 335.265924 -269.751912) (xy 335.216178 -269.77475) (xy 335.163678 -269.790243) (xy 335.109503 -269.798072)
			(xy 335.082134 -269.798546) (xy 335.054885 -269.79799) (xy 335.000942 -269.790239) (xy 334.948651 -269.77489)
			(xy 334.899077 -269.752256) (xy 334.853228 -269.722797) (xy 334.812038 -269.687113) (xy 334.776346 -269.64593)
			(xy 334.746878 -269.600087) (xy 334.724235 -269.550516) (xy 334.708876 -269.498228) (xy 334.701115 -269.444287)
			(xy 334.700626 -269.417038) (xy 332.995249 -269.417038) (xy 333.043022 -269.580868) (xy 333.043784 -269.583408)
			(xy 333.043784 -269.583662) (xy 333.044292 -269.58544) (xy 333.047086 -269.594838) (xy 333.047086 -269.595346)
			(xy 333.086202 -269.729204) (xy 333.087307 -269.733172) (xy 333.088333 -269.741343) (xy 333.088234 -269.74546)
			(xy 333.082392 -269.88008) (xy 333.082392 -269.880842) (xy 333.082138 -269.890494) (xy 333.081884 -269.895066)
			(xy 333.081884 -269.896336) (xy 333.08163 -269.899384) (xy 333.079598 -269.949168) (xy 332.940914 -273.172174)
			(xy 332.913228 -273.813524) (xy 332.913228 -273.813778) (xy 332.91272 -273.827748) (xy 332.903322 -274.040346)
			(xy 332.902903 -274.046409) (xy 332.899566 -274.058091) (xy 332.896718 -274.06346) (xy 332.792832 -274.245578)
			(xy 332.792578 -274.246086) (xy 332.78445 -274.260564) (xy 332.7527 -274.31619) (xy 332.7527 -274.316444)
			(xy 332.546452 -274.677886) (xy 331.989938 -275.654008) (xy 331.988668 -275.662898) (xy 331.987906 -275.666962)
			(xy 331.987906 -277.864824) (xy 335.665826 -277.864824) (xy 335.666352 -277.835907) (xy 335.675078 -277.778736)
			(xy 335.692334 -277.723537) (xy 335.717724 -277.671575) (xy 335.750667 -277.624041) (xy 335.790407 -277.582024)
			(xy 335.812892 -277.563834) (xy 335.821673 -277.556201) (xy 335.831871 -277.53532) (xy 335.83245 -277.523702)
			(xy 335.83245 -277.443946) (xy 335.831945 -277.432309) (xy 335.821734 -277.411399) (xy 335.812892 -277.403814)
			(xy 335.790414 -277.385617) (xy 335.750678 -277.343598) (xy 335.717739 -277.296065) (xy 335.69235 -277.244104)
			(xy 335.675092 -277.188908) (xy 335.666362 -277.13174) (xy 335.665826 -277.102824) (xy 335.666409 -277.073417)
			(xy 335.675439 -277.015299) (xy 335.693274 -276.959253) (xy 335.719492 -276.906605) (xy 335.753473 -276.858599)
			(xy 335.794413 -276.816372) (xy 335.841345 -276.780923) (xy 335.866994 -276.766528) (xy 335.878932 -276.760178)
			(xy 335.893156 -276.737826) (xy 335.898998 -276.624288) (xy 335.88706 -276.600412) (xy 335.876138 -276.593046)
			(xy 335.85438 -276.577735) (xy 335.814901 -276.542071) (xy 335.780757 -276.50127) (xy 335.75261 -276.456123)
			(xy 335.731005 -276.407505) (xy 335.716362 -276.356357) (xy 335.708964 -276.303671) (xy 335.708498 -276.27707)
			(xy 335.708947 -276.249699) (xy 335.716769 -276.195519) (xy 335.732262 -276.143016) (xy 335.755108 -276.09327)
			(xy 335.784835 -276.047303) (xy 335.802478 -276.026372) (xy 335.802732 -276.026118) (xy 335.808321 -276.019033)
			(xy 335.814565 -276.002115) (xy 335.814924 -275.993098) (xy 335.814924 -275.926042) (xy 335.814542 -275.917028)
			(xy 335.808311 -275.900111) (xy 335.802732 -275.893022) (xy 335.802478 -275.893022) (xy 335.802478 -275.892768)
			(xy 335.784854 -275.871824) (xy 335.755141 -275.825854) (xy 335.732302 -275.77611) (xy 335.716807 -275.723612)
			(xy 335.708975 -275.669438) (xy 335.708498 -275.64207) (xy 335.708498 -275.641816) (xy 335.709069 -275.612017)
			(xy 335.718346 -275.553146) (xy 335.736663 -275.496434) (xy 335.763574 -275.443258) (xy 335.798424 -275.394912)
			(xy 335.818988 -275.373338) (xy 335.826354 -275.365972) (xy 335.833974 -275.34743) (xy 335.832958 -275.25472)
			(xy 335.825084 -275.236178) (xy 335.817718 -275.229066) (xy 335.799761 -275.211015) (xy 335.768263 -275.171012)
			(xy 335.742365 -275.127176) (xy 335.722525 -275.080286) (xy 335.709097 -275.031173) (xy 335.70232 -274.980711)
			(xy 335.701894 -274.955254) (xy 335.702335 -274.928002) (xy 335.710098 -274.874052) (xy 335.725459 -274.821756)
			(xy 335.748106 -274.772179) (xy 335.777577 -274.726329) (xy 335.813273 -274.685139) (xy 335.854467 -274.649448)
			(xy 335.900321 -274.619983) (xy 335.949901 -274.597342) (xy 336.002199 -274.581988) (xy 336.056149 -274.574232)
			(xy 336.083402 -274.573746) (xy 336.11232 -274.574246) (xy 336.169493 -274.582976) (xy 336.224693 -274.600237)
			(xy 336.276655 -274.625632) (xy 336.324188 -274.658579) (xy 336.366203 -274.698324) (xy 336.384392 -274.720812)
			(xy 336.39201 -274.729607) (xy 336.412903 -274.739797) (xy 336.424524 -274.74037) (xy 336.50428 -274.74037)
			(xy 336.51591 -274.739816) (xy 336.536821 -274.729639) (xy 336.544412 -274.720812) (xy 336.561165 -274.700029)
			(xy 336.599519 -274.662899) (xy 336.642673 -274.631477) (xy 336.689787 -274.606378) (xy 336.739939 -274.588092)
			(xy 336.79215 -274.576975) (xy 336.845402 -274.573245) (xy 336.898654 -274.576975) (xy 336.950865 -274.588092)
			(xy 337.001017 -274.606378) (xy 337.048131 -274.631477) (xy 337.091285 -274.662899) (xy 337.129639 -274.700029)
			(xy 337.146392 -274.720812) (xy 337.15401 -274.729607) (xy 337.174903 -274.739797) (xy 337.186524 -274.74037)
			(xy 337.26628 -274.74037) (xy 337.27791 -274.739816) (xy 337.298821 -274.729639) (xy 337.306412 -274.720812)
			(xy 337.324599 -274.698325) (xy 337.366619 -274.65859) (xy 337.414155 -274.625651) (xy 337.466117 -274.600263)
			(xy 337.521315 -274.583007) (xy 337.578486 -274.57428) (xy 337.607402 -274.573746) (xy 337.634651 -274.574276)
			(xy 337.688595 -274.582031) (xy 337.740886 -274.597384) (xy 337.79046 -274.620022) (xy 337.836308 -274.649485)
			(xy 337.877497 -274.685171) (xy 337.913189 -274.726356) (xy 337.942656 -274.772201) (xy 337.9653 -274.821773)
			(xy 337.980659 -274.874062) (xy 337.988421 -274.928005) (xy 337.98891 -274.955254) (xy 337.98891 -274.955508)
			(xy 337.988352 -274.985307) (xy 337.979071 -275.044178) (xy 337.960751 -275.100891) (xy 337.933837 -275.154067)
			(xy 337.898985 -275.202413) (xy 337.87842 -275.223986) (xy 337.871054 -275.231352) (xy 337.863434 -275.249894)
			(xy 337.86445 -275.342604) (xy 337.872324 -275.361146) (xy 337.87969 -275.368258) (xy 337.89766 -275.386296)
			(xy 337.929156 -275.426302) (xy 337.955053 -275.470141) (xy 337.97489 -275.517034) (xy 337.988315 -275.566148)
			(xy 337.99509 -275.616612) (xy 337.995514 -275.64207) (xy 337.995007 -275.670988) (xy 337.98628 -275.728161)
			(xy 337.969022 -275.783361) (xy 337.943629 -275.835324) (xy 337.910681 -275.882857) (xy 337.870936 -275.924872)
			(xy 337.848448 -275.94306) (xy 337.83966 -275.950685) (xy 337.829468 -275.971573) (xy 337.82889 -275.983192)
			(xy 337.82889 -276.062948) (xy 337.829419 -276.074581) (xy 337.839615 -276.09549) (xy 337.848448 -276.10308)
			(xy 337.870932 -276.12127) (xy 337.910665 -276.163292) (xy 337.943602 -276.210827) (xy 337.96899 -276.262788)
			(xy 337.986247 -276.317985) (xy 337.994978 -276.375154) (xy 337.995514 -276.40407) (xy 337.995017 -276.431322)
			(xy 337.987264 -276.485271) (xy 337.971912 -276.537568) (xy 337.949274 -276.587148) (xy 337.919809 -276.633001)
			(xy 337.884119 -276.674194) (xy 337.84293 -276.709888) (xy 337.797079 -276.739356) (xy 337.747502 -276.762)
			(xy 337.695206 -276.777356) (xy 337.641258 -276.785114) (xy 337.614006 -276.785578) (xy 337.585089 -276.785064)
			(xy 337.527917 -276.776335) (xy 337.472718 -276.759077) (xy 337.420756 -276.733684) (xy 337.373222 -276.70074)
			(xy 337.331206 -276.660998) (xy 337.313016 -276.638512) (xy 337.30539 -276.629724) (xy 337.284504 -276.619529)
			(xy 337.272884 -276.618954) (xy 337.193128 -276.618954) (xy 337.181497 -276.619505) (xy 337.160586 -276.629683)
			(xy 337.152996 -276.638512) (xy 337.142965 -276.651117) (xy 337.121089 -276.674769) (xy 337.109308 -276.685756)
			(xy 337.100418 -276.693884) (xy 337.091782 -276.715982) (xy 337.100418 -276.808692) (xy 337.102114 -276.820317)
			(xy 337.114422 -276.840299) (xy 337.12404 -276.847046) (xy 337.124294 -276.8473) (xy 337.147602 -276.862308)
			(xy 337.190041 -276.897972) (xy 337.226868 -276.939406) (xy 337.257308 -276.985735) (xy 337.28072 -277.035983)
			(xy 337.296609 -277.089091) (xy 337.304642 -277.143941) (xy 337.305142 -277.171658) (xy 337.304656 -277.198909)
			(xy 337.2969 -277.252857) (xy 337.281545 -277.305152) (xy 337.258903 -277.354729) (xy 337.229437 -277.400579)
			(xy 337.193746 -277.44177) (xy 337.152555 -277.477461) (xy 337.106705 -277.506927) (xy 337.057128 -277.529569)
			(xy 337.004833 -277.544924) (xy 336.950885 -277.55268) (xy 336.896383 -277.55268) (xy 336.842435 -277.544924)
			(xy 336.79014 -277.529569) (xy 336.740563 -277.506927) (xy 336.694713 -277.477461) (xy 336.653522 -277.44177)
			(xy 336.617831 -277.400579) (xy 336.588365 -277.354729) (xy 336.565723 -277.305152) (xy 336.550368 -277.252857)
			(xy 336.542612 -277.198909) (xy 336.542126 -277.171658) (xy 336.542599 -277.14524) (xy 336.549883 -277.09291)
			(xy 336.564319 -277.042086) (xy 336.585632 -276.99374) (xy 336.613413 -276.948798) (xy 336.647131 -276.908121)
			(xy 336.666332 -276.889972) (xy 336.675222 -276.881844) (xy 336.683858 -276.859746) (xy 336.675222 -276.767036)
			(xy 336.673535 -276.755408) (xy 336.661222 -276.735426) (xy 336.6516 -276.728682) (xy 336.651346 -276.728428)
			(xy 336.62973 -276.71459) (xy 336.590072 -276.682011) (xy 336.555155 -276.644394) (xy 336.525613 -276.602425)
			(xy 336.513424 -276.579838) (xy 336.507836 -276.56917) (xy 336.488786 -276.5552) (xy 336.396584 -276.539706)
			(xy 336.38488 -276.538458) (xy 336.362394 -276.545319) (xy 336.353404 -276.552914) (xy 336.35315 -276.553168)
			(xy 336.334296 -276.57061) (xy 336.292756 -276.600817) (xy 336.270346 -276.613366) (xy 336.258408 -276.619716)
			(xy 336.244184 -276.642068) (xy 336.238342 -276.755606) (xy 336.25028 -276.779482) (xy 336.261202 -276.786848)
			(xy 336.282944 -276.802182) (xy 336.322426 -276.83784) (xy 336.356574 -276.878636) (xy 336.384724 -276.923779)
			(xy 336.406331 -276.972394) (xy 336.420976 -277.02354) (xy 336.428376 -277.076224) (xy 336.428842 -277.102824)
			(xy 336.428291 -277.13174) (xy 336.419572 -277.188911) (xy 336.402322 -277.24411) (xy 336.376936 -277.296072)
			(xy 336.343997 -277.343607) (xy 336.30426 -277.385624) (xy 336.281776 -277.403814) (xy 336.272968 -277.411421)
			(xy 336.262786 -277.432322) (xy 336.262218 -277.443946) (xy 336.262218 -277.523702) (xy 336.262764 -277.535333)
			(xy 336.272947 -277.556243) (xy 336.281776 -277.563834) (xy 336.304271 -277.582012) (xy 336.344006 -277.624034)
			(xy 336.376945 -277.671571) (xy 336.402331 -277.723535) (xy 336.419585 -277.778735) (xy 336.42831 -277.835907)
			(xy 336.428842 -277.864824) (xy 336.428356 -277.892075) (xy 336.4206 -277.946023) (xy 336.405245 -277.998318)
			(xy 336.382603 -278.047895) (xy 336.353137 -278.093745) (xy 336.317446 -278.134936) (xy 336.276255 -278.170627)
			(xy 336.230405 -278.200093) (xy 336.180828 -278.222735) (xy 336.128533 -278.23809) (xy 336.074585 -278.245846)
			(xy 336.020083 -278.245846) (xy 335.966135 -278.23809) (xy 335.91384 -278.222735) (xy 335.864263 -278.200093)
			(xy 335.818413 -278.170627) (xy 335.777222 -278.134936) (xy 335.741531 -278.093745) (xy 335.712065 -278.047895)
			(xy 335.689423 -277.998318) (xy 335.674068 -277.946023) (xy 335.666312 -277.892075) (xy 335.665826 -277.864824)
			(xy 331.987906 -277.864824) (xy 331.987906 -280.082244) (xy 331.988402 -280.092245) (xy 331.996069 -280.110721)
			(xy 332.010221 -280.124859) (xy 332.028704 -280.132508) (xy 332.038706 -280.133044) (xy 336.326988 -280.133044)
			(xy 336.358546 -280.133594) (xy 336.421115 -280.141886) (xy 336.482073 -280.158251) (xy 336.540382 -280.182411)
			(xy 336.59505 -280.213955) (xy 336.645148 -280.252347) (xy 336.667856 -280.274268) (xy 337.870546 -281.476958)
			(xy 337.877945 -281.483802) (xy 337.896544 -281.491526) (xy 337.906614 -281.491944) (xy 338.082382 -281.491944)
			(xy 338.09133 -281.491585) (xy 338.108132 -281.48542) (xy 338.1218 -281.473866) (xy 338.126578 -281.46629)
			(xy 338.170012 -281.389836) (xy 338.174201 -281.381913) (xy 338.177274 -281.364269) (xy 338.174041 -281.346653)
			(xy 338.169758 -281.338782) (xy 338.157087 -281.316612) (xy 338.137133 -281.269606) (xy 338.123628 -281.220359)
			(xy 338.116814 -281.169751) (xy 338.116418 -281.144218) (xy 338.116469 -281.133592) (xy 338.117613 -281.11237)
			(xy 338.118704 -281.1018) (xy 338.11972 -281.092402) (xy 338.114894 -281.074114) (xy 338.06892 -281.010614)
			(xy 338.063102 -281.003316) (xy 338.047474 -280.99314) (xy 338.03844 -280.990802) (xy 338.038186 -280.990802)
			(xy 338.009403 -280.984305) (xy 337.954136 -280.963637) (xy 337.902708 -280.934713) (xy 337.856342 -280.89822)
			(xy 337.816142 -280.855029) (xy 337.783067 -280.806166) (xy 337.769962 -280.779728) (xy 337.766152 -280.7716)
			(xy 337.307682 -280.31313) (xy 337.288247 -280.292991) (xy 337.255319 -280.247738) (xy 337.22988 -280.197888)
			(xy 337.212558 -280.144671) (xy 337.20378 -280.089398) (xy 337.203288 -280.061416) (xy 337.203288 -278.931624)
			(xy 337.203857 -278.903647) (xy 337.212644 -278.848386) (xy 337.229958 -278.795178) (xy 337.255375 -278.745328)
			(xy 337.288269 -278.700064) (xy 337.307682 -278.67991) (xy 338.841334 -277.146258) (xy 338.848181 -277.13886)
			(xy 338.855911 -277.120261) (xy 338.85632 -277.11019) (xy 338.85632 -268.788896) (xy 338.856833 -268.760949)
			(xy 338.865565 -268.70574) (xy 338.88283 -268.652579) (xy 338.908202 -268.602775) (xy 338.941055 -268.557554)
			(xy 338.96046 -268.537436) (xy 340.987888 -266.510008) (xy 341.008043 -266.490646) (xy 341.053266 -266.457811)
			(xy 341.103063 -266.432441) (xy 341.156211 -266.415161) (xy 341.211405 -266.406393) (xy 341.239348 -266.405868)
			(xy 342.565482 -266.405868) (xy 342.575545 -266.405429) (xy 342.594125 -266.39769) (xy 342.60155 -266.390882)
			(xy 350.130618 -258.86156) (xy 350.137467 -258.854163) (xy 350.1452 -258.835564) (xy 350.145604 -258.825492)
			(xy 350.145604 -256.717546) (xy 350.146179 -256.689571) (xy 350.154977 -256.634317) (xy 350.172301 -256.581117)
			(xy 350.197725 -256.531277) (xy 350.230626 -256.486022) (xy 350.249998 -256.465832) (xy 352.98253 -253.7333)
			(xy 353.002686 -253.713941) (xy 353.047911 -253.681112) (xy 353.097708 -253.655749) (xy 353.150855 -253.638475)
			(xy 353.206048 -253.629714) (xy 353.23399 -253.62916) (xy 354.163376 -253.62916) (xy 354.171758 -253.626112)
			(xy 354.202978 -253.615605) (xy 354.267857 -253.604239) (xy 354.30079 -253.603506) (xy 354.328042 -253.603969)
			(xy 354.381992 -253.611724) (xy 354.434289 -253.627079) (xy 354.483869 -253.64972) (xy 354.529722 -253.679186)
			(xy 354.570914 -253.714879) (xy 354.606608 -253.75607) (xy 354.636075 -253.801922) (xy 354.658718 -253.851501)
			(xy 354.674074 -253.903798) (xy 354.681831 -253.957748) (xy 354.681831 -254.012252) (xy 354.674074 -254.066202)
			(xy 354.658718 -254.118499) (xy 354.636075 -254.168078) (xy 354.606608 -254.21393) (xy 354.570914 -254.255121)
			(xy 354.529722 -254.290814) (xy 354.483869 -254.32028) (xy 354.434289 -254.342921) (xy 354.381992 -254.358276)
			(xy 354.328042 -254.366031) (xy 354.30079 -254.366522) (xy 354.267856 -254.365806) (xy 354.202976 -254.354432)
			(xy 354.171758 -254.343916) (xy 354.163376 -254.340868) (xy 353.4029 -254.340868) (xy 353.392829 -254.34129)
			(xy 353.374222 -254.349001) (xy 353.366832 -254.355854) (xy 350.872806 -256.850134) (xy 350.865964 -256.857534)
			(xy 350.858241 -256.876132) (xy 350.85782 -256.886202) (xy 350.85782 -258.994148) (xy 350.857246 -259.022123)
			(xy 350.848449 -259.077378) (xy 350.831127 -259.13058) (xy 350.805704 -259.180421) (xy 350.772805 -259.225678)
			(xy 350.753426 -259.245862) (xy 347.803724 -262.195564) (xy 348.581978 -262.195564) (xy 348.586049 -262.139942)
			(xy 348.598175 -262.085505) (xy 348.618098 -262.033414) (xy 348.645394 -261.984779) (xy 348.67948 -261.940636)
			(xy 348.719629 -261.901927) (xy 348.764987 -261.869476) (xy 348.814587 -261.843975) (xy 348.867371 -261.825968)
			(xy 348.922214 -261.815838) (xy 348.977948 -261.813801) (xy 349.033385 -261.819901) (xy 349.087342 -261.834007)
			(xy 349.138671 -261.855819) (xy 349.186277 -261.884873) (xy 349.229145 -261.920548) (xy 349.266362 -261.962085)
			(xy 349.297135 -262.008598) (xy 349.320807 -262.059095) (xy 349.336875 -262.112502) (xy 349.344995 -262.167678)
			(xy 349.345504 -262.195564) (xy 349.344995 -262.22345) (xy 349.336875 -262.278626) (xy 349.320807 -262.332033)
			(xy 349.297135 -262.38253) (xy 349.266362 -262.429043) (xy 349.229145 -262.47058) (xy 349.186277 -262.506255)
			(xy 349.138671 -262.535309) (xy 349.087342 -262.557121) (xy 349.033385 -262.571227) (xy 348.977948 -262.577327)
			(xy 348.922214 -262.57529) (xy 348.867371 -262.56516) (xy 348.814587 -262.547153) (xy 348.764987 -262.521652)
			(xy 348.719629 -262.489201) (xy 348.67948 -262.450492) (xy 348.645394 -262.406349) (xy 348.618098 -262.357714)
			(xy 348.598175 -262.305623) (xy 348.586049 -262.251186) (xy 348.581978 -262.195564) (xy 347.803724 -262.195564)
			(xy 346.927424 -263.071864) (xy 348.581978 -263.071864) (xy 348.586049 -263.016242) (xy 348.598175 -262.961805)
			(xy 348.618098 -262.909714) (xy 348.645394 -262.861079) (xy 348.67948 -262.816936) (xy 348.719629 -262.778227)
			(xy 348.764987 -262.745776) (xy 348.814587 -262.720275) (xy 348.867371 -262.702268) (xy 348.922214 -262.692138)
			(xy 348.977948 -262.690101) (xy 349.033385 -262.696201) (xy 349.087342 -262.710307) (xy 349.138671 -262.732119)
			(xy 349.186277 -262.761173) (xy 349.229145 -262.796848) (xy 349.266362 -262.838385) (xy 349.297135 -262.884898)
			(xy 349.320807 -262.935395) (xy 349.336875 -262.988802) (xy 349.344995 -263.043978) (xy 349.345504 -263.071864)
			(xy 349.344995 -263.09975) (xy 349.336875 -263.154926) (xy 349.320807 -263.208333) (xy 349.297135 -263.25883)
			(xy 349.266362 -263.305343) (xy 349.229145 -263.34688) (xy 349.186277 -263.382555) (xy 349.138671 -263.411609)
			(xy 349.087342 -263.433421) (xy 349.033385 -263.447527) (xy 348.977948 -263.453627) (xy 348.922214 -263.45159)
			(xy 348.867371 -263.44146) (xy 348.814587 -263.423453) (xy 348.764987 -263.397952) (xy 348.719629 -263.365501)
			(xy 348.67948 -263.326792) (xy 348.645394 -263.282649) (xy 348.618098 -263.234014) (xy 348.598175 -263.181923)
			(xy 348.586049 -263.127486) (xy 348.581978 -263.071864) (xy 346.927424 -263.071864) (xy 345.869768 -264.12952)
			(xy 346.649292 -264.12952) (xy 346.653363 -264.073898) (xy 346.665489 -264.019461) (xy 346.685412 -263.96737)
			(xy 346.712708 -263.918735) (xy 346.746794 -263.874592) (xy 346.786943 -263.835883) (xy 346.832301 -263.803432)
			(xy 346.881901 -263.777931) (xy 346.934685 -263.759924) (xy 346.989528 -263.749794) (xy 347.045262 -263.747757)
			(xy 347.100699 -263.753857) (xy 347.154656 -263.767963) (xy 347.200951 -263.787636) (xy 349.771968 -263.787636)
			(xy 349.776039 -263.732014) (xy 349.788165 -263.677577) (xy 349.808088 -263.625486) (xy 349.835384 -263.576851)
			(xy 349.86947 -263.532708) (xy 349.909619 -263.493999) (xy 349.954977 -263.461548) (xy 350.004577 -263.436047)
			(xy 350.057361 -263.41804) (xy 350.112204 -263.40791) (xy 350.167938 -263.405873) (xy 350.223375 -263.411973)
			(xy 350.277332 -263.426079) (xy 350.328661 -263.447891) (xy 350.376267 -263.476945) (xy 350.419135 -263.51262)
			(xy 350.456352 -263.554157) (xy 350.487125 -263.60067) (xy 350.510797 -263.651167) (xy 350.526865 -263.704574)
			(xy 350.534985 -263.75975) (xy 350.535494 -263.787636) (xy 350.534985 -263.815522) (xy 350.526865 -263.870698)
			(xy 350.510797 -263.924105) (xy 350.487125 -263.974602) (xy 350.456352 -264.021115) (xy 350.419135 -264.062652)
			(xy 350.376267 -264.098327) (xy 350.328661 -264.127381) (xy 350.277332 -264.149193) (xy 350.223375 -264.163299)
			(xy 350.167938 -264.169399) (xy 350.112204 -264.167362) (xy 350.057361 -264.157232) (xy 350.004577 -264.139225)
			(xy 349.954977 -264.113724) (xy 349.909619 -264.081273) (xy 349.86947 -264.042564) (xy 349.835384 -263.998421)
			(xy 349.808088 -263.949786) (xy 349.788165 -263.897695) (xy 349.776039 -263.843258) (xy 349.771968 -263.787636)
			(xy 347.200951 -263.787636) (xy 347.205985 -263.789775) (xy 347.253591 -263.818829) (xy 347.296459 -263.854504)
			(xy 347.333676 -263.896041) (xy 347.364449 -263.942554) (xy 347.388121 -263.993051) (xy 347.404189 -264.046458)
			(xy 347.412309 -264.101634) (xy 347.412818 -264.12952) (xy 347.412309 -264.157406) (xy 347.404189 -264.212582)
			(xy 347.388121 -264.265989) (xy 347.364449 -264.316486) (xy 347.333676 -264.362999) (xy 347.296459 -264.404536)
			(xy 347.253591 -264.440211) (xy 347.205985 -264.469265) (xy 347.154656 -264.491077) (xy 347.100699 -264.505183)
			(xy 347.045262 -264.511283) (xy 346.989528 -264.509246) (xy 346.934685 -264.499116) (xy 346.881901 -264.481109)
			(xy 346.832301 -264.455608) (xy 346.786943 -264.423157) (xy 346.746794 -264.384448) (xy 346.712708 -264.340305)
			(xy 346.685412 -264.29167) (xy 346.665489 -264.239579) (xy 346.653363 -264.185142) (xy 346.649292 -264.12952)
			(xy 345.869768 -264.12952) (xy 342.985852 -267.013436) (xy 342.965694 -267.032792) (xy 342.920468 -267.065616)
			(xy 342.870671 -267.090974) (xy 342.817524 -267.108243) (xy 342.762333 -267.117001) (xy 342.734392 -267.117576)
			(xy 341.408258 -267.117576) (xy 341.398191 -267.118006) (xy 341.379595 -267.125729) (xy 341.37219 -267.132562)
			(xy 339.583014 -268.921738) (xy 339.576172 -268.929138) (xy 339.568449 -268.947736) (xy 339.568028 -268.957806)
			(xy 339.568028 -276.051264) (xy 341.2617 -276.051264) (xy 341.262145 -276.023893) (xy 341.269968 -275.969713)
			(xy 341.285462 -275.91721) (xy 341.308308 -275.867463) (xy 341.338037 -275.821497) (xy 341.35568 -275.800566)
			(xy 341.355934 -275.800312) (xy 341.361525 -275.793229) (xy 341.367768 -275.776309) (xy 341.368126 -275.767292)
			(xy 341.368126 -275.700236) (xy 341.367746 -275.691222) (xy 341.361514 -275.674305) (xy 341.355934 -275.667216)
			(xy 341.35568 -275.667216) (xy 341.35568 -275.666962) (xy 341.338006 -275.646057) (xy 341.308286 -275.600083)
			(xy 341.285446 -275.550332) (xy 341.269954 -275.497826) (xy 341.26213 -275.443645) (xy 341.262134 -275.388901)
			(xy 341.269966 -275.334721) (xy 341.285465 -275.282217) (xy 341.308312 -275.232469) (xy 341.338039 -275.1865)
			(xy 341.35568 -275.165566) (xy 341.355934 -275.165312) (xy 341.361525 -275.158229) (xy 341.367768 -275.141309)
			(xy 341.368126 -275.132292) (xy 341.368126 -275.065236) (xy 341.367746 -275.056222) (xy 341.361514 -275.039305)
			(xy 341.355934 -275.032216) (xy 341.35568 -275.032216) (xy 341.35568 -275.031962) (xy 341.338053 -275.01102)
			(xy 341.30834 -274.96505) (xy 341.285502 -274.915305) (xy 341.270008 -274.862806) (xy 341.262176 -274.808632)
			(xy 341.2617 -274.781264) (xy 341.262144 -274.754011) (xy 341.269906 -274.700062) (xy 341.285266 -274.647766)
			(xy 341.307912 -274.598188) (xy 341.337383 -274.552337) (xy 341.373079 -274.511147) (xy 341.414273 -274.475456)
			(xy 341.460127 -274.445991) (xy 341.509707 -274.423351) (xy 341.562005 -274.407997) (xy 341.615955 -274.400241)
			(xy 341.643208 -274.399756) (xy 341.670579 -274.400204) (xy 341.724759 -274.408024) (xy 341.777263 -274.423516)
			(xy 341.82701 -274.446363) (xy 341.872975 -274.476092) (xy 341.893906 -274.493736) (xy 341.89416 -274.49399)
			(xy 341.901255 -274.499565) (xy 341.918165 -274.505819) (xy 341.92718 -274.506182) (xy 341.994236 -274.506182)
			(xy 342.003255 -274.505846) (xy 342.020172 -274.499584) (xy 342.027256 -274.49399) (xy 342.027256 -274.493736)
			(xy 342.02751 -274.493736) (xy 342.048432 -274.476084) (xy 342.094407 -274.446373) (xy 342.144157 -274.423539)
			(xy 342.19666 -274.408051) (xy 342.250838 -274.400227) (xy 342.278208 -274.399756) (xy 342.305458 -274.40027)
			(xy 342.359403 -274.408027) (xy 342.411695 -274.423381) (xy 342.46127 -274.446021) (xy 342.507118 -274.475484)
			(xy 342.548307 -274.511173) (xy 342.583999 -274.552359) (xy 342.613466 -274.598206) (xy 342.636109 -274.647779)
			(xy 342.651467 -274.70007) (xy 342.659228 -274.754014) (xy 342.659716 -274.781264) (xy 342.659249 -274.808634)
			(xy 342.651435 -274.862814) (xy 342.635947 -274.915318) (xy 342.613105 -274.965065) (xy 342.583379 -275.011031)
			(xy 342.565736 -275.031962) (xy 342.565482 -275.032216) (xy 342.559881 -275.039292) (xy 342.553643 -275.056217)
			(xy 342.55329 -275.065236) (xy 342.55329 -275.132292) (xy 342.553653 -275.141308) (xy 342.559897 -275.158225)
			(xy 342.565482 -275.165312) (xy 342.565736 -275.165312) (xy 342.565736 -275.165566) (xy 342.583343 -275.186527)
			(xy 342.613072 -275.232489) (xy 342.635922 -275.28223) (xy 342.651422 -275.334728) (xy 342.659255 -275.388904)
			(xy 342.659259 -275.443642) (xy 342.651434 -275.497819) (xy 342.635941 -275.550319) (xy 342.613098 -275.600064)
			(xy 342.583376 -275.64603) (xy 342.565736 -275.666962) (xy 342.565482 -275.667216) (xy 342.559881 -275.674292)
			(xy 342.553643 -275.691217) (xy 342.55329 -275.700236) (xy 342.55329 -275.767292) (xy 342.553653 -275.776308)
			(xy 342.559897 -275.793225) (xy 342.565482 -275.800312) (xy 342.565736 -275.800312) (xy 342.565736 -275.800566)
			(xy 342.583343 -275.821527) (xy 342.613072 -275.867489) (xy 342.635922 -275.91723) (xy 342.651422 -275.969728)
			(xy 342.659255 -276.023904) (xy 342.659259 -276.078642) (xy 342.651434 -276.132819) (xy 342.635941 -276.185319)
			(xy 342.613098 -276.235064) (xy 342.583376 -276.28103) (xy 342.565736 -276.301962) (xy 342.565482 -276.302216)
			(xy 342.559881 -276.309292) (xy 342.553643 -276.326217) (xy 342.55329 -276.335236) (xy 342.55329 -276.402292)
			(xy 342.553653 -276.411308) (xy 342.559897 -276.428225) (xy 342.565482 -276.435312) (xy 342.565736 -276.435312)
			(xy 342.565736 -276.43582) (xy 342.581886 -276.454875) (xy 342.609553 -276.496465) (xy 342.631554 -276.54131)
			(xy 342.639904 -276.564852) (xy 342.643714 -276.576282) (xy 342.660224 -276.593046) (xy 342.748108 -276.622764)
			(xy 342.759411 -276.62603) (xy 342.782715 -276.622965) (xy 342.792812 -276.616922) (xy 342.793066 -276.616668)
			(xy 342.816823 -276.601327) (xy 342.867881 -276.577017) (xy 342.921967 -276.560507) (xy 342.977897 -276.552158)
			(xy 343.006172 -276.551644) (xy 343.03342 -276.552204) (xy 343.087363 -276.559956) (xy 343.139653 -276.575305)
			(xy 343.189227 -276.597939) (xy 343.235075 -276.627398) (xy 343.276265 -276.663082) (xy 343.311956 -276.704264)
			(xy 343.341424 -276.750106) (xy 343.364069 -276.799675) (xy 343.379428 -276.851963) (xy 343.38719 -276.905904)
			(xy 343.38768 -276.933152) (xy 343.387254 -276.959467) (xy 343.380011 -277.011598) (xy 343.365685 -277.062242)
			(xy 343.344544 -277.110441) (xy 343.316991 -277.155283) (xy 343.283545 -277.195921) (xy 343.26449 -277.214076)
			(xy 343.257095 -277.221603) (xy 343.248567 -277.240879) (xy 343.24798 -277.251414) (xy 343.24798 -277.32609)
			(xy 343.248507 -277.33664) (xy 343.257044 -277.355935) (xy 343.26449 -277.363428) (xy 343.28355 -277.381579)
			(xy 343.317007 -277.422209) (xy 343.344566 -277.467051) (xy 343.363395 -277.509986) (xy 344.834972 -277.509986)
			(xy 344.834972 -270.45539) (xy 344.835472 -270.427408) (xy 344.844249 -270.372136) (xy 344.86157 -270.318919)
			(xy 344.887006 -270.26907) (xy 344.919932 -270.223816) (xy 344.939366 -270.203676) (xy 350.652842 -264.489946)
			(xy 350.659602 -264.48249) (xy 350.667323 -264.463929) (xy 350.667828 -264.453878) (xy 350.667828 -263.466326)
			(xy 350.667408 -263.456256) (xy 350.659686 -263.437657) (xy 350.652842 -263.430258) (xy 350.312482 -263.089644)
			(xy 350.293095 -263.069467) (xy 350.260197 -263.024208) (xy 350.234776 -262.974365) (xy 350.217455 -262.921162)
			(xy 350.208661 -262.865905) (xy 350.208088 -262.83793) (xy 350.208088 -261.58317) (xy 350.208635 -261.55519)
			(xy 350.2174 -261.49992) (xy 350.234709 -261.446703) (xy 350.260136 -261.396853) (xy 350.293053 -261.351597)
			(xy 350.312482 -261.331456) (xy 351.781618 -259.86232) (xy 351.788444 -259.854909) (xy 351.796171 -259.836318)
			(xy 351.796604 -259.826252) (xy 351.796604 -256.534412) (xy 351.797188 -256.506472) (xy 351.805944 -256.451281)
			(xy 351.823212 -256.398134) (xy 351.848567 -256.348337) (xy 351.881389 -256.30311) (xy 351.900744 -256.282952)
			(xy 353.226878 -254.956818) (xy 353.230688 -254.94869) (xy 353.242589 -254.92448) (xy 353.272231 -254.879408)
			(xy 353.307925 -254.838958) (xy 353.348959 -254.803938) (xy 353.394516 -254.775045) (xy 353.443687 -254.752855)
			(xy 353.495493 -254.73781) (xy 353.548901 -254.730209) (xy 353.575874 -254.729742) (xy 353.603128 -254.73018)
			(xy 353.657083 -254.737934) (xy 353.709384 -254.75329) (xy 353.758968 -254.775933) (xy 353.804823 -254.805403)
			(xy 353.846018 -254.841099) (xy 353.881712 -254.882296) (xy 353.911179 -254.928153) (xy 353.933819 -254.977738)
			(xy 353.949171 -255.030041) (xy 353.956922 -255.083995) (xy 353.957382 -255.11125) (xy 353.956903 -255.138224)
			(xy 353.949321 -255.191636) (xy 353.934287 -255.243447) (xy 353.912102 -255.292622) (xy 353.883209 -255.33818)
			(xy 353.848183 -255.379211) (xy 353.807724 -255.414897) (xy 353.76264 -255.444524) (xy 353.738434 -255.456436)
			(xy 353.730306 -255.460246) (xy 352.523298 -256.667254) (xy 352.516485 -256.674676) (xy 352.50875 -256.693258)
			(xy 352.508312 -256.703322) (xy 352.508312 -259.995162) (xy 352.507707 -260.023101) (xy 352.498956 -260.078291)
			(xy 352.481693 -260.131437) (xy 352.456342 -260.181235) (xy 352.423525 -260.226463) (xy 352.404172 -260.246622)
			(xy 351.135361 -261.515652) (xy 351.594883 -261.515652) (xy 351.594883 -261.461148) (xy 351.60264 -261.407198)
			(xy 351.617997 -261.354902) (xy 351.64064 -261.305324) (xy 351.670108 -261.259473) (xy 351.705802 -261.218282)
			(xy 351.746995 -261.182591) (xy 351.792848 -261.153126) (xy 351.842428 -261.130487) (xy 351.894726 -261.115135)
			(xy 351.948676 -261.107381) (xy 351.975928 -261.10692) (xy 352.004527 -261.107402) (xy 352.061083 -261.115945)
			(xy 352.115731 -261.132835) (xy 352.167244 -261.157694) (xy 352.214469 -261.189964) (xy 352.256348 -261.228923)
			(xy 352.291941 -261.273698) (xy 352.320451 -261.323284) (xy 352.34124 -261.37657) (xy 352.348038 -261.404354)
			(xy 352.350455 -261.413351) (xy 352.360755 -261.428854) (xy 352.368104 -261.43458) (xy 352.42373 -261.474204)
			(xy 352.431597 -261.479254) (xy 352.449714 -261.483806) (xy 352.459036 -261.483094) (xy 352.45929 -261.483094)
			(xy 352.470548 -261.481798) (xy 352.49317 -261.480402) (xy 352.504502 -261.4803) (xy 352.531754 -261.48077)
			(xy 352.585702 -261.488527) (xy 352.637998 -261.503882) (xy 352.687576 -261.526524) (xy 352.733427 -261.555991)
			(xy 352.774618 -261.591683) (xy 352.81031 -261.632874) (xy 352.839777 -261.678726) (xy 352.862418 -261.728304)
			(xy 352.877774 -261.7806) (xy 352.88553 -261.834548) (xy 352.88553 -261.889052) (xy 352.877774 -261.943)
			(xy 352.862418 -261.995296) (xy 352.839777 -262.044874) (xy 352.81031 -262.090726) (xy 352.774618 -262.131917)
			(xy 352.733427 -262.167609) (xy 352.687576 -262.197076) (xy 352.637998 -262.219718) (xy 352.585702 -262.235073)
			(xy 352.531754 -262.24283) (xy 352.504502 -262.243316) (xy 352.475905 -262.242779) (xy 352.419353 -262.234242)
			(xy 352.364708 -262.217357) (xy 352.313196 -262.192505) (xy 352.265972 -262.160241) (xy 352.224093 -262.121289)
			(xy 352.188498 -262.076522) (xy 352.159985 -262.026943) (xy 352.139193 -261.973663) (xy 352.132392 -261.945882)
			(xy 352.129951 -261.936894) (xy 352.119667 -261.921386) (xy 352.112326 -261.915656) (xy 352.0567 -261.876032)
			(xy 352.048823 -261.870999) (xy 352.030714 -261.866435) (xy 352.021394 -261.867142) (xy 352.02114 -261.867142)
			(xy 352.009881 -261.868435) (xy 351.98726 -261.869833) (xy 351.975928 -261.869936) (xy 351.948676 -261.869419)
			(xy 351.894726 -261.861665) (xy 351.842428 -261.846313) (xy 351.792848 -261.823674) (xy 351.746995 -261.794209)
			(xy 351.705802 -261.758518) (xy 351.670108 -261.717327) (xy 351.64064 -261.671476) (xy 351.617997 -261.621898)
			(xy 351.60264 -261.569602) (xy 351.594883 -261.515652) (xy 351.135361 -261.515652) (xy 350.93529 -261.715758)
			(xy 350.928475 -261.723177) (xy 350.920741 -261.741762) (xy 350.920304 -261.751826) (xy 350.920304 -262.580882)
			(xy 351.353118 -262.580882) (xy 351.357189 -262.52526) (xy 351.369315 -262.470823) (xy 351.389238 -262.418732)
			(xy 351.416534 -262.370097) (xy 351.45062 -262.325954) (xy 351.490769 -262.287245) (xy 351.536127 -262.254794)
			(xy 351.585727 -262.229293) (xy 351.638511 -262.211286) (xy 351.693354 -262.201156) (xy 351.749088 -262.199119)
			(xy 351.804525 -262.205219) (xy 351.858482 -262.219325) (xy 351.909811 -262.241137) (xy 351.957417 -262.270191)
			(xy 352.000285 -262.305866) (xy 352.037502 -262.347403) (xy 352.068275 -262.393916) (xy 352.091947 -262.444413)
			(xy 352.108015 -262.49782) (xy 352.116135 -262.552996) (xy 352.116644 -262.580882) (xy 352.116135 -262.608768)
			(xy 352.108015 -262.663944) (xy 352.091947 -262.717351) (xy 352.068275 -262.767848) (xy 352.037502 -262.814361)
			(xy 352.000285 -262.855898) (xy 351.957417 -262.891573) (xy 351.909811 -262.920627) (xy 351.858482 -262.942439)
			(xy 351.804525 -262.956545) (xy 351.749088 -262.962645) (xy 351.693354 -262.960608) (xy 351.638511 -262.950478)
			(xy 351.585727 -262.932471) (xy 351.536127 -262.90697) (xy 351.490769 -262.874519) (xy 351.45062 -262.83581)
			(xy 351.416534 -262.791667) (xy 351.389238 -262.743032) (xy 351.369315 -262.690941) (xy 351.357189 -262.636504)
			(xy 351.353118 -262.580882) (xy 350.920304 -262.580882) (xy 350.920304 -262.669274) (xy 350.920716 -262.679345)
			(xy 350.928443 -262.697945) (xy 350.93529 -262.705342) (xy 351.27565 -263.045956) (xy 351.295042 -263.066128)
			(xy 351.327938 -263.111389) (xy 351.353358 -263.161233) (xy 351.360564 -263.18337) (xy 355.16896 -263.18337)
			(xy 355.173031 -263.127748) (xy 355.185157 -263.073311) (xy 355.20508 -263.02122) (xy 355.232376 -262.972585)
			(xy 355.266462 -262.928442) (xy 355.306611 -262.889733) (xy 355.351969 -262.857282) (xy 355.401569 -262.831781)
			(xy 355.454353 -262.813774) (xy 355.509196 -262.803644) (xy 355.56493 -262.801607) (xy 355.620367 -262.807707)
			(xy 355.674324 -262.821813) (xy 355.725653 -262.843625) (xy 355.773259 -262.872679) (xy 355.816127 -262.908354)
			(xy 355.853344 -262.949891) (xy 355.884117 -262.996404) (xy 355.907789 -263.046901) (xy 355.923857 -263.100308)
			(xy 355.931977 -263.155484) (xy 355.932486 -263.18337) (xy 355.931977 -263.211256) (xy 355.923857 -263.266432)
			(xy 355.907789 -263.319839) (xy 355.884117 -263.370336) (xy 355.853344 -263.416849) (xy 355.816127 -263.458386)
			(xy 355.773259 -263.494061) (xy 355.725653 -263.523115) (xy 355.674324 -263.544927) (xy 355.620367 -263.559033)
			(xy 355.56493 -263.565133) (xy 355.509196 -263.563096) (xy 355.454353 -263.552966) (xy 355.401569 -263.534959)
			(xy 355.351969 -263.509458) (xy 355.306611 -263.477007) (xy 355.266462 -263.438298) (xy 355.232376 -263.394155)
			(xy 355.20508 -263.34552) (xy 355.185157 -263.293429) (xy 355.173031 -263.238992) (xy 355.16896 -263.18337)
			(xy 351.360564 -263.18337) (xy 351.370678 -263.214437) (xy 351.379471 -263.269694) (xy 351.380044 -263.29767)
			(xy 351.380044 -263.82091) (xy 351.643948 -263.82091) (xy 351.648019 -263.765288) (xy 351.660145 -263.710851)
			(xy 351.680068 -263.65876) (xy 351.707364 -263.610125) (xy 351.74145 -263.565982) (xy 351.781599 -263.527273)
			(xy 351.826957 -263.494822) (xy 351.876557 -263.469321) (xy 351.929341 -263.451314) (xy 351.984184 -263.441184)
			(xy 352.039918 -263.439147) (xy 352.095355 -263.445247) (xy 352.149312 -263.459353) (xy 352.200641 -263.481165)
			(xy 352.248247 -263.510219) (xy 352.291115 -263.545894) (xy 352.328332 -263.587431) (xy 352.359105 -263.633944)
			(xy 352.382777 -263.684441) (xy 352.398845 -263.737848) (xy 352.406965 -263.793024) (xy 352.407474 -263.82091)
			(xy 352.406965 -263.848796) (xy 352.398845 -263.903972) (xy 352.382777 -263.957379) (xy 352.359105 -264.007876)
			(xy 352.328332 -264.054389) (xy 352.291115 -264.095926) (xy 352.281574 -264.103866) (xy 355.18039 -264.103866)
			(xy 355.184461 -264.048244) (xy 355.196587 -263.993807) (xy 355.21651 -263.941716) (xy 355.243806 -263.893081)
			(xy 355.277892 -263.848938) (xy 355.318041 -263.810229) (xy 355.363399 -263.777778) (xy 355.412999 -263.752277)
			(xy 355.465783 -263.73427) (xy 355.520626 -263.72414) (xy 355.57636 -263.722103) (xy 355.631797 -263.728203)
			(xy 355.685754 -263.742309) (xy 355.737083 -263.764121) (xy 355.784689 -263.793175) (xy 355.827557 -263.82885)
			(xy 355.864774 -263.870387) (xy 355.895547 -263.9169) (xy 355.919219 -263.967397) (xy 355.935287 -264.020804)
			(xy 355.943407 -264.07598) (xy 355.943916 -264.103866) (xy 355.943407 -264.131752) (xy 355.935287 -264.186928)
			(xy 355.919219 -264.240335) (xy 355.895547 -264.290832) (xy 355.864774 -264.337345) (xy 355.827557 -264.378882)
			(xy 355.784689 -264.414557) (xy 355.737083 -264.443611) (xy 355.685754 -264.465423) (xy 355.631797 -264.479529)
			(xy 355.57636 -264.485629) (xy 355.520626 -264.483592) (xy 355.465783 -264.473462) (xy 355.412999 -264.455455)
			(xy 355.363399 -264.429954) (xy 355.318041 -264.397503) (xy 355.277892 -264.358794) (xy 355.243806 -264.314651)
			(xy 355.21651 -264.266016) (xy 355.196587 -264.213925) (xy 355.184461 -264.159488) (xy 355.18039 -264.103866)
			(xy 352.281574 -264.103866) (xy 352.248247 -264.131601) (xy 352.200641 -264.160655) (xy 352.149312 -264.182467)
			(xy 352.095355 -264.196573) (xy 352.039918 -264.202673) (xy 351.984184 -264.200636) (xy 351.929341 -264.190506)
			(xy 351.876557 -264.172499) (xy 351.826957 -264.146998) (xy 351.781599 -264.114547) (xy 351.74145 -264.075838)
			(xy 351.707364 -264.031695) (xy 351.680068 -263.98306) (xy 351.660145 -263.930969) (xy 351.648019 -263.876532)
			(xy 351.643948 -263.82091) (xy 351.380044 -263.82091) (xy 351.380044 -264.622534) (xy 351.379491 -264.650514)
			(xy 351.370726 -264.705783) (xy 351.353418 -264.758999) (xy 351.327993 -264.80885) (xy 351.295078 -264.854106)
			(xy 351.27565 -264.874248) (xy 351.213931 -264.93597) (xy 352.61753 -264.93597) (xy 352.621601 -264.880348)
			(xy 352.633727 -264.825911) (xy 352.65365 -264.77382) (xy 352.680946 -264.725185) (xy 352.715032 -264.681042)
			(xy 352.755181 -264.642333) (xy 352.800539 -264.609882) (xy 352.850139 -264.584381) (xy 352.902923 -264.566374)
			(xy 352.957766 -264.556244) (xy 353.0135 -264.554207) (xy 353.068937 -264.560307) (xy 353.122894 -264.574413)
			(xy 353.174223 -264.596225) (xy 353.221829 -264.625279) (xy 353.264697 -264.660954) (xy 353.301914 -264.702491)
			(xy 353.332687 -264.749004) (xy 353.356359 -264.799501) (xy 353.372427 -264.852908) (xy 353.380547 -264.908084)
			(xy 353.381056 -264.93597) (xy 353.380547 -264.963856) (xy 353.372427 -265.019032) (xy 353.356359 -265.072439)
			(xy 353.332687 -265.122936) (xy 353.301914 -265.169449) (xy 353.264697 -265.210986) (xy 353.221829 -265.246661)
			(xy 353.174223 -265.275715) (xy 353.122894 -265.297527) (xy 353.068937 -265.311633) (xy 353.0135 -265.317733)
			(xy 352.957766 -265.315696) (xy 352.902923 -265.305566) (xy 352.850139 -265.287559) (xy 352.800539 -265.262058)
			(xy 352.755181 -265.229607) (xy 352.715032 -265.190898) (xy 352.680946 -265.146755) (xy 352.65365 -265.09812)
			(xy 352.633727 -265.046029) (xy 352.621601 -264.991592) (xy 352.61753 -264.93597) (xy 351.213931 -264.93597)
			(xy 350.315827 -265.834114) (xy 351.44659 -265.834114) (xy 351.450661 -265.778492) (xy 351.462787 -265.724055)
			(xy 351.48271 -265.671964) (xy 351.510006 -265.623329) (xy 351.544092 -265.579186) (xy 351.584241 -265.540477)
			(xy 351.629599 -265.508026) (xy 351.679199 -265.482525) (xy 351.731983 -265.464518) (xy 351.786826 -265.454388)
			(xy 351.84256 -265.452351) (xy 351.897997 -265.458451) (xy 351.951954 -265.472557) (xy 352.003283 -265.494369)
			(xy 352.050889 -265.523423) (xy 352.093757 -265.559098) (xy 352.130974 -265.600635) (xy 352.161747 -265.647148)
			(xy 352.185419 -265.697645) (xy 352.201487 -265.751052) (xy 352.209607 -265.806228) (xy 352.210116 -265.834114)
			(xy 352.209607 -265.862) (xy 352.201487 -265.917176) (xy 352.185419 -265.970583) (xy 352.161747 -266.02108)
			(xy 352.130974 -266.067593) (xy 352.093757 -266.10913) (xy 352.050889 -266.144805) (xy 352.003283 -266.173859)
			(xy 351.951954 -266.195671) (xy 351.897997 -266.209777) (xy 351.84256 -266.215877) (xy 351.786826 -266.21384)
			(xy 351.731983 -266.20371) (xy 351.679199 -266.185703) (xy 351.629599 -266.160202) (xy 351.584241 -266.127751)
			(xy 351.544092 -266.089042) (xy 351.510006 -266.044899) (xy 351.48271 -265.996264) (xy 351.462787 -265.944173)
			(xy 351.450661 -265.889736) (xy 351.44659 -265.834114) (xy 350.315827 -265.834114) (xy 345.562174 -270.587978)
			(xy 345.555347 -270.595388) (xy 345.54762 -270.61398) (xy 345.547188 -270.624046) (xy 345.547188 -277.34133)
			(xy 345.547575 -277.351404) (xy 345.55532 -277.370003) (xy 345.562174 -277.377398) (xy 346.527374 -278.342852)
			(xy 346.546769 -278.363022) (xy 346.56423 -278.387048) (xy 350.086168 -278.387048) (xy 350.086168 -269.555214)
			(xy 350.086685 -269.527233) (xy 350.095458 -269.471961) (xy 350.112775 -269.418745) (xy 350.138208 -269.368895)
			(xy 350.17113 -269.32364) (xy 350.190562 -269.3035) (xy 352.59645 -266.897612) (xy 352.616554 -266.878192)
			(xy 352.661779 -266.845342) (xy 352.711587 -266.819974) (xy 352.764751 -266.802713) (xy 352.819962 -266.793983)
			(xy 352.84791 -266.793472) (xy 353.603052 -266.793472) (xy 353.613119 -266.793029) (xy 353.631718 -266.785321)
			(xy 353.63912 -266.778486) (xy 356.295706 -264.1219) (xy 356.302539 -264.114495) (xy 356.310263 -264.095899)
			(xy 356.310692 -264.085832) (xy 356.310692 -262.09879) (xy 356.310274 -262.08872) (xy 356.302548 -262.070122)
			(xy 356.295706 -262.062722) (xy 355.351588 -261.118604) (xy 355.332207 -261.098463) (xy 355.29935 -261.05325)
			(xy 355.273973 -261.003451) (xy 355.256703 -260.950294) (xy 355.247964 -260.89509) (xy 355.247448 -260.867144)
			(xy 355.247448 -253.998476) (xy 355.247049 -253.988404) (xy 355.239311 -253.969805) (xy 355.232462 -253.962408)
			(xy 354.696014 -253.426214) (xy 354.688602 -253.419389) (xy 354.670012 -253.41166) (xy 354.659946 -253.411228)
			(xy 351.04324 -253.411228) (xy 351.034858 -253.414022) (xy 351.003646 -253.424559) (xy 350.938761 -253.435919)
			(xy 350.905826 -253.436628) (xy 350.878573 -253.436126) (xy 350.824622 -253.428373) (xy 350.772324 -253.41302)
			(xy 350.722743 -253.39038) (xy 350.676889 -253.360914) (xy 350.635696 -253.325223) (xy 350.600001 -253.284031)
			(xy 350.570532 -253.238179) (xy 350.547889 -253.1886) (xy 350.532533 -253.136303) (xy 350.524775 -253.082353)
			(xy 350.524775 -253.027847) (xy 350.532533 -252.973897) (xy 350.547889 -252.9216) (xy 350.570532 -252.872021)
			(xy 350.600001 -252.826169) (xy 350.635696 -252.784977) (xy 350.676889 -252.749286) (xy 350.722743 -252.71982)
			(xy 350.772324 -252.69718) (xy 350.824622 -252.681827) (xy 350.878573 -252.674074) (xy 350.905826 -252.673612)
			(xy 350.938759 -252.674341) (xy 351.003638 -252.685709) (xy 351.034858 -252.696218) (xy 351.04324 -252.699012)
			(xy 354.828602 -252.699012) (xy 354.856584 -252.699506) (xy 354.911857 -252.708283) (xy 354.965075 -252.725604)
			(xy 355.014924 -252.751042) (xy 355.060177 -252.783971) (xy 355.080316 -252.803406) (xy 355.855016 -253.578106)
			(xy 355.874402 -253.598242) (xy 355.907259 -253.643457) (xy 355.932635 -253.693257) (xy 355.949904 -253.746414)
			(xy 355.958641 -253.80162) (xy 355.959156 -253.829566) (xy 355.959156 -258.71932) (xy 355.959769 -258.730703)
			(xy 355.969518 -258.751275) (xy 355.977952 -258.758944) (xy 356.039674 -258.808728) (xy 356.048884 -258.815329)
			(xy 356.070892 -258.820605) (xy 356.082092 -258.818888) (xy 356.082346 -258.818888) (xy 356.10217 -258.814876)
			(xy 356.142386 -258.810546) (xy 356.16261 -258.810252) (xy 356.189858 -258.810819) (xy 356.243799 -258.818576)
			(xy 356.296087 -258.83393) (xy 356.345658 -258.856569) (xy 356.391502 -258.886033) (xy 356.432687 -258.921721)
			(xy 356.468373 -258.962906) (xy 356.497835 -259.008751) (xy 356.520473 -259.058323) (xy 356.535826 -259.110611)
			(xy 356.543582 -259.164552) (xy 356.543582 -259.219048) (xy 356.535826 -259.272989) (xy 356.520473 -259.325277)
			(xy 356.497835 -259.374849) (xy 356.468373 -259.420694) (xy 356.432687 -259.461879) (xy 356.391502 -259.497567)
			(xy 356.345658 -259.527031) (xy 356.296087 -259.54967) (xy 356.243799 -259.565024) (xy 356.189858 -259.572781)
			(xy 356.16261 -259.573268) (xy 356.142386 -259.572975) (xy 356.102169 -259.568653) (xy 356.082346 -259.564632)
			(xy 356.082092 -259.564632) (xy 356.070888 -259.562876) (xy 356.048863 -259.568146) (xy 356.039674 -259.574792)
			(xy 355.977952 -259.624576) (xy 355.969416 -259.632171) (xy 355.959621 -259.652785) (xy 355.959156 -259.6642)
			(xy 355.959156 -260.698234) (xy 355.959549 -260.708307) (xy 355.967291 -260.726906) (xy 355.974142 -260.734302)
			(xy 356.91826 -261.67842) (xy 356.937661 -261.698542) (xy 356.970514 -261.743762) (xy 356.995886 -261.793565)
			(xy 357.013152 -261.846726) (xy 357.021886 -261.901933) (xy 357.0224 -261.92988) (xy 357.0224 -264.254742)
			(xy 357.021849 -264.282684) (xy 357.013085 -264.337876) (xy 356.995809 -264.391023) (xy 356.970446 -264.440819)
			(xy 356.937618 -264.486045) (xy 356.91826 -264.506202) (xy 354.023422 -267.40104) (xy 354.003278 -267.420417)
			(xy 353.958065 -267.453274) (xy 353.908267 -267.478651) (xy 353.855111 -267.495922) (xy 353.799908 -267.504663)
			(xy 353.771962 -267.50518) (xy 353.01682 -267.50518) (xy 353.006749 -267.505595) (xy 352.98815 -267.51332)
			(xy 352.980752 -267.520166) (xy 351.084102 -269.417038) (xy 357.085646 -269.417038) (xy 357.086146 -269.388298)
			(xy 357.094777 -269.331471) (xy 357.111833 -269.27658) (xy 357.13693 -269.224869) (xy 357.169498 -269.177507)
			(xy 357.18877 -269.15618) (xy 357.195374 -269.149322) (xy 357.202486 -269.131288) (xy 357.202486 -269.042388)
			(xy 357.195374 -269.024354) (xy 357.18877 -269.017496) (xy 357.169523 -268.996149) (xy 357.136952 -268.948793)
			(xy 357.111854 -268.897086) (xy 357.094798 -268.8422) (xy 357.08617 -268.785376) (xy 357.085646 -268.756638)
			(xy 357.086213 -268.72939) (xy 357.093964 -268.675447) (xy 357.109312 -268.623157) (xy 357.131945 -268.573583)
			(xy 357.161403 -268.527735) (xy 357.197086 -268.486545) (xy 357.238267 -268.450853) (xy 357.284109 -268.421385)
			(xy 357.333678 -268.398741) (xy 357.385965 -268.383381) (xy 357.439906 -268.375619) (xy 357.467154 -268.37513)
			(xy 357.494524 -268.375616) (xy 357.548702 -268.383428) (xy 357.601205 -268.398912) (xy 357.650953 -268.421749)
			(xy 357.69692 -268.45147) (xy 357.717852 -268.46911) (xy 357.718106 -268.469364) (xy 357.725181 -268.474967)
			(xy 357.742107 -268.481202) (xy 357.751126 -268.481556) (xy 357.818182 -268.481556) (xy 357.827199 -268.4812)
			(xy 357.844117 -268.474953) (xy 357.851202 -268.469364) (xy 357.851202 -268.46911) (xy 357.851456 -268.46911)
			(xy 357.872389 -268.451469) (xy 357.918357 -268.421745) (xy 357.968103 -268.398899) (xy 358.020605 -268.383403)
			(xy 358.074783 -268.375574) (xy 358.129525 -268.375574) (xy 358.183703 -268.383403) (xy 358.236205 -268.398899)
			(xy 358.285951 -268.421745) (xy 358.331919 -268.451469) (xy 358.352852 -268.46911) (xy 358.353106 -268.469364)
			(xy 358.360181 -268.474967) (xy 358.377107 -268.481202) (xy 358.386126 -268.481556) (xy 358.453182 -268.481556)
			(xy 358.462199 -268.4812) (xy 358.479117 -268.474953) (xy 358.486202 -268.469364) (xy 358.486202 -268.46911)
			(xy 358.486456 -268.46911) (xy 358.507389 -268.451469) (xy 358.553357 -268.421745) (xy 358.603103 -268.398899)
			(xy 358.655605 -268.383403) (xy 358.709783 -268.375574) (xy 358.764525 -268.375574) (xy 358.818703 -268.383403)
			(xy 358.871205 -268.398899) (xy 358.920951 -268.421745) (xy 358.966919 -268.451469) (xy 358.987852 -268.46911)
			(xy 358.988106 -268.469364) (xy 358.995181 -268.474967) (xy 359.012107 -268.481202) (xy 359.021126 -268.481556)
			(xy 359.088182 -268.481556) (xy 359.097199 -268.4812) (xy 359.114117 -268.474953) (xy 359.121202 -268.469364)
			(xy 359.121202 -268.46911) (xy 359.121456 -268.46911) (xy 359.142389 -268.451469) (xy 359.188357 -268.421745)
			(xy 359.238103 -268.398899) (xy 359.290605 -268.383403) (xy 359.344783 -268.375574) (xy 359.399525 -268.375574)
			(xy 359.453703 -268.383403) (xy 359.506205 -268.398899) (xy 359.555951 -268.421745) (xy 359.601919 -268.451469)
			(xy 359.622852 -268.46911) (xy 359.623106 -268.469364) (xy 359.630181 -268.474967) (xy 359.647107 -268.481202)
			(xy 359.656126 -268.481556) (xy 359.723182 -268.481556) (xy 359.732199 -268.4812) (xy 359.749117 -268.474953)
			(xy 359.756202 -268.469364) (xy 359.756202 -268.46911) (xy 359.756456 -268.46911) (xy 359.777395 -268.45148)
			(xy 359.823366 -268.421766) (xy 359.873112 -268.398928) (xy 359.925611 -268.383435) (xy 359.979785 -268.375605)
			(xy 360.007154 -268.37513) (xy 360.034407 -268.375598) (xy 360.08836 -268.38335) (xy 360.14066 -268.398702)
			(xy 360.190243 -268.421342) (xy 360.236098 -268.450809) (xy 360.277292 -268.486502) (xy 360.312987 -268.527696)
			(xy 360.342454 -268.57355) (xy 360.365095 -268.623132) (xy 360.380448 -268.675432) (xy 360.388201 -268.729385)
			(xy 360.388662 -268.756638) (xy 360.388145 -268.785377) (xy 360.379518 -268.842204) (xy 360.362466 -268.897094)
			(xy 360.337373 -268.948806) (xy 360.304808 -268.996169) (xy 360.285538 -269.017496) (xy 360.278934 -269.024354)
			(xy 360.271822 -269.042388) (xy 360.271822 -269.131288) (xy 360.278934 -269.149322) (xy 360.285538 -269.15618)
			(xy 360.304823 -269.177495) (xy 360.337388 -269.22486) (xy 360.362478 -269.276574) (xy 360.379525 -269.331468)
			(xy 360.388144 -269.388298) (xy 360.388662 -269.417038) (xy 360.38828 -269.444294) (xy 360.380517 -269.49825)
			(xy 360.365154 -269.550552) (xy 360.342504 -269.600136) (xy 360.313027 -269.645991) (xy 360.277325 -269.687184)
			(xy 360.236124 -269.722878) (xy 360.190262 -269.752344) (xy 360.140674 -269.774983) (xy 360.088368 -269.790335)
			(xy 360.03441 -269.798086) (xy 360.007154 -269.798546) (xy 359.979784 -269.798061) (xy 359.925605 -269.79025)
			(xy 359.873102 -269.774766) (xy 359.823355 -269.751928) (xy 359.777388 -269.722206) (xy 359.756456 -269.704566)
			(xy 359.756202 -269.704312) (xy 359.749118 -269.698721) (xy 359.732199 -269.692477) (xy 359.723182 -269.69212)
			(xy 359.656126 -269.69212) (xy 359.64711 -269.692485) (xy 359.630193 -269.698727) (xy 359.623106 -269.704312)
			(xy 359.622852 -269.704566) (xy 359.601919 -269.722207) (xy 359.555951 -269.751931) (xy 359.506205 -269.774777)
			(xy 359.453703 -269.790273) (xy 359.399525 -269.798102) (xy 359.344783 -269.798102) (xy 359.290605 -269.790273)
			(xy 359.238103 -269.774777) (xy 359.188357 -269.751931) (xy 359.142389 -269.722207) (xy 359.121456 -269.704566)
			(xy 359.121202 -269.704312) (xy 359.114118 -269.698721) (xy 359.097199 -269.692477) (xy 359.088182 -269.69212)
			(xy 359.021126 -269.69212) (xy 359.01211 -269.692485) (xy 358.995193 -269.698727) (xy 358.988106 -269.704312)
			(xy 358.988106 -269.704566) (xy 358.987852 -269.704566) (xy 358.966919 -269.722207) (xy 358.920951 -269.751931)
			(xy 358.871205 -269.774777) (xy 358.818703 -269.790273) (xy 358.764525 -269.798102) (xy 358.709783 -269.798102)
			(xy 358.655605 -269.790273) (xy 358.603103 -269.774777) (xy 358.553357 -269.751931) (xy 358.507389 -269.722207)
			(xy 358.486456 -269.704566) (xy 358.486202 -269.704312) (xy 358.479118 -269.698721) (xy 358.462199 -269.692477)
			(xy 358.453182 -269.69212) (xy 358.386126 -269.69212) (xy 358.37711 -269.692485) (xy 358.360193 -269.698727)
			(xy 358.353106 -269.704312) (xy 358.353106 -269.704566) (xy 358.352852 -269.704566) (xy 358.331919 -269.722207)
			(xy 358.285951 -269.751931) (xy 358.236205 -269.774777) (xy 358.183703 -269.790273) (xy 358.129525 -269.798102)
			(xy 358.074783 -269.798102) (xy 358.020605 -269.790273) (xy 357.968103 -269.774777) (xy 357.918357 -269.751931)
			(xy 357.872389 -269.722207) (xy 357.851456 -269.704566) (xy 357.851202 -269.704312) (xy 357.844118 -269.698721)
			(xy 357.827199 -269.692477) (xy 357.818182 -269.69212) (xy 357.751126 -269.69212) (xy 357.74211 -269.692485)
			(xy 357.725193 -269.698727) (xy 357.718106 -269.704312) (xy 357.718106 -269.704566) (xy 357.717852 -269.704566)
			(xy 357.696907 -269.722189) (xy 357.650938 -269.751904) (xy 357.601194 -269.774744) (xy 357.548696 -269.790239)
			(xy 357.494522 -269.79807) (xy 357.467154 -269.798546) (xy 357.439903 -269.798065) (xy 357.385957 -269.790303)
			(xy 357.333665 -269.774944) (xy 357.28409 -269.752301) (xy 357.238242 -269.722833) (xy 357.197053 -269.687141)
			(xy 357.161362 -269.645952) (xy 357.131896 -269.600103) (xy 357.109253 -269.550528) (xy 357.093895 -269.498235)
			(xy 357.086134 -269.444289) (xy 357.085646 -269.417038) (xy 351.084102 -269.417038) (xy 350.81337 -269.687802)
			(xy 350.806532 -269.695204) (xy 350.798812 -269.713802) (xy 350.798384 -269.72387) (xy 350.798384 -276.027896)
			(xy 352.727006 -276.027896) (xy 352.727468 -276.000526) (xy 352.735287 -275.946346) (xy 352.750777 -275.893843)
			(xy 352.773619 -275.844096) (xy 352.803344 -275.79813) (xy 352.820986 -275.777198) (xy 352.82124 -275.776944)
			(xy 352.826819 -275.769853) (xy 352.833069 -275.752939) (xy 352.833432 -275.743924) (xy 352.833432 -275.676868)
			(xy 352.833083 -275.66785) (xy 352.826829 -275.650934) (xy 352.82124 -275.643848) (xy 352.820986 -275.643848)
			(xy 352.820986 -275.643594) (xy 352.803343 -275.622664) (xy 352.773622 -275.576694) (xy 352.750779 -275.526948)
			(xy 352.735285 -275.474445) (xy 352.727457 -275.420267) (xy 352.727458 -275.365527) (xy 352.735286 -275.311349)
			(xy 352.750781 -275.258847) (xy 352.773624 -275.2091) (xy 352.803347 -275.163132) (xy 352.820986 -275.142198)
			(xy 352.82124 -275.141944) (xy 352.826819 -275.134853) (xy 352.833069 -275.117939) (xy 352.833432 -275.108924)
			(xy 352.833432 -275.041868) (xy 352.833083 -275.03285) (xy 352.826829 -275.015934) (xy 352.82124 -275.008848)
			(xy 352.820986 -275.008848) (xy 352.820986 -275.008594) (xy 352.803328 -274.987677) (xy 352.77362 -274.9417)
			(xy 352.750788 -274.891948) (xy 352.735301 -274.839444) (xy 352.727477 -274.785266) (xy 352.727006 -274.757896)
			(xy 352.727452 -274.730642) (xy 352.73521 -274.67669) (xy 352.750567 -274.624391) (xy 352.773211 -274.57481)
			(xy 352.80268 -274.528956) (xy 352.838376 -274.487763) (xy 352.879571 -274.45207) (xy 352.925426 -274.422602)
			(xy 352.975008 -274.39996) (xy 353.027308 -274.384606) (xy 353.08126 -274.37685) (xy 353.108514 -274.376388)
			(xy 353.135884 -274.376849) (xy 353.190064 -274.384668) (xy 353.242567 -274.400159) (xy 353.292313 -274.423002)
			(xy 353.33828 -274.452727) (xy 353.359212 -274.470368) (xy 353.359466 -274.470622) (xy 353.366556 -274.476203)
			(xy 353.38347 -274.482452) (xy 353.392486 -274.482814) (xy 353.459542 -274.482814) (xy 353.468556 -274.482426)
			(xy 353.485473 -274.4762) (xy 353.492562 -274.470622) (xy 353.492562 -274.470368) (xy 353.492816 -274.470368)
			(xy 353.513765 -274.45275) (xy 353.559734 -274.423036) (xy 353.609477 -274.400196) (xy 353.661974 -274.3847)
			(xy 353.716146 -274.376866) (xy 353.743514 -274.376388) (xy 353.770765 -274.376865) (xy 353.824713 -274.384623)
			(xy 353.877008 -274.39998) (xy 353.926585 -274.422622) (xy 353.972435 -274.45209) (xy 354.013625 -274.487782)
			(xy 354.049316 -274.528973) (xy 354.078783 -274.574824) (xy 354.101424 -274.624401) (xy 354.116779 -274.676697)
			(xy 354.124536 -274.730645) (xy 354.125022 -274.757896) (xy 354.124573 -274.785267) (xy 354.116754 -274.839448)
			(xy 354.101262 -274.891952) (xy 354.078416 -274.941698) (xy 354.048686 -274.987664) (xy 354.031042 -275.008594)
			(xy 354.030788 -275.008848) (xy 354.025216 -275.015944) (xy 354.018961 -275.032854) (xy 354.018596 -275.041868)
			(xy 354.018596 -275.108924) (xy 354.018943 -275.117942) (xy 354.025198 -275.134859) (xy 354.030788 -275.141944)
			(xy 354.031042 -275.141944) (xy 354.031042 -275.142198) (xy 354.04868 -275.163133) (xy 354.078407 -275.2091)
			(xy 354.101255 -275.258846) (xy 354.116753 -275.311347) (xy 354.124582 -275.365526) (xy 354.124583 -275.420268)
			(xy 354.116754 -275.474447) (xy 354.101257 -275.526949) (xy 354.07841 -275.576695) (xy 354.048684 -275.622662)
			(xy 354.031042 -275.643594) (xy 354.030788 -275.643848) (xy 354.025216 -275.650944) (xy 354.018961 -275.667854)
			(xy 354.018596 -275.676868) (xy 354.018596 -275.743924) (xy 354.018943 -275.752942) (xy 354.025198 -275.769859)
			(xy 354.030788 -275.776944) (xy 354.031042 -275.776944) (xy 354.031042 -275.777198) (xy 354.04868 -275.798133)
			(xy 354.078407 -275.8441) (xy 354.101255 -275.893846) (xy 354.116753 -275.946347) (xy 354.124582 -276.000526)
			(xy 354.124583 -276.046184) (xy 356.66045 -276.046184) (xy 356.660895 -276.018813) (xy 356.668716 -275.964632)
			(xy 356.684209 -275.912129) (xy 356.707056 -275.862382) (xy 356.736786 -275.816417) (xy 356.75443 -275.795486)
			(xy 356.754684 -275.795232) (xy 356.760262 -275.788139) (xy 356.766514 -275.771227) (xy 356.766876 -275.762212)
			(xy 356.766876 -275.695156) (xy 356.766497 -275.686141) (xy 356.760265 -275.669224) (xy 356.754684 -275.662136)
			(xy 356.75443 -275.662136) (xy 356.75443 -275.661882) (xy 356.736821 -275.640926) (xy 356.707103 -275.59496)
			(xy 356.684261 -275.545219) (xy 356.668763 -275.492723) (xy 356.660928 -275.438552) (xy 356.66045 -275.411184)
			(xy 356.660963 -275.383934) (xy 356.66872 -275.32999) (xy 356.684075 -275.277698) (xy 356.706715 -275.228124)
			(xy 356.736179 -275.182275) (xy 356.771868 -275.141086) (xy 356.813054 -275.105395) (xy 356.858901 -275.075928)
			(xy 356.908474 -275.053285) (xy 356.960764 -275.037926) (xy 357.014708 -275.030165) (xy 357.041958 -275.029676)
			(xy 357.069328 -275.030148) (xy 357.123508 -275.037962) (xy 357.176012 -275.053448) (xy 357.225759 -275.076289)
			(xy 357.271725 -275.106014) (xy 357.292656 -275.123656) (xy 357.29291 -275.12391) (xy 357.299989 -275.129508)
			(xy 357.316912 -275.135748) (xy 357.32593 -275.136102) (xy 357.392986 -275.136102) (xy 357.402002 -275.135738)
			(xy 357.418919 -275.129495) (xy 357.426006 -275.12391) (xy 357.426006 -275.123656) (xy 357.42626 -275.123656)
			(xy 357.447193 -275.106015) (xy 357.493161 -275.076291) (xy 357.542907 -275.053445) (xy 357.595409 -275.037949)
			(xy 357.649587 -275.03012) (xy 357.704329 -275.03012) (xy 357.758507 -275.037949) (xy 357.811009 -275.053445)
			(xy 357.860755 -275.076291) (xy 357.906723 -275.106015) (xy 357.927656 -275.123656) (xy 357.92791 -275.12391)
			(xy 357.934989 -275.129508) (xy 357.951912 -275.135748) (xy 357.96093 -275.136102) (xy 358.027986 -275.136102)
			(xy 358.037002 -275.135738) (xy 358.053919 -275.129495) (xy 358.061006 -275.12391) (xy 358.061006 -275.123656)
			(xy 358.06126 -275.123656) (xy 358.082193 -275.106015) (xy 358.128161 -275.076291) (xy 358.177907 -275.053445)
			(xy 358.230409 -275.037949) (xy 358.284587 -275.03012) (xy 358.339329 -275.03012) (xy 358.393507 -275.037949)
			(xy 358.446009 -275.053445) (xy 358.495755 -275.076291) (xy 358.541723 -275.106015) (xy 358.562656 -275.123656)
			(xy 358.56291 -275.12391) (xy 358.569989 -275.129508) (xy 358.586912 -275.135748) (xy 358.59593 -275.136102)
			(xy 358.662986 -275.136102) (xy 358.672002 -275.135738) (xy 358.688919 -275.129495) (xy 358.696006 -275.12391)
			(xy 358.696006 -275.123656) (xy 358.69626 -275.123656) (xy 358.717193 -275.106015) (xy 358.763161 -275.076291)
			(xy 358.812907 -275.053445) (xy 358.865409 -275.037949) (xy 358.919587 -275.03012) (xy 358.974329 -275.03012)
			(xy 359.028507 -275.037949) (xy 359.081009 -275.053445) (xy 359.130755 -275.076291) (xy 359.176723 -275.106015)
			(xy 359.197656 -275.123656) (xy 359.19791 -275.12391) (xy 359.204989 -275.129508) (xy 359.221912 -275.135748)
			(xy 359.23093 -275.136102) (xy 359.297986 -275.136102) (xy 359.307002 -275.135738) (xy 359.323919 -275.129495)
			(xy 359.331006 -275.12391) (xy 359.331006 -275.123656) (xy 359.33126 -275.123656) (xy 359.35219 -275.106015)
			(xy 359.398164 -275.076305) (xy 359.447912 -275.05347) (xy 359.500413 -275.037979) (xy 359.554589 -275.03015)
			(xy 359.581958 -275.029676) (xy 359.609209 -275.030194) (xy 359.663157 -275.037945) (xy 359.715453 -275.053295)
			(xy 359.765032 -275.075932) (xy 359.810885 -275.105394) (xy 359.852077 -275.141082) (xy 359.887772 -275.182269)
			(xy 359.917241 -275.228117) (xy 359.939885 -275.277693) (xy 359.955242 -275.329986) (xy 359.963002 -275.383933)
			(xy 359.963466 -275.411184) (xy 359.962999 -275.438554) (xy 359.955183 -275.492734) (xy 359.939694 -275.545237)
			(xy 359.916852 -275.594984) (xy 359.887128 -275.640951) (xy 359.869486 -275.661882) (xy 359.869232 -275.662136)
			(xy 359.863658 -275.669231) (xy 359.857406 -275.686142) (xy 359.85704 -275.695156) (xy 359.85704 -275.762212)
			(xy 359.857382 -275.771231) (xy 359.863639 -275.788148) (xy 359.869232 -275.795232) (xy 359.869486 -275.795232)
			(xy 359.869486 -275.795486) (xy 359.88713 -275.816414) (xy 359.916841 -275.862388) (xy 359.939677 -275.912136)
			(xy 359.955167 -275.964638) (xy 359.962993 -276.018815) (xy 359.963466 -276.046184) (xy 359.96303 -276.073438)
			(xy 359.955274 -276.127392) (xy 359.939918 -276.179693) (xy 359.917274 -276.229276) (xy 359.887804 -276.275131)
			(xy 359.852107 -276.316325) (xy 359.810911 -276.352019) (xy 359.765053 -276.381486) (xy 359.715469 -276.404127)
			(xy 359.663167 -276.419479) (xy 359.609212 -276.427232) (xy 359.581958 -276.427692) (xy 359.554589 -276.427194)
			(xy 359.500411 -276.419384) (xy 359.447908 -276.403903) (xy 359.398161 -276.381068) (xy 359.352193 -276.35135)
			(xy 359.33126 -276.333712) (xy 359.331006 -276.333458) (xy 359.323926 -276.327863) (xy 359.307004 -276.321622)
			(xy 359.297986 -276.321266) (xy 359.23093 -276.321266) (xy 359.221915 -276.321645) (xy 359.204999 -276.327878)
			(xy 359.19791 -276.333458) (xy 359.197656 -276.333712) (xy 359.176723 -276.351353) (xy 359.130755 -276.381077)
			(xy 359.081009 -276.403923) (xy 359.028507 -276.419419) (xy 358.974329 -276.427248) (xy 358.919587 -276.427248)
			(xy 358.865409 -276.419419) (xy 358.812907 -276.403923) (xy 358.763161 -276.381077) (xy 358.717193 -276.351353)
			(xy 358.69626 -276.333712) (xy 358.696006 -276.333458) (xy 358.688926 -276.327863) (xy 358.672004 -276.321622)
			(xy 358.662986 -276.321266) (xy 358.59593 -276.321266) (xy 358.586915 -276.321645) (xy 358.569999 -276.327878)
			(xy 358.56291 -276.333458) (xy 358.56291 -276.333712) (xy 358.562656 -276.333712) (xy 358.541723 -276.351353)
			(xy 358.495755 -276.381077) (xy 358.446009 -276.403923) (xy 358.393507 -276.419419) (xy 358.339329 -276.427248)
			(xy 358.284587 -276.427248) (xy 358.230409 -276.419419) (xy 358.177907 -276.403923) (xy 358.128161 -276.381077)
			(xy 358.082193 -276.351353) (xy 358.06126 -276.333712) (xy 358.061006 -276.333458) (xy 358.053926 -276.327863)
			(xy 358.037004 -276.321622) (xy 358.027986 -276.321266) (xy 357.96093 -276.321266) (xy 357.951915 -276.321645)
			(xy 357.934999 -276.327878) (xy 357.92791 -276.333458) (xy 357.92791 -276.333712) (xy 357.927656 -276.333712)
			(xy 357.906723 -276.351353) (xy 357.860755 -276.381077) (xy 357.811009 -276.403923) (xy 357.758507 -276.419419)
			(xy 357.704329 -276.427248) (xy 357.649587 -276.427248) (xy 357.595409 -276.419419) (xy 357.542907 -276.403923)
			(xy 357.493161 -276.381077) (xy 357.447193 -276.351353) (xy 357.42626 -276.333712) (xy 357.426006 -276.333458)
			(xy 357.418926 -276.327863) (xy 357.402004 -276.321622) (xy 357.392986 -276.321266) (xy 357.32593 -276.321266)
			(xy 357.316915 -276.321645) (xy 357.299999 -276.327878) (xy 357.29291 -276.333458) (xy 357.29291 -276.333712)
			(xy 357.292656 -276.333712) (xy 357.271715 -276.35134) (xy 357.225745 -276.381053) (xy 357.175999 -276.403891)
			(xy 357.123501 -276.419385) (xy 357.069327 -276.427216) (xy 357.041958 -276.427692) (xy 357.014705 -276.427261)
			(xy 356.960754 -276.419499) (xy 356.908458 -276.404137) (xy 356.858879 -276.38149) (xy 356.813028 -276.352018)
			(xy 356.771838 -276.316321) (xy 356.736147 -276.275125) (xy 356.706682 -276.22927) (xy 356.684042 -276.179688)
			(xy 356.668689 -276.127389) (xy 356.660935 -276.073437) (xy 356.66045 -276.046184) (xy 354.124583 -276.046184)
			(xy 354.124583 -276.055268) (xy 354.116754 -276.109447) (xy 354.101257 -276.161949) (xy 354.07841 -276.211695)
			(xy 354.048684 -276.257662) (xy 354.031042 -276.278594) (xy 354.030788 -276.278848) (xy 354.025216 -276.285944)
			(xy 354.018961 -276.302854) (xy 354.018596 -276.311868) (xy 354.018596 -276.378924) (xy 354.018943 -276.387942)
			(xy 354.025198 -276.404859) (xy 354.030788 -276.411944) (xy 354.031042 -276.411944) (xy 354.031042 -276.412198)
			(xy 354.048701 -276.433114) (xy 354.078408 -276.479092) (xy 354.10124 -276.528844) (xy 354.116727 -276.581348)
			(xy 354.124551 -276.635526) (xy 354.125022 -276.662896) (xy 354.124536 -276.690147) (xy 354.11678 -276.744095)
			(xy 354.101425 -276.79639) (xy 354.078783 -276.845967) (xy 354.049317 -276.891817) (xy 354.013626 -276.933008)
			(xy 353.972435 -276.968699) (xy 353.926585 -276.998165) (xy 353.877008 -277.020807) (xy 353.824713 -277.036162)
			(xy 353.770765 -277.043918) (xy 353.716263 -277.043918) (xy 353.662315 -277.036162) (xy 353.61002 -277.020807)
			(xy 353.560443 -276.998165) (xy 353.514593 -276.968699) (xy 353.473402 -276.933008) (xy 353.437711 -276.891817)
			(xy 353.408245 -276.845967) (xy 353.385603 -276.79639) (xy 353.370248 -276.744095) (xy 353.362492 -276.690147)
			(xy 353.362006 -276.662896) (xy 353.362542 -276.633418) (xy 353.371612 -276.575165) (xy 353.389535 -276.519)
			(xy 353.415885 -276.466261) (xy 353.450035 -276.418203) (xy 353.47021 -276.396704) (xy 353.476737 -276.389364)
			(xy 353.484187 -276.371208) (xy 353.484688 -276.361398) (xy 353.484688 -276.308058) (xy 353.477322 -276.3012)
			(xy 353.469975 -276.294682) (xy 353.451824 -276.287227) (xy 353.442016 -276.286722) (xy 353.410012 -276.286722)
			(xy 353.400199 -276.287218) (xy 353.382034 -276.294656) (xy 353.374706 -276.3012) (xy 353.353196 -276.321362)
			(xy 353.30514 -276.35551) (xy 353.252404 -276.38186) (xy 353.196241 -276.399783) (xy 353.13799 -276.408854)
			(xy 353.108514 -276.409404) (xy 353.081261 -276.408932) (xy 353.027311 -276.401176) (xy 352.975013 -276.385822)
			(xy 352.925432 -276.363181) (xy 352.879579 -276.333714) (xy 352.838386 -276.298021) (xy 352.802692 -276.256829)
			(xy 352.773224 -276.210977) (xy 352.750581 -276.161397) (xy 352.735226 -276.109099) (xy 352.727469 -276.055149)
			(xy 352.727006 -276.027896) (xy 350.798384 -276.027896) (xy 350.798384 -277.634192) (xy 352.285046 -277.634192)
			(xy 352.285601 -277.605067) (xy 352.294469 -277.547495) (xy 352.311982 -277.49194) (xy 352.337734 -277.43969)
			(xy 352.371127 -277.391961) (xy 352.411385 -277.349861) (xy 352.434144 -277.331678) (xy 352.443288 -277.324566)
			(xy 352.453702 -277.304246) (xy 352.455988 -277.213568) (xy 352.455627 -277.202192) (xy 352.446251 -277.181483)
			(xy 352.437954 -277.17369) (xy 352.417226 -277.155498) (xy 352.380759 -277.114124) (xy 352.35063 -277.06793)
			(xy 352.327467 -277.017878) (xy 352.311754 -276.965013) (xy 352.303818 -276.910436) (xy 352.303334 -276.88286)
			(xy 352.30382 -276.855609) (xy 352.311576 -276.801661) (xy 352.326931 -276.749366) (xy 352.349573 -276.699789)
			(xy 352.379039 -276.653939) (xy 352.41473 -276.612748) (xy 352.455921 -276.577057) (xy 352.501771 -276.547591)
			(xy 352.551348 -276.524949) (xy 352.603643 -276.509594) (xy 352.657591 -276.501838) (xy 352.712093 -276.501838)
			(xy 352.766041 -276.509594) (xy 352.818336 -276.524949) (xy 352.867913 -276.547591) (xy 352.913763 -276.577057)
			(xy 352.954954 -276.612748) (xy 352.990645 -276.653939) (xy 353.020111 -276.699789) (xy 353.042753 -276.749366)
			(xy 353.058108 -276.801661) (xy 353.065864 -276.855609) (xy 353.06635 -276.88286) (xy 353.065762 -276.911984)
			(xy 353.056902 -276.969554) (xy 353.039395 -277.025109) (xy 353.013649 -277.077359) (xy 352.980262 -277.125088)
			(xy 352.940009 -277.16719) (xy 352.917252 -277.185374) (xy 352.908108 -277.192486) (xy 352.897694 -277.212806)
			(xy 352.895408 -277.303484) (xy 352.895798 -277.314857) (xy 352.905153 -277.335566) (xy 352.913442 -277.343362)
			(xy 352.934146 -277.36158) (xy 352.970615 -277.402949) (xy 353.000747 -277.449137) (xy 353.023914 -277.499184)
			(xy 353.039632 -277.552045) (xy 353.040313 -277.556722) (xy 353.207826 -277.556722) (xy 353.211897 -277.5011)
			(xy 353.224023 -277.446663) (xy 353.243946 -277.394572) (xy 353.271242 -277.345937) (xy 353.305328 -277.301794)
			(xy 353.345477 -277.263085) (xy 353.390835 -277.230634) (xy 353.440435 -277.205133) (xy 353.493219 -277.187126)
			(xy 353.548062 -277.176996) (xy 353.603796 -277.174959) (xy 353.659233 -277.181059) (xy 353.71319 -277.195165)
			(xy 353.764519 -277.216977) (xy 353.812125 -277.246031) (xy 353.854993 -277.281706) (xy 353.89221 -277.323243)
			(xy 353.922983 -277.369756) (xy 353.946655 -277.420253) (xy 353.962723 -277.47366) (xy 353.970843 -277.528836)
			(xy 353.971352 -277.556722) (xy 353.970843 -277.584608) (xy 353.962723 -277.639784) (xy 353.961349 -277.644352)
			(xy 359.283762 -277.644352) (xy 359.284178 -277.618036) (xy 359.29142 -277.565904) (xy 359.305748 -277.51526)
			(xy 359.32689 -277.467061) (xy 359.354446 -277.422219) (xy 359.387895 -277.381582) (xy 359.406952 -277.363428)
			(xy 359.414336 -277.355891) (xy 359.422872 -277.336623) (xy 359.423462 -277.32609) (xy 359.423462 -277.251414)
			(xy 359.42295 -277.240862) (xy 359.414404 -277.221566) (xy 359.406952 -277.214076) (xy 359.387883 -277.195935)
			(xy 359.354429 -277.155301) (xy 359.326873 -277.110457) (xy 359.305737 -277.062254) (xy 359.291422 -277.011604)
			(xy 359.2842 -276.959469) (xy 359.283762 -276.933152) (xy 359.284248 -276.905901) (xy 359.292004 -276.851953)
			(xy 359.307359 -276.799658) (xy 359.330001 -276.750081) (xy 359.359467 -276.704231) (xy 359.395158 -276.66304)
			(xy 359.436349 -276.627349) (xy 359.482199 -276.597883) (xy 359.531776 -276.575241) (xy 359.584071 -276.559886)
			(xy 359.638019 -276.55213) (xy 359.692521 -276.55213) (xy 359.746469 -276.559886) (xy 359.798764 -276.575241)
			(xy 359.848341 -276.597883) (xy 359.894191 -276.627349) (xy 359.935382 -276.66304) (xy 359.971073 -276.704231)
			(xy 360.000539 -276.750081) (xy 360.023181 -276.799658) (xy 360.038536 -276.851953) (xy 360.046292 -276.905901)
			(xy 360.046778 -276.933152) (xy 360.046352 -276.959467) (xy 360.03911 -277.011598) (xy 360.024783 -277.062242)
			(xy 360.003643 -277.110441) (xy 359.976089 -277.155283) (xy 359.942643 -277.195921) (xy 359.923588 -277.214076)
			(xy 359.916193 -277.221603) (xy 359.907665 -277.240879) (xy 359.907078 -277.251414) (xy 359.907078 -277.32609)
			(xy 359.907605 -277.33664) (xy 359.916142 -277.355935) (xy 359.923588 -277.363428) (xy 359.942648 -277.381579)
			(xy 359.976105 -277.42221) (xy 360.003664 -277.467051) (xy 360.024802 -277.515252) (xy 360.039118 -277.565901)
			(xy 360.046341 -277.618036) (xy 360.046778 -277.644352) (xy 360.046292 -277.671603) (xy 360.038536 -277.725551)
			(xy 360.023181 -277.777846) (xy 360.000539 -277.827423) (xy 359.971073 -277.873273) (xy 359.935382 -277.914464)
			(xy 359.894191 -277.950155) (xy 359.848341 -277.979621) (xy 359.798764 -278.002263) (xy 359.746469 -278.017618)
			(xy 359.692521 -278.025374) (xy 359.638019 -278.025374) (xy 359.584071 -278.017618) (xy 359.531776 -278.002263)
			(xy 359.482199 -277.979621) (xy 359.436349 -277.950155) (xy 359.395158 -277.914464) (xy 359.359467 -277.873273)
			(xy 359.330001 -277.827423) (xy 359.307359 -277.777846) (xy 359.292004 -277.725551) (xy 359.284248 -277.671603)
			(xy 359.283762 -277.644352) (xy 353.961349 -277.644352) (xy 353.946655 -277.693191) (xy 353.922983 -277.743688)
			(xy 353.89221 -277.790201) (xy 353.854993 -277.831738) (xy 353.812125 -277.867413) (xy 353.764519 -277.896467)
			(xy 353.71319 -277.918279) (xy 353.659233 -277.932385) (xy 353.603796 -277.938485) (xy 353.548062 -277.936448)
			(xy 353.493219 -277.926318) (xy 353.440435 -277.908311) (xy 353.390835 -277.88281) (xy 353.345477 -277.850359)
			(xy 353.305328 -277.81165) (xy 353.271242 -277.767507) (xy 353.243946 -277.718872) (xy 353.224023 -277.666781)
			(xy 353.211897 -277.612344) (xy 353.207826 -277.556722) (xy 353.040313 -277.556722) (xy 353.047575 -277.606618)
			(xy 353.048062 -277.634192) (xy 353.047576 -277.661443) (xy 353.03982 -277.715391) (xy 353.024465 -277.767686)
			(xy 353.001823 -277.817263) (xy 352.972357 -277.863113) (xy 352.936666 -277.904304) (xy 352.895475 -277.939995)
			(xy 352.849625 -277.969461) (xy 352.800048 -277.992103) (xy 352.747753 -278.007458) (xy 352.693805 -278.015214)
			(xy 352.639303 -278.015214) (xy 352.585355 -278.007458) (xy 352.53306 -277.992103) (xy 352.483483 -277.969461)
			(xy 352.437633 -277.939995) (xy 352.396442 -277.904304) (xy 352.360751 -277.863113) (xy 352.331285 -277.817263)
			(xy 352.308643 -277.767686) (xy 352.293288 -277.715391) (xy 352.285532 -277.661443) (xy 352.285046 -277.634192)
			(xy 350.798384 -277.634192) (xy 350.798384 -278.218392) (xy 350.798791 -278.228464) (xy 350.806522 -278.247063)
			(xy 350.81337 -278.25446) (xy 352.048572 -279.489662) (xy 352.055992 -279.496477) (xy 352.074576 -279.504212)
			(xy 352.08464 -279.504648) (xy 354.017834 -279.504648) (xy 354.045814 -279.505203) (xy 354.101083 -279.513968)
			(xy 354.154299 -279.531276) (xy 354.204149 -279.5567) (xy 354.249406 -279.589614) (xy 354.269548 -279.609042)
			(xy 354.928678 -280.268172) (xy 354.936806 -280.271982) (xy 354.961012 -280.28389) (xy 355.006085 -280.313531)
			(xy 355.046535 -280.349223) (xy 355.081555 -280.390256) (xy 355.110449 -280.435812) (xy 355.13264 -280.484982)
			(xy 355.147685 -280.536788) (xy 355.155286 -280.590195) (xy 355.155754 -280.617168) (xy 355.155696 -280.627794)
			(xy 355.154553 -280.649015) (xy 355.153468 -280.659586) (xy 355.152452 -280.668984) (xy 355.157278 -280.687272)
			(xy 355.203252 -280.750772) (xy 355.209088 -280.758052) (xy 355.224707 -280.768222) (xy 355.233732 -280.770584)
			(xy 355.233986 -280.770584) (xy 355.24948 -280.77414) (xy 355.259 -280.776056) (xy 355.278207 -280.773298)
			(xy 355.286818 -280.768806) (xy 355.348032 -280.733754) (xy 355.356304 -280.728551) (xy 355.368454 -280.713269)
			(xy 355.371654 -280.704036) (xy 355.371654 -280.703782) (xy 355.379657 -280.677664) (xy 355.402208 -280.627909)
			(xy 355.431629 -280.581881) (xy 355.467317 -280.540523) (xy 355.508542 -280.504681) (xy 355.55446 -280.475089)
			(xy 355.604131 -280.452353) (xy 355.656538 -280.436938) (xy 355.710608 -280.429159) (xy 355.737922 -280.4287)
			(xy 355.763094 -280.429091) (xy 355.813001 -280.435712) (xy 355.861605 -280.448836) (xy 355.884988 -280.458164)
			(xy 355.895133 -280.461858) (xy 355.916696 -280.461341) (xy 355.926644 -280.457148) (xy 356.004622 -280.420064)
			(xy 356.018592 -280.403808) (xy 356.02164 -280.39314) (xy 356.03041 -280.36523) (xy 356.055346 -280.312308)
			(xy 356.088071 -280.263814) (xy 356.127817 -280.220887) (xy 356.173653 -280.184533) (xy 356.224503 -280.155605)
			(xy 356.279174 -280.134781) (xy 356.336383 -280.122551) (xy 356.365556 -280.120344) (xy 356.36581 -280.120344)
			(xy 356.377085 -280.118993) (xy 356.396872 -280.107918) (xy 356.40391 -280.099008) (xy 356.456742 -280.02484)
			(xy 356.460552 -280.002234) (xy 356.457504 -279.991058) (xy 356.45074 -279.965556) (xy 356.443473 -279.913298)
			(xy 356.443026 -279.886918) (xy 356.443512 -279.859667) (xy 356.451268 -279.805719) (xy 356.466623 -279.753424)
			(xy 356.489265 -279.703847) (xy 356.518731 -279.657997) (xy 356.554422 -279.616806) (xy 356.595613 -279.581115)
			(xy 356.641463 -279.551649) (xy 356.69104 -279.529007) (xy 356.743335 -279.513652) (xy 356.797283 -279.505896)
			(xy 356.851785 -279.505896) (xy 356.905733 -279.513652) (xy 356.958028 -279.529007) (xy 357.007605 -279.551649)
			(xy 357.053455 -279.581115) (xy 357.094646 -279.616806) (xy 357.130337 -279.657997) (xy 357.159803 -279.703847)
			(xy 357.182445 -279.753424) (xy 357.1978 -279.805719) (xy 357.205556 -279.859667) (xy 357.206042 -279.886918)
			(xy 357.205565 -279.915793) (xy 357.196881 -279.972886) (xy 357.179684 -280.028016) (xy 357.154368 -280.079921)
			(xy 357.121512 -280.127413) (xy 357.081868 -280.169406) (xy 357.036343 -280.204938) (xy 356.985979 -280.233196)
			(xy 356.931929 -280.253534) (xy 356.87543 -280.265486) (xy 356.846632 -280.267664) (xy 356.846378 -280.267664)
			(xy 356.83511 -280.269043) (xy 356.815323 -280.280101) (xy 356.808278 -280.289) (xy 356.755446 -280.363168)
			(xy 356.751636 -280.385774) (xy 356.754684 -280.39695) (xy 356.761449 -280.422452) (xy 356.768716 -280.47471)
			(xy 356.769162 -280.50109) (xy 356.768395 -280.535173) (xy 356.756263 -280.602251) (xy 356.745032 -280.63444)
			(xy 356.740714 -280.64587) (xy 356.743254 -280.669492) (xy 356.800658 -280.758138) (xy 356.821486 -280.77033)
			(xy 356.833424 -280.771092) (xy 356.862031 -280.773559) (xy 356.918098 -280.785938) (xy 356.971677 -280.806576)
			(xy 357.02156 -280.835007) (xy 357.066621 -280.87059) (xy 357.105843 -280.912522) (xy 357.138341 -280.959857)
			(xy 357.163381 -281.011526) (xy 357.180399 -281.066362) (xy 357.189009 -281.12313) (xy 357.189532 -281.151838)
			(xy 357.189046 -281.179089) (xy 357.18129 -281.233037) (xy 357.165935 -281.285332) (xy 357.143293 -281.334909)
			(xy 357.113827 -281.380759) (xy 357.078136 -281.42195) (xy 357.036945 -281.457641) (xy 356.991095 -281.487107)
			(xy 356.941518 -281.509749) (xy 356.889223 -281.525104) (xy 356.835275 -281.53286) (xy 356.780773 -281.53286)
			(xy 356.726825 -281.525104) (xy 356.67453 -281.509749) (xy 356.624953 -281.487107) (xy 356.579103 -281.457641)
			(xy 356.537912 -281.42195) (xy 356.502221 -281.380759) (xy 356.472755 -281.334909) (xy 356.450113 -281.285332)
			(xy 356.434758 -281.233037) (xy 356.427002 -281.179089) (xy 356.426516 -281.151838) (xy 356.427266 -281.117754)
			(xy 356.43941 -281.050676) (xy 356.450646 -281.018488) (xy 356.454964 -281.007058) (xy 356.452424 -280.983436)
			(xy 356.39502 -280.89479) (xy 356.374192 -280.882598) (xy 356.362254 -280.881836) (xy 356.330956 -280.879094)
			(xy 356.269811 -280.864671) (xy 356.240588 -280.853134) (xy 356.230447 -280.849426) (xy 356.20888 -280.849952)
			(xy 356.198932 -280.85415) (xy 356.120954 -280.891234) (xy 356.106984 -280.90749) (xy 356.103936 -280.918158)
			(xy 356.095755 -280.944134) (xy 356.073075 -280.993644) (xy 356.043585 -281.039426) (xy 356.007884 -281.08055)
			(xy 355.966699 -281.11618) (xy 355.920866 -281.14559) (xy 355.871316 -281.168185) (xy 355.819057 -281.183505)
			(xy 355.765151 -281.191237) (xy 355.737922 -281.191716) (xy 355.714566 -281.191351) (xy 355.668207 -281.18562)
			(xy 355.645466 -281.180286) (xy 355.635943 -281.178393) (xy 355.616739 -281.181135) (xy 355.608128 -281.18562)
			(xy 355.546914 -281.220672) (xy 355.538644 -281.225877) (xy 355.526491 -281.241157) (xy 355.523292 -281.25039)
			(xy 355.523292 -281.250644) (xy 355.515264 -281.276753) (xy 355.492713 -281.326506) (xy 355.463294 -281.372531)
			(xy 355.427609 -281.413888) (xy 355.386387 -281.449729) (xy 355.340473 -281.479322) (xy 355.290806 -281.502061)
			(xy 355.238403 -281.51748) (xy 355.184336 -281.525263) (xy 355.157024 -281.525726) (xy 355.129773 -281.525222)
			(xy 355.075824 -281.517469) (xy 355.023528 -281.502117) (xy 354.973949 -281.479479) (xy 354.928097 -281.450015)
			(xy 354.886904 -281.414325) (xy 354.85121 -281.373137) (xy 354.821741 -281.327288) (xy 354.799098 -281.277711)
			(xy 354.78374 -281.225417) (xy 354.775981 -281.171469) (xy 354.775516 -281.144218) (xy 354.775573 -281.133592)
			(xy 354.776716 -281.112371) (xy 354.777802 -281.1018) (xy 354.778818 -281.092402) (xy 354.773992 -281.074114)
			(xy 354.728018 -281.010614) (xy 354.722196 -281.003322) (xy 354.706566 -280.993159) (xy 354.697538 -280.990802)
			(xy 354.697284 -280.990802) (xy 354.668486 -280.984348) (xy 354.613199 -280.963704) (xy 354.561753 -280.934788)
			(xy 354.515378 -280.898289) (xy 354.475182 -280.855079) (xy 354.442124 -280.806192) (xy 354.42906 -280.779728)
			(xy 354.42525 -280.7716) (xy 353.885246 -280.23185) (xy 353.877818 -280.225045) (xy 353.85924 -280.217303)
			(xy 353.849178 -280.216864) (xy 351.915984 -280.216864) (xy 351.888002 -280.216357) (xy 351.832731 -280.20758)
			(xy 351.779515 -280.190261) (xy 351.729665 -280.164826) (xy 351.684411 -280.131902) (xy 351.66427 -280.11247)
			(xy 350.190562 -278.638762) (xy 350.17118 -278.61858) (xy 350.138283 -278.573322) (xy 350.112861 -278.52348)
			(xy 350.095539 -278.470278) (xy 350.086742 -278.415023) (xy 350.086168 -278.387048) (xy 346.56423 -278.387048)
			(xy 346.579663 -278.408283) (xy 346.605082 -278.458129) (xy 346.622401 -278.511333) (xy 346.631195 -278.56659)
			(xy 346.631768 -278.594566) (xy 346.631768 -280.479754) (xy 346.634562 -280.488136) (xy 346.645099 -280.519348)
			(xy 346.656458 -280.584233) (xy 346.657168 -280.617168) (xy 346.65711 -280.627794) (xy 346.655967 -280.649015)
			(xy 346.654882 -280.659586) (xy 346.653866 -280.668984) (xy 346.658692 -280.687272) (xy 346.704666 -280.750772)
			(xy 346.710497 -280.758056) (xy 346.72612 -280.768224) (xy 346.735146 -280.770584) (xy 346.7354 -280.770584)
			(xy 346.750894 -280.77414) (xy 346.76042 -280.776008) (xy 346.77962 -280.773282) (xy 346.788232 -280.768806)
			(xy 346.849446 -280.733754) (xy 346.85772 -280.728555) (xy 346.869869 -280.71327) (xy 346.873068 -280.704036)
			(xy 346.873068 -280.703782) (xy 346.881148 -280.67769) (xy 346.903692 -280.627939) (xy 346.933104 -280.581914)
			(xy 346.968783 -280.540557) (xy 347.009998 -280.504714) (xy 347.055905 -280.475119) (xy 347.105566 -280.452377)
			(xy 347.157964 -280.436954) (xy 347.212026 -280.429165) (xy 347.239336 -280.4287) (xy 347.264508 -280.429087)
			(xy 347.314415 -280.435709) (xy 347.363019 -280.448835) (xy 347.386402 -280.458164) (xy 347.396544 -280.461866)
			(xy 347.41811 -280.461344) (xy 347.428058 -280.457148) (xy 347.506036 -280.420064) (xy 347.520006 -280.403808)
			(xy 347.523054 -280.39314) (xy 347.531813 -280.365226) (xy 347.55675 -280.312303) (xy 347.589476 -280.263809)
			(xy 347.629224 -280.220882) (xy 347.675062 -280.184528) (xy 347.725913 -280.155601) (xy 347.780586 -280.134779)
			(xy 347.837797 -280.12255) (xy 347.86697 -280.120344) (xy 347.867224 -280.120344) (xy 347.8785 -280.119)
			(xy 347.898286 -280.10792) (xy 347.905324 -280.099008) (xy 347.958156 -280.02484) (xy 347.961966 -280.002234)
			(xy 347.958918 -279.991058) (xy 347.952155 -279.965556) (xy 347.944887 -279.913298) (xy 347.94444 -279.886918)
			(xy 347.944926 -279.859667) (xy 347.952682 -279.805719) (xy 347.968037 -279.753424) (xy 347.990679 -279.703847)
			(xy 348.020145 -279.657997) (xy 348.055836 -279.616806) (xy 348.097027 -279.581115) (xy 348.142877 -279.551649)
			(xy 348.192454 -279.529007) (xy 348.244749 -279.513652) (xy 348.298697 -279.505896) (xy 348.353199 -279.505896)
			(xy 348.407147 -279.513652) (xy 348.459442 -279.529007) (xy 348.509019 -279.551649) (xy 348.554869 -279.581115)
			(xy 348.59606 -279.616806) (xy 348.631751 -279.657997) (xy 348.661217 -279.703847) (xy 348.683859 -279.753424)
			(xy 348.699214 -279.805719) (xy 348.70697 -279.859667) (xy 348.707456 -279.886918) (xy 348.706966 -279.915793)
			(xy 348.698282 -279.972884) (xy 348.681086 -280.028013) (xy 348.655771 -280.079917) (xy 348.622917 -280.127409)
			(xy 348.583274 -280.169402) (xy 348.537751 -280.204934) (xy 348.487389 -280.233193) (xy 348.433341 -280.253532)
			(xy 348.376843 -280.265485) (xy 348.348046 -280.267664) (xy 348.347792 -280.267664) (xy 348.336525 -280.26905)
			(xy 348.316738 -280.280103) (xy 348.309692 -280.289) (xy 348.25686 -280.363168) (xy 348.25305 -280.385774)
			(xy 348.256098 -280.39695) (xy 348.262863 -280.422452) (xy 348.27013 -280.47471) (xy 348.270576 -280.50109)
			(xy 348.269808 -280.535173) (xy 348.257676 -280.602251) (xy 348.246446 -280.63444) (xy 348.242128 -280.64587)
			(xy 348.244668 -280.669492) (xy 348.302072 -280.758138) (xy 348.3229 -280.77033) (xy 348.334838 -280.771092)
			(xy 348.363446 -280.773547) (xy 348.419513 -280.785928) (xy 348.473093 -280.806567) (xy 348.522976 -280.835)
			(xy 348.568036 -280.870585) (xy 348.607258 -280.912518) (xy 348.639756 -280.959854) (xy 348.664796 -281.011524)
			(xy 348.681813 -281.066361) (xy 348.690423 -281.123129) (xy 348.690946 -281.151838) (xy 348.69046 -281.179089)
			(xy 348.682704 -281.233037) (xy 348.667349 -281.285332) (xy 348.644707 -281.334909) (xy 348.615241 -281.380759)
			(xy 348.57955 -281.42195) (xy 348.538359 -281.457641) (xy 348.492509 -281.487107) (xy 348.442932 -281.509749)
			(xy 348.390637 -281.525104) (xy 348.336689 -281.53286) (xy 348.282187 -281.53286) (xy 348.228239 -281.525104)
			(xy 348.175944 -281.509749) (xy 348.126367 -281.487107) (xy 348.080517 -281.457641) (xy 348.039326 -281.42195)
			(xy 348.003635 -281.380759) (xy 347.974169 -281.334909) (xy 347.951527 -281.285332) (xy 347.936172 -281.233037)
			(xy 347.928416 -281.179089) (xy 347.92793 -281.151838) (xy 347.928679 -281.117754) (xy 347.940823 -281.050676)
			(xy 347.95206 -281.018488) (xy 347.956378 -281.007058) (xy 347.953838 -280.983436) (xy 347.896434 -280.89479)
			(xy 347.875606 -280.882598) (xy 347.863668 -280.881836) (xy 347.83237 -280.87909) (xy 347.771225 -280.86467)
			(xy 347.742002 -280.853134) (xy 347.731859 -280.849434) (xy 347.710294 -280.849955) (xy 347.700346 -280.85415)
			(xy 347.622368 -280.891234) (xy 347.608398 -280.90749) (xy 347.60535 -280.918158) (xy 347.597156 -280.944129)
			(xy 347.574477 -280.993639) (xy 347.544989 -281.039421) (xy 347.50929 -281.080545) (xy 347.468106 -281.116174)
			(xy 347.422275 -281.145586) (xy 347.372727 -281.168181) (xy 347.320469 -281.183502) (xy 347.266565 -281.191236)
			(xy 347.239336 -281.191716) (xy 347.21598 -281.191348) (xy 347.169622 -281.185619) (xy 347.14688 -281.180286)
			(xy 347.137356 -281.1784) (xy 347.118153 -281.181137) (xy 347.109542 -281.18562) (xy 347.048328 -281.220672)
			(xy 347.04006 -281.225881) (xy 347.027906 -281.241158) (xy 347.024706 -281.25039) (xy 347.024706 -281.250644)
			(xy 347.016665 -281.276749) (xy 346.994116 -281.326501) (xy 346.964698 -281.372526) (xy 346.929014 -281.413882)
			(xy 346.887794 -281.449724) (xy 346.841882 -281.479318) (xy 346.792217 -281.502057) (xy 346.739815 -281.517477)
			(xy 346.68575 -281.525262) (xy 346.658438 -281.525726) (xy 346.631187 -281.525209) (xy 346.577239 -281.517458)
			(xy 346.524943 -281.502108) (xy 346.475364 -281.479471) (xy 346.429512 -281.450009) (xy 346.388319 -281.41432)
			(xy 346.352625 -281.373133) (xy 346.323156 -281.327285) (xy 346.300512 -281.277709) (xy 346.285154 -281.225416)
			(xy 346.277395 -281.171469) (xy 346.27693 -281.144218) (xy 346.276987 -281.133592) (xy 346.27813 -281.112371)
			(xy 346.279216 -281.1018) (xy 346.280232 -281.092402) (xy 346.275406 -281.074114) (xy 346.229432 -281.010614)
			(xy 346.223605 -281.003327) (xy 346.207979 -280.993161) (xy 346.198952 -280.990802) (xy 346.198698 -280.990802)
			(xy 346.170398 -280.984438) (xy 346.11601 -280.964277) (xy 346.065302 -280.936114) (xy 346.019442 -280.900598)
			(xy 345.979488 -280.858548) (xy 345.946361 -280.810934) (xy 345.920825 -280.758853) (xy 345.903468 -280.703507)
			(xy 345.894691 -280.64617) (xy 345.894152 -280.617168) (xy 345.894877 -280.584235) (xy 345.906248 -280.519356)
			(xy 345.916758 -280.488136) (xy 345.919552 -280.479754) (xy 345.919552 -278.763222) (xy 345.919128 -278.753152)
			(xy 345.911408 -278.734554) (xy 345.904566 -278.727154) (xy 344.939366 -277.7617) (xy 344.919955 -277.741545)
			(xy 344.887061 -277.69628) (xy 344.861645 -277.646431) (xy 344.844329 -277.593223) (xy 344.835541 -277.537963)
			(xy 344.834972 -277.509986) (xy 343.363395 -277.509986) (xy 343.365704 -277.515252) (xy 343.38002 -277.565901)
			(xy 343.387243 -277.618036) (xy 343.38768 -277.644352) (xy 343.3872 -277.671605) (xy 343.379449 -277.725557)
			(xy 343.364097 -277.777856) (xy 343.341458 -277.827438) (xy 343.311993 -277.873293) (xy 343.276301 -277.914486)
			(xy 343.235109 -277.950181) (xy 343.189255 -277.979649) (xy 343.139675 -278.00229) (xy 343.087376 -278.017645)
			(xy 343.033425 -278.025399) (xy 343.006172 -278.02586) (xy 342.979701 -278.025468) (xy 342.927265 -278.01817)
			(xy 342.876343 -278.00369) (xy 342.827912 -277.982306) (xy 342.782904 -277.95443) (xy 342.742184 -277.920597)
			(xy 342.706535 -277.881457) (xy 342.676641 -277.837764) (xy 342.653077 -277.790356) (xy 342.636297 -277.740144)
			(xy 342.631014 -277.714202) (xy 342.628728 -277.701756) (xy 342.613488 -277.682452) (xy 342.513666 -277.638002)
			(xy 342.488774 -277.63978) (xy 342.478106 -277.646384) (xy 342.455508 -277.659731) (xy 342.40744 -277.680798)
			(xy 342.356939 -277.695082) (xy 342.304957 -277.702314) (xy 342.278716 -277.702772) (xy 342.278208 -277.702772)
			(xy 342.250954 -277.702337) (xy 342.197 -277.69458) (xy 342.144699 -277.679223) (xy 342.095117 -277.656579)
			(xy 342.049262 -277.627109) (xy 342.008068 -277.591412) (xy 341.972374 -277.550216) (xy 341.942907 -277.504359)
			(xy 341.920267 -277.454774) (xy 341.904914 -277.402473) (xy 341.897161 -277.348518) (xy 341.8967 -277.321264)
			(xy 341.897145 -277.293893) (xy 341.904968 -277.239713) (xy 341.920462 -277.18721) (xy 341.943308 -277.137463)
			(xy 341.973037 -277.091497) (xy 341.99068 -277.070566) (xy 341.990934 -277.070312) (xy 341.996525 -277.063229)
			(xy 342.002768 -277.046309) (xy 342.003126 -277.037292) (xy 342.003126 -276.970236) (xy 342.002746 -276.961222)
			(xy 341.996514 -276.944305) (xy 341.990934 -276.937216) (xy 341.99068 -276.937216) (xy 341.99068 -276.936962)
			(xy 341.973053 -276.91602) (xy 341.94334 -276.87005) (xy 341.920502 -276.820305) (xy 341.905008 -276.767806)
			(xy 341.897176 -276.713632) (xy 341.8967 -276.686264) (xy 341.89728 -276.656788) (xy 341.906339 -276.598537)
			(xy 341.924252 -276.542372) (xy 341.950593 -276.489632) (xy 341.984733 -276.441573) (xy 342.004904 -276.420072)
			(xy 342.011444 -276.412742) (xy 342.018886 -276.394578) (xy 342.019382 -276.384766) (xy 342.019382 -276.331426)
			(xy 342.012016 -276.324568) (xy 342.004674 -276.318043) (xy 341.986519 -276.310593) (xy 341.97671 -276.31009)
			(xy 341.944706 -276.31009) (xy 341.934893 -276.310591) (xy 341.916729 -276.318026) (xy 341.9094 -276.324568)
			(xy 341.887903 -276.344744) (xy 341.839843 -276.378888) (xy 341.787102 -276.405234) (xy 341.730938 -276.423154)
			(xy 341.672685 -276.432223) (xy 341.643208 -276.432772) (xy 341.615954 -276.432337) (xy 341.562 -276.42458)
			(xy 341.509699 -276.409223) (xy 341.460117 -276.386579) (xy 341.414262 -276.357109) (xy 341.373068 -276.321412)
			(xy 341.337374 -276.280216) (xy 341.307907 -276.234359) (xy 341.285267 -276.184774) (xy 341.269914 -276.132473)
			(xy 341.262161 -276.078518) (xy 341.2617 -276.051264) (xy 339.568028 -276.051264) (xy 339.568028 -277.2791)
			(xy 339.567516 -277.307048) (xy 339.558785 -277.362257) (xy 339.541522 -277.415421) (xy 339.516154 -277.465228)
			(xy 339.483304 -277.510451) (xy 339.463888 -277.53056) (xy 337.93049 -279.064212) (xy 337.923636 -279.071607)
			(xy 337.915891 -279.090206) (xy 337.915504 -279.10028) (xy 337.915504 -279.89276) (xy 337.915938 -279.902825)
			(xy 337.923668 -279.921413) (xy 337.93049 -279.928828) (xy 338.26958 -280.268172) (xy 338.277708 -280.271982)
			(xy 338.301913 -280.283896) (xy 338.346997 -280.313526) (xy 338.387455 -280.349212) (xy 338.422483 -280.390243)
			(xy 338.45138 -280.435799) (xy 338.47357 -280.484973) (xy 338.488611 -280.536782) (xy 338.496203 -280.590194)
			(xy 338.496656 -280.617168) (xy 338.496605 -280.627794) (xy 338.495462 -280.649016) (xy 338.49437 -280.659586)
			(xy 338.493354 -280.668984) (xy 338.49818 -280.687272) (xy 338.544154 -280.750772) (xy 338.549975 -280.758063)
			(xy 338.565608 -280.76822) (xy 338.574634 -280.770584) (xy 338.574888 -280.770584) (xy 338.590128 -280.77414)
			(xy 338.590636 -280.77414) (xy 338.600034 -280.776426) (xy 338.619338 -280.773886) (xy 338.688934 -280.733754)
			(xy 338.697206 -280.728549) (xy 338.709366 -280.713272) (xy 338.712556 -280.704036) (xy 338.712556 -280.703782)
			(xy 338.720626 -280.67769) (xy 338.743192 -280.627953) (xy 338.772618 -280.581942) (xy 338.808303 -280.540596)
			(xy 338.849517 -280.50476) (xy 338.89542 -280.475165) (xy 338.945073 -280.452416) (xy 338.997462 -280.436979)
			(xy 339.051516 -280.429168) (xy 339.078824 -280.4287) (xy 339.103995 -280.429105) (xy 339.1539 -280.435725)
			(xy 339.202502 -280.448849) (xy 339.22589 -280.458164) (xy 339.236023 -280.461926) (xy 339.257608 -280.461398)
			(xy 339.267546 -280.457148) (xy 339.345524 -280.420064) (xy 339.359494 -280.403808) (xy 339.362542 -280.39314)
			(xy 339.371333 -280.365238) (xy 339.396267 -280.312319) (xy 339.42899 -280.263828) (xy 339.468734 -280.220904)
			(xy 339.514567 -280.184552) (xy 339.565414 -280.155626) (xy 339.620082 -280.134804) (xy 339.677288 -280.122574)
			(xy 339.706458 -280.120344) (xy 339.706712 -280.120344) (xy 339.717986 -280.118992) (xy 339.737776 -280.107919)
			(xy 339.744812 -280.099008) (xy 339.797644 -280.02484) (xy 339.801454 -280.002234) (xy 339.798406 -279.991058)
			(xy 339.791636 -279.965557) (xy 339.784366 -279.913299) (xy 339.783928 -279.886918) (xy 339.784414 -279.859667)
			(xy 339.79217 -279.805719) (xy 339.807525 -279.753424) (xy 339.830167 -279.703847) (xy 339.859633 -279.657997)
			(xy 339.895324 -279.616806) (xy 339.936515 -279.581115) (xy 339.982365 -279.551649) (xy 340.031942 -279.529007)
			(xy 340.084237 -279.513652) (xy 340.138185 -279.505896) (xy 340.192687 -279.505896) (xy 340.246635 -279.513652)
			(xy 340.29893 -279.529007) (xy 340.348507 -279.551649) (xy 340.394357 -279.581115) (xy 340.435548 -279.616806)
			(xy 340.471239 -279.657997) (xy 340.500705 -279.703847) (xy 340.523347 -279.753424) (xy 340.538702 -279.805719)
			(xy 340.546458 -279.859667) (xy 340.546944 -279.886918) (xy 340.546404 -279.915783) (xy 340.537687 -279.972852)
			(xy 340.520469 -280.027956) (xy 340.495145 -280.079835) (xy 340.462291 -280.127306) (xy 340.422659 -280.169284)
			(xy 340.377154 -280.204811) (xy 340.326815 -280.233074) (xy 340.272791 -280.253429) (xy 340.216317 -280.26541)
			(xy 340.187534 -280.267664) (xy 340.18728 -280.267664) (xy 340.176007 -280.269018) (xy 340.156221 -280.280093)
			(xy 340.14918 -280.289) (xy 340.096348 -280.363168) (xy 340.092538 -280.385774) (xy 340.095586 -280.39695)
			(xy 340.102356 -280.422451) (xy 340.109625 -280.474709) (xy 340.110064 -280.50109) (xy 340.10957 -280.528797)
			(xy 340.101536 -280.583626) (xy 340.094062 -280.61031) (xy 340.089998 -280.623772) (xy 340.096856 -280.650696)
			(xy 340.218522 -280.772362) (xy 340.23046 -280.778966) (xy 340.237572 -280.780744) (xy 340.263034 -280.78728)
			(xy 340.312 -280.806403) (xy 340.357878 -280.832067) (xy 340.399797 -280.863786) (xy 340.436964 -280.900961)
			(xy 340.468676 -280.942887) (xy 340.49433 -280.988769) (xy 340.513443 -281.03774) (xy 340.52002 -281.063192)
			(xy 340.521798 -281.070304) (xy 340.528402 -281.082242) (xy 340.531704 -281.085544) (xy 340.531704 -281.538934)
			(xy 340.532078 -281.547722) (xy 340.538035 -281.564259) (xy 340.549235 -281.577805) (xy 340.556596 -281.582622)
			(xy 340.64321 -281.634184) (xy 340.66988 -281.634692) (xy 340.681818 -281.628088) (xy 340.709942 -281.61353)
			(xy 340.769817 -281.592918) (xy 340.832274 -281.582472) (xy 340.863936 -281.58186) (xy 340.892557 -281.582373)
			(xy 340.949157 -281.590921) (xy 341.003848 -281.607819) (xy 341.055404 -281.63269) (xy 341.079328 -281.648408)
			(xy 341.090758 -281.656282) (xy 341.119206 -281.65806) (xy 341.211154 -281.609546) (xy 341.219134 -281.604897)
			(xy 341.23136 -281.591074) (xy 341.237895 -281.573815) (xy 341.238332 -281.564588) (xy 341.238332 -281.361134)
			(xy 341.237829 -281.351082) (xy 341.230112 -281.332517) (xy 341.223346 -281.325066) (xy 341.167466 -281.26944)
			(xy 341.146727 -281.247865) (xy 341.111558 -281.19945) (xy 341.084391 -281.146132) (xy 341.065894 -281.089222)
			(xy 341.056523 -281.03012) (xy 341.05596 -281.0002) (xy 341.05596 -280.999692) (xy 341.056445 -280.972452)
			(xy 341.064196 -280.918526) (xy 341.079539 -280.86625) (xy 341.102161 -280.816689) (xy 341.131604 -280.770849)
			(xy 341.167267 -280.729664) (xy 341.208427 -280.693971) (xy 341.254245 -280.664495) (xy 341.303789 -280.641836)
			(xy 341.356054 -280.626455) (xy 341.409974 -280.618665) (xy 341.437214 -280.618184) (xy 341.467194 -280.618743)
			(xy 341.526413 -280.628129) (xy 341.583435 -280.646667) (xy 341.636852 -280.673901) (xy 341.685349 -280.709159)
			(xy 341.706962 -280.729944) (xy 341.889334 -280.912316) (xy 341.910069 -280.933892) (xy 341.945231 -280.982308)
			(xy 341.972391 -281.035627) (xy 341.990879 -281.092537) (xy 342.000242 -281.151637) (xy 342.00084 -281.181556)
			(xy 342.00084 -282.414726) (xy 342.000232 -282.444641) (xy 341.990842 -282.503732) (xy 341.972343 -282.560633)
			(xy 341.94519 -282.613948) (xy 341.910046 -282.662372) (xy 341.889334 -282.683966) (xy 341.617554 -282.955746)
			(xy 341.610709 -282.963144) (xy 341.602983 -282.981743) (xy 341.602568 -282.991814) (xy 341.602568 -283.029152)
			(xy 341.602979 -283.039182) (xy 341.610639 -283.057721) (xy 341.624812 -283.071916) (xy 341.643339 -283.079606)
			(xy 341.653368 -283.079952) (xy 341.66175 -283.079952) (xy 341.669878 -283.077158) (xy 341.700182 -283.067333)
			(xy 341.762996 -283.056742) (xy 341.794846 -283.056076) (xy 341.7951 -283.056076) (xy 341.822352 -283.056562)
			(xy 341.8763 -283.064318) (xy 341.928596 -283.079673) (xy 341.978174 -283.102314) (xy 342.024026 -283.13178)
			(xy 342.065217 -283.167471) (xy 342.10091 -283.208661) (xy 342.130378 -283.254512) (xy 342.153021 -283.304089)
			(xy 342.168378 -283.356384) (xy 342.176137 -283.410332) (xy 342.176608 -283.437584) (xy 342.176061 -283.467061)
			(xy 342.166994 -283.525315) (xy 342.149074 -283.58148) (xy 342.122727 -283.63422) (xy 342.088581 -283.682279)
			(xy 342.068404 -283.703776) (xy 342.061854 -283.711102) (xy 342.054405 -283.729267) (xy 342.053926 -283.739082)
			(xy 342.053926 -283.792422) (xy 342.064848 -283.802836) (xy 342.58504 -284.323282) (xy 342.59244 -284.330124)
			(xy 342.611038 -284.337847) (xy 342.621108 -284.338268) (xy 343.826084 -284.338268) (xy 343.83699 -284.337812)
			(xy 343.856875 -284.328866) (xy 343.864438 -284.320996) (xy 343.91473 -284.263592) (xy 343.921473 -284.255215)
			(xy 343.9278 -284.234685) (xy 343.926922 -284.223968) (xy 343.926922 -284.223714) (xy 343.925502 -284.211763)
			(xy 343.923974 -284.187742) (xy 343.923874 -284.175708) (xy 343.923874 -284.175454) (xy 343.924439 -284.145329)
			(xy 343.933905 -284.085827) (xy 343.95261 -284.028554) (xy 343.980089 -283.974935) (xy 344.015658 -283.926304)
			(xy 344.03665 -283.90469) (xy 344.0435 -283.897293) (xy 344.051239 -283.878695) (xy 344.051636 -283.868622)
			(xy 344.051636 -283.796486) (xy 344.051209 -283.786418) (xy 344.043484 -283.767824) (xy 344.03665 -283.760418)
			(xy 344.015673 -283.738793) (xy 343.980118 -283.690158) (xy 343.952647 -283.63654) (xy 343.933942 -283.579272)
			(xy 343.924467 -283.519777) (xy 343.923874 -283.489654) (xy 343.924471 -283.459817) (xy 343.933782 -283.400873)
			(xy 343.942416 -283.372306) (xy 343.945718 -283.361892) (xy 343.943432 -283.340302) (xy 343.89314 -283.25572)
			(xy 343.875868 -283.243274) (xy 343.864946 -283.241242) (xy 343.837097 -283.235368) (xy 343.783413 -283.216466)
			(xy 343.733136 -283.189794) (xy 343.687382 -283.155944) (xy 343.647169 -283.115668) (xy 343.61339 -283.069862)
			(xy 343.586796 -283.019543) (xy 343.567977 -282.96583) (xy 343.562178 -282.937966) (xy 343.559638 -282.92552)
			(xy 343.544398 -282.906216) (xy 343.443306 -282.862528) (xy 343.418668 -282.864306) (xy 343.408 -282.871164)
			(xy 343.385007 -282.885157) (xy 343.335928 -282.907253) (xy 343.284235 -282.922248) (xy 343.23095 -282.929844)
			(xy 343.204038 -282.930346) (xy 343.18602 -282.93011) (xy 343.150146 -282.926673) (xy 343.13241 -282.923488)
			(xy 343.122758 -282.92171) (xy 343.103708 -282.925266) (xy 343.028778 -282.973272) (xy 343.017348 -282.98902)
			(xy 343.015062 -282.998418) (xy 343.007678 -283.025468) (xy 342.986064 -283.077204) (xy 342.957108 -283.125219)
			(xy 342.921434 -283.168477) (xy 342.879811 -283.206046) (xy 342.833137 -283.237116) (xy 342.782416 -283.261018)
			(xy 342.728743 -283.277237) (xy 342.673273 -283.285422) (xy 342.645238 -283.285946) (xy 342.617984 -283.285463)
			(xy 342.56403 -283.277711) (xy 342.511729 -283.262359) (xy 342.462144 -283.239721) (xy 342.416286 -283.210256)
			(xy 342.375088 -283.174565) (xy 342.339389 -283.133375) (xy 342.309915 -283.087523) (xy 342.287267 -283.037943)
			(xy 342.271905 -282.985644) (xy 342.264143 -282.931692) (xy 342.26373 -282.904438) (xy 342.264214 -282.876862)
			(xy 342.272151 -282.822285) (xy 342.287864 -282.76942) (xy 342.311026 -282.719369) (xy 342.341155 -282.673174)
			(xy 342.377622 -282.6318) (xy 342.39835 -282.613608) (xy 342.406436 -282.606065) (xy 342.415765 -282.586043)
			(xy 342.416384 -282.575) (xy 342.416384 -282.497276) (xy 342.415775 -282.486236) (xy 342.406419 -282.466228)
			(xy 342.39835 -282.458668) (xy 342.377645 -282.440452) (xy 342.341182 -282.39908) (xy 342.311054 -282.352889)
			(xy 342.28789 -282.302843) (xy 342.272172 -282.249983) (xy 342.264228 -282.195412) (xy 342.26373 -282.167838)
			(xy 342.264214 -282.140262) (xy 342.272151 -282.085685) (xy 342.287864 -282.03282) (xy 342.311026 -281.982769)
			(xy 342.341155 -281.936574) (xy 342.377622 -281.8952) (xy 342.39835 -281.877008) (xy 342.406436 -281.869465)
			(xy 342.415765 -281.849443) (xy 342.416384 -281.8384) (xy 342.416384 -281.760676) (xy 342.415775 -281.749636)
			(xy 342.406419 -281.729628) (xy 342.39835 -281.722068) (xy 342.377645 -281.703852) (xy 342.341182 -281.66248)
			(xy 342.311054 -281.616289) (xy 342.28789 -281.566243) (xy 342.272172 -281.513383) (xy 342.264228 -281.458812)
			(xy 342.26373 -281.431238) (xy 342.264191 -281.403984) (xy 342.271944 -281.350031) (xy 342.287297 -281.297731)
			(xy 342.309938 -281.248149) (xy 342.339405 -281.202293) (xy 342.375099 -281.161099) (xy 342.416293 -281.125405)
			(xy 342.462149 -281.095938) (xy 342.511731 -281.073297) (xy 342.564031 -281.057944) (xy 342.617984 -281.050191)
			(xy 342.645238 -281.04973) (xy 342.673098 -281.050232) (xy 342.728227 -281.058327) (xy 342.781593 -281.074355)
			(xy 342.83206 -281.097974) (xy 342.878555 -281.128682) (xy 342.920089 -281.165826) (xy 342.955779 -281.208616)
			(xy 342.984866 -281.256142) (xy 343.006731 -281.307393) (xy 343.0143 -281.33421) (xy 343.016586 -281.3431)
			(xy 343.027254 -281.35834) (xy 343.099136 -281.406092) (xy 343.11717 -281.410156) (xy 343.126314 -281.408886)
			(xy 343.139329 -281.407202) (xy 343.165515 -281.405422) (xy 343.178638 -281.40533) (xy 343.191761 -281.405436)
			(xy 343.217946 -281.407215) (xy 343.230962 -281.408886) (xy 343.240106 -281.410156) (xy 343.25814 -281.406092)
			(xy 343.330022 -281.35834) (xy 343.34069 -281.3431) (xy 343.342976 -281.33421) (xy 343.350569 -281.307405)
			(xy 343.372455 -281.256173) (xy 343.401553 -281.208665) (xy 343.437246 -281.16589) (xy 343.478776 -281.128756)
			(xy 343.525262 -281.09805) (xy 343.575715 -281.074426) (xy 343.629067 -281.058384) (xy 343.684183 -281.050265)
			(xy 343.712038 -281.04973) (xy 343.739286 -281.050219) (xy 343.793228 -281.05798) (xy 343.845516 -281.073339)
			(xy 343.895086 -281.095983) (xy 343.940929 -281.12545) (xy 343.982111 -281.161143) (xy 344.017795 -281.202332)
			(xy 344.047254 -281.248181) (xy 344.069888 -281.297755) (xy 344.085236 -281.350046) (xy 344.092987 -281.403989)
			(xy 344.093546 -281.431238) (xy 344.093078 -281.458536) (xy 344.085292 -281.512575) (xy 344.069885 -281.564954)
			(xy 344.047172 -281.614602) (xy 344.017616 -281.660506) (xy 344.000074 -281.681428) (xy 343.993724 -281.688794)
			(xy 343.987374 -281.706574) (xy 343.990676 -281.795728) (xy 343.99855 -281.813508) (xy 344.005408 -281.820112)
			(xy 344.026517 -281.84176) (xy 344.062308 -281.890489) (xy 344.089969 -281.944252) (xy 344.108806 -282.001704)
			(xy 344.118349 -282.061407) (xy 344.118946 -282.091638) (xy 344.118459 -282.119278) (xy 344.110484 -282.173979)
			(xy 344.094693 -282.226955) (xy 344.071416 -282.277095) (xy 344.041142 -282.323348) (xy 344.023188 -282.344368)
			(xy 344.014806 -282.353766) (xy 344.008964 -282.37815) (xy 344.033094 -282.47213) (xy 344.036764 -282.484095)
			(xy 344.053547 -282.502621) (xy 344.065098 -282.507436) (xy 344.092505 -282.517775) (xy 344.144022 -282.545652)
			(xy 344.190667 -282.581081) (xy 344.231344 -282.623229) (xy 344.265095 -282.671104) (xy 344.291125 -282.723578)
			(xy 344.308821 -282.779416) (xy 344.317768 -282.837304) (xy 344.318336 -282.866592) (xy 344.317787 -282.893855)
			(xy 344.647947 -282.893855) (xy 344.647947 -282.839345) (xy 344.655705 -282.785391) (xy 344.671063 -282.73309)
			(xy 344.693708 -282.683507) (xy 344.723179 -282.637651) (xy 344.758877 -282.596457) (xy 344.800074 -282.560763)
			(xy 344.845931 -282.531295) (xy 344.895516 -282.508653) (xy 344.947818 -282.493299) (xy 345.001773 -282.485545)
			(xy 345.029028 -282.485084) (xy 345.0564 -282.485513) (xy 345.110581 -282.493337) (xy 345.163086 -282.508833)
			(xy 345.212832 -282.531684) (xy 345.258796 -282.561418) (xy 345.279726 -282.579064) (xy 345.27998 -282.579318)
			(xy 345.287067 -282.584904) (xy 345.303983 -282.591151) (xy 345.313 -282.59151) (xy 345.380056 -282.59151)
			(xy 345.389071 -282.59113) (xy 345.405988 -282.584898) (xy 345.413076 -282.579318) (xy 345.413076 -282.579064)
			(xy 345.41333 -282.579064) (xy 345.434273 -282.561439) (xy 345.480243 -282.531726) (xy 345.529988 -282.508888)
			(xy 345.582486 -282.493394) (xy 345.63666 -282.485561) (xy 345.664028 -282.485084) (xy 345.691277 -282.485588)
			(xy 345.745221 -282.493347) (xy 345.797511 -282.508704) (xy 345.847084 -282.531347) (xy 345.89293 -282.560813)
			(xy 345.934116 -282.596504) (xy 345.969804 -282.637693) (xy 345.999267 -282.683541) (xy 346.021905 -282.733115)
			(xy 346.037259 -282.785406) (xy 346.045014 -282.839351) (xy 346.045014 -282.893849) (xy 346.037259 -282.947794)
			(xy 346.021905 -283.000085) (xy 345.999267 -283.049659) (xy 345.969804 -283.095507) (xy 345.934116 -283.136696)
			(xy 345.89293 -283.172387) (xy 345.847084 -283.201853) (xy 345.797511 -283.224496) (xy 345.745221 -283.239853)
			(xy 345.691277 -283.247612) (xy 345.664028 -283.2481) (xy 345.636658 -283.247618) (xy 345.58248 -283.239804)
			(xy 345.529977 -283.224318) (xy 345.48023 -283.20148) (xy 345.434262 -283.171759) (xy 345.41333 -283.15412)
			(xy 345.413076 -283.153866) (xy 345.406003 -283.148259) (xy 345.389076 -283.142026) (xy 345.380056 -283.141674)
			(xy 345.313 -283.141674) (xy 345.303984 -283.142037) (xy 345.287067 -283.148281) (xy 345.27998 -283.153866)
			(xy 345.27998 -283.15412) (xy 345.279726 -283.15412) (xy 345.258798 -283.171763) (xy 345.212823 -283.201474)
			(xy 345.163075 -283.224309) (xy 345.110574 -283.239799) (xy 345.056397 -283.247626) (xy 345.029028 -283.2481)
			(xy 345.001773 -283.247655) (xy 344.947818 -283.239901) (xy 344.895516 -283.224547) (xy 344.845931 -283.201905)
			(xy 344.800074 -283.172437) (xy 344.758877 -283.136743) (xy 344.723179 -283.095549) (xy 344.693708 -283.049693)
			(xy 344.671063 -283.00011) (xy 344.655705 -282.947809) (xy 344.647947 -282.893855) (xy 344.317787 -282.893855)
			(xy 344.317735 -282.896428) (xy 344.308418 -282.955371) (xy 344.299794 -282.98394) (xy 344.296492 -282.994354)
			(xy 344.298778 -283.015944) (xy 344.34907 -283.100526) (xy 344.366342 -283.112972) (xy 344.377264 -283.115004)
			(xy 344.403067 -283.120406) (xy 344.452982 -283.137369) (xy 344.500085 -283.161044) (xy 344.54348 -283.190978)
			(xy 344.582341 -283.226601) (xy 344.615927 -283.267236) (xy 344.643599 -283.312108) (xy 344.664829 -283.360362)
			(xy 344.679213 -283.41108) (xy 344.686478 -283.463295) (xy 344.68689 -283.489654) (xy 344.686324 -283.519779)
			(xy 344.676858 -283.579282) (xy 344.658155 -283.636556) (xy 344.630678 -283.690177) (xy 344.595113 -283.738811)
			(xy 344.574114 -283.760418) (xy 344.567269 -283.767817) (xy 344.559539 -283.786415) (xy 344.559128 -283.796486)
			(xy 344.559128 -283.868622) (xy 344.559556 -283.87869) (xy 344.567279 -283.897286) (xy 344.574114 -283.90469)
			(xy 344.595092 -283.926315) (xy 344.630649 -283.974949) (xy 344.658122 -284.028566) (xy 344.676828 -284.085835)
			(xy 344.686302 -284.145331) (xy 344.68689 -284.175454) (xy 344.68689 -284.175962) (xy 344.686471 -284.200828)
			(xy 344.679971 -284.250134) (xy 344.673936 -284.27426) (xy 344.672158 -284.28061) (xy 344.672158 -284.287468)
			(xy 344.67264 -284.297483) (xy 344.680292 -284.315993) (xy 344.694445 -284.330166) (xy 344.712944 -284.337845)
			(xy 344.722958 -284.338268) (xy 344.758264 -284.338268) (xy 344.768328 -284.337833) (xy 344.786913 -284.330098)
			(xy 344.794332 -284.323282) (xy 345.662504 -283.454856) (xy 345.684118 -283.434077) (xy 345.732623 -283.398839)
			(xy 345.786042 -283.371621) (xy 345.843061 -283.353092) (xy 345.902275 -283.343708) (xy 345.932252 -283.343096)
			(xy 348.26956 -283.343096) (xy 348.299541 -283.343651) (xy 348.358765 -283.35303) (xy 348.415791 -283.371563)
			(xy 348.469214 -283.398792) (xy 348.517716 -283.434048) (xy 348.539308 -283.454856) (xy 348.760542 -283.67609)
			(xy 348.767942 -283.682931) (xy 348.786541 -283.690652) (xy 348.79661 -283.691076) (xy 349.497142 -283.691076)
			(xy 349.509212 -283.690408) (xy 349.530695 -283.679399) (xy 349.53829 -283.669994) (xy 349.586296 -283.603446)
			(xy 349.592809 -283.593263) (xy 349.59651 -283.56941) (xy 349.593408 -283.557726) (xy 349.584402 -283.52864)
			(xy 349.574697 -283.468534) (xy 349.574104 -283.438092) (xy 349.574104 -283.437584) (xy 349.574576 -283.410219)
			(xy 349.582395 -283.35605) (xy 349.597871 -283.303554) (xy 349.620686 -283.253806) (xy 349.650372 -283.207827)
			(xy 349.686322 -283.166559) (xy 349.727797 -283.130849) (xy 349.750634 -283.115766) (xy 349.76054 -283.10967)
			(xy 349.772478 -283.090112) (xy 349.782638 -282.999688) (xy 349.783202 -282.988278) (xy 349.775536 -282.966792)
			(xy 349.767906 -282.958286) (xy 349.51035 -282.700984) (xy 349.489615 -282.679408) (xy 349.454455 -282.630991)
			(xy 349.427297 -282.577672) (xy 349.408809 -282.520762) (xy 349.399447 -282.461662) (xy 349.398844 -282.431744)
			(xy 349.398844 -282.362148) (xy 349.398452 -282.352913) (xy 349.391913 -282.33564) (xy 349.37967 -282.321812)
			(xy 349.371666 -282.31719) (xy 349.279718 -282.268676) (xy 349.25127 -282.270454) (xy 349.23984 -282.278328)
			(xy 349.215922 -282.294058) (xy 349.164367 -282.31894) (xy 349.109675 -282.335843) (xy 349.053071 -282.344386)
			(xy 349.024448 -282.344876) (xy 348.997195 -282.344416) (xy 348.943244 -282.336665) (xy 348.890944 -282.321315)
			(xy 348.841362 -282.298677) (xy 348.795507 -282.269213) (xy 348.754312 -282.233522) (xy 348.718616 -282.192331)
			(xy 348.689146 -282.14648) (xy 348.666502 -282.096901) (xy 348.651145 -282.044603) (xy 348.643387 -281.990653)
			(xy 348.643387 -281.936147) (xy 348.651145 -281.882197) (xy 348.666502 -281.829899) (xy 348.689146 -281.78032)
			(xy 348.718616 -281.734469) (xy 348.754312 -281.693278) (xy 348.795507 -281.657587) (xy 348.841362 -281.628123)
			(xy 348.890944 -281.605485) (xy 348.943244 -281.590135) (xy 348.997195 -281.582384) (xy 349.024448 -281.58186)
			(xy 349.053069 -281.582374) (xy 349.109668 -281.590923) (xy 349.164358 -281.607823) (xy 349.215913 -281.632695)
			(xy 349.23984 -281.648408) (xy 349.25127 -281.656282) (xy 349.279718 -281.65806) (xy 349.371666 -281.609546)
			(xy 349.379645 -281.604896) (xy 349.391868 -281.591072) (xy 349.398401 -281.573814) (xy 349.398844 -281.564588)
			(xy 349.398844 -281.01671) (xy 349.39933 -280.989477) (xy 349.407081 -280.935565) (xy 349.422426 -280.883305)
			(xy 349.445052 -280.833761) (xy 349.474499 -280.787941) (xy 349.510166 -280.746778) (xy 349.551329 -280.711111)
			(xy 349.597149 -280.681664) (xy 349.646693 -280.659038) (xy 349.698953 -280.643693) (xy 349.752865 -280.635942)
			(xy 349.807331 -280.635942) (xy 349.861243 -280.643693) (xy 349.913503 -280.659038) (xy 349.963047 -280.681664)
			(xy 350.008867 -280.711111) (xy 350.05003 -280.746778) (xy 350.085697 -280.787941) (xy 350.115144 -280.833761)
			(xy 350.13777 -280.883305) (xy 350.153115 -280.935565) (xy 350.160866 -280.989477) (xy 350.161352 -281.01671)
			(xy 350.161352 -282.252166) (xy 350.161789 -282.26223) (xy 350.169526 -282.280812) (xy 350.176338 -282.288234)
			(xy 350.642682 -282.754578) (xy 350.651628 -282.762581) (xy 350.674425 -282.769994) (xy 350.68637 -282.768802)
			(xy 350.76765 -282.756356) (xy 350.779399 -282.753934) (xy 350.7989 -282.740021) (xy 350.804988 -282.729686)
			(xy 350.804988 -282.729432) (xy 350.81671 -282.707558) (xy 350.844975 -282.666768) (xy 350.878295 -282.62999)
			(xy 350.896936 -282.613608) (xy 350.905024 -282.606066) (xy 350.914356 -282.586044) (xy 350.91497 -282.575)
			(xy 350.91497 -282.497276) (xy 350.91436 -282.486237) (xy 350.905003 -282.46623) (xy 350.896936 -282.458668)
			(xy 350.876231 -282.440451) (xy 350.83977 -282.399079) (xy 350.809643 -282.352888) (xy 350.78648 -282.302842)
			(xy 350.770763 -282.249983) (xy 350.762819 -282.195411) (xy 350.762316 -282.167838) (xy 350.7628 -282.140263)
			(xy 350.770738 -282.085688) (xy 350.786454 -282.032825) (xy 350.80962 -281.982777) (xy 350.839753 -281.936587)
			(xy 350.876225 -281.895219) (xy 350.896936 -281.877008) (xy 350.905024 -281.869466) (xy 350.914356 -281.849444)
			(xy 350.91497 -281.8384) (xy 350.91497 -281.760676) (xy 350.91436 -281.749637) (xy 350.905003 -281.72963)
			(xy 350.896936 -281.722068) (xy 350.876231 -281.703851) (xy 350.83977 -281.662479) (xy 350.809643 -281.616288)
			(xy 350.78648 -281.566242) (xy 350.770763 -281.513383) (xy 350.762819 -281.458811) (xy 350.762316 -281.431238)
			(xy 350.762777 -281.403984) (xy 350.770529 -281.35003) (xy 350.785882 -281.297729) (xy 350.808523 -281.248146)
			(xy 350.83799 -281.20229) (xy 350.873684 -281.161094) (xy 350.914878 -281.125399) (xy 350.960734 -281.09593)
			(xy 351.010316 -281.073287) (xy 351.062617 -281.057932) (xy 351.11657 -281.050178) (xy 351.143824 -281.04973)
			(xy 351.171685 -281.050231) (xy 351.226816 -281.058325) (xy 351.280183 -281.074351) (xy 351.330651 -281.097969)
			(xy 351.377148 -281.128677) (xy 351.418684 -281.16582) (xy 351.454375 -281.208611) (xy 351.483464 -281.256137)
			(xy 351.50533 -281.307389) (xy 351.512886 -281.33421) (xy 351.515172 -281.3431) (xy 351.52584 -281.35834)
			(xy 351.597722 -281.406092) (xy 351.615756 -281.410156) (xy 351.6249 -281.408886) (xy 351.637915 -281.407202)
			(xy 351.664101 -281.40542) (xy 351.677224 -281.40533) (xy 351.690347 -281.405436) (xy 351.716532 -281.407213)
			(xy 351.729548 -281.408886) (xy 351.738692 -281.410156) (xy 351.756726 -281.406092) (xy 351.828608 -281.35834)
			(xy 351.839276 -281.3431) (xy 351.841562 -281.33421) (xy 351.849155 -281.307404) (xy 351.871041 -281.256171)
			(xy 351.900139 -281.208662) (xy 351.935831 -281.165886) (xy 351.977361 -281.12875) (xy 352.023846 -281.098043)
			(xy 352.0743 -281.074417) (xy 352.127652 -281.058373) (xy 352.182768 -281.050253) (xy 352.210624 -281.04973)
			(xy 352.237875 -281.050195) (xy 352.291821 -281.057955) (xy 352.344114 -281.073313) (xy 352.393689 -281.095958)
			(xy 352.439536 -281.125427) (xy 352.480723 -281.161121) (xy 352.51641 -281.202314) (xy 352.545872 -281.248166)
			(xy 352.568508 -281.297744) (xy 352.583858 -281.35004) (xy 352.591609 -281.403987) (xy 352.592132 -281.431238)
			(xy 352.591664 -281.458536) (xy 352.583878 -281.512575) (xy 352.568471 -281.564953) (xy 352.545757 -281.614601)
			(xy 352.5162 -281.660505) (xy 352.49866 -281.681428) (xy 352.49231 -281.688794) (xy 352.48596 -281.706574)
			(xy 352.489262 -281.795728) (xy 352.497136 -281.813508) (xy 352.503994 -281.820112) (xy 352.525104 -281.84176)
			(xy 352.560896 -281.890488) (xy 352.588558 -281.944251) (xy 352.607396 -282.001703) (xy 352.61694 -282.061407)
			(xy 352.617532 -282.091638) (xy 352.617045 -282.119278) (xy 352.60907 -282.173979) (xy 352.593278 -282.226954)
			(xy 352.570001 -282.277094) (xy 352.539726 -282.323346) (xy 352.521774 -282.344368) (xy 352.513392 -282.353766)
			(xy 352.50755 -282.37815) (xy 352.53168 -282.47213) (xy 352.53535 -282.484096) (xy 352.55213 -282.502626)
			(xy 352.563684 -282.507436) (xy 352.591092 -282.517774) (xy 352.64261 -282.54565) (xy 352.689257 -282.581079)
			(xy 352.729936 -282.623227) (xy 352.763688 -282.671101) (xy 352.789719 -282.723576) (xy 352.807416 -282.779415)
			(xy 352.816363 -282.837304) (xy 352.816922 -282.866592) (xy 352.816373 -282.893854) (xy 353.146547 -282.893854)
			(xy 353.146547 -282.839346) (xy 353.154305 -282.785393) (xy 353.169662 -282.733093) (xy 353.192306 -282.683511)
			(xy 353.221776 -282.637656) (xy 353.257472 -282.596462) (xy 353.298667 -282.560767) (xy 353.344523 -282.531299)
			(xy 353.394106 -282.508657) (xy 353.446406 -282.493302) (xy 353.50036 -282.485546) (xy 353.527614 -282.485084)
			(xy 353.554986 -282.485521) (xy 353.609167 -282.493343) (xy 353.661671 -282.508838) (xy 353.711417 -282.531686)
			(xy 353.757382 -282.561419) (xy 353.778312 -282.579064) (xy 353.778566 -282.579318) (xy 353.785657 -282.584898)
			(xy 353.80257 -282.591148) (xy 353.811586 -282.59151) (xy 353.878642 -282.59151) (xy 353.887656 -282.591123)
			(xy 353.904573 -282.584896) (xy 353.911662 -282.579318) (xy 353.911662 -282.579064) (xy 353.911916 -282.579064)
			(xy 353.932864 -282.561445) (xy 353.978833 -282.531732) (xy 354.028577 -282.508892) (xy 354.081074 -282.493396)
			(xy 354.135246 -282.485562) (xy 354.162614 -282.485084) (xy 354.189864 -282.485587) (xy 354.243809 -282.493345)
			(xy 354.296101 -282.508701) (xy 354.345676 -282.531342) (xy 354.391523 -282.560808) (xy 354.432711 -282.596499)
			(xy 354.4684 -282.637688) (xy 354.497865 -282.683537) (xy 354.520504 -282.733112) (xy 354.535858 -282.785405)
			(xy 354.543614 -282.83935) (xy 354.543614 -282.89385) (xy 354.535858 -282.947795) (xy 354.520504 -283.000088)
			(xy 354.497865 -283.049663) (xy 354.4684 -283.095512) (xy 354.432711 -283.136701) (xy 354.391523 -283.172392)
			(xy 354.345676 -283.201858) (xy 354.296101 -283.224499) (xy 354.243809 -283.239855) (xy 354.189864 -283.247613)
			(xy 354.162614 -283.2481) (xy 354.135244 -283.247626) (xy 354.081065 -283.23981) (xy 354.028562 -283.224323)
			(xy 353.978815 -283.201483) (xy 353.932848 -283.17176) (xy 353.911916 -283.15412) (xy 353.911662 -283.153866)
			(xy 353.904565 -283.148295) (xy 353.887656 -283.14204) (xy 353.878642 -283.141674) (xy 353.811586 -283.141674)
			(xy 353.802569 -283.14203) (xy 353.785653 -283.148279) (xy 353.778566 -283.153866) (xy 353.778566 -283.15412)
			(xy 353.778312 -283.15412) (xy 353.757389 -283.17177) (xy 353.711413 -283.20148) (xy 353.661663 -283.224313)
			(xy 353.609161 -283.239802) (xy 353.554984 -283.247627) (xy 353.527614 -283.2481) (xy 353.50036 -283.247654)
			(xy 353.446406 -283.239898) (xy 353.394106 -283.224543) (xy 353.344523 -283.201901) (xy 353.298667 -283.172433)
			(xy 353.257472 -283.136738) (xy 353.221776 -283.095544) (xy 353.192306 -283.049689) (xy 353.169662 -283.000107)
			(xy 353.154305 -282.947807) (xy 353.146547 -282.893854) (xy 352.816373 -282.893854) (xy 352.816321 -282.896428)
			(xy 352.807004 -282.955371) (xy 352.79838 -282.98394) (xy 352.795078 -282.994354) (xy 352.797364 -283.015944)
			(xy 352.847656 -283.100526) (xy 352.864928 -283.112972) (xy 352.87585 -283.115004) (xy 352.901649 -283.12041)
			(xy 352.951554 -283.137382) (xy 352.998648 -283.161062) (xy 353.042033 -283.190999) (xy 353.080885 -283.226624)
			(xy 353.114462 -283.267257) (xy 353.142127 -283.312126) (xy 353.163351 -283.360376) (xy 353.177732 -283.411089)
			(xy 353.184994 -283.463298) (xy 353.185476 -283.489654) (xy 353.18491 -283.519779) (xy 353.175444 -283.579282)
			(xy 353.15674 -283.636555) (xy 353.129263 -283.690175) (xy 353.093697 -283.738808) (xy 353.0727 -283.760418)
			(xy 353.065857 -283.767818) (xy 353.058129 -283.786416) (xy 353.057714 -283.796486) (xy 353.057714 -283.868622)
			(xy 353.058142 -283.87869) (xy 353.065863 -283.897287) (xy 353.0727 -283.90469) (xy 353.093675 -283.926317)
			(xy 353.129224 -283.974953) (xy 353.15669 -284.028571) (xy 353.175392 -284.085838) (xy 353.184864 -284.145332)
			(xy 353.185476 -284.175454) (xy 353.18499 -284.202705) (xy 353.177234 -284.256653) (xy 353.161879 -284.308948)
			(xy 353.139237 -284.358525) (xy 353.109771 -284.404375) (xy 353.07408 -284.445566) (xy 353.032889 -284.481257)
			(xy 352.987039 -284.510723) (xy 352.937462 -284.533365) (xy 352.885167 -284.54872) (xy 352.831219 -284.556476)
			(xy 352.776717 -284.556476) (xy 352.722769 -284.54872) (xy 352.670474 -284.533365) (xy 352.620897 -284.510723)
			(xy 352.575047 -284.481257) (xy 352.533856 -284.445566) (xy 352.498165 -284.404375) (xy 352.468699 -284.358525)
			(xy 352.446057 -284.308948) (xy 352.430702 -284.256653) (xy 352.422946 -284.202705) (xy 352.42246 -284.175454)
			(xy 352.423025 -284.145329) (xy 352.432491 -284.085827) (xy 352.451196 -284.028553) (xy 352.478674 -283.974934)
			(xy 352.514242 -283.926302) (xy 352.535236 -283.90469) (xy 352.542088 -283.897294) (xy 352.549828 -283.878695)
			(xy 352.550222 -283.868622) (xy 352.550222 -283.796486) (xy 352.549797 -283.786416) (xy 352.542081 -283.767814)
			(xy 352.535236 -283.760418) (xy 352.51426 -283.738792) (xy 352.478706 -283.690157) (xy 352.451236 -283.636539)
			(xy 352.432531 -283.579272) (xy 352.423057 -283.519776) (xy 352.42246 -283.489654) (xy 352.423057 -283.459817)
			(xy 352.432368 -283.400873) (xy 352.441002 -283.372306) (xy 352.444304 -283.361892) (xy 352.442018 -283.340302)
			(xy 352.391726 -283.25572) (xy 352.374454 -283.243274) (xy 352.363532 -283.241242) (xy 352.335683 -283.235367)
			(xy 352.282001 -283.216464) (xy 352.231726 -283.18979) (xy 352.185974 -283.15594) (xy 352.145762 -283.115664)
			(xy 352.111985 -283.069858) (xy 352.085392 -283.01954) (xy 352.066574 -282.965828) (xy 352.060764 -282.937966)
			(xy 352.058224 -282.92552) (xy 352.042984 -282.906216) (xy 351.941892 -282.862528) (xy 351.917254 -282.864306)
			(xy 351.906586 -282.871164) (xy 351.883593 -282.885156) (xy 351.834514 -282.907251) (xy 351.78282 -282.922243)
			(xy 351.729535 -282.929837) (xy 351.702624 -282.930346) (xy 351.684606 -282.93011) (xy 351.648733 -282.926671)
			(xy 351.630996 -282.923488) (xy 351.621344 -282.92171) (xy 351.602294 -282.925266) (xy 351.527364 -282.973272)
			(xy 351.515934 -282.98902) (xy 351.513648 -282.998418) (xy 351.506264 -283.025467) (xy 351.484649 -283.077203)
			(xy 351.455693 -283.125217) (xy 351.420019 -283.168473) (xy 351.378396 -283.206041) (xy 351.331721 -283.237109)
			(xy 351.281001 -283.261009) (xy 351.227328 -283.277226) (xy 351.171859 -283.28541) (xy 351.143824 -283.285946)
			(xy 351.129735 -283.285784) (xy 351.101638 -283.283625) (xy 351.08769 -283.281628) (xy 351.087182 -283.281628)
			(xy 351.076328 -283.280553) (xy 351.055395 -283.286604) (xy 351.046796 -283.293312) (xy 350.988376 -283.343604)
			(xy 350.980356 -283.351178) (xy 350.971142 -283.371194) (xy 350.970596 -283.382212) (xy 350.970596 -284.47111)
			(xy 350.969989 -284.501026) (xy 350.960602 -284.560119) (xy 350.942108 -284.617023) (xy 350.914958 -284.670343)
			(xy 350.87982 -284.718772) (xy 350.85909 -284.74035) (xy 349.273622 -286.325564) (xy 349.266783 -286.332965)
			(xy 349.259069 -286.351563) (xy 349.258636 -286.361632) (xy 349.258636 -294.532304) (xy 349.259105 -294.542578)
			(xy 349.267151 -294.561486) (xy 349.281957 -294.575735) (xy 349.291402 -294.579802) (xy 349.395542 -294.619172)
			(xy 349.426022 -294.611552) (xy 349.436436 -294.599614) (xy 349.45463 -294.579676) (xy 349.495669 -294.544617)
			(xy 349.54124 -294.515693) (xy 349.590434 -294.493482) (xy 349.642268 -294.478429) (xy 349.695706 -294.470833)
			(xy 349.722694 -294.470328) (xy 349.749945 -294.470791) (xy 349.803891 -294.478546) (xy 349.856185 -294.4939)
			(xy 349.905761 -294.51654) (xy 349.95161 -294.546006) (xy 349.9928 -294.581696) (xy 350.028491 -294.622885)
			(xy 350.057957 -294.668734) (xy 350.080597 -294.71831) (xy 350.095952 -294.770603) (xy 350.103709 -294.824549)
			(xy 350.103709 -294.851836) (xy 350.906078 -294.851836) (xy 350.910149 -294.796214) (xy 350.922275 -294.741777)
			(xy 350.942198 -294.689686) (xy 350.969494 -294.641051) (xy 351.00358 -294.596908) (xy 351.043729 -294.558199)
			(xy 351.089087 -294.525748) (xy 351.138687 -294.500247) (xy 351.191471 -294.48224) (xy 351.246314 -294.47211)
			(xy 351.302048 -294.470073) (xy 351.357485 -294.476173) (xy 351.411442 -294.490279) (xy 351.462771 -294.512091)
			(xy 351.510377 -294.541145) (xy 351.553245 -294.57682) (xy 351.590462 -294.618357) (xy 351.621235 -294.66487)
			(xy 351.644907 -294.715367) (xy 351.660975 -294.768774) (xy 351.669095 -294.82395) (xy 351.669604 -294.851836)
			(xy 351.669095 -294.879722) (xy 351.660975 -294.934898) (xy 351.644907 -294.988305) (xy 351.621235 -295.038802)
			(xy 351.590462 -295.085315) (xy 351.553245 -295.126852) (xy 351.510377 -295.162527) (xy 351.462771 -295.191581)
			(xy 351.411442 -295.213393) (xy 351.357485 -295.227499) (xy 351.302048 -295.233599) (xy 351.246314 -295.231562)
			(xy 351.191471 -295.221432) (xy 351.138687 -295.203425) (xy 351.089087 -295.177924) (xy 351.043729 -295.145473)
			(xy 351.00358 -295.106764) (xy 350.969494 -295.062621) (xy 350.942198 -295.013986) (xy 350.922275 -294.961895)
			(xy 350.910149 -294.907458) (xy 350.906078 -294.851836) (xy 350.103709 -294.851836) (xy 350.103709 -294.879051)
			(xy 350.095952 -294.932997) (xy 350.080597 -294.98529) (xy 350.057957 -295.034866) (xy 350.028491 -295.080715)
			(xy 349.9928 -295.121904) (xy 349.95161 -295.157594) (xy 349.905761 -295.18706) (xy 349.856185 -295.2097)
			(xy 349.803891 -295.225054) (xy 349.749945 -295.232809) (xy 349.722694 -295.233344) (xy 349.695374 -295.232875)
			(xy 349.641293 -295.225078) (xy 349.588878 -295.209644) (xy 349.539201 -295.186888) (xy 349.49328 -295.157277)
			(xy 349.452054 -295.121417) (xy 349.416366 -295.080041) (xy 349.386948 -295.033997) (xy 349.375222 -295.009316)
			(xy 349.37115 -295.001177) (xy 349.358356 -294.988251) (xy 349.341846 -294.980622) (xy 349.332804 -294.979598)
			(xy 349.229934 -294.971724) (xy 349.205042 -294.98417) (xy 349.197422 -294.995854) (xy 349.186319 -295.012545)
			(xy 349.161122 -295.043728) (xy 349.14713 -295.058084) (xy 348.68993 -295.515284) (xy 348.679008 -295.525698)
			(xy 348.679008 -295.579038) (xy 348.679517 -295.588845) (xy 348.686975 -295.606991) (xy 348.693486 -295.614344)
			(xy 348.713659 -295.635844) (xy 348.747804 -295.683902) (xy 348.774149 -295.736642) (xy 348.792066 -295.792807)
			(xy 348.80113 -295.851059) (xy 348.80169 -295.880536) (xy 348.801216 -295.907905) (xy 348.793387 -295.962081)
			(xy 348.777896 -296.014581) (xy 348.75506 -296.064328) (xy 348.725348 -296.110301) (xy 348.70771 -296.131234)
			(xy 348.70771 -296.131488) (xy 348.707456 -296.131488) (xy 348.701873 -296.138576) (xy 348.695633 -296.155493)
			(xy 348.695264 -296.164508) (xy 348.695264 -296.231564) (xy 348.695617 -296.240583) (xy 348.701851 -296.25751)
			(xy 348.707456 -296.264584) (xy 348.70771 -296.264838) (xy 348.725347 -296.285771) (xy 348.755063 -296.331739)
			(xy 348.777902 -296.381484) (xy 348.793392 -296.433984) (xy 348.801215 -296.488159) (xy 348.801211 -296.542896)
			(xy 348.79338 -296.597069) (xy 348.777883 -296.649567) (xy 348.755037 -296.699308) (xy 348.725314 -296.745272)
			(xy 348.70771 -296.766234) (xy 348.70771 -296.766488) (xy 348.707456 -296.766488) (xy 348.701873 -296.773576)
			(xy 348.695633 -296.790493) (xy 348.695264 -296.799508) (xy 348.695264 -296.866564) (xy 348.695617 -296.875583)
			(xy 348.701851 -296.89251) (xy 348.707456 -296.899584) (xy 348.70771 -296.899838) (xy 348.725347 -296.920771)
			(xy 348.755063 -296.966739) (xy 348.777902 -297.016484) (xy 348.793392 -297.068984) (xy 348.801215 -297.123159)
			(xy 348.801211 -297.177896) (xy 348.79338 -297.232069) (xy 348.777883 -297.284567) (xy 348.755037 -297.334308)
			(xy 348.725314 -297.380272) (xy 348.70771 -297.401234) (xy 348.70771 -297.401488) (xy 348.707456 -297.401488)
			(xy 348.701873 -297.408576) (xy 348.695633 -297.425493) (xy 348.695264 -297.434508) (xy 348.695264 -297.501564)
			(xy 348.695617 -297.510583) (xy 348.701851 -297.52751) (xy 348.707456 -297.534584) (xy 348.70771 -297.534838)
			(xy 348.725347 -297.555771) (xy 348.755063 -297.601739) (xy 348.777902 -297.651484) (xy 348.793392 -297.703984)
			(xy 348.801215 -297.758159) (xy 348.801211 -297.812896) (xy 348.79338 -297.867069) (xy 348.777883 -297.919567)
			(xy 348.755037 -297.969308) (xy 348.725314 -298.015272) (xy 348.70771 -298.036234) (xy 348.70771 -298.036488)
			(xy 348.707456 -298.036488) (xy 348.701873 -298.043576) (xy 348.695633 -298.060493) (xy 348.695264 -298.069508)
			(xy 348.695264 -298.136564) (xy 348.695617 -298.145583) (xy 348.701851 -298.16251) (xy 348.707456 -298.169584)
			(xy 348.70771 -298.169838) (xy 348.725349 -298.19077) (xy 348.75507 -298.236738) (xy 348.777908 -298.286485)
			(xy 348.793392 -298.338988) (xy 348.801205 -298.393166) (xy 348.80169 -298.420536) (xy 352.35388 -298.420536)
			(xy 352.354348 -298.393166) (xy 352.362162 -298.338986) (xy 352.37765 -298.286482) (xy 352.400492 -298.236735)
			(xy 352.430218 -298.190769) (xy 352.44786 -298.169838) (xy 352.448114 -298.169584) (xy 352.453715 -298.162507)
			(xy 352.459953 -298.145583) (xy 352.460306 -298.136564) (xy 352.460306 -298.069508) (xy 352.459944 -298.060492)
			(xy 352.4537 -298.043575) (xy 352.448114 -298.036488) (xy 352.44786 -298.036488) (xy 352.44786 -298.036234)
			(xy 352.430253 -298.015273) (xy 352.400524 -297.969311) (xy 352.377675 -297.91957) (xy 352.362174 -297.867072)
			(xy 352.354342 -297.812896) (xy 352.354338 -297.758158) (xy 352.362163 -297.703981) (xy 352.377656 -297.651481)
			(xy 352.400498 -297.601736) (xy 352.43022 -297.55577) (xy 352.44786 -297.534838) (xy 352.448114 -297.534584)
			(xy 352.453715 -297.527507) (xy 352.459953 -297.510583) (xy 352.460306 -297.501564) (xy 352.460306 -297.434508)
			(xy 352.459944 -297.425492) (xy 352.4537 -297.408575) (xy 352.448114 -297.401488) (xy 352.44786 -297.401488)
			(xy 352.44786 -297.401234) (xy 352.430253 -297.380273) (xy 352.400524 -297.334311) (xy 352.377675 -297.28457)
			(xy 352.362174 -297.232072) (xy 352.354342 -297.177896) (xy 352.354338 -297.123158) (xy 352.362163 -297.068981)
			(xy 352.377656 -297.016481) (xy 352.400498 -296.966736) (xy 352.43022 -296.92077) (xy 352.44786 -296.899838)
			(xy 352.448114 -296.899584) (xy 352.453715 -296.892507) (xy 352.459953 -296.875583) (xy 352.460306 -296.866564)
			(xy 352.460306 -296.799508) (xy 352.459944 -296.790492) (xy 352.4537 -296.773575) (xy 352.448114 -296.766488)
			(xy 352.44786 -296.766488) (xy 352.44786 -296.766234) (xy 352.430253 -296.745273) (xy 352.400524 -296.699311)
			(xy 352.377675 -296.64957) (xy 352.362174 -296.597072) (xy 352.354342 -296.542896) (xy 352.354338 -296.488158)
			(xy 352.362163 -296.433981) (xy 352.377656 -296.381481) (xy 352.400498 -296.331736) (xy 352.43022 -296.28577)
			(xy 352.44786 -296.264838) (xy 352.448114 -296.264584) (xy 352.453715 -296.257507) (xy 352.459953 -296.240583)
			(xy 352.460306 -296.231564) (xy 352.460306 -296.164508) (xy 352.459944 -296.155492) (xy 352.4537 -296.138575)
			(xy 352.448114 -296.131488) (xy 352.44786 -296.131488) (xy 352.44786 -296.131234) (xy 352.430253 -296.110273)
			(xy 352.400524 -296.064311) (xy 352.377675 -296.01457) (xy 352.362174 -295.962072) (xy 352.354342 -295.907896)
			(xy 352.354338 -295.853158) (xy 352.362163 -295.798981) (xy 352.377656 -295.746481) (xy 352.400498 -295.696736)
			(xy 352.43022 -295.65077) (xy 352.44786 -295.629838) (xy 352.448114 -295.629584) (xy 352.453715 -295.622507)
			(xy 352.459953 -295.605583) (xy 352.460306 -295.596564) (xy 352.460306 -295.529508) (xy 352.459944 -295.520492)
			(xy 352.4537 -295.503575) (xy 352.448114 -295.496488) (xy 352.44786 -295.496488) (xy 352.44786 -295.496234)
			(xy 352.430217 -295.475305) (xy 352.400507 -295.429331) (xy 352.377672 -295.379583) (xy 352.362182 -295.327081)
			(xy 352.354354 -295.272905) (xy 352.35388 -295.245536) (xy 352.354389 -295.218285) (xy 352.362141 -295.164336)
			(xy 352.377491 -295.11204) (xy 352.400129 -295.06246) (xy 352.429592 -295.016608) (xy 352.465281 -294.975415)
			(xy 352.506469 -294.939721) (xy 352.552318 -294.910252) (xy 352.601895 -294.887608) (xy 352.654189 -294.872251)
			(xy 352.708137 -294.864492) (xy 352.735388 -294.864028) (xy 352.762758 -294.864494) (xy 352.816938 -294.872311)
			(xy 352.869441 -294.8878) (xy 352.919188 -294.910642) (xy 352.965155 -294.940366) (xy 352.986086 -294.958008)
			(xy 352.98634 -294.958262) (xy 352.993434 -294.963837) (xy 353.010345 -294.970089) (xy 353.01936 -294.970454)
			(xy 353.086416 -294.970454) (xy 353.095435 -294.970115) (xy 353.112352 -294.963856) (xy 353.119436 -294.958262)
			(xy 353.119436 -294.958008) (xy 353.11969 -294.958008) (xy 353.140616 -294.940361) (xy 353.18659 -294.91065)
			(xy 353.236339 -294.887816) (xy 353.288841 -294.872327) (xy 353.343018 -294.864501) (xy 353.370388 -294.864028)
			(xy 353.397642 -294.864467) (xy 353.451596 -294.872223) (xy 353.503896 -294.887579) (xy 353.553479 -294.910223)
			(xy 353.599334 -294.939693) (xy 353.640528 -294.975389) (xy 353.676221 -295.016585) (xy 353.705689 -295.062442)
			(xy 353.728329 -295.112026) (xy 353.743682 -295.164328) (xy 353.751435 -295.218282) (xy 353.751896 -295.245536)
			(xy 353.751452 -295.272907) (xy 353.743629 -295.327087) (xy 353.728135 -295.379591) (xy 353.705288 -295.429337)
			(xy 353.675559 -295.475303) (xy 353.657916 -295.496234) (xy 353.657662 -295.496488) (xy 353.65207 -295.503571)
			(xy 353.645828 -295.520491) (xy 353.64547 -295.529508) (xy 353.64547 -295.596564) (xy 353.645851 -295.605578)
			(xy 353.652083 -295.622495) (xy 353.657662 -295.629584) (xy 353.657916 -295.629584) (xy 353.657916 -295.629838)
			(xy 353.67559 -295.650743) (xy 353.70531 -295.696717) (xy 353.728151 -295.746468) (xy 353.743643 -295.798974)
			(xy 353.751467 -295.853155) (xy 353.751463 -295.907899) (xy 353.743631 -295.962079) (xy 353.728132 -296.014583)
			(xy 353.705284 -296.064331) (xy 353.675557 -296.1103) (xy 353.657916 -296.131234) (xy 353.657662 -296.131488)
			(xy 353.65207 -296.138571) (xy 353.645828 -296.155491) (xy 353.64547 -296.164508) (xy 353.64547 -296.231564)
			(xy 353.645851 -296.240578) (xy 353.652083 -296.257495) (xy 353.657662 -296.264584) (xy 353.657916 -296.264584)
			(xy 353.657916 -296.264838) (xy 353.67559 -296.285743) (xy 353.70531 -296.331717) (xy 353.728151 -296.381468)
			(xy 353.743643 -296.433974) (xy 353.751467 -296.488155) (xy 353.751463 -296.542899) (xy 353.743631 -296.597079)
			(xy 353.728132 -296.649583) (xy 353.705284 -296.699331) (xy 353.675557 -296.7453) (xy 353.657916 -296.766234)
			(xy 353.657662 -296.766488) (xy 353.65207 -296.773571) (xy 353.645828 -296.790491) (xy 353.64547 -296.799508)
			(xy 353.64547 -296.866564) (xy 353.645851 -296.875578) (xy 353.652083 -296.892495) (xy 353.657662 -296.899584)
			(xy 353.657916 -296.899584) (xy 353.657916 -296.899838) (xy 353.67559 -296.920743) (xy 353.70531 -296.966717)
			(xy 353.728151 -297.016468) (xy 353.743643 -297.068974) (xy 353.751467 -297.123155) (xy 353.751463 -297.177899)
			(xy 353.743631 -297.232079) (xy 353.728132 -297.284583) (xy 353.705284 -297.334331) (xy 353.675557 -297.3803)
			(xy 353.657916 -297.401234) (xy 353.657662 -297.401488) (xy 353.65207 -297.408571) (xy 353.645828 -297.425491)
			(xy 353.64547 -297.434508) (xy 353.64547 -297.501564) (xy 353.645851 -297.510578) (xy 353.652083 -297.527495)
			(xy 353.657662 -297.534584) (xy 353.657916 -297.534584) (xy 353.657916 -297.534838) (xy 353.67559 -297.555743)
			(xy 353.70531 -297.601717) (xy 353.728151 -297.651468) (xy 353.743643 -297.703974) (xy 353.751467 -297.758155)
			(xy 353.751463 -297.812899) (xy 353.743631 -297.867079) (xy 353.728132 -297.919583) (xy 353.705284 -297.969331)
			(xy 353.675557 -298.0153) (xy 353.657916 -298.036234) (xy 353.657662 -298.036488) (xy 353.65207 -298.043571)
			(xy 353.645828 -298.060491) (xy 353.64547 -298.069508) (xy 353.64547 -298.136564) (xy 353.645851 -298.145578)
			(xy 353.652083 -298.162495) (xy 353.657662 -298.169584) (xy 353.657916 -298.169584) (xy 353.657916 -298.169838)
			(xy 353.675542 -298.190781) (xy 353.705255 -298.236751) (xy 353.728093 -298.286496) (xy 353.743588 -298.338994)
			(xy 353.75142 -298.393168) (xy 353.751896 -298.420536) (xy 353.751456 -298.447789) (xy 353.743694 -298.501739)
			(xy 353.728334 -298.554035) (xy 353.705687 -298.603613) (xy 353.676216 -298.649464) (xy 353.64052 -298.690654)
			(xy 353.599325 -298.726345) (xy 353.553471 -298.75581) (xy 353.50389 -298.77845) (xy 353.451592 -298.793804)
			(xy 353.397641 -298.801559) (xy 353.370388 -298.802044) (xy 353.343017 -298.801599) (xy 353.288836 -298.793778)
			(xy 353.236332 -298.778285) (xy 353.186586 -298.755438) (xy 353.14062 -298.725708) (xy 353.11969 -298.708064)
			(xy 353.119436 -298.70781) (xy 353.112342 -298.702233) (xy 353.095431 -298.69598) (xy 353.086416 -298.695618)
			(xy 353.01936 -298.695618) (xy 353.010341 -298.695952) (xy 352.993424 -298.702215) (xy 352.98634 -298.70781)
			(xy 352.98634 -298.708064) (xy 352.986086 -298.708064) (xy 352.965128 -298.725671) (xy 352.919163 -298.755389)
			(xy 352.869422 -298.778231) (xy 352.816927 -298.79373) (xy 352.762755 -298.801566) (xy 352.735388 -298.802044)
			(xy 352.708138 -298.801533) (xy 352.654193 -298.793776) (xy 352.601901 -298.778421) (xy 352.552326 -298.755782)
			(xy 352.506478 -298.726317) (xy 352.465288 -298.690629) (xy 352.429597 -298.649442) (xy 352.40013 -298.603595)
			(xy 352.377487 -298.554021) (xy 352.362129 -298.50173) (xy 352.354368 -298.447786) (xy 352.35388 -298.420536)
			(xy 348.80169 -298.420536) (xy 348.801201 -298.447785) (xy 348.79344 -298.501728) (xy 348.778082 -298.554017)
			(xy 348.755439 -298.603589) (xy 348.725971 -298.649433) (xy 348.690279 -298.690618) (xy 348.64909 -298.726304)
			(xy 348.603241 -298.755765) (xy 348.553667 -298.778401) (xy 348.501375 -298.793752) (xy 348.447431 -298.801505)
			(xy 348.420182 -298.802044) (xy 348.392813 -298.801571) (xy 348.338637 -298.793744) (xy 348.286136 -298.778253)
			(xy 348.236388 -298.755416) (xy 348.190416 -298.725703) (xy 348.169484 -298.708064) (xy 348.16923 -298.708064)
			(xy 348.16923 -298.70781) (xy 348.162145 -298.702219) (xy 348.145228 -298.695966) (xy 348.13621 -298.695618)
			(xy 348.069154 -298.695618) (xy 348.060141 -298.695985) (xy 348.043236 -298.702246) (xy 348.036134 -298.70781)
			(xy 348.03588 -298.708064) (xy 348.014949 -298.725706) (xy 347.968983 -298.755433) (xy 347.919236 -298.778276)
			(xy 347.866732 -298.793765) (xy 347.812552 -298.801581) (xy 347.785182 -298.802044) (xy 347.757931 -298.801557)
			(xy 347.703983 -298.793799) (xy 347.651688 -298.778442) (xy 347.602111 -298.755801) (xy 347.55626 -298.726334)
			(xy 347.515069 -298.690643) (xy 347.479376 -298.649454) (xy 347.449908 -298.603605) (xy 347.427264 -298.554029)
			(xy 347.411905 -298.501735) (xy 347.404144 -298.447787) (xy 347.403674 -298.420536) (xy 347.40415 -298.393168)
			(xy 347.411984 -298.338995) (xy 347.42748 -298.286499) (xy 347.450322 -298.236756) (xy 347.480039 -298.19079)
			(xy 347.497654 -298.169838) (xy 347.497654 -298.169584) (xy 347.497908 -298.169584) (xy 347.50349 -298.162496)
			(xy 347.509726 -298.145579) (xy 347.5101 -298.136564) (xy 347.5101 -298.069508) (xy 347.509742 -298.060491)
			(xy 347.503497 -298.043573) (xy 347.497908 -298.036488) (xy 347.497654 -298.036234) (xy 347.48001 -298.015302)
			(xy 347.450278 -297.969334) (xy 347.427426 -297.919586) (xy 347.411924 -297.867082) (xy 347.40409 -297.8129)
			(xy 347.404086 -297.758154) (xy 347.411912 -297.703971) (xy 347.427407 -297.651465) (xy 347.450252 -297.601714)
			(xy 347.479977 -297.555742) (xy 347.497654 -297.534838) (xy 347.497654 -297.534584) (xy 347.497908 -297.534584)
			(xy 347.50349 -297.527496) (xy 347.509726 -297.510579) (xy 347.5101 -297.501564) (xy 347.5101 -297.434508)
			(xy 347.509742 -297.425491) (xy 347.503497 -297.408573) (xy 347.497908 -297.401488) (xy 347.497654 -297.401234)
			(xy 347.48001 -297.380302) (xy 347.450278 -297.334334) (xy 347.427426 -297.284586) (xy 347.411924 -297.232082)
			(xy 347.40409 -297.1779) (xy 347.404086 -297.123154) (xy 347.411912 -297.068971) (xy 347.427407 -297.016465)
			(xy 347.450252 -296.966714) (xy 347.479977 -296.920742) (xy 347.497654 -296.899838) (xy 347.497654 -296.899584)
			(xy 347.497908 -296.899584) (xy 347.50349 -296.892496) (xy 347.509726 -296.875579) (xy 347.5101 -296.866564)
			(xy 347.5101 -296.799508) (xy 347.509742 -296.790491) (xy 347.503497 -296.773573) (xy 347.497908 -296.766488)
			(xy 347.497654 -296.766234) (xy 347.48001 -296.745302) (xy 347.450278 -296.699334) (xy 347.427426 -296.649586)
			(xy 347.411924 -296.597082) (xy 347.40409 -296.5429) (xy 347.404086 -296.488154) (xy 347.411912 -296.433971)
			(xy 347.427407 -296.381465) (xy 347.450252 -296.331714) (xy 347.479977 -296.285742) (xy 347.497654 -296.264838)
			(xy 347.497654 -296.264584) (xy 347.497908 -296.264584) (xy 347.50349 -296.257496) (xy 347.509726 -296.240579)
			(xy 347.5101 -296.231564) (xy 347.5101 -296.164508) (xy 347.509742 -296.155491) (xy 347.503497 -296.138573)
			(xy 347.497908 -296.131488) (xy 347.497654 -296.131234) (xy 347.48001 -296.110302) (xy 347.450278 -296.064334)
			(xy 347.427426 -296.014586) (xy 347.411924 -295.962082) (xy 347.40409 -295.9079) (xy 347.404086 -295.853154)
			(xy 347.411912 -295.798971) (xy 347.427407 -295.746465) (xy 347.450252 -295.696714) (xy 347.479977 -295.650742)
			(xy 347.497654 -295.629838) (xy 347.497654 -295.629584) (xy 347.497908 -295.629584) (xy 347.50349 -295.622496)
			(xy 347.509726 -295.605579) (xy 347.5101 -295.596564) (xy 347.5101 -295.529508) (xy 347.509742 -295.520491)
			(xy 347.503497 -295.503573) (xy 347.497908 -295.496488) (xy 347.497654 -295.496234) (xy 347.480008 -295.475304)
			(xy 347.450274 -295.42934) (xy 347.427423 -295.379594) (xy 347.411925 -295.327089) (xy 347.404101 -295.272908)
			(xy 347.403674 -295.245536) (xy 347.404134 -295.218281) (xy 347.411887 -295.164325) (xy 347.42724 -295.112022)
			(xy 347.44988 -295.062436) (xy 347.479347 -295.016577) (xy 347.51504 -294.975379) (xy 347.556234 -294.939679)
			(xy 347.602089 -294.910206) (xy 347.651671 -294.887559) (xy 347.703972 -294.872199) (xy 347.757927 -294.864438)
			(xy 347.785182 -294.864028) (xy 347.81466 -294.864575) (xy 347.872915 -294.87364) (xy 347.929082 -294.891558)
			(xy 347.981825 -294.917901) (xy 348.029888 -294.952043) (xy 348.051374 -294.972232) (xy 348.058702 -294.978778)
			(xy 348.076866 -294.986222) (xy 348.08668 -294.98671) (xy 348.14002 -294.98671) (xy 348.150434 -294.975788)
			(xy 348.481142 -294.645334) (xy 348.487984 -294.637935) (xy 348.495704 -294.619336) (xy 348.496128 -294.609266)
			(xy 348.496128 -286.182054) (xy 348.496738 -286.152139) (xy 348.50613 -286.093049) (xy 348.524629 -286.03615)
			(xy 348.551783 -285.982835) (xy 348.586926 -285.934412) (xy 348.607634 -285.912814) (xy 349.979742 -284.540706)
			(xy 349.986561 -284.53334) (xy 349.99429 -284.514832) (xy 349.994331 -284.494775) (xy 349.990918 -284.485334)
			(xy 349.985076 -284.47111) (xy 349.959676 -284.454092) (xy 348.61754 -284.454092) (xy 348.587559 -284.453537)
			(xy 348.528335 -284.444158) (xy 348.47131 -284.425624) (xy 348.417887 -284.398394) (xy 348.369386 -284.363138)
			(xy 348.347792 -284.342332) (xy 348.126558 -284.121098) (xy 348.119157 -284.114258) (xy 348.100559 -284.10654)
			(xy 348.09049 -284.106112) (xy 346.111322 -284.106112) (xy 346.101258 -284.10655) (xy 346.082676 -284.114285)
			(xy 346.075254 -284.121098) (xy 345.207082 -284.98927) (xy 345.185505 -285.010004) (xy 345.137088 -285.045162)
			(xy 345.083769 -285.072318) (xy 345.02686 -285.090805) (xy 344.96776 -285.100166) (xy 344.937842 -285.100776)
			(xy 342.699594 -285.100776) (xy 342.689548 -285.101201) (xy 342.670992 -285.108907) (xy 342.656809 -285.123139)
			(xy 342.652604 -285.132272) (xy 342.646508 -285.146496) (xy 342.652604 -285.176468) (xy 343.08669 -285.610554)
			(xy 343.107426 -285.63213) (xy 343.142591 -285.680546) (xy 343.169755 -285.733865) (xy 343.18825 -285.790774)
			(xy 343.197621 -285.849875) (xy 343.198196 -285.879794) (xy 343.198196 -286.761682) (xy 343.197591 -286.791599)
			(xy 343.188208 -286.850694) (xy 343.169717 -286.907601) (xy 343.14257 -286.960924) (xy 343.107433 -287.009356)
			(xy 343.08669 -287.030922) (xy 342.509094 -287.608264) (xy 342.502258 -287.615666) (xy 342.494548 -287.634264)
			(xy 342.494108 -287.644332) (xy 342.494108 -291.441378) (xy 342.493503 -291.471295) (xy 342.484121 -291.530391)
			(xy 342.465631 -291.587298) (xy 342.438485 -291.640622) (xy 342.403349 -291.689056) (xy 342.382602 -291.710618)
			(xy 341.11311 -292.979856) (xy 341.106271 -292.987257) (xy 341.098555 -293.005855) (xy 341.098124 -293.015924)
			(xy 341.098124 -294.1828) (xy 342.809828 -294.1828) (xy 342.813899 -294.127178) (xy 342.826025 -294.072741)
			(xy 342.845948 -294.02065) (xy 342.873244 -293.972015) (xy 342.90733 -293.927872) (xy 342.947479 -293.889163)
			(xy 342.992837 -293.856712) (xy 343.042437 -293.831211) (xy 343.095221 -293.813204) (xy 343.150064 -293.803074)
			(xy 343.205798 -293.801037) (xy 343.261235 -293.807137) (xy 343.315192 -293.821243) (xy 343.366521 -293.843055)
			(xy 343.414127 -293.872109) (xy 343.456995 -293.907784) (xy 343.494212 -293.949321) (xy 343.524985 -293.995834)
			(xy 343.548657 -294.046331) (xy 343.564725 -294.099738) (xy 343.572845 -294.154914) (xy 343.573354 -294.1828)
			(xy 343.572845 -294.210686) (xy 343.564725 -294.265862) (xy 343.548657 -294.319269) (xy 343.524985 -294.369766)
			(xy 343.494212 -294.416279) (xy 343.456995 -294.457816) (xy 343.414127 -294.493491) (xy 343.366521 -294.522545)
			(xy 343.315192 -294.544357) (xy 343.261235 -294.558463) (xy 343.205798 -294.564563) (xy 343.150064 -294.562526)
			(xy 343.095221 -294.552396) (xy 343.042437 -294.534389) (xy 342.992837 -294.508888) (xy 342.947479 -294.476437)
			(xy 342.90733 -294.437728) (xy 342.873244 -294.393585) (xy 342.845948 -294.34495) (xy 342.826025 -294.292859)
			(xy 342.813899 -294.238422) (xy 342.809828 -294.1828) (xy 341.098124 -294.1828) (xy 341.098124 -294.787066)
			(xy 341.098797 -294.799134) (xy 341.109812 -294.820608) (xy 341.119206 -294.828214) (xy 341.186008 -294.87622)
			(xy 341.196191 -294.882741) (xy 341.220049 -294.88646) (xy 341.231728 -294.883332) (xy 341.260814 -294.87433)
			(xy 341.32092 -294.864633) (xy 341.351362 -294.864028) (xy 341.35187 -294.864028) (xy 341.379123 -294.864489)
			(xy 341.433076 -294.872243) (xy 341.485375 -294.887597) (xy 341.534957 -294.910238) (xy 341.580811 -294.939706)
			(xy 341.622004 -294.9754) (xy 341.657698 -295.016594) (xy 341.687165 -295.062449) (xy 341.709805 -295.112031)
			(xy 341.725158 -295.16433) (xy 341.732911 -295.218283) (xy 341.733378 -295.245536) (xy 341.732904 -295.272905)
			(xy 341.725075 -295.32708) (xy 341.709583 -295.379581) (xy 341.686747 -295.429328) (xy 341.657034 -295.4753)
			(xy 341.639398 -295.496234) (xy 341.639398 -295.496488) (xy 341.639144 -295.496488) (xy 341.633553 -295.503573)
			(xy 341.627302 -295.52049) (xy 341.626952 -295.529508) (xy 341.626952 -295.596564) (xy 341.627304 -295.605584)
			(xy 341.633538 -295.622511) (xy 341.639144 -295.629584) (xy 341.639398 -295.629838) (xy 341.657035 -295.650771)
			(xy 341.686753 -295.696739) (xy 341.709592 -295.746484) (xy 341.725082 -295.798983) (xy 341.732906 -295.853158)
			(xy 341.732902 -295.907896) (xy 341.725071 -295.96207) (xy 341.709573 -296.014567) (xy 341.686727 -296.064309)
			(xy 341.657002 -296.110272) (xy 341.639398 -296.131234) (xy 341.639398 -296.131488) (xy 341.639144 -296.131488)
			(xy 341.633553 -296.138573) (xy 341.627302 -296.15549) (xy 341.626952 -296.164508) (xy 341.626952 -296.231564)
			(xy 341.627304 -296.240584) (xy 341.633538 -296.257511) (xy 341.639144 -296.264584) (xy 341.639398 -296.264838)
			(xy 341.657035 -296.285771) (xy 341.686753 -296.331739) (xy 341.709592 -296.381484) (xy 341.725082 -296.433983)
			(xy 341.732906 -296.488158) (xy 341.732902 -296.542896) (xy 341.725071 -296.59707) (xy 341.709573 -296.649567)
			(xy 341.686727 -296.699309) (xy 341.657002 -296.745272) (xy 341.639398 -296.766234) (xy 341.639398 -296.766488)
			(xy 341.639144 -296.766488) (xy 341.633553 -296.773573) (xy 341.627302 -296.79049) (xy 341.626952 -296.799508)
			(xy 341.626952 -296.866564) (xy 341.627304 -296.875584) (xy 341.633538 -296.892511) (xy 341.639144 -296.899584)
			(xy 341.639398 -296.899838) (xy 341.657035 -296.920771) (xy 341.686753 -296.966739) (xy 341.709592 -297.016484)
			(xy 341.725082 -297.068983) (xy 341.732906 -297.123158) (xy 341.732902 -297.177896) (xy 341.725071 -297.23207)
			(xy 341.709573 -297.284567) (xy 341.686727 -297.334309) (xy 341.657002 -297.380272) (xy 341.639398 -297.401234)
			(xy 341.639398 -297.401488) (xy 341.639144 -297.401488) (xy 341.633553 -297.408573) (xy 341.627302 -297.42549)
			(xy 341.626952 -297.434508) (xy 341.626952 -297.501564) (xy 341.627304 -297.510584) (xy 341.633538 -297.527511)
			(xy 341.639144 -297.534584) (xy 341.639398 -297.534838) (xy 341.657035 -297.555771) (xy 341.686753 -297.601739)
			(xy 341.709592 -297.651484) (xy 341.725082 -297.703983) (xy 341.732906 -297.758158) (xy 341.732902 -297.812896)
			(xy 341.725071 -297.86707) (xy 341.709573 -297.919567) (xy 341.686727 -297.969309) (xy 341.657002 -298.015272)
			(xy 341.639398 -298.036234) (xy 341.639398 -298.036488) (xy 341.639144 -298.036488) (xy 341.633553 -298.043573)
			(xy 341.627302 -298.06049) (xy 341.626952 -298.069508) (xy 341.626952 -298.136564) (xy 341.627304 -298.145584)
			(xy 341.633538 -298.162511) (xy 341.639144 -298.169584) (xy 341.639398 -298.169838) (xy 341.657038 -298.19077)
			(xy 341.68676 -298.236737) (xy 341.709598 -298.286485) (xy 341.725083 -298.338988) (xy 341.732896 -298.393166)
			(xy 341.733378 -298.420536) (xy 342.763094 -298.420536) (xy 342.763583 -298.393167) (xy 342.771395 -298.338989)
			(xy 342.786879 -298.286486) (xy 342.809716 -298.236739) (xy 342.839435 -298.190771) (xy 342.857074 -298.169838)
			(xy 342.857328 -298.169584) (xy 342.862931 -298.162508) (xy 342.869167 -298.145583) (xy 342.86952 -298.136564)
			(xy 342.86952 -298.069508) (xy 342.869155 -298.060492) (xy 342.862912 -298.043575) (xy 342.857328 -298.036488)
			(xy 342.857074 -298.036488) (xy 342.857074 -298.036234) (xy 342.839467 -298.015274) (xy 342.809737 -297.969312)
			(xy 342.786886 -297.91957) (xy 342.771385 -297.867072) (xy 342.763552 -297.812897) (xy 342.763548 -297.758158)
			(xy 342.771374 -297.703981) (xy 342.786867 -297.65148) (xy 342.809711 -297.601736) (xy 342.839434 -297.55577)
			(xy 342.857074 -297.534838) (xy 342.857328 -297.534584) (xy 342.862931 -297.527508) (xy 342.869167 -297.510583)
			(xy 342.86952 -297.501564) (xy 342.86952 -297.434508) (xy 342.869155 -297.425492) (xy 342.862912 -297.408575)
			(xy 342.857328 -297.401488) (xy 342.857074 -297.401488) (xy 342.857074 -297.401234) (xy 342.839467 -297.380274)
			(xy 342.809737 -297.334312) (xy 342.786886 -297.28457) (xy 342.771385 -297.232072) (xy 342.763552 -297.177897)
			(xy 342.763548 -297.123158) (xy 342.771374 -297.068981) (xy 342.786867 -297.01648) (xy 342.809711 -296.966736)
			(xy 342.839434 -296.92077) (xy 342.857074 -296.899838) (xy 342.857328 -296.899584) (xy 342.862931 -296.892508)
			(xy 342.869167 -296.875583) (xy 342.86952 -296.866564) (xy 342.86952 -296.799508) (xy 342.869155 -296.790492)
			(xy 342.862912 -296.773575) (xy 342.857328 -296.766488) (xy 342.857074 -296.766488) (xy 342.857074 -296.766234)
			(xy 342.839467 -296.745274) (xy 342.809737 -296.699312) (xy 342.786886 -296.64957) (xy 342.771385 -296.597072)
			(xy 342.763552 -296.542897) (xy 342.763548 -296.488158) (xy 342.771374 -296.433981) (xy 342.786867 -296.38148)
			(xy 342.809711 -296.331736) (xy 342.839434 -296.28577) (xy 342.857074 -296.264838) (xy 342.857328 -296.264584)
			(xy 342.862931 -296.257508) (xy 342.869167 -296.240583) (xy 342.86952 -296.231564) (xy 342.86952 -296.164508)
			(xy 342.869155 -296.155492) (xy 342.862912 -296.138575) (xy 342.857328 -296.131488) (xy 342.857074 -296.131488)
			(xy 342.857074 -296.131234) (xy 342.839467 -296.110274) (xy 342.809737 -296.064312) (xy 342.786886 -296.01457)
			(xy 342.771385 -295.962072) (xy 342.763552 -295.907897) (xy 342.763548 -295.853158) (xy 342.771374 -295.798981)
			(xy 342.786867 -295.74648) (xy 342.809711 -295.696736) (xy 342.839434 -295.65077) (xy 342.857074 -295.629838)
			(xy 342.857328 -295.629584) (xy 342.862931 -295.622508) (xy 342.869167 -295.605583) (xy 342.86952 -295.596564)
			(xy 342.86952 -295.529508) (xy 342.869155 -295.520492) (xy 342.862912 -295.503575) (xy 342.857328 -295.496488)
			(xy 342.857074 -295.496488) (xy 342.857074 -295.496234) (xy 342.839433 -295.475303) (xy 342.809723 -295.42933)
			(xy 342.786887 -295.379582) (xy 342.771397 -295.327081) (xy 342.763568 -295.272905) (xy 342.763094 -295.245536)
			(xy 342.763589 -295.218284) (xy 342.771341 -295.164334) (xy 342.786692 -295.112037) (xy 342.809331 -295.062457)
			(xy 342.838795 -295.016603) (xy 342.874486 -294.97541) (xy 342.915676 -294.939716) (xy 342.961527 -294.910247)
			(xy 343.011105 -294.887604) (xy 343.063401 -294.872248) (xy 343.11735 -294.864491) (xy 343.144602 -294.864028)
			(xy 343.171973 -294.864486) (xy 343.226152 -294.872305) (xy 343.278656 -294.887795) (xy 343.328403 -294.910639)
			(xy 343.374369 -294.940366) (xy 343.3953 -294.958008) (xy 343.395554 -294.958262) (xy 343.402644 -294.963843)
			(xy 343.419558 -294.970091) (xy 343.428574 -294.970454) (xy 343.49563 -294.970454) (xy 343.50465 -294.970121)
			(xy 343.521567 -294.963858) (xy 343.52865 -294.958262) (xy 343.52865 -294.958008) (xy 343.528904 -294.958008)
			(xy 343.549825 -294.940355) (xy 343.595801 -294.910645) (xy 343.645551 -294.887811) (xy 343.698054 -294.872324)
			(xy 343.752232 -294.8645) (xy 343.779602 -294.864028) (xy 343.806857 -294.864454) (xy 343.860811 -294.872212)
			(xy 343.913111 -294.88757) (xy 343.962694 -294.910215) (xy 344.008549 -294.939687) (xy 344.049742 -294.975385)
			(xy 344.085436 -295.016582) (xy 344.114903 -295.062439) (xy 344.137543 -295.112024) (xy 344.152896 -295.164326)
			(xy 344.160649 -295.218281) (xy 344.16111 -295.245536) (xy 344.160663 -295.272907) (xy 344.15284 -295.327087)
			(xy 344.137346 -295.37959) (xy 344.114501 -295.429336) (xy 344.084773 -295.475303) (xy 344.06713 -295.496234)
			(xy 344.066876 -295.496488) (xy 344.061286 -295.503572) (xy 344.055042 -295.520491) (xy 344.054684 -295.529508)
			(xy 344.054684 -295.596564) (xy 344.055062 -295.605579) (xy 344.061295 -295.622496) (xy 344.066876 -295.629584)
			(xy 344.06713 -295.629584) (xy 344.06713 -295.629838) (xy 344.084808 -295.650741) (xy 344.114534 -295.696713)
			(xy 344.13738 -295.746464) (xy 344.152876 -295.798971) (xy 344.160702 -295.853154) (xy 344.160698 -295.9079)
			(xy 344.152864 -295.962082) (xy 344.137361 -296.014587) (xy 344.114508 -296.064334) (xy 344.084775 -296.110302)
			(xy 344.06713 -296.131234) (xy 344.066876 -296.131488) (xy 344.061286 -296.138572) (xy 344.055042 -296.155491)
			(xy 344.054684 -296.164508) (xy 344.054684 -296.231564) (xy 344.055062 -296.240579) (xy 344.061295 -296.257496)
			(xy 344.066876 -296.264584) (xy 344.06713 -296.264584) (xy 344.06713 -296.264838) (xy 344.084808 -296.285741)
			(xy 344.114534 -296.331713) (xy 344.13738 -296.381464) (xy 344.152876 -296.433971) (xy 344.160702 -296.488154)
			(xy 344.160698 -296.5429) (xy 344.152864 -296.597082) (xy 344.137361 -296.649587) (xy 344.114508 -296.699334)
			(xy 344.084775 -296.745302) (xy 344.06713 -296.766234) (xy 344.066876 -296.766488) (xy 344.061286 -296.773572)
			(xy 344.055042 -296.790491) (xy 344.054684 -296.799508) (xy 344.054684 -296.866564) (xy 344.055062 -296.875579)
			(xy 344.061295 -296.892496) (xy 344.066876 -296.899584) (xy 344.06713 -296.899584) (xy 344.06713 -296.899838)
			(xy 344.084808 -296.920741) (xy 344.114534 -296.966713) (xy 344.13738 -297.016464) (xy 344.152876 -297.068971)
			(xy 344.160702 -297.123154) (xy 344.160698 -297.1779) (xy 344.152864 -297.232082) (xy 344.137361 -297.284587)
			(xy 344.114508 -297.334334) (xy 344.084775 -297.380302) (xy 344.06713 -297.401234) (xy 344.066876 -297.401488)
			(xy 344.061286 -297.408572) (xy 344.055042 -297.425491) (xy 344.054684 -297.434508) (xy 344.054684 -297.501564)
			(xy 344.055062 -297.510579) (xy 344.061295 -297.527496) (xy 344.066876 -297.534584) (xy 344.06713 -297.534584)
			(xy 344.06713 -297.534838) (xy 344.084808 -297.555741) (xy 344.114534 -297.601713) (xy 344.13738 -297.651464)
			(xy 344.152876 -297.703971) (xy 344.160702 -297.758154) (xy 344.160698 -297.8129) (xy 344.152864 -297.867082)
			(xy 344.137361 -297.919587) (xy 344.114508 -297.969334) (xy 344.084775 -298.015302) (xy 344.06713 -298.036234)
			(xy 344.066876 -298.036488) (xy 344.061286 -298.043572) (xy 344.055042 -298.060491) (xy 344.054684 -298.069508)
			(xy 344.054684 -298.136564) (xy 344.055062 -298.145579) (xy 344.061295 -298.162496) (xy 344.066876 -298.169584)
			(xy 344.06713 -298.169584) (xy 344.06713 -298.169838) (xy 344.084758 -298.190779) (xy 344.114471 -298.23675)
			(xy 344.137308 -298.286495) (xy 344.152802 -298.338994) (xy 344.160634 -298.393168) (xy 344.16111 -298.420536)
			(xy 344.160656 -298.447788) (xy 344.152894 -298.501737) (xy 344.137535 -298.554032) (xy 344.11489 -298.603609)
			(xy 344.08542 -298.649459) (xy 344.049725 -298.690649) (xy 344.008532 -298.72634) (xy 343.962679 -298.755806)
			(xy 343.9131 -298.778447) (xy 343.860804 -298.793802) (xy 343.806854 -298.801558) (xy 343.779602 -298.802044)
			(xy 343.752231 -298.80159) (xy 343.698051 -298.793772) (xy 343.645547 -298.77828) (xy 343.595801 -298.755436)
			(xy 343.549835 -298.725707) (xy 343.528904 -298.708064) (xy 343.52865 -298.70781) (xy 343.521552 -298.702239)
			(xy 343.504644 -298.695983) (xy 343.49563 -298.695618) (xy 343.428574 -298.695618) (xy 343.419555 -298.695959)
			(xy 343.402638 -298.702217) (xy 343.395554 -298.70781) (xy 343.395554 -298.708064) (xy 343.3953 -298.708064)
			(xy 343.374374 -298.725711) (xy 343.3284 -298.755423) (xy 343.278651 -298.778258) (xy 343.226149 -298.793747)
			(xy 343.171972 -298.801572) (xy 343.144602 -298.802044) (xy 343.117352 -298.80152) (xy 343.063408 -298.793765)
			(xy 343.011116 -298.778412) (xy 342.961541 -298.755774) (xy 342.915693 -298.726311) (xy 342.874503 -298.690624)
			(xy 342.838812 -298.649438) (xy 342.809344 -298.603592) (xy 342.786701 -298.55402) (xy 342.771343 -298.501729)
			(xy 342.763582 -298.447786) (xy 342.763094 -298.420536) (xy 341.733378 -298.420536) (xy 341.732889 -298.447785)
			(xy 341.725128 -298.501727) (xy 341.70977 -298.554016) (xy 341.687126 -298.603586) (xy 341.657659 -298.64943)
			(xy 341.621967 -298.690613) (xy 341.580777 -298.726298) (xy 341.534928 -298.755758) (xy 341.485354 -298.778393)
			(xy 341.433062 -298.793742) (xy 341.379119 -298.801494) (xy 341.35187 -298.802044) (xy 341.324501 -298.80157)
			(xy 341.270326 -298.793741) (xy 341.217826 -298.778249) (xy 341.168079 -298.755412) (xy 341.122108 -298.725698)
			(xy 341.101172 -298.708064) (xy 341.100918 -298.708064) (xy 341.100918 -298.70781) (xy 341.093832 -298.702221)
			(xy 341.076915 -298.695972) (xy 341.067898 -298.695618) (xy 341.000842 -298.695618) (xy 340.991823 -298.695971)
			(xy 340.974899 -298.702209) (xy 340.967822 -298.70781) (xy 340.967568 -298.708064) (xy 340.946637 -298.725706)
			(xy 340.90067 -298.755431) (xy 340.850923 -298.778272) (xy 340.79842 -298.793759) (xy 340.74424 -298.801574)
			(xy 340.71687 -298.802044) (xy 340.689619 -298.801556) (xy 340.635673 -298.793796) (xy 340.58338 -298.778439)
			(xy 340.533804 -298.755797) (xy 340.487955 -298.72633) (xy 340.446765 -298.690639) (xy 340.411073 -298.64945)
			(xy 340.381606 -298.603601) (xy 340.358963 -298.554026) (xy 340.343605 -298.501733) (xy 340.335844 -298.447787)
			(xy 340.335362 -298.420536) (xy 340.335838 -298.393168) (xy 340.343671 -298.338995) (xy 340.359168 -298.286498)
			(xy 340.382008 -298.236755) (xy 340.411725 -298.190788) (xy 340.429342 -298.169838) (xy 340.429342 -298.169584)
			(xy 340.429596 -298.169584) (xy 340.435179 -298.162497) (xy 340.441416 -298.145579) (xy 340.441788 -298.136564)
			(xy 340.441788 -298.069508) (xy 340.44143 -298.060491) (xy 340.435183 -298.043574) (xy 340.429596 -298.036488)
			(xy 340.429342 -298.036234) (xy 340.411698 -298.015301) (xy 340.381967 -297.969333) (xy 340.359116 -297.919586)
			(xy 340.343614 -297.867081) (xy 340.335781 -297.8129) (xy 340.335777 -297.758155) (xy 340.343603 -297.703972)
			(xy 340.359097 -297.651465) (xy 340.381941 -297.601714) (xy 340.411665 -297.555742) (xy 340.429342 -297.534838)
			(xy 340.429342 -297.534584) (xy 340.429596 -297.534584) (xy 340.435179 -297.527497) (xy 340.441416 -297.510579)
			(xy 340.441788 -297.501564) (xy 340.441788 -297.434508) (xy 340.44143 -297.425491) (xy 340.435183 -297.408574)
			(xy 340.429596 -297.401488) (xy 340.429342 -297.401234) (xy 340.411698 -297.380301) (xy 340.381967 -297.334333)
			(xy 340.359116 -297.284586) (xy 340.343614 -297.232081) (xy 340.335781 -297.1779) (xy 340.335777 -297.123155)
			(xy 340.343603 -297.068972) (xy 340.359097 -297.016465) (xy 340.381941 -296.966714) (xy 340.411665 -296.920742)
			(xy 340.429342 -296.899838) (xy 340.429342 -296.899584) (xy 340.429596 -296.899584) (xy 340.435179 -296.892497)
			(xy 340.441416 -296.875579) (xy 340.441788 -296.866564) (xy 340.441788 -296.799508) (xy 340.44143 -296.790491)
			(xy 340.435183 -296.773574) (xy 340.429596 -296.766488) (xy 340.429342 -296.766234) (xy 340.411698 -296.745301)
			(xy 340.381967 -296.699333) (xy 340.359116 -296.649586) (xy 340.343614 -296.597081) (xy 340.335781 -296.5429)
			(xy 340.335777 -296.488155) (xy 340.343603 -296.433972) (xy 340.359097 -296.381465) (xy 340.381941 -296.331714)
			(xy 340.411665 -296.285742) (xy 340.429342 -296.264838) (xy 340.429342 -296.264584) (xy 340.429596 -296.264584)
			(xy 340.435179 -296.257497) (xy 340.441416 -296.240579) (xy 340.441788 -296.231564) (xy 340.441788 -296.164508)
			(xy 340.44143 -296.155491) (xy 340.435183 -296.138574) (xy 340.429596 -296.131488) (xy 340.429342 -296.131234)
			(xy 340.411698 -296.110301) (xy 340.381967 -296.064333) (xy 340.359116 -296.014586) (xy 340.343614 -295.962081)
			(xy 340.335781 -295.9079) (xy 340.335777 -295.853155) (xy 340.343603 -295.798972) (xy 340.359097 -295.746465)
			(xy 340.381941 -295.696714) (xy 340.411665 -295.650742) (xy 340.429342 -295.629838) (xy 340.429342 -295.629584)
			(xy 340.429596 -295.629584) (xy 340.435179 -295.622497) (xy 340.441416 -295.605579) (xy 340.441788 -295.596564)
			(xy 340.442042 -295.520364) (xy 340.435438 -295.503092) (xy 340.429342 -295.496234) (xy 340.411754 -295.475336)
			(xy 340.382119 -295.429452) (xy 340.359343 -295.379806) (xy 340.343892 -295.327415) (xy 340.336083 -295.273355)
			(xy 340.335616 -295.246044) (xy 340.335616 -292.836346) (xy 340.336226 -292.806431) (xy 340.345619 -292.747342)
			(xy 340.364119 -292.690443) (xy 340.391273 -292.637128) (xy 340.426415 -292.588705) (xy 340.447122 -292.567106)
			(xy 341.716614 -291.297868) (xy 341.723465 -291.290472) (xy 341.731201 -291.271873) (xy 341.7316 -291.2618)
			(xy 341.7316 -287.464754) (xy 341.73221 -287.434839) (xy 341.741601 -287.375749) (xy 341.7601 -287.318848)
			(xy 341.787252 -287.265532) (xy 341.822393 -287.217107) (xy 341.843106 -287.195514) (xy 341.91702 -287.1216)
			(xy 341.924218 -287.113661) (xy 341.931965 -287.093708) (xy 341.932006 -287.082992) (xy 341.927434 -286.996886)
			(xy 341.917782 -286.977836) (xy 341.9094 -286.970978) (xy 341.882913 -286.948703) (xy 341.83599 -286.897832)
			(xy 341.815928 -286.869632) (xy 341.808562 -286.85871) (xy 341.784686 -286.846772) (xy 341.68461 -286.852614)
			(xy 341.675962 -286.85343) (xy 341.659945 -286.860119) (xy 341.647103 -286.871797) (xy 341.6427 -286.879284)
			(xy 341.62832 -286.904987) (xy 341.59288 -286.952023) (xy 341.550639 -286.993062) (xy 341.502599 -287.02713)
			(xy 341.449899 -287.05342) (xy 341.393788 -287.071309) (xy 341.335597 -287.080372) (xy 341.30615 -287.08096)
			(xy 341.278905 -287.08047) (xy 341.224969 -287.072709) (xy 341.172687 -287.057352) (xy 341.123122 -287.03471)
			(xy 341.077284 -287.005247) (xy 341.036105 -286.96956) (xy 341.000423 -286.928376) (xy 340.970966 -286.882534)
			(xy 340.948331 -286.832966) (xy 340.93298 -286.780682) (xy 340.925226 -286.726746) (xy 340.925226 -286.672254)
			(xy 340.93298 -286.618318) (xy 340.948331 -286.566034) (xy 340.970966 -286.516466) (xy 341.000423 -286.470624)
			(xy 341.036105 -286.42944) (xy 341.077284 -286.393753) (xy 341.123122 -286.364289) (xy 341.172687 -286.341648)
			(xy 341.224969 -286.326291) (xy 341.278905 -286.31853) (xy 341.30615 -286.317944) (xy 341.316395 -286.318033)
			(xy 341.336853 -286.319179) (xy 341.347044 -286.32023) (xy 341.357521 -286.320806) (xy 341.377507 -286.314491)
			(xy 341.39333 -286.300743) (xy 341.398352 -286.291528) (xy 341.439754 -286.205168) (xy 341.443784 -286.19549)
			(xy 341.444498 -286.17456) (xy 341.436843 -286.155067) (xy 341.429848 -286.147256) (xy 340.019386 -284.737048)
			(xy 339.997367 -284.71433) (xy 339.958851 -284.664137) (xy 339.927219 -284.609345) (xy 339.903011 -284.550892)
			(xy 339.886642 -284.489779) (xy 339.878392 -284.427052) (xy 339.877908 -284.395418) (xy 339.877908 -282.843986)
			(xy 339.877483 -282.833917) (xy 339.869766 -282.815315) (xy 339.862922 -282.807918) (xy 339.545676 -282.490418)
			(xy 339.538277 -282.483573) (xy 339.519679 -282.475845) (xy 339.509608 -282.475432) (xy 338.299298 -282.475432)
			(xy 338.297012 -282.473146) (xy 338.289616 -282.466293) (xy 338.271018 -282.458547) (xy 338.260944 -282.45816)
			(xy 337.876642 -282.45816) (xy 337.867054 -282.458568) (xy 337.849207 -282.465586) (xy 337.835151 -282.478633)
			(xy 337.830668 -282.487116) (xy 337.784948 -282.58389) (xy 337.788504 -282.612592) (xy 337.798156 -282.624276)
			(xy 337.8145 -282.644844) (xy 337.841984 -282.689616) (xy 337.863068 -282.737734) (xy 337.877355 -282.788289)
			(xy 337.884574 -282.840325) (xy 337.885024 -282.866592) (xy 337.884539 -282.893844) (xy 337.876783 -282.947793)
			(xy 337.861429 -283.00009) (xy 337.838789 -283.049669) (xy 337.809323 -283.095522) (xy 337.773631 -283.136714)
			(xy 337.732441 -283.172408) (xy 337.68659 -283.201877) (xy 337.637013 -283.224521) (xy 337.584717 -283.239878)
			(xy 337.530768 -283.247637) (xy 337.503516 -283.2481) (xy 337.476148 -283.247622) (xy 337.421976 -283.239788)
			(xy 337.369479 -283.224291) (xy 337.319736 -283.201452) (xy 337.273768 -283.171737) (xy 337.252818 -283.15412)
			(xy 337.252564 -283.15412) (xy 337.252564 -283.153866) (xy 337.245474 -283.148289) (xy 337.228558 -283.142063)
			(xy 337.219544 -283.141674) (xy 337.152488 -283.141674) (xy 337.143472 -283.142035) (xy 337.126557 -283.148283)
			(xy 337.119468 -283.153866) (xy 337.119214 -283.15412) (xy 337.098282 -283.171762) (xy 337.052316 -283.201488)
			(xy 337.002569 -283.224332) (xy 336.950066 -283.239823) (xy 336.895887 -283.247643) (xy 336.868516 -283.2481)
			(xy 336.841263 -283.247638) (xy 336.787311 -283.239883) (xy 336.735013 -283.224528) (xy 336.685432 -283.201887)
			(xy 336.639578 -283.17242) (xy 336.598384 -283.136728) (xy 336.562689 -283.095535) (xy 336.53322 -283.049682)
			(xy 336.510577 -283.000102) (xy 336.495221 -282.947804) (xy 336.487463 -282.893853) (xy 336.487463 -282.839347)
			(xy 336.495221 -282.785396) (xy 336.510577 -282.733098) (xy 336.53322 -282.683518) (xy 336.562689 -282.637665)
			(xy 336.598384 -282.596472) (xy 336.639578 -282.56078) (xy 336.685432 -282.531313) (xy 336.735013 -282.508672)
			(xy 336.787311 -282.493317) (xy 336.841263 -282.485562) (xy 336.868516 -282.485084) (xy 336.895886 -282.485557)
			(xy 336.950063 -282.493382) (xy 337.002566 -282.508871) (xy 337.052316 -282.531704) (xy 337.098292 -282.561412)
			(xy 337.119214 -282.579064) (xy 337.119468 -282.579064) (xy 337.119468 -282.579318) (xy 337.126554 -282.584906)
			(xy 337.143471 -282.591156) (xy 337.152488 -282.59151) (xy 337.219544 -282.59151) (xy 337.228558 -282.591143)
			(xy 337.245465 -282.584886) (xy 337.252564 -282.579318) (xy 337.252818 -282.579064) (xy 337.275178 -282.560253)
			(xy 337.32455 -282.529004) (xy 337.351116 -282.516834) (xy 337.35137 -282.516834) (xy 337.359108 -282.513043)
			(xy 337.371649 -282.501242) (xy 337.379553 -282.485943) (xy 337.381088 -282.477464) (xy 337.393534 -282.391866)
			(xy 337.394396 -282.383261) (xy 337.390983 -282.366318) (xy 337.382148 -282.351463) (xy 337.375754 -282.345638)
			(xy 337.34375 -282.316682) (xy 336.14106 -281.113738) (xy 336.133661 -281.106894) (xy 336.115063 -281.099168)
			(xy 336.104992 -281.098752) (xy 335.97596 -281.098752) (xy 335.967174 -281.099128) (xy 335.950643 -281.10509)
			(xy 335.937107 -281.116295) (xy 335.932272 -281.123644) (xy 335.88071 -281.210512) (xy 335.880202 -281.237182)
			(xy 335.886806 -281.24912) (xy 335.901364 -281.277244) (xy 335.921976 -281.337119) (xy 335.932421 -281.399576)
			(xy 335.933034 -281.431238) (xy 335.932566 -281.458536) (xy 335.92478 -281.512575) (xy 335.909373 -281.564953)
			(xy 335.886659 -281.614601) (xy 335.857102 -281.660505) (xy 335.839562 -281.681428) (xy 335.833212 -281.688794)
			(xy 335.826862 -281.706574) (xy 335.830164 -281.795728) (xy 335.838038 -281.813508) (xy 335.844896 -281.820112)
			(xy 335.866005 -281.84176) (xy 335.901798 -281.890489) (xy 335.92946 -281.944251) (xy 335.948298 -282.001704)
			(xy 335.957841 -282.061407) (xy 335.958434 -282.091638) (xy 335.957947 -282.119278) (xy 335.949972 -282.173979)
			(xy 335.93418 -282.226955) (xy 335.910903 -282.277094) (xy 335.880628 -282.323346) (xy 335.862676 -282.344368)
			(xy 335.854294 -282.353766) (xy 335.848452 -282.37815) (xy 335.872582 -282.47213) (xy 335.876252 -282.484096)
			(xy 335.893033 -282.502626) (xy 335.904586 -282.507436) (xy 335.931994 -282.517774) (xy 335.983512 -282.54565)
			(xy 336.030159 -282.581079) (xy 336.070837 -282.623227) (xy 336.104589 -282.671102) (xy 336.13062 -282.723576)
			(xy 336.148317 -282.779415) (xy 336.157264 -282.837304) (xy 336.157824 -282.866592) (xy 336.157223 -282.896428)
			(xy 336.147906 -282.955371) (xy 336.139282 -282.98394) (xy 336.13598 -282.994354) (xy 336.138266 -283.015944)
			(xy 336.188558 -283.100526) (xy 336.20583 -283.112972) (xy 336.216752 -283.115004) (xy 336.242551 -283.120411)
			(xy 336.292456 -283.137382) (xy 336.339549 -283.161062) (xy 336.382935 -283.191) (xy 336.421786 -283.226624)
			(xy 336.455363 -283.267258) (xy 336.483027 -283.312127) (xy 336.504252 -283.360377) (xy 336.518632 -283.411089)
			(xy 336.525894 -283.463298) (xy 336.526378 -283.489654) (xy 336.525812 -283.519779) (xy 336.516346 -283.579282)
			(xy 336.497642 -283.636555) (xy 336.470165 -283.690176) (xy 336.434599 -283.738809) (xy 336.413602 -283.760418)
			(xy 336.406758 -283.767818) (xy 336.39903 -283.786415) (xy 336.398616 -283.796486) (xy 336.398616 -283.868622)
			(xy 336.399044 -283.87869) (xy 336.406765 -283.897287) (xy 336.413602 -283.90469) (xy 336.434576 -283.926317)
			(xy 336.470126 -283.974953) (xy 336.497592 -284.028571) (xy 336.516293 -284.085838) (xy 336.525765 -284.145332)
			(xy 336.526378 -284.175454) (xy 336.525892 -284.202705) (xy 336.518136 -284.256653) (xy 336.502781 -284.308948)
			(xy 336.480139 -284.358525) (xy 336.450673 -284.404375) (xy 336.414982 -284.445566) (xy 336.373791 -284.481257)
			(xy 336.327941 -284.510723) (xy 336.278364 -284.533365) (xy 336.226069 -284.54872) (xy 336.172121 -284.556476)
			(xy 336.117619 -284.556476) (xy 336.063671 -284.54872) (xy 336.011376 -284.533365) (xy 335.961799 -284.510723)
			(xy 335.915949 -284.481257) (xy 335.874758 -284.445566) (xy 335.839067 -284.404375) (xy 335.809601 -284.358525)
			(xy 335.786959 -284.308948) (xy 335.771604 -284.256653) (xy 335.763848 -284.202705) (xy 335.763362 -284.175454)
			(xy 335.763927 -284.145329) (xy 335.773393 -284.085827) (xy 335.792098 -284.028553) (xy 335.819576 -283.974934)
			(xy 335.855144 -283.926302) (xy 335.876138 -283.90469) (xy 335.88299 -283.897294) (xy 335.89073 -283.878695)
			(xy 335.891124 -283.868622) (xy 335.891124 -283.796486) (xy 335.890699 -283.786416) (xy 335.882984 -283.767813)
			(xy 335.876138 -283.760418) (xy 335.855162 -283.738792) (xy 335.819608 -283.690157) (xy 335.792138 -283.636539)
			(xy 335.773433 -283.579272) (xy 335.763959 -283.519776) (xy 335.763362 -283.489654) (xy 335.763959 -283.459817)
			(xy 335.77327 -283.400873) (xy 335.781904 -283.372306) (xy 335.785206 -283.361892) (xy 335.78292 -283.340302)
			(xy 335.732628 -283.25572) (xy 335.715356 -283.243274) (xy 335.704434 -283.241242) (xy 335.676585 -283.235367)
			(xy 335.622903 -283.216464) (xy 335.572627 -283.189791) (xy 335.526875 -283.15594) (xy 335.486663 -283.115665)
			(xy 335.452886 -283.069859) (xy 335.426292 -283.01954) (xy 335.407475 -282.965828) (xy 335.401666 -282.937966)
			(xy 335.399126 -282.92552) (xy 335.383886 -282.906216) (xy 335.282794 -282.862528) (xy 335.258156 -282.864306)
			(xy 335.247488 -282.871164) (xy 335.224495 -282.885156) (xy 335.175416 -282.907251) (xy 335.123722 -282.922244)
			(xy 335.070437 -282.929838) (xy 335.043526 -282.930346) (xy 335.025508 -282.93011) (xy 334.989635 -282.926672)
			(xy 334.971898 -282.923488) (xy 334.962246 -282.92171) (xy 334.943196 -282.925266) (xy 334.868266 -282.973272)
			(xy 334.856836 -282.98902) (xy 334.85455 -282.998418) (xy 334.847166 -283.025467) (xy 334.825551 -283.077203)
			(xy 334.796595 -283.125217) (xy 334.760921 -283.168474) (xy 334.719298 -283.206041) (xy 334.672624 -283.23711)
			(xy 334.621903 -283.261011) (xy 334.56823 -283.277228) (xy 334.512761 -283.285411) (xy 334.484726 -283.285946)
			(xy 334.457473 -283.285462) (xy 334.40352 -283.277709) (xy 334.35122 -283.262356) (xy 334.301637 -283.239717)
			(xy 334.255781 -283.210252) (xy 334.214584 -283.174561) (xy 334.178886 -283.133371) (xy 334.149414 -283.087519)
			(xy 334.126766 -283.03794) (xy 334.111405 -282.985643) (xy 334.103643 -282.931691) (xy 334.103218 -282.904438)
			(xy 334.103702 -282.876863) (xy 334.11164 -282.822288) (xy 334.127356 -282.769425) (xy 334.150522 -282.719377)
			(xy 334.180655 -282.673188) (xy 334.217127 -282.63182) (xy 334.237838 -282.613608) (xy 334.245926 -282.606066)
			(xy 334.255257 -282.586044) (xy 334.255872 -282.575) (xy 334.255872 -282.497276) (xy 334.255262 -282.486236)
			(xy 334.245905 -282.46623) (xy 334.237838 -282.458668) (xy 334.217133 -282.440451) (xy 334.180671 -282.399079)
			(xy 334.150545 -282.352889) (xy 334.127382 -282.302842) (xy 334.111664 -282.249983) (xy 334.10372 -282.195411)
			(xy 334.103218 -282.167838) (xy 334.103702 -282.140263) (xy 334.11164 -282.085688) (xy 334.127356 -282.032825)
			(xy 334.150522 -281.982777) (xy 334.180655 -281.936588) (xy 334.217127 -281.89522) (xy 334.237838 -281.877008)
			(xy 334.245926 -281.869466) (xy 334.255257 -281.849444) (xy 334.255872 -281.8384) (xy 334.255872 -281.760676)
			(xy 334.255262 -281.749636) (xy 334.245905 -281.72963) (xy 334.237838 -281.722068) (xy 334.217133 -281.703851)
			(xy 334.180671 -281.662479) (xy 334.150545 -281.616289) (xy 334.127382 -281.566242) (xy 334.111664 -281.513383)
			(xy 334.10372 -281.458811) (xy 334.103218 -281.431238) (xy 334.103845 -281.399577) (xy 334.114297 -281.337125)
			(xy 334.134904 -281.277251) (xy 334.149446 -281.24912) (xy 334.15605 -281.237182) (xy 334.155542 -281.210512)
			(xy 334.10398 -281.123644) (xy 334.099175 -281.116278) (xy 334.085618 -281.105096) (xy 334.069079 -281.099156)
			(xy 334.060292 -281.098752) (xy 332.038706 -281.098752) (xy 332.028694 -281.099238) (xy 332.010192 -281.106895)
			(xy 331.996025 -281.121047) (xy 331.988349 -281.139541) (xy 331.987906 -281.149552) (xy 331.987906 -286.462724)
			(xy 331.9889 -286.473542) (xy 331.998718 -286.492899) (xy 332.015627 -286.506506) (xy 332.026006 -286.509714)
			(xy 332.10686 -286.526734) (xy 332.266958 -286.567668) (xy 332.424864 -286.616379) (xy 332.5802 -286.672752)
			(xy 332.732594 -286.736652) (xy 332.881682 -286.807925) (xy 333.027108 -286.886401) (xy 333.168523 -286.971893)
			(xy 333.305589 -287.064196) (xy 333.43798 -287.16309) (xy 333.565377 -287.268337) (xy 333.687477 -287.379687)
			(xy 333.803987 -287.496873) (xy 333.914629 -287.619614) (xy 334.019138 -287.747618) (xy 334.117264 -287.880578)
			(xy 334.208773 -288.018176) (xy 334.293446 -288.160083) (xy 334.371081 -288.30596) (xy 334.44149 -288.455457)
			(xy 334.504508 -288.608219) (xy 334.559981 -288.763878) (xy 334.607779 -288.922063) (xy 334.647786 -289.082395)
			(xy 334.679908 -289.244492) (xy 334.704066 -289.407965) (xy 334.720204 -289.572424) (xy 334.728283 -289.737475)
			(xy 334.728283 -289.902724) (xy 334.720204 -290.067775) (xy 334.704066 -290.232233) (xy 334.679908 -290.395707)
			(xy 334.647787 -290.557803) (xy 334.60778 -290.718136) (xy 334.559982 -290.876321) (xy 334.504508 -291.03198)
			(xy 334.441491 -291.184741) (xy 334.371081 -291.334239) (xy 334.293447 -291.480116) (xy 334.208774 -291.622023)
			(xy 334.117265 -291.759621) (xy 334.019139 -291.892581) (xy 333.91463 -292.020584) (xy 333.803988 -292.143326)
			(xy 333.687478 -292.260512) (xy 333.565378 -292.371861) (xy 333.437981 -292.477109) (xy 333.305591 -292.576003)
			(xy 333.168524 -292.668306) (xy 333.027109 -292.753798) (xy 332.881684 -292.832274) (xy 332.732596 -292.903548)
			(xy 332.580202 -292.967447) (xy 332.424866 -293.02382) (xy 332.26696 -293.072532) (xy 332.106861 -293.113466)
			(xy 332.026006 -293.130478) (xy 332.015621 -293.133676) (xy 331.998703 -293.14728) (xy 331.988896 -293.166647)
			(xy 331.987906 -293.177468) (xy 331.987906 -294.851836) (xy 334.24698 -294.851836) (xy 334.251051 -294.796214)
			(xy 334.263177 -294.741777) (xy 334.2831 -294.689686) (xy 334.310396 -294.641051) (xy 334.344482 -294.596908)
			(xy 334.384631 -294.558199) (xy 334.429989 -294.525748) (xy 334.479589 -294.500247) (xy 334.532373 -294.48224)
			(xy 334.587216 -294.47211) (xy 334.64295 -294.470073) (xy 334.698387 -294.476173) (xy 334.752344 -294.490279)
			(xy 334.803673 -294.512091) (xy 334.851279 -294.541145) (xy 334.894147 -294.57682) (xy 334.931364 -294.618357)
			(xy 334.962137 -294.66487) (xy 334.985809 -294.715367) (xy 335.001877 -294.768774) (xy 335.009997 -294.82395)
			(xy 335.010506 -294.851836) (xy 335.009997 -294.879722) (xy 335.001877 -294.934898) (xy 334.985809 -294.988305)
			(xy 334.962137 -295.038802) (xy 334.931364 -295.085315) (xy 334.894147 -295.126852) (xy 334.851279 -295.162527)
			(xy 334.803673 -295.191581) (xy 334.752344 -295.213393) (xy 334.698387 -295.227499) (xy 334.64295 -295.233599)
			(xy 334.587216 -295.231562) (xy 334.532373 -295.221432) (xy 334.479589 -295.203425) (xy 334.429989 -295.177924)
			(xy 334.384631 -295.145473) (xy 334.344482 -295.106764) (xy 334.310396 -295.062621) (xy 334.2831 -295.013986)
			(xy 334.263177 -294.961895) (xy 334.251051 -294.907458) (xy 334.24698 -294.851836) (xy 331.987906 -294.851836)
			(xy 331.987906 -298.420536) (xy 335.694782 -298.420536) (xy 335.695249 -298.393166) (xy 335.703064 -298.338986)
			(xy 335.718551 -298.286482) (xy 335.741393 -298.236735) (xy 335.77112 -298.190769) (xy 335.788762 -298.169838)
			(xy 335.789016 -298.169584) (xy 335.794617 -298.162508) (xy 335.800855 -298.145583) (xy 335.801208 -298.136564)
			(xy 335.801208 -298.069508) (xy 335.800845 -298.060492) (xy 335.794602 -298.043575) (xy 335.789016 -298.036488)
			(xy 335.788762 -298.036488) (xy 335.788762 -298.036234) (xy 335.771155 -298.015273) (xy 335.741426 -297.969311)
			(xy 335.718577 -297.91957) (xy 335.703076 -297.867072) (xy 335.695243 -297.812896) (xy 335.695239 -297.758158)
			(xy 335.703064 -297.703981) (xy 335.718558 -297.651481) (xy 335.7414 -297.601736) (xy 335.771122 -297.55577)
			(xy 335.788762 -297.534838) (xy 335.789016 -297.534584) (xy 335.794617 -297.527508) (xy 335.800855 -297.510583)
			(xy 335.801208 -297.501564) (xy 335.801208 -297.434508) (xy 335.800845 -297.425492) (xy 335.794602 -297.408575)
			(xy 335.789016 -297.401488) (xy 335.788762 -297.401488) (xy 335.788762 -297.401234) (xy 335.771155 -297.380273)
			(xy 335.741426 -297.334311) (xy 335.718577 -297.28457) (xy 335.703076 -297.232072) (xy 335.695243 -297.177896)
			(xy 335.695239 -297.123158) (xy 335.703064 -297.068981) (xy 335.718558 -297.016481) (xy 335.7414 -296.966736)
			(xy 335.771122 -296.92077) (xy 335.788762 -296.899838) (xy 335.789016 -296.899584) (xy 335.794617 -296.892508)
			(xy 335.800855 -296.875583) (xy 335.801208 -296.866564) (xy 335.801208 -296.799508) (xy 335.800845 -296.790492)
			(xy 335.794602 -296.773575) (xy 335.789016 -296.766488) (xy 335.788762 -296.766488) (xy 335.788762 -296.766234)
			(xy 335.771155 -296.745273) (xy 335.741426 -296.699311) (xy 335.718577 -296.64957) (xy 335.703076 -296.597072)
			(xy 335.695243 -296.542896) (xy 335.695239 -296.488158) (xy 335.703064 -296.433981) (xy 335.718558 -296.381481)
			(xy 335.7414 -296.331736) (xy 335.771122 -296.28577) (xy 335.788762 -296.264838) (xy 335.789016 -296.264584)
			(xy 335.794617 -296.257508) (xy 335.800855 -296.240583) (xy 335.801208 -296.231564) (xy 335.801208 -296.164508)
			(xy 335.800845 -296.155492) (xy 335.794602 -296.138575) (xy 335.789016 -296.131488) (xy 335.788762 -296.131488)
			(xy 335.788762 -296.131234) (xy 335.771155 -296.110273) (xy 335.741426 -296.064311) (xy 335.718577 -296.01457)
			(xy 335.703076 -295.962072) (xy 335.695243 -295.907896) (xy 335.695239 -295.853158) (xy 335.703064 -295.798981)
			(xy 335.718558 -295.746481) (xy 335.7414 -295.696736) (xy 335.771122 -295.65077) (xy 335.788762 -295.629838)
			(xy 335.789016 -295.629584) (xy 335.794617 -295.622508) (xy 335.800855 -295.605583) (xy 335.801208 -295.596564)
			(xy 335.801208 -295.529508) (xy 335.800845 -295.520492) (xy 335.794602 -295.503575) (xy 335.789016 -295.496488)
			(xy 335.788762 -295.496488) (xy 335.788762 -295.496234) (xy 335.771119 -295.475305) (xy 335.741409 -295.429331)
			(xy 335.718574 -295.379582) (xy 335.703084 -295.327081) (xy 335.695256 -295.272905) (xy 335.694782 -295.245536)
			(xy 335.695289 -295.218284) (xy 335.703041 -295.164336) (xy 335.718392 -295.112039) (xy 335.741029 -295.06246)
			(xy 335.770492 -295.016607) (xy 335.806182 -294.975414) (xy 335.84737 -294.93972) (xy 335.893219 -294.910251)
			(xy 335.942796 -294.887608) (xy 335.995091 -294.87225) (xy 336.049039 -294.864492) (xy 336.07629 -294.864028)
			(xy 336.10366 -294.864493) (xy 336.15784 -294.87231) (xy 336.210343 -294.887799) (xy 336.26009 -294.910641)
			(xy 336.306057 -294.940366) (xy 336.326988 -294.958008) (xy 336.327242 -294.958262) (xy 336.334336 -294.963838)
			(xy 336.351247 -294.970089) (xy 336.360262 -294.970454) (xy 336.427318 -294.970454) (xy 336.436337 -294.970116)
			(xy 336.453254 -294.963856) (xy 336.460338 -294.958262) (xy 336.460338 -294.958008) (xy 336.460592 -294.958008)
			(xy 336.481517 -294.94036) (xy 336.527492 -294.91065) (xy 336.577241 -294.887815) (xy 336.629743 -294.872326)
			(xy 336.68392 -294.864501) (xy 336.71129 -294.864028) (xy 336.738544 -294.864465) (xy 336.792498 -294.872221)
			(xy 336.844799 -294.887578) (xy 336.894381 -294.910222) (xy 336.940236 -294.939692) (xy 336.98143 -294.975389)
			(xy 337.017123 -295.016585) (xy 337.046591 -295.062442) (xy 337.069231 -295.112026) (xy 337.084584 -295.164327)
			(xy 337.092337 -295.218282) (xy 337.092798 -295.245536) (xy 337.092354 -295.272907) (xy 337.084531 -295.327087)
			(xy 337.069036 -295.37959) (xy 337.04619 -295.429337) (xy 337.016461 -295.475303) (xy 336.998818 -295.496234)
			(xy 336.998564 -295.496488) (xy 336.992972 -295.503571) (xy 336.98673 -295.520491) (xy 336.986372 -295.529508)
			(xy 336.986372 -295.596564) (xy 336.986752 -295.605578) (xy 336.992984 -295.622495) (xy 336.998564 -295.629584)
			(xy 336.998818 -295.629584) (xy 336.998818 -295.629838) (xy 337.016492 -295.650743) (xy 337.046212 -295.696717)
			(xy 337.069052 -295.746468) (xy 337.084544 -295.798974) (xy 337.092368 -295.853155) (xy 337.092364 -295.907899)
			(xy 337.084532 -295.962079) (xy 337.069033 -296.014583) (xy 337.046186 -296.064331) (xy 337.016459 -296.1103)
			(xy 336.998818 -296.131234) (xy 336.998564 -296.131488) (xy 336.992972 -296.138571) (xy 336.98673 -296.155491)
			(xy 336.986372 -296.164508) (xy 336.986372 -296.231564) (xy 336.986752 -296.240578) (xy 336.992984 -296.257495)
			(xy 336.998564 -296.264584) (xy 336.998818 -296.264584) (xy 336.998818 -296.264838) (xy 337.016492 -296.285743)
			(xy 337.046212 -296.331717) (xy 337.069052 -296.381468) (xy 337.084544 -296.433974) (xy 337.092368 -296.488155)
			(xy 337.092364 -296.542899) (xy 337.084532 -296.597079) (xy 337.069033 -296.649583) (xy 337.046186 -296.699331)
			(xy 337.016459 -296.7453) (xy 336.998818 -296.766234) (xy 336.998564 -296.766488) (xy 336.992972 -296.773571)
			(xy 336.98673 -296.790491) (xy 336.986372 -296.799508) (xy 336.986372 -296.866564) (xy 336.986752 -296.875578)
			(xy 336.992984 -296.892495) (xy 336.998564 -296.899584) (xy 336.998818 -296.899584) (xy 336.998818 -296.899838)
			(xy 337.016492 -296.920743) (xy 337.046212 -296.966717) (xy 337.069052 -297.016468) (xy 337.084544 -297.068974)
			(xy 337.092368 -297.123155) (xy 337.092364 -297.177899) (xy 337.084532 -297.232079) (xy 337.069033 -297.284583)
			(xy 337.046186 -297.334331) (xy 337.016459 -297.3803) (xy 336.998818 -297.401234) (xy 336.998564 -297.401488)
			(xy 336.992972 -297.408571) (xy 336.98673 -297.425491) (xy 336.986372 -297.434508) (xy 336.986372 -297.501564)
			(xy 336.986752 -297.510578) (xy 336.992984 -297.527495) (xy 336.998564 -297.534584) (xy 336.998818 -297.534584)
			(xy 336.998818 -297.534838) (xy 337.016492 -297.555743) (xy 337.046212 -297.601717) (xy 337.069052 -297.651468)
			(xy 337.084544 -297.703974) (xy 337.092368 -297.758155) (xy 337.092364 -297.812899) (xy 337.084532 -297.867079)
			(xy 337.069033 -297.919583) (xy 337.046186 -297.969331) (xy 337.016459 -298.0153) (xy 336.998818 -298.036234)
			(xy 336.998564 -298.036488) (xy 336.992972 -298.043571) (xy 336.98673 -298.060491) (xy 336.986372 -298.069508)
			(xy 336.986372 -298.136564) (xy 336.986752 -298.145578) (xy 336.992984 -298.162495) (xy 336.998564 -298.169584)
			(xy 336.998818 -298.169584) (xy 336.998818 -298.169838) (xy 337.016444 -298.19078) (xy 337.046157 -298.236751)
			(xy 337.068996 -298.286496) (xy 337.08449 -298.338994) (xy 337.092322 -298.393168) (xy 337.092798 -298.420536)
			(xy 337.092356 -298.447789) (xy 337.084594 -298.501738) (xy 337.069234 -298.554035) (xy 337.046588 -298.603613)
			(xy 337.017117 -298.649463) (xy 336.981421 -298.690653) (xy 336.940226 -298.726344) (xy 336.894372 -298.75581)
			(xy 336.844791 -298.77845) (xy 336.792493 -298.793804) (xy 336.738543 -298.801559) (xy 336.71129 -298.802044)
			(xy 336.683919 -298.801597) (xy 336.629738 -298.793777) (xy 336.577235 -298.778284) (xy 336.527488 -298.755438)
			(xy 336.481523 -298.725708) (xy 336.460592 -298.708064) (xy 336.460338 -298.70781) (xy 336.453244 -298.702234)
			(xy 336.436333 -298.695981) (xy 336.427318 -298.695618) (xy 336.360262 -298.695618) (xy 336.351243 -298.695953)
			(xy 336.334326 -298.702215) (xy 336.327242 -298.70781) (xy 336.327242 -298.708064) (xy 336.326988 -298.708064)
			(xy 336.306029 -298.72567) (xy 336.260064 -298.755388) (xy 336.210324 -298.778231) (xy 336.157829 -298.79373)
			(xy 336.103657 -298.801566) (xy 336.07629 -298.802044) (xy 336.04904 -298.801532) (xy 335.995095 -298.793775)
			(xy 335.942803 -298.77842) (xy 335.893228 -298.75578) (xy 335.84738 -298.726316) (xy 335.806191 -298.690628)
			(xy 335.770499 -298.649441) (xy 335.741032 -298.603595) (xy 335.718389 -298.554021) (xy 335.703031 -298.50173)
			(xy 335.69527 -298.447786) (xy 335.694782 -298.420536) (xy 331.987906 -298.420536) (xy 331.987906 -301.424086)
			(xy 335.023714 -301.424086) (xy 335.024168 -301.396715) (xy 335.031989 -301.342536) (xy 335.04748 -301.290032)
			(xy 335.070325 -301.240286) (xy 335.100052 -301.194319) (xy 335.117694 -301.173388) (xy 335.117948 -301.173134)
			(xy 335.123532 -301.166046) (xy 335.129779 -301.14913) (xy 335.13014 -301.140114) (xy 335.13014 -301.073058)
			(xy 335.129768 -301.064042) (xy 335.123532 -301.047125) (xy 335.117948 -301.040038) (xy 335.117694 -301.040038)
			(xy 335.117694 -301.039784) (xy 335.100041 -301.018862) (xy 335.070319 -300.972891) (xy 335.047477 -300.923143)
			(xy 335.031983 -300.87064) (xy 335.024156 -300.81646) (xy 335.024158 -300.761719) (xy 335.031987 -300.70754)
			(xy 335.047484 -300.655037) (xy 335.070329 -300.60529) (xy 335.100054 -300.559321) (xy 335.117694 -300.538388)
			(xy 335.117948 -300.538134) (xy 335.123532 -300.531046) (xy 335.129779 -300.51413) (xy 335.13014 -300.505114)
			(xy 335.13014 -300.438058) (xy 335.129768 -300.429042) (xy 335.123532 -300.412125) (xy 335.117948 -300.405038)
			(xy 335.117694 -300.405038) (xy 335.117694 -300.404784) (xy 335.100041 -300.383862) (xy 335.070319 -300.337891)
			(xy 335.047477 -300.288143) (xy 335.031983 -300.23564) (xy 335.024156 -300.18146) (xy 335.024158 -300.126719)
			(xy 335.031987 -300.07254) (xy 335.047484 -300.020037) (xy 335.070329 -299.97029) (xy 335.100054 -299.924321)
			(xy 335.117694 -299.903388) (xy 335.117948 -299.903134) (xy 335.123532 -299.896046) (xy 335.129779 -299.87913)
			(xy 335.13014 -299.870114) (xy 335.13014 -299.803058) (xy 335.129768 -299.794042) (xy 335.123532 -299.777125)
			(xy 335.117948 -299.770038) (xy 335.117694 -299.770038) (xy 335.117694 -299.769784) (xy 335.10008 -299.748832)
			(xy 335.070365 -299.702864) (xy 335.047524 -299.653122) (xy 335.032027 -299.600626) (xy 335.024192 -299.546454)
			(xy 335.023714 -299.519086) (xy 335.0242 -299.491835) (xy 335.031956 -299.437887) (xy 335.047311 -299.385592)
			(xy 335.069953 -299.336015) (xy 335.099419 -299.290165) (xy 335.13511 -299.248974) (xy 335.176301 -299.213283)
			(xy 335.222151 -299.183817) (xy 335.271728 -299.161175) (xy 335.324023 -299.14582) (xy 335.377971 -299.138064)
			(xy 335.432473 -299.138064) (xy 335.486421 -299.14582) (xy 335.538716 -299.161175) (xy 335.588293 -299.183817)
			(xy 335.634143 -299.213283) (xy 335.675334 -299.248974) (xy 335.711025 -299.290165) (xy 335.740491 -299.336015)
			(xy 335.763133 -299.385592) (xy 335.778488 -299.437887) (xy 335.786244 -299.491835) (xy 335.78673 -299.519086)
			(xy 335.786273 -299.546457) (xy 335.778455 -299.600637) (xy 335.762965 -299.653141) (xy 335.740121 -299.702888)
			(xy 335.710393 -299.748853) (xy 335.69275 -299.769784) (xy 335.692496 -299.770038) (xy 335.686929 -299.777138)
			(xy 335.680671 -299.794044) (xy 335.680304 -299.803058) (xy 335.680304 -299.870114) (xy 335.680654 -299.879132)
			(xy 335.686906 -299.896049) (xy 335.692496 -299.903134) (xy 335.69275 -299.903134) (xy 335.69275 -299.903388)
			(xy 335.710378 -299.924331) (xy 335.740105 -299.970297) (xy 335.762953 -300.020041) (xy 335.778451 -300.072542)
			(xy 335.786281 -300.126719) (xy 335.786283 -300.18146) (xy 335.778455 -300.235638) (xy 335.76296 -300.288139)
			(xy 335.740115 -300.337885) (xy 335.710391 -300.383852) (xy 335.69275 -300.404784) (xy 335.692496 -300.405038)
			(xy 335.686929 -300.412138) (xy 335.680671 -300.429044) (xy 335.680304 -300.438058) (xy 335.680304 -300.505114)
			(xy 335.680654 -300.514132) (xy 335.686906 -300.531049) (xy 335.692496 -300.538134) (xy 335.69275 -300.538134)
			(xy 335.69275 -300.538388) (xy 335.710378 -300.559331) (xy 335.740105 -300.605297) (xy 335.762953 -300.655041)
			(xy 335.778451 -300.707542) (xy 335.786281 -300.761719) (xy 335.786283 -300.81646) (xy 335.778455 -300.870638)
			(xy 335.76296 -300.923139) (xy 335.740115 -300.972885) (xy 335.710391 -301.018852) (xy 335.69275 -301.039784)
			(xy 335.692496 -301.040038) (xy 335.686929 -301.047138) (xy 335.680671 -301.064044) (xy 335.680304 -301.073058)
			(xy 335.680304 -301.140114) (xy 335.680654 -301.149132) (xy 335.686906 -301.166049) (xy 335.692496 -301.173134)
			(xy 335.69275 -301.173134) (xy 335.69275 -301.173388) (xy 335.710389 -301.19432) (xy 335.740103 -301.240292)
			(xy 335.762939 -301.29004) (xy 335.77843 -301.342541) (xy 335.786257 -301.396717) (xy 335.78673 -301.424086)
			(xy 335.786244 -301.451337) (xy 335.78242 -301.477934) (xy 338.655914 -301.477934) (xy 338.656397 -301.450564)
			(xy 338.66421 -301.396386) (xy 338.679695 -301.343883) (xy 338.702533 -301.294136) (xy 338.732254 -301.248168)
			(xy 338.749894 -301.227236) (xy 338.750148 -301.226982) (xy 338.755754 -301.219909) (xy 338.761988 -301.202982)
			(xy 338.76234 -301.193962) (xy 338.76234 -301.126906) (xy 338.761993 -301.117888) (xy 338.75574 -301.10097)
			(xy 338.750148 -301.093886) (xy 338.749894 -301.093886) (xy 338.749894 -301.093632) (xy 338.732288 -301.072672)
			(xy 338.702564 -301.026708) (xy 338.679719 -300.976966) (xy 338.664222 -300.924468) (xy 338.65639 -300.870294)
			(xy 338.656387 -300.815557) (xy 338.664211 -300.761382) (xy 338.679701 -300.708882) (xy 338.70254 -300.659137)
			(xy 338.732257 -300.613169) (xy 338.749894 -300.592236) (xy 338.750148 -300.591982) (xy 338.755754 -300.584909)
			(xy 338.761988 -300.567982) (xy 338.76234 -300.558962) (xy 338.76234 -300.491906) (xy 338.761993 -300.482888)
			(xy 338.75574 -300.46597) (xy 338.750148 -300.458886) (xy 338.749894 -300.458886) (xy 338.749894 -300.458632)
			(xy 338.732288 -300.437672) (xy 338.702564 -300.391708) (xy 338.679719 -300.341966) (xy 338.664222 -300.289468)
			(xy 338.65639 -300.235294) (xy 338.656387 -300.180557) (xy 338.664211 -300.126382) (xy 338.679701 -300.073882)
			(xy 338.70254 -300.024137) (xy 338.732257 -299.978169) (xy 338.749894 -299.957236) (xy 338.750148 -299.956982)
			(xy 338.755754 -299.949909) (xy 338.761988 -299.932982) (xy 338.76234 -299.923962) (xy 338.76234 -299.856906)
			(xy 338.761993 -299.847888) (xy 338.75574 -299.83097) (xy 338.750148 -299.823886) (xy 338.749894 -299.823886)
			(xy 338.749894 -299.823632) (xy 338.732256 -299.802699) (xy 338.702544 -299.756727) (xy 338.679708 -299.706979)
			(xy 338.664217 -299.654479) (xy 338.656388 -299.600303) (xy 338.655914 -299.572934) (xy 338.6564 -299.545683)
			(xy 338.664156 -299.491735) (xy 338.679511 -299.43944) (xy 338.702153 -299.389863) (xy 338.731619 -299.344013)
			(xy 338.76731 -299.302822) (xy 338.808501 -299.267131) (xy 338.854351 -299.237665) (xy 338.903928 -299.215023)
			(xy 338.956223 -299.199668) (xy 339.010171 -299.191912) (xy 339.064673 -299.191912) (xy 339.118621 -299.199668)
			(xy 339.170916 -299.215023) (xy 339.220493 -299.237665) (xy 339.266343 -299.267131) (xy 339.307534 -299.302822)
			(xy 339.343225 -299.344013) (xy 339.372691 -299.389863) (xy 339.395333 -299.43944) (xy 339.410688 -299.491735)
			(xy 339.418444 -299.545683) (xy 339.41893 -299.572934) (xy 339.418501 -299.600306) (xy 339.410677 -299.654487)
			(xy 339.39518 -299.706991) (xy 339.37233 -299.756738) (xy 339.342596 -299.802702) (xy 339.32495 -299.823632)
			(xy 339.324696 -299.823886) (xy 339.319109 -299.830972) (xy 339.312863 -299.847889) (xy 339.312504 -299.856906)
			(xy 339.312504 -299.923962) (xy 339.312879 -299.932977) (xy 339.319114 -299.949894) (xy 339.324696 -299.956982)
			(xy 339.32495 -299.956982) (xy 339.32495 -299.957236) (xy 339.342625 -299.978141) (xy 339.37235 -300.024113)
			(xy 339.395195 -300.073864) (xy 339.41069 -300.12637) (xy 339.418515 -300.180553) (xy 339.418512 -300.235298)
			(xy 339.410679 -300.28948) (xy 339.395177 -300.341984) (xy 339.372325 -300.391732) (xy 339.342594 -300.4377)
			(xy 339.32495 -300.458632) (xy 339.324696 -300.458886) (xy 339.319109 -300.465972) (xy 339.312863 -300.482889)
			(xy 339.312504 -300.491906) (xy 339.312504 -300.558962) (xy 339.312879 -300.567977) (xy 339.319114 -300.584894)
			(xy 339.324696 -300.591982) (xy 339.32495 -300.591982) (xy 339.32495 -300.592236) (xy 339.342625 -300.613141)
			(xy 339.37235 -300.659113) (xy 339.395195 -300.708864) (xy 339.41069 -300.76137) (xy 339.418515 -300.815553)
			(xy 339.418512 -300.870298) (xy 339.410679 -300.92448) (xy 339.395177 -300.976984) (xy 339.372325 -301.026732)
			(xy 339.342594 -301.0727) (xy 339.32495 -301.093632) (xy 339.324696 -301.093886) (xy 339.319109 -301.100972)
			(xy 339.312863 -301.117889) (xy 339.312504 -301.126906) (xy 339.312504 -301.193962) (xy 339.312879 -301.202977)
			(xy 339.319114 -301.219894) (xy 339.324696 -301.226982) (xy 339.32495 -301.226982) (xy 339.32495 -301.227236)
			(xy 339.342565 -301.248188) (xy 339.372282 -301.294154) (xy 339.395123 -301.343897) (xy 339.41062 -301.396393)
			(xy 339.414624 -301.424086) (xy 341.863934 -301.424086) (xy 341.864384 -301.396715) (xy 341.872204 -301.342535)
			(xy 341.887697 -301.290031) (xy 341.910542 -301.240285) (xy 341.940271 -301.194319) (xy 341.957914 -301.173388)
			(xy 341.958168 -301.173134) (xy 341.963754 -301.166048) (xy 341.969999 -301.14913) (xy 341.97036 -301.140114)
			(xy 341.97036 -301.073058) (xy 341.969984 -301.064043) (xy 341.963751 -301.047125) (xy 341.958168 -301.040038)
			(xy 341.957914 -301.040038) (xy 341.957914 -301.039784) (xy 341.94026 -301.018862) (xy 341.910537 -300.972892)
			(xy 341.887693 -300.923144) (xy 341.872199 -300.87064) (xy 341.864372 -300.816461) (xy 341.864373 -300.761718)
			(xy 341.872203 -300.707539) (xy 341.887701 -300.655036) (xy 341.910547 -300.605289) (xy 341.940273 -300.559321)
			(xy 341.957914 -300.538388) (xy 341.958168 -300.538134) (xy 341.963754 -300.531048) (xy 341.969999 -300.51413)
			(xy 341.97036 -300.505114) (xy 341.97036 -300.438058) (xy 341.969984 -300.429043) (xy 341.963751 -300.412125)
			(xy 341.958168 -300.405038) (xy 341.957914 -300.405038) (xy 341.957914 -300.404784) (xy 341.94026 -300.383862)
			(xy 341.910537 -300.337892) (xy 341.887693 -300.288144) (xy 341.872199 -300.23564) (xy 341.864372 -300.181461)
			(xy 341.864373 -300.126718) (xy 341.872203 -300.072539) (xy 341.887701 -300.020036) (xy 341.910547 -299.970289)
			(xy 341.940273 -299.924321) (xy 341.957914 -299.903388) (xy 341.958168 -299.903134) (xy 341.963754 -299.896048)
			(xy 341.969999 -299.87913) (xy 341.97036 -299.870114) (xy 341.97036 -299.803058) (xy 341.969984 -299.794043)
			(xy 341.963751 -299.777125) (xy 341.958168 -299.770038) (xy 341.957914 -299.770038) (xy 341.957914 -299.769784)
			(xy 341.940303 -299.748829) (xy 341.910586 -299.702863) (xy 341.887745 -299.653121) (xy 341.872247 -299.600625)
			(xy 341.864412 -299.546454) (xy 341.863934 -299.519086) (xy 341.86442 -299.491835) (xy 341.872176 -299.437887)
			(xy 341.887531 -299.385592) (xy 341.910173 -299.336015) (xy 341.939639 -299.290165) (xy 341.97533 -299.248974)
			(xy 342.016521 -299.213283) (xy 342.062371 -299.183817) (xy 342.111948 -299.161175) (xy 342.164243 -299.14582)
			(xy 342.218191 -299.138064) (xy 342.272693 -299.138064) (xy 342.326641 -299.14582) (xy 342.378936 -299.161175)
			(xy 342.428513 -299.183817) (xy 342.474363 -299.213283) (xy 342.515554 -299.248974) (xy 342.551245 -299.290165)
			(xy 342.580711 -299.336015) (xy 342.603353 -299.385592) (xy 342.618708 -299.437887) (xy 342.626464 -299.491835)
			(xy 342.62695 -299.519086) (xy 342.626488 -299.546457) (xy 342.618671 -299.600636) (xy 342.603182 -299.65314)
			(xy 342.580339 -299.702887) (xy 342.550612 -299.748853) (xy 342.53297 -299.769784) (xy 342.532716 -299.770038)
			(xy 342.527151 -299.777139) (xy 342.520891 -299.794045) (xy 342.520524 -299.803058) (xy 342.520524 -299.870114)
			(xy 342.520869 -299.879132) (xy 342.527124 -299.896049) (xy 342.532716 -299.903134) (xy 342.53297 -299.903134)
			(xy 342.53297 -299.903388) (xy 342.550597 -299.924332) (xy 342.580323 -299.970298) (xy 342.603169 -300.020042)
			(xy 342.618667 -300.072542) (xy 342.626497 -300.126719) (xy 342.626498 -300.181459) (xy 342.618671 -300.235637)
			(xy 342.603176 -300.288138) (xy 342.580333 -300.337884) (xy 342.55061 -300.383851) (xy 342.53297 -300.404784)
			(xy 342.532716 -300.405038) (xy 342.527151 -300.412139) (xy 342.520891 -300.429045) (xy 342.520524 -300.438058)
			(xy 342.520524 -300.505114) (xy 342.520869 -300.514132) (xy 342.527124 -300.531049) (xy 342.532716 -300.538134)
			(xy 342.53297 -300.538134) (xy 342.53297 -300.538388) (xy 342.550597 -300.559332) (xy 342.580323 -300.605298)
			(xy 342.603169 -300.655042) (xy 342.618667 -300.707542) (xy 342.626497 -300.761719) (xy 342.626498 -300.816459)
			(xy 342.618671 -300.870637) (xy 342.603176 -300.923138) (xy 342.580333 -300.972884) (xy 342.55061 -301.018851)
			(xy 342.53297 -301.039784) (xy 342.532716 -301.040038) (xy 342.527151 -301.047139) (xy 342.520891 -301.064045)
			(xy 342.520524 -301.073058) (xy 342.520524 -301.140114) (xy 342.520869 -301.149132) (xy 342.527124 -301.166049)
			(xy 342.532716 -301.173134) (xy 342.53297 -301.173134) (xy 342.53297 -301.173388) (xy 342.550612 -301.194318)
			(xy 342.580325 -301.240291) (xy 342.60316 -301.290039) (xy 342.618651 -301.34254) (xy 342.626477 -301.396717)
			(xy 342.62695 -301.424086) (xy 342.626464 -301.451337) (xy 342.62264 -301.477934) (xy 345.496134 -301.477934)
			(xy 345.496612 -301.450564) (xy 345.504425 -301.396385) (xy 345.519911 -301.343882) (xy 345.542751 -301.294135)
			(xy 345.572473 -301.248168) (xy 345.590114 -301.227236) (xy 345.590368 -301.226982) (xy 345.595976 -301.219911)
			(xy 345.602208 -301.202982) (xy 345.60256 -301.193962) (xy 345.60256 -301.126906) (xy 345.602209 -301.117888)
			(xy 345.595958 -301.100971) (xy 345.590368 -301.093886) (xy 345.590114 -301.093886) (xy 345.590114 -301.093632)
			(xy 345.572507 -301.072672) (xy 345.542782 -301.026709) (xy 345.519935 -300.976967) (xy 345.504437 -300.924469)
			(xy 345.496606 -300.870294) (xy 345.496602 -300.815557) (xy 345.504426 -300.761381) (xy 345.519917 -300.708881)
			(xy 345.542757 -300.659136) (xy 345.572476 -300.613169) (xy 345.590114 -300.592236) (xy 345.590368 -300.591982)
			(xy 345.595976 -300.584911) (xy 345.602208 -300.567982) (xy 345.60256 -300.558962) (xy 345.60256 -300.491906)
			(xy 345.602209 -300.482888) (xy 345.595958 -300.465971) (xy 345.590368 -300.458886) (xy 345.590114 -300.458886)
			(xy 345.590114 -300.458632) (xy 345.572507 -300.437672) (xy 345.542782 -300.391709) (xy 345.519935 -300.341967)
			(xy 345.504437 -300.289469) (xy 345.496606 -300.235294) (xy 345.496602 -300.180557) (xy 345.504426 -300.126381)
			(xy 345.519917 -300.073881) (xy 345.542757 -300.024136) (xy 345.572476 -299.978169) (xy 345.590114 -299.957236)
			(xy 345.590368 -299.956982) (xy 345.595976 -299.949911) (xy 345.602208 -299.932982) (xy 345.60256 -299.923962)
			(xy 345.60256 -299.856906) (xy 345.602209 -299.847888) (xy 345.595958 -299.830971) (xy 345.590368 -299.823886)
			(xy 345.590114 -299.823886) (xy 345.590114 -299.823632) (xy 345.572479 -299.802697) (xy 345.542766 -299.756725)
			(xy 345.519929 -299.706978) (xy 345.504437 -299.654478) (xy 345.496608 -299.600303) (xy 345.496134 -299.572934)
			(xy 345.49662 -299.545683) (xy 345.504376 -299.491735) (xy 345.519731 -299.43944) (xy 345.542373 -299.389863)
			(xy 345.571839 -299.344013) (xy 345.60753 -299.302822) (xy 345.648721 -299.267131) (xy 345.694571 -299.237665)
			(xy 345.744148 -299.215023) (xy 345.796443 -299.199668) (xy 345.850391 -299.191912) (xy 345.904893 -299.191912)
			(xy 345.958841 -299.199668) (xy 346.011136 -299.215023) (xy 346.060713 -299.237665) (xy 346.106563 -299.267131)
			(xy 346.147754 -299.302822) (xy 346.183445 -299.344013) (xy 346.212911 -299.389863) (xy 346.235553 -299.43944)
			(xy 346.250908 -299.491735) (xy 346.258664 -299.545683) (xy 346.25915 -299.572934) (xy 346.258716 -299.600306)
			(xy 346.250892 -299.654486) (xy 346.235396 -299.70699) (xy 346.212547 -299.756737) (xy 346.182815 -299.802702)
			(xy 346.16517 -299.823632) (xy 346.164916 -299.823886) (xy 346.159331 -299.830974) (xy 346.153083 -299.84789)
			(xy 346.152724 -299.856906) (xy 346.152724 -299.923962) (xy 346.153094 -299.932978) (xy 346.159332 -299.949895)
			(xy 346.164916 -299.956982) (xy 346.16517 -299.956982) (xy 346.16517 -299.957236) (xy 346.182844 -299.978142)
			(xy 346.212568 -300.024114) (xy 346.235411 -300.073865) (xy 346.250905 -300.126371) (xy 346.258731 -300.180553)
			(xy 346.258727 -300.235298) (xy 346.250894 -300.289479) (xy 346.235393 -300.341983) (xy 346.212543 -300.391731)
			(xy 346.182813 -300.437699) (xy 346.16517 -300.458632) (xy 346.164916 -300.458886) (xy 346.159331 -300.465974)
			(xy 346.153083 -300.48289) (xy 346.152724 -300.491906) (xy 346.152724 -300.558962) (xy 346.153094 -300.567978)
			(xy 346.159332 -300.584895) (xy 346.164916 -300.591982) (xy 346.16517 -300.591982) (xy 346.16517 -300.592236)
			(xy 346.182844 -300.613142) (xy 346.212568 -300.659114) (xy 346.235411 -300.708865) (xy 346.250905 -300.761371)
			(xy 346.258731 -300.815553) (xy 346.258727 -300.870298) (xy 346.250894 -300.924479) (xy 346.235393 -300.976983)
			(xy 346.212543 -301.026731) (xy 346.182813 -301.072699) (xy 346.16517 -301.093632) (xy 346.164916 -301.093886)
			(xy 346.159331 -301.100974) (xy 346.153083 -301.11789) (xy 346.152724 -301.126906) (xy 346.152724 -301.193962)
			(xy 346.153094 -301.202978) (xy 346.159332 -301.219895) (xy 346.164916 -301.226982) (xy 346.16517 -301.226982)
			(xy 346.16517 -301.227236) (xy 346.182788 -301.248185) (xy 346.212504 -301.294153) (xy 346.235344 -301.343896)
			(xy 346.25084 -301.396393) (xy 346.254845 -301.424086) (xy 353.617022 -301.424086) (xy 353.617475 -301.396715)
			(xy 353.625295 -301.342535) (xy 353.640787 -301.290032) (xy 353.663632 -301.240285) (xy 353.693359 -301.194319)
			(xy 353.711002 -301.173388) (xy 353.711256 -301.173134) (xy 353.716841 -301.166047) (xy 353.723087 -301.14913)
			(xy 353.723448 -301.140114) (xy 353.723448 -301.073058) (xy 353.723075 -301.064043) (xy 353.71684 -301.047125)
			(xy 353.711256 -301.040038) (xy 353.711002 -301.040038) (xy 353.711002 -301.039784) (xy 353.693349 -301.018862)
			(xy 353.663626 -300.972892) (xy 353.640783 -300.923143) (xy 353.625289 -300.87064) (xy 353.617462 -300.81646)
			(xy 353.617464 -300.761718) (xy 353.625294 -300.707539) (xy 353.640791 -300.655037) (xy 353.663636 -300.60529)
			(xy 353.693361 -300.559321) (xy 353.711002 -300.538388) (xy 353.711256 -300.538134) (xy 353.716841 -300.531047)
			(xy 353.723087 -300.51413) (xy 353.723448 -300.505114) (xy 353.723448 -300.438058) (xy 353.723075 -300.429043)
			(xy 353.71684 -300.412125) (xy 353.711256 -300.405038) (xy 353.711002 -300.405038) (xy 353.711002 -300.404784)
			(xy 353.693349 -300.383862) (xy 353.663626 -300.337892) (xy 353.640783 -300.288143) (xy 353.625289 -300.23564)
			(xy 353.617462 -300.18146) (xy 353.617464 -300.126718) (xy 353.625294 -300.072539) (xy 353.640791 -300.020037)
			(xy 353.663636 -299.97029) (xy 353.693361 -299.924321) (xy 353.711002 -299.903388) (xy 353.711256 -299.903134)
			(xy 353.716841 -299.896047) (xy 353.723087 -299.87913) (xy 353.723448 -299.870114) (xy 353.723448 -299.803058)
			(xy 353.723075 -299.794043) (xy 353.71684 -299.777125) (xy 353.711256 -299.770038) (xy 353.711002 -299.770038)
			(xy 353.711002 -299.769784) (xy 353.693389 -299.748831) (xy 353.663673 -299.702864) (xy 353.640832 -299.653122)
			(xy 353.625335 -299.600626) (xy 353.6175 -299.546454) (xy 353.617022 -299.519086) (xy 353.617508 -299.491835)
			(xy 353.625264 -299.437887) (xy 353.640619 -299.385592) (xy 353.663261 -299.336015) (xy 353.692727 -299.290165)
			(xy 353.728418 -299.248974) (xy 353.769609 -299.213283) (xy 353.815459 -299.183817) (xy 353.865036 -299.161175)
			(xy 353.917331 -299.14582) (xy 353.971279 -299.138064) (xy 354.025781 -299.138064) (xy 354.079729 -299.14582)
			(xy 354.132024 -299.161175) (xy 354.181601 -299.183817) (xy 354.227451 -299.213283) (xy 354.268642 -299.248974)
			(xy 354.304333 -299.290165) (xy 354.333799 -299.336015) (xy 354.356441 -299.385592) (xy 354.371796 -299.437887)
			(xy 354.379552 -299.491835) (xy 354.380038 -299.519086) (xy 354.379579 -299.546457) (xy 354.371762 -299.600637)
			(xy 354.356272 -299.65314) (xy 354.333428 -299.702887) (xy 354.303701 -299.748853) (xy 354.286058 -299.769784)
			(xy 354.285804 -299.770038) (xy 354.280238 -299.777139) (xy 354.273979 -299.794045) (xy 354.273612 -299.803058)
			(xy 354.273612 -299.870114) (xy 354.27396 -299.879132) (xy 354.280213 -299.896049) (xy 354.285804 -299.903134)
			(xy 354.286058 -299.903134) (xy 354.286058 -299.903388) (xy 354.303686 -299.924332) (xy 354.333412 -299.970297)
			(xy 354.356259 -300.020041) (xy 354.371757 -300.072542) (xy 354.379587 -300.126719) (xy 354.379589 -300.18146)
			(xy 354.371762 -300.235637) (xy 354.356267 -300.288139) (xy 354.333422 -300.337884) (xy 354.303698 -300.383852)
			(xy 354.286058 -300.404784) (xy 354.285804 -300.405038) (xy 354.280238 -300.412139) (xy 354.273979 -300.429045)
			(xy 354.273612 -300.438058) (xy 354.273612 -300.505114) (xy 354.27396 -300.514132) (xy 354.280213 -300.531049)
			(xy 354.285804 -300.538134) (xy 354.286058 -300.538134) (xy 354.286058 -300.538388) (xy 354.303686 -300.559332)
			(xy 354.333412 -300.605297) (xy 354.356259 -300.655041) (xy 354.371757 -300.707542) (xy 354.379587 -300.761719)
			(xy 354.379589 -300.81646) (xy 354.371762 -300.870637) (xy 354.356267 -300.923139) (xy 354.333422 -300.972884)
			(xy 354.303698 -301.018852) (xy 354.286058 -301.039784) (xy 354.285804 -301.040038) (xy 354.280238 -301.047139)
			(xy 354.273979 -301.064045) (xy 354.273612 -301.073058) (xy 354.273612 -301.140114) (xy 354.27396 -301.149132)
			(xy 354.280213 -301.166049) (xy 354.285804 -301.173134) (xy 354.286058 -301.173134) (xy 354.286058 -301.173388)
			(xy 354.303698 -301.194319) (xy 354.333411 -301.240292) (xy 354.356248 -301.290039) (xy 354.371738 -301.34254)
			(xy 354.379565 -301.396717) (xy 354.380038 -301.424086) (xy 354.379552 -301.451337) (xy 354.375728 -301.477934)
			(xy 357.249222 -301.477934) (xy 357.249703 -301.450564) (xy 357.257516 -301.396386) (xy 357.273002 -301.343882)
			(xy 357.29584 -301.294135) (xy 357.325562 -301.248168) (xy 357.343202 -301.227236) (xy 357.343456 -301.226982)
			(xy 357.349063 -301.21991) (xy 357.355296 -301.202982) (xy 357.355648 -301.193962) (xy 357.355648 -301.126906)
			(xy 357.355299 -301.117888) (xy 357.349047 -301.100971) (xy 357.343456 -301.093886) (xy 357.343202 -301.093886)
			(xy 357.343202 -301.093632) (xy 357.325596 -301.072672) (xy 357.295871 -301.026708) (xy 357.273026 -300.976966)
			(xy 357.257528 -300.924469) (xy 357.249697 -300.870294) (xy 357.249693 -300.815557) (xy 357.257517 -300.761381)
			(xy 357.273008 -300.708882) (xy 357.295847 -300.659137) (xy 357.325565 -300.613169) (xy 357.343202 -300.592236)
			(xy 357.343456 -300.591982) (xy 357.349063 -300.58491) (xy 357.355296 -300.567982) (xy 357.355648 -300.558962)
			(xy 357.355648 -300.491906) (xy 357.355299 -300.482888) (xy 357.349047 -300.465971) (xy 357.343456 -300.458886)
			(xy 357.343202 -300.458886) (xy 357.343202 -300.458632) (xy 357.325596 -300.437672) (xy 357.295871 -300.391708)
			(xy 357.273026 -300.341966) (xy 357.257528 -300.289469) (xy 357.249697 -300.235294) (xy 357.249693 -300.180557)
			(xy 357.257517 -300.126381) (xy 357.273008 -300.073882) (xy 357.295847 -300.024137) (xy 357.325565 -299.978169)
			(xy 357.343202 -299.957236) (xy 357.343456 -299.956982) (xy 357.349063 -299.94991) (xy 357.355296 -299.932982)
			(xy 357.355648 -299.923962) (xy 357.355648 -299.856906) (xy 357.355299 -299.847888) (xy 357.349047 -299.830971)
			(xy 357.343456 -299.823886) (xy 357.343202 -299.823886) (xy 357.343202 -299.823632) (xy 357.325565 -299.802698)
			(xy 357.295853 -299.756726) (xy 357.273016 -299.706979) (xy 357.257525 -299.654479) (xy 357.249696 -299.600303)
			(xy 357.249222 -299.572934) (xy 357.249708 -299.545683) (xy 357.257464 -299.491735) (xy 357.272819 -299.43944)
			(xy 357.295461 -299.389863) (xy 357.324927 -299.344013) (xy 357.360618 -299.302822) (xy 357.401809 -299.267131)
			(xy 357.447659 -299.237665) (xy 357.497236 -299.215023) (xy 357.549531 -299.199668) (xy 357.603479 -299.191912)
			(xy 357.657981 -299.191912) (xy 357.711929 -299.199668) (xy 357.764224 -299.215023) (xy 357.813801 -299.237665)
			(xy 357.859651 -299.267131) (xy 357.900842 -299.302822) (xy 357.936533 -299.344013) (xy 357.965999 -299.389863)
			(xy 357.988641 -299.43944) (xy 358.003996 -299.491735) (xy 358.011752 -299.545683) (xy 358.012238 -299.572934)
			(xy 358.011807 -299.600306) (xy 358.003983 -299.654487) (xy 357.988487 -299.706991) (xy 357.965637 -299.756737)
			(xy 357.935904 -299.802702) (xy 357.918258 -299.823632) (xy 357.918004 -299.823886) (xy 357.912418 -299.830973)
			(xy 357.906171 -299.847889) (xy 357.905812 -299.856906) (xy 357.905812 -299.923962) (xy 357.906185 -299.932977)
			(xy 357.912421 -299.949894) (xy 357.918004 -299.956982) (xy 357.918258 -299.956982) (xy 357.918258 -299.957236)
			(xy 357.935933 -299.978141) (xy 357.965657 -300.024114) (xy 357.988501 -300.073864) (xy 358.003996 -300.126371)
			(xy 358.011822 -300.180553) (xy 358.011818 -300.235298) (xy 358.003985 -300.289479) (xy 357.988483 -300.341984)
			(xy 357.965633 -300.391731) (xy 357.935902 -300.437699) (xy 357.918258 -300.458632) (xy 357.918004 -300.458886)
			(xy 357.912418 -300.465973) (xy 357.906171 -300.482889) (xy 357.905812 -300.491906) (xy 357.905812 -300.558962)
			(xy 357.906185 -300.567977) (xy 357.912421 -300.584894) (xy 357.918004 -300.591982) (xy 357.918258 -300.591982)
			(xy 357.918258 -300.592236) (xy 357.935933 -300.613141) (xy 357.965657 -300.659114) (xy 357.988501 -300.708864)
			(xy 358.003996 -300.761371) (xy 358.011822 -300.815553) (xy 358.011818 -300.870298) (xy 358.003985 -300.924479)
			(xy 357.988483 -300.976984) (xy 357.965633 -301.026731) (xy 357.935902 -301.072699) (xy 357.918258 -301.093632)
			(xy 357.918004 -301.093886) (xy 357.912418 -301.100973) (xy 357.906171 -301.117889) (xy 357.905812 -301.126906)
			(xy 357.905812 -301.193962) (xy 357.906185 -301.202977) (xy 357.912421 -301.219894) (xy 357.918004 -301.226982)
			(xy 357.918258 -301.226982) (xy 357.918258 -301.227236) (xy 357.935874 -301.248187) (xy 357.965591 -301.294154)
			(xy 357.988432 -301.343896) (xy 358.003928 -301.396393) (xy 358.007932 -301.424086) (xy 360.457242 -301.424086)
			(xy 360.45769 -301.396715) (xy 360.46551 -301.342535) (xy 360.481003 -301.290031) (xy 360.503849 -301.240284)
			(xy 360.533578 -301.194319) (xy 360.551222 -301.173388) (xy 360.551476 -301.173134) (xy 360.557063 -301.166048)
			(xy 360.563308 -301.149131) (xy 360.563668 -301.140114) (xy 360.563668 -301.073058) (xy 360.56329 -301.064043)
			(xy 360.557058 -301.047126) (xy 360.551476 -301.040038) (xy 360.551222 -301.040038) (xy 360.551222 -301.039784)
			(xy 360.533568 -301.018862) (xy 360.503844 -300.972892) (xy 360.481 -300.923144) (xy 360.465505 -300.870641)
			(xy 360.457678 -300.816461) (xy 360.457679 -300.761718) (xy 360.465509 -300.707539) (xy 360.481007 -300.655036)
			(xy 360.503854 -300.605289) (xy 360.533581 -300.559321) (xy 360.551222 -300.538388) (xy 360.551476 -300.538134)
			(xy 360.557063 -300.531048) (xy 360.563308 -300.514131) (xy 360.563668 -300.505114) (xy 360.563668 -300.438058)
			(xy 360.56329 -300.429043) (xy 360.557058 -300.412126) (xy 360.551476 -300.405038) (xy 360.551222 -300.405038)
			(xy 360.551222 -300.404784) (xy 360.533568 -300.383862) (xy 360.503844 -300.337892) (xy 360.481 -300.288144)
			(xy 360.465505 -300.235641) (xy 360.457678 -300.181461) (xy 360.457679 -300.126718) (xy 360.465509 -300.072539)
			(xy 360.481007 -300.020036) (xy 360.503854 -299.970289) (xy 360.533581 -299.924321) (xy 360.551222 -299.903388)
			(xy 360.551476 -299.903134) (xy 360.557063 -299.896048) (xy 360.563308 -299.879131) (xy 360.563668 -299.870114)
			(xy 360.563668 -299.803058) (xy 360.56329 -299.794043) (xy 360.557058 -299.777126) (xy 360.551476 -299.770038)
			(xy 360.551222 -299.770038) (xy 360.551222 -299.769784) (xy 360.533612 -299.748828) (xy 360.503895 -299.702862)
			(xy 360.481053 -299.653121) (xy 360.465555 -299.600625) (xy 360.45772 -299.546454) (xy 360.457242 -299.519086)
			(xy 360.457728 -299.491835) (xy 360.465484 -299.437887) (xy 360.480839 -299.385592) (xy 360.503481 -299.336015)
			(xy 360.532947 -299.290165) (xy 360.568638 -299.248974) (xy 360.609829 -299.213283) (xy 360.655679 -299.183817)
			(xy 360.705256 -299.161175) (xy 360.757551 -299.14582) (xy 360.811499 -299.138064) (xy 360.866001 -299.138064)
			(xy 360.919949 -299.14582) (xy 360.972244 -299.161175) (xy 361.021821 -299.183817) (xy 361.067671 -299.213283)
			(xy 361.108862 -299.248974) (xy 361.144553 -299.290165) (xy 361.174019 -299.336015) (xy 361.196661 -299.385592)
			(xy 361.212016 -299.437887) (xy 361.219772 -299.491835) (xy 361.220258 -299.519086) (xy 361.219794 -299.546456)
			(xy 361.211977 -299.600636) (xy 361.196488 -299.65314) (xy 361.173646 -299.702886) (xy 361.14392 -299.748853)
			(xy 361.126278 -299.769784) (xy 361.126024 -299.770038) (xy 361.120448 -299.777132) (xy 361.114197 -299.794043)
			(xy 361.113832 -299.803058) (xy 361.113832 -299.870114) (xy 361.114175 -299.879132) (xy 361.120432 -299.89605)
			(xy 361.126024 -299.903134) (xy 361.126278 -299.903134) (xy 361.126278 -299.903388) (xy 361.143905 -299.924332)
			(xy 361.17363 -299.970298) (xy 361.196476 -300.020042) (xy 361.211973 -300.072543) (xy 361.219803 -300.12672)
			(xy 361.219804 -300.181459) (xy 361.211977 -300.235637) (xy 361.196483 -300.288138) (xy 361.17364 -300.337884)
			(xy 361.143917 -300.383851) (xy 361.126278 -300.404784) (xy 361.126024 -300.405038) (xy 361.120448 -300.412132)
			(xy 361.114197 -300.429043) (xy 361.113832 -300.438058) (xy 361.113832 -300.505114) (xy 361.114175 -300.514132)
			(xy 361.120432 -300.53105) (xy 361.126024 -300.538134) (xy 361.126278 -300.538134) (xy 361.126278 -300.538388)
			(xy 361.143905 -300.559332) (xy 361.17363 -300.605298) (xy 361.196476 -300.655042) (xy 361.211973 -300.707543)
			(xy 361.219803 -300.76172) (xy 361.219804 -300.816459) (xy 361.211977 -300.870637) (xy 361.196483 -300.923138)
			(xy 361.17364 -300.972884) (xy 361.143917 -301.018851) (xy 361.126278 -301.039784) (xy 361.126024 -301.040038)
			(xy 361.120448 -301.047132) (xy 361.114197 -301.064043) (xy 361.113832 -301.073058) (xy 361.113832 -301.140114)
			(xy 361.114175 -301.149132) (xy 361.120432 -301.16605) (xy 361.126024 -301.173134) (xy 361.126278 -301.173134)
			(xy 361.126278 -301.173388) (xy 361.143922 -301.194317) (xy 361.173633 -301.24029) (xy 361.196469 -301.290038)
			(xy 361.211959 -301.34254) (xy 361.219785 -301.396717) (xy 361.220258 -301.424086) (xy 361.219772 -301.451337)
			(xy 361.215948 -301.477934) (xy 364.089442 -301.477934) (xy 364.089918 -301.450564) (xy 364.097732 -301.396385)
			(xy 364.113218 -301.343882) (xy 364.136058 -301.294134) (xy 364.165781 -301.248168) (xy 364.183422 -301.227236)
			(xy 364.183676 -301.226982) (xy 364.189285 -301.219911) (xy 364.195516 -301.202982) (xy 364.195868 -301.193962)
			(xy 364.195868 -301.126906) (xy 364.195515 -301.117889) (xy 364.189265 -301.100971) (xy 364.183676 -301.093886)
			(xy 364.183422 -301.093886) (xy 364.183422 -301.093632) (xy 364.165815 -301.072672) (xy 364.136089 -301.026709)
			(xy 364.113242 -300.976967) (xy 364.097743 -300.924469) (xy 364.089912 -300.870295) (xy 364.089908 -300.815557)
			(xy 364.097732 -300.761381) (xy 364.113224 -300.708881) (xy 364.136064 -300.659136) (xy 364.165784 -300.613169)
			(xy 364.183422 -300.592236) (xy 364.183676 -300.591982) (xy 364.189285 -300.584911) (xy 364.195516 -300.567982)
			(xy 364.195868 -300.558962) (xy 364.195868 -300.491906) (xy 364.195515 -300.482889) (xy 364.189265 -300.465971)
			(xy 364.183676 -300.458886) (xy 364.183422 -300.458886) (xy 364.183422 -300.458632) (xy 364.165815 -300.437672)
			(xy 364.136089 -300.391709) (xy 364.113242 -300.341967) (xy 364.097743 -300.289469) (xy 364.089912 -300.235295)
			(xy 364.089908 -300.180557) (xy 364.097732 -300.126381) (xy 364.113224 -300.073881) (xy 364.136064 -300.024136)
			(xy 364.165784 -299.978169) (xy 364.183422 -299.957236) (xy 364.183676 -299.956982) (xy 364.189285 -299.949911)
			(xy 364.195516 -299.932982) (xy 364.195868 -299.923962) (xy 364.195868 -299.856906) (xy 364.195515 -299.847889)
			(xy 364.189265 -299.830971) (xy 364.183676 -299.823886) (xy 364.183422 -299.823886) (xy 364.183422 -299.823632)
			(xy 364.165788 -299.802696) (xy 364.136075 -299.756725) (xy 364.113237 -299.706978) (xy 364.097745 -299.654478)
			(xy 364.089916 -299.600303) (xy 364.089442 -299.572934) (xy 364.089928 -299.545683) (xy 364.097684 -299.491735)
			(xy 364.113039 -299.43944) (xy 364.135681 -299.389863) (xy 364.165147 -299.344013) (xy 364.200838 -299.302822)
			(xy 364.242029 -299.267131) (xy 364.287879 -299.237665) (xy 364.337456 -299.215023) (xy 364.389751 -299.199668)
			(xy 364.443699 -299.191912) (xy 364.498201 -299.191912) (xy 364.552149 -299.199668) (xy 364.604444 -299.215023)
			(xy 364.654021 -299.237665) (xy 364.699871 -299.267131) (xy 364.741062 -299.302822) (xy 364.776753 -299.344013)
			(xy 364.806219 -299.389863) (xy 364.828861 -299.43944) (xy 364.844216 -299.491735) (xy 364.851972 -299.545683)
			(xy 364.852458 -299.572934) (xy 364.852022 -299.600305) (xy 364.844199 -299.654486) (xy 364.828703 -299.70699)
			(xy 364.805854 -299.756736) (xy 364.776123 -299.802702) (xy 364.758478 -299.823632) (xy 364.758224 -299.823886)
			(xy 364.752628 -299.830966) (xy 364.746389 -299.847888) (xy 364.746032 -299.856906) (xy 364.746032 -299.923962)
			(xy 364.7464 -299.932978) (xy 364.752639 -299.949895) (xy 364.758224 -299.956982) (xy 364.758478 -299.956982)
			(xy 364.758478 -299.957236) (xy 364.776152 -299.978142) (xy 364.805875 -300.024114) (xy 364.828718 -300.073865)
			(xy 364.844211 -300.126371) (xy 364.852037 -300.180553) (xy 364.852033 -300.235298) (xy 364.8442 -300.289479)
			(xy 364.8287 -300.341983) (xy 364.80585 -300.391731) (xy 364.776121 -300.437699) (xy 364.758478 -300.458632)
			(xy 364.758224 -300.458886) (xy 364.752628 -300.465966) (xy 364.746389 -300.482888) (xy 364.746032 -300.491906)
			(xy 364.746032 -300.558962) (xy 364.7464 -300.567978) (xy 364.752639 -300.584895) (xy 364.758224 -300.591982)
			(xy 364.758478 -300.591982) (xy 364.758478 -300.592236) (xy 364.776152 -300.613142) (xy 364.805875 -300.659114)
			(xy 364.828718 -300.708865) (xy 364.844211 -300.761371) (xy 364.852037 -300.815553) (xy 364.852033 -300.870298)
			(xy 364.8442 -300.924479) (xy 364.8287 -300.976983) (xy 364.80585 -301.026731) (xy 364.776121 -301.072699)
			(xy 364.758478 -301.093632) (xy 364.758224 -301.093886) (xy 364.752628 -301.100966) (xy 364.746389 -301.117888)
			(xy 364.746032 -301.126906) (xy 364.746032 -301.193962) (xy 364.7464 -301.202978) (xy 364.752639 -301.219895)
			(xy 364.758224 -301.226982) (xy 364.758478 -301.226982) (xy 364.758478 -301.227236) (xy 364.776097 -301.248184)
			(xy 364.805813 -301.294152) (xy 364.828653 -301.343896) (xy 364.844149 -301.396393) (xy 364.851982 -301.450566)
			(xy 364.852458 -301.477934) (xy 364.851972 -301.505185) (xy 364.844216 -301.559133) (xy 364.828861 -301.611428)
			(xy 364.806219 -301.661005) (xy 364.776753 -301.706855) (xy 364.741062 -301.748046) (xy 364.699871 -301.783737)
			(xy 364.654021 -301.813203) (xy 364.604444 -301.835845) (xy 364.552149 -301.8512) (xy 364.498201 -301.858956)
			(xy 364.443699 -301.858956) (xy 364.389751 -301.8512) (xy 364.337456 -301.835845) (xy 364.287879 -301.813203)
			(xy 364.242029 -301.783737) (xy 364.200838 -301.748046) (xy 364.165147 -301.706855) (xy 364.135681 -301.661005)
			(xy 364.113039 -301.611428) (xy 364.097684 -301.559133) (xy 364.089928 -301.505185) (xy 364.089442 -301.477934)
			(xy 361.215948 -301.477934) (xy 361.212016 -301.505285) (xy 361.196661 -301.55758) (xy 361.174019 -301.607157)
			(xy 361.144553 -301.653007) (xy 361.108862 -301.694198) (xy 361.067671 -301.729889) (xy 361.021821 -301.759355)
			(xy 360.972244 -301.781997) (xy 360.919949 -301.797352) (xy 360.866001 -301.805108) (xy 360.811499 -301.805108)
			(xy 360.757551 -301.797352) (xy 360.705256 -301.781997) (xy 360.655679 -301.759355) (xy 360.609829 -301.729889)
			(xy 360.568638 -301.694198) (xy 360.532947 -301.653007) (xy 360.503481 -301.607157) (xy 360.480839 -301.55758)
			(xy 360.465484 -301.505285) (xy 360.457728 -301.451337) (xy 360.457242 -301.424086) (xy 358.007932 -301.424086)
			(xy 358.011761 -301.450566) (xy 358.012238 -301.477934) (xy 358.011752 -301.505185) (xy 358.003996 -301.559133)
			(xy 357.988641 -301.611428) (xy 357.965999 -301.661005) (xy 357.936533 -301.706855) (xy 357.900842 -301.748046)
			(xy 357.859651 -301.783737) (xy 357.813801 -301.813203) (xy 357.764224 -301.835845) (xy 357.711929 -301.8512)
			(xy 357.657981 -301.858956) (xy 357.603479 -301.858956) (xy 357.549531 -301.8512) (xy 357.497236 -301.835845)
			(xy 357.447659 -301.813203) (xy 357.401809 -301.783737) (xy 357.360618 -301.748046) (xy 357.324927 -301.706855)
			(xy 357.295461 -301.661005) (xy 357.272819 -301.611428) (xy 357.257464 -301.559133) (xy 357.249708 -301.505185)
			(xy 357.249222 -301.477934) (xy 354.375728 -301.477934) (xy 354.371796 -301.505285) (xy 354.356441 -301.55758)
			(xy 354.333799 -301.607157) (xy 354.304333 -301.653007) (xy 354.268642 -301.694198) (xy 354.227451 -301.729889)
			(xy 354.181601 -301.759355) (xy 354.132024 -301.781997) (xy 354.079729 -301.797352) (xy 354.025781 -301.805108)
			(xy 353.971279 -301.805108) (xy 353.917331 -301.797352) (xy 353.865036 -301.781997) (xy 353.815459 -301.759355)
			(xy 353.769609 -301.729889) (xy 353.728418 -301.694198) (xy 353.692727 -301.653007) (xy 353.663261 -301.607157)
			(xy 353.640619 -301.55758) (xy 353.625264 -301.505285) (xy 353.617508 -301.451337) (xy 353.617022 -301.424086)
			(xy 346.254845 -301.424086) (xy 346.258674 -301.450566) (xy 346.25915 -301.477934) (xy 346.258664 -301.505185)
			(xy 346.250908 -301.559133) (xy 346.235553 -301.611428) (xy 346.212911 -301.661005) (xy 346.183445 -301.706855)
			(xy 346.147754 -301.748046) (xy 346.106563 -301.783737) (xy 346.060713 -301.813203) (xy 346.011136 -301.835845)
			(xy 345.958841 -301.8512) (xy 345.904893 -301.858956) (xy 345.850391 -301.858956) (xy 345.796443 -301.8512)
			(xy 345.744148 -301.835845) (xy 345.694571 -301.813203) (xy 345.648721 -301.783737) (xy 345.60753 -301.748046)
			(xy 345.571839 -301.706855) (xy 345.542373 -301.661005) (xy 345.519731 -301.611428) (xy 345.504376 -301.559133)
			(xy 345.49662 -301.505185) (xy 345.496134 -301.477934) (xy 342.62264 -301.477934) (xy 342.618708 -301.505285)
			(xy 342.603353 -301.55758) (xy 342.580711 -301.607157) (xy 342.551245 -301.653007) (xy 342.515554 -301.694198)
			(xy 342.474363 -301.729889) (xy 342.428513 -301.759355) (xy 342.378936 -301.781997) (xy 342.326641 -301.797352)
			(xy 342.272693 -301.805108) (xy 342.218191 -301.805108) (xy 342.164243 -301.797352) (xy 342.111948 -301.781997)
			(xy 342.062371 -301.759355) (xy 342.016521 -301.729889) (xy 341.97533 -301.694198) (xy 341.939639 -301.653007)
			(xy 341.910173 -301.607157) (xy 341.887531 -301.55758) (xy 341.872176 -301.505285) (xy 341.86442 -301.451337)
			(xy 341.863934 -301.424086) (xy 339.414624 -301.424086) (xy 339.418453 -301.450566) (xy 339.41893 -301.477934)
			(xy 339.418444 -301.505185) (xy 339.410688 -301.559133) (xy 339.395333 -301.611428) (xy 339.372691 -301.661005)
			(xy 339.343225 -301.706855) (xy 339.307534 -301.748046) (xy 339.266343 -301.783737) (xy 339.220493 -301.813203)
			(xy 339.170916 -301.835845) (xy 339.118621 -301.8512) (xy 339.064673 -301.858956) (xy 339.010171 -301.858956)
			(xy 338.956223 -301.8512) (xy 338.903928 -301.835845) (xy 338.854351 -301.813203) (xy 338.808501 -301.783737)
			(xy 338.76731 -301.748046) (xy 338.731619 -301.706855) (xy 338.702153 -301.661005) (xy 338.679511 -301.611428)
			(xy 338.664156 -301.559133) (xy 338.6564 -301.505185) (xy 338.655914 -301.477934) (xy 335.78242 -301.477934)
			(xy 335.778488 -301.505285) (xy 335.763133 -301.55758) (xy 335.740491 -301.607157) (xy 335.711025 -301.653007)
			(xy 335.675334 -301.694198) (xy 335.634143 -301.729889) (xy 335.588293 -301.759355) (xy 335.538716 -301.781997)
			(xy 335.486421 -301.797352) (xy 335.432473 -301.805108) (xy 335.377971 -301.805108) (xy 335.324023 -301.797352)
			(xy 335.271728 -301.781997) (xy 335.222151 -301.759355) (xy 335.176301 -301.729889) (xy 335.13511 -301.694198)
			(xy 335.099419 -301.653007) (xy 335.069953 -301.607157) (xy 335.047311 -301.55758) (xy 335.031956 -301.505285)
			(xy 335.0242 -301.451337) (xy 335.023714 -301.424086) (xy 331.987906 -301.424086) (xy 331.987906 -302.925734)
			(xy 334.435704 -302.925734) (xy 334.436189 -302.898364) (xy 334.444002 -302.844186) (xy 334.459487 -302.791683)
			(xy 334.482324 -302.741936) (xy 334.512045 -302.695968) (xy 334.529684 -302.675036) (xy 334.529938 -302.674782)
			(xy 334.535542 -302.667708) (xy 334.541777 -302.650781) (xy 334.54213 -302.641762) (xy 334.54213 -302.574706)
			(xy 334.541763 -302.56569) (xy 334.535522 -302.548774) (xy 334.529938 -302.541686) (xy 334.529684 -302.541686)
			(xy 334.529684 -302.541432) (xy 334.512044 -302.520501) (xy 334.482333 -302.474527) (xy 334.459497 -302.42478)
			(xy 334.444006 -302.372279) (xy 334.436178 -302.318103) (xy 334.435704 -302.290734) (xy 334.43619 -302.263483)
			(xy 334.443946 -302.209535) (xy 334.459301 -302.15724) (xy 334.481943 -302.107663) (xy 334.511409 -302.061813)
			(xy 334.5471 -302.020622) (xy 334.588291 -301.984931) (xy 334.634141 -301.955465) (xy 334.683718 -301.932823)
			(xy 334.736013 -301.917468) (xy 334.789961 -301.909712) (xy 334.844463 -301.909712) (xy 334.898411 -301.917468)
			(xy 334.950706 -301.932823) (xy 335.000283 -301.955465) (xy 335.046133 -301.984931) (xy 335.087324 -302.020622)
			(xy 335.123015 -302.061813) (xy 335.152481 -302.107663) (xy 335.175123 -302.15724) (xy 335.190478 -302.209535)
			(xy 335.198234 -302.263483) (xy 335.19872 -302.290734) (xy 335.198293 -302.318106) (xy 335.190469 -302.372287)
			(xy 335.174972 -302.424792) (xy 335.152121 -302.474538) (xy 335.122386 -302.520502) (xy 335.10474 -302.541432)
			(xy 335.104486 -302.541686) (xy 335.098898 -302.548771) (xy 335.092652 -302.565689) (xy 335.092294 -302.574706)
			(xy 335.092294 -302.641762) (xy 335.09267 -302.650777) (xy 335.098905 -302.667694) (xy 335.104486 -302.674782)
			(xy 335.10474 -302.674782) (xy 335.10474 -302.675036) (xy 335.122369 -302.695976) (xy 335.152081 -302.741947)
			(xy 335.174919 -302.791693) (xy 335.190412 -302.844191) (xy 335.198244 -302.898365) (xy 335.19872 -302.925734)
			(xy 337.855814 -302.925734) (xy 337.856297 -302.898364) (xy 337.86411 -302.844186) (xy 337.879595 -302.791683)
			(xy 337.902433 -302.741936) (xy 337.932154 -302.695968) (xy 337.949794 -302.675036) (xy 337.950048 -302.674782)
			(xy 337.955654 -302.667709) (xy 337.961888 -302.650782) (xy 337.96224 -302.641762) (xy 337.96224 -302.574706)
			(xy 337.961893 -302.565688) (xy 337.95564 -302.54877) (xy 337.950048 -302.541686) (xy 337.949794 -302.541686)
			(xy 337.949794 -302.541432) (xy 337.932156 -302.520499) (xy 337.902444 -302.474527) (xy 337.879608 -302.424779)
			(xy 337.864117 -302.372279) (xy 337.856288 -302.318103) (xy 337.855814 -302.290734) (xy 337.8563 -302.263483)
			(xy 337.864056 -302.209535) (xy 337.879411 -302.15724) (xy 337.902053 -302.107663) (xy 337.931519 -302.061813)
			(xy 337.96721 -302.020622) (xy 338.008401 -301.984931) (xy 338.054251 -301.955465) (xy 338.103828 -301.932823)
			(xy 338.156123 -301.917468) (xy 338.210071 -301.909712) (xy 338.264573 -301.909712) (xy 338.318521 -301.917468)
			(xy 338.370816 -301.932823) (xy 338.420393 -301.955465) (xy 338.466243 -301.984931) (xy 338.507434 -302.020622)
			(xy 338.543125 -302.061813) (xy 338.572591 -302.107663) (xy 338.595233 -302.15724) (xy 338.610588 -302.209535)
			(xy 338.618344 -302.263483) (xy 338.61883 -302.290734) (xy 338.618401 -302.318106) (xy 338.610577 -302.372287)
			(xy 338.59508 -302.424791) (xy 338.57223 -302.474538) (xy 338.542496 -302.520502) (xy 338.52485 -302.541432)
			(xy 338.524596 -302.541686) (xy 338.519009 -302.548772) (xy 338.512763 -302.565689) (xy 338.512404 -302.574706)
			(xy 338.512404 -302.641762) (xy 338.512779 -302.650777) (xy 338.519014 -302.667694) (xy 338.524596 -302.674782)
			(xy 338.52485 -302.674782) (xy 338.52485 -302.675036) (xy 338.542465 -302.695988) (xy 338.572182 -302.741954)
			(xy 338.595023 -302.791697) (xy 338.61052 -302.844193) (xy 338.618353 -302.898366) (xy 338.61883 -302.925734)
			(xy 339.243924 -302.925734) (xy 339.244404 -302.898364) (xy 339.252218 -302.844185) (xy 339.267703 -302.791682)
			(xy 339.290542 -302.741935) (xy 339.320264 -302.695968) (xy 339.337904 -302.675036) (xy 339.338158 -302.674782)
			(xy 339.343765 -302.66771) (xy 339.349998 -302.650782) (xy 339.35035 -302.641762) (xy 339.35035 -302.574706)
			(xy 339.350001 -302.565688) (xy 339.343749 -302.548771) (xy 339.338158 -302.541686) (xy 339.337904 -302.541686)
			(xy 339.337904 -302.541432) (xy 339.320267 -302.520498) (xy 339.290555 -302.474526) (xy 339.267718 -302.424779)
			(xy 339.252227 -302.372279) (xy 339.244398 -302.318103) (xy 339.243924 -302.290734) (xy 339.24441 -302.263483)
			(xy 339.252166 -302.209535) (xy 339.267521 -302.15724) (xy 339.290163 -302.107663) (xy 339.319629 -302.061813)
			(xy 339.35532 -302.020622) (xy 339.396511 -301.984931) (xy 339.442361 -301.955465) (xy 339.491938 -301.932823)
			(xy 339.544233 -301.917468) (xy 339.598181 -301.909712) (xy 339.652683 -301.909712) (xy 339.706631 -301.917468)
			(xy 339.758926 -301.932823) (xy 339.808503 -301.955465) (xy 339.854353 -301.984931) (xy 339.895544 -302.020622)
			(xy 339.931235 -302.061813) (xy 339.960701 -302.107663) (xy 339.983343 -302.15724) (xy 339.998698 -302.209535)
			(xy 340.006454 -302.263483) (xy 340.00694 -302.290734) (xy 340.006508 -302.318106) (xy 339.998685 -302.372287)
			(xy 339.983188 -302.424791) (xy 339.960338 -302.474537) (xy 339.930605 -302.520502) (xy 339.91296 -302.541432)
			(xy 339.912706 -302.541686) (xy 339.90712 -302.548773) (xy 339.900873 -302.565689) (xy 339.900514 -302.574706)
			(xy 339.900514 -302.641762) (xy 339.900886 -302.650777) (xy 339.907123 -302.667695) (xy 339.912706 -302.674782)
			(xy 339.91296 -302.674782) (xy 339.91296 -302.675036) (xy 339.930576 -302.695987) (xy 339.960293 -302.741954)
			(xy 339.983134 -302.791696) (xy 339.99863 -302.844193) (xy 340.006463 -302.898366) (xy 340.00694 -302.925734)
			(xy 341.275924 -302.925734) (xy 341.276404 -302.898364) (xy 341.284218 -302.844185) (xy 341.299703 -302.791682)
			(xy 341.322542 -302.741935) (xy 341.352264 -302.695968) (xy 341.369904 -302.675036) (xy 341.370158 -302.674782)
			(xy 341.375765 -302.66771) (xy 341.381998 -302.650782) (xy 341.38235 -302.641762) (xy 341.38235 -302.574706)
			(xy 341.382001 -302.565688) (xy 341.375749 -302.548771) (xy 341.370158 -302.541686) (xy 341.369904 -302.541686)
			(xy 341.369904 -302.541432) (xy 341.352267 -302.520498) (xy 341.322555 -302.474526) (xy 341.299718 -302.424779)
			(xy 341.284227 -302.372279) (xy 341.276398 -302.318103) (xy 341.275924 -302.290734) (xy 341.27641 -302.263483)
			(xy 341.284166 -302.209535) (xy 341.299521 -302.15724) (xy 341.322163 -302.107663) (xy 341.351629 -302.061813)
			(xy 341.38732 -302.020622) (xy 341.428511 -301.984931) (xy 341.474361 -301.955465) (xy 341.523938 -301.932823)
			(xy 341.576233 -301.917468) (xy 341.630181 -301.909712) (xy 341.684683 -301.909712) (xy 341.738631 -301.917468)
			(xy 341.790926 -301.932823) (xy 341.840503 -301.955465) (xy 341.886353 -301.984931) (xy 341.927544 -302.020622)
			(xy 341.963235 -302.061813) (xy 341.992701 -302.107663) (xy 342.015343 -302.15724) (xy 342.030698 -302.209535)
			(xy 342.038454 -302.263483) (xy 342.03894 -302.290734) (xy 342.038508 -302.318106) (xy 342.030685 -302.372287)
			(xy 342.015188 -302.424791) (xy 341.992338 -302.474537) (xy 341.962605 -302.520502) (xy 341.94496 -302.541432)
			(xy 341.944706 -302.541686) (xy 341.93912 -302.548773) (xy 341.932873 -302.565689) (xy 341.932514 -302.574706)
			(xy 341.932514 -302.641762) (xy 341.932886 -302.650777) (xy 341.939123 -302.667695) (xy 341.944706 -302.674782)
			(xy 341.94496 -302.674782) (xy 341.94496 -302.675036) (xy 341.962576 -302.695987) (xy 341.992293 -302.741954)
			(xy 342.015134 -302.791696) (xy 342.03063 -302.844193) (xy 342.038463 -302.898366) (xy 342.03894 -302.925734)
			(xy 346.084144 -302.925734) (xy 346.084619 -302.898364) (xy 346.092433 -302.844185) (xy 346.10792 -302.791681)
			(xy 346.13076 -302.741934) (xy 346.160483 -302.695968) (xy 346.178124 -302.675036) (xy 346.178378 -302.674782)
			(xy 346.183987 -302.667711) (xy 346.190218 -302.650782) (xy 346.19057 -302.641762) (xy 346.19057 -302.574706)
			(xy 346.190217 -302.565689) (xy 346.183967 -302.548771) (xy 346.178378 -302.541686) (xy 346.178124 -302.541686)
			(xy 346.178124 -302.541432) (xy 346.16049 -302.520496) (xy 346.130777 -302.474524) (xy 346.107939 -302.424778)
			(xy 346.092447 -302.372278) (xy 346.084618 -302.318103) (xy 346.084144 -302.290734) (xy 346.08463 -302.263483)
			(xy 346.092386 -302.209535) (xy 346.107741 -302.15724) (xy 346.130383 -302.107663) (xy 346.159849 -302.061813)
			(xy 346.19554 -302.020622) (xy 346.236731 -301.984931) (xy 346.282581 -301.955465) (xy 346.332158 -301.932823)
			(xy 346.384453 -301.917468) (xy 346.438401 -301.909712) (xy 346.492903 -301.909712) (xy 346.546851 -301.917468)
			(xy 346.599146 -301.932823) (xy 346.648723 -301.955465) (xy 346.694573 -301.984931) (xy 346.735764 -302.020622)
			(xy 346.771455 -302.061813) (xy 346.800921 -302.107663) (xy 346.823563 -302.15724) (xy 346.838918 -302.209535)
			(xy 346.846674 -302.263483) (xy 346.84716 -302.290734) (xy 346.846724 -302.318105) (xy 346.8389 -302.372286)
			(xy 346.823405 -302.42479) (xy 346.800556 -302.474536) (xy 346.770825 -302.520502) (xy 346.75318 -302.541432)
			(xy 346.752926 -302.541686) (xy 346.74733 -302.548766) (xy 346.741091 -302.565688) (xy 346.740734 -302.574706)
			(xy 346.740734 -302.641762) (xy 346.741102 -302.650778) (xy 346.747341 -302.667695) (xy 346.752926 -302.674782)
			(xy 346.75318 -302.674782) (xy 346.75318 -302.675036) (xy 346.770799 -302.695984) (xy 346.800515 -302.741952)
			(xy 346.823355 -302.791696) (xy 346.838851 -302.844193) (xy 346.846684 -302.898366) (xy 346.84716 -302.925734)
			(xy 346.846674 -302.952985) (xy 346.838918 -303.006933) (xy 346.823563 -303.059228) (xy 346.800921 -303.108805)
			(xy 346.771455 -303.154655) (xy 346.735764 -303.195846) (xy 346.694573 -303.231537) (xy 346.648723 -303.261003)
			(xy 346.599146 -303.283645) (xy 346.546851 -303.299) (xy 346.492903 -303.306756) (xy 346.438401 -303.306756)
			(xy 346.384453 -303.299) (xy 346.332158 -303.283645) (xy 346.282581 -303.261003) (xy 346.236731 -303.231537)
			(xy 346.19554 -303.195846) (xy 346.159849 -303.154655) (xy 346.130383 -303.108805) (xy 346.107741 -303.059228)
			(xy 346.092386 -303.006933) (xy 346.08463 -302.952985) (xy 346.084144 -302.925734) (xy 342.03894 -302.925734)
			(xy 342.038454 -302.952985) (xy 342.030698 -303.006933) (xy 342.015343 -303.059228) (xy 341.992701 -303.108805)
			(xy 341.963235 -303.154655) (xy 341.927544 -303.195846) (xy 341.886353 -303.231537) (xy 341.840503 -303.261003)
			(xy 341.790926 -303.283645) (xy 341.738631 -303.299) (xy 341.684683 -303.306756) (xy 341.630181 -303.306756)
			(xy 341.576233 -303.299) (xy 341.523938 -303.283645) (xy 341.474361 -303.261003) (xy 341.428511 -303.231537)
			(xy 341.38732 -303.195846) (xy 341.351629 -303.154655) (xy 341.322163 -303.108805) (xy 341.299521 -303.059228)
			(xy 341.284166 -303.006933) (xy 341.27641 -302.952985) (xy 341.275924 -302.925734) (xy 340.00694 -302.925734)
			(xy 340.006454 -302.952985) (xy 339.998698 -303.006933) (xy 339.983343 -303.059228) (xy 339.960701 -303.108805)
			(xy 339.931235 -303.154655) (xy 339.895544 -303.195846) (xy 339.854353 -303.231537) (xy 339.808503 -303.261003)
			(xy 339.758926 -303.283645) (xy 339.706631 -303.299) (xy 339.652683 -303.306756) (xy 339.598181 -303.306756)
			(xy 339.544233 -303.299) (xy 339.491938 -303.283645) (xy 339.442361 -303.261003) (xy 339.396511 -303.231537)
			(xy 339.35532 -303.195846) (xy 339.319629 -303.154655) (xy 339.290163 -303.108805) (xy 339.267521 -303.059228)
			(xy 339.252166 -303.006933) (xy 339.24441 -302.952985) (xy 339.243924 -302.925734) (xy 338.61883 -302.925734)
			(xy 338.618344 -302.952985) (xy 338.610588 -303.006933) (xy 338.595233 -303.059228) (xy 338.572591 -303.108805)
			(xy 338.543125 -303.154655) (xy 338.507434 -303.195846) (xy 338.466243 -303.231537) (xy 338.420393 -303.261003)
			(xy 338.370816 -303.283645) (xy 338.318521 -303.299) (xy 338.264573 -303.306756) (xy 338.210071 -303.306756)
			(xy 338.156123 -303.299) (xy 338.103828 -303.283645) (xy 338.054251 -303.261003) (xy 338.008401 -303.231537)
			(xy 337.96721 -303.195846) (xy 337.931519 -303.154655) (xy 337.902053 -303.108805) (xy 337.879411 -303.059228)
			(xy 337.864056 -303.006933) (xy 337.8563 -302.952985) (xy 337.855814 -302.925734) (xy 335.19872 -302.925734)
			(xy 335.198234 -302.952985) (xy 335.190478 -303.006933) (xy 335.175123 -303.059228) (xy 335.152481 -303.108805)
			(xy 335.123015 -303.154655) (xy 335.087324 -303.195846) (xy 335.046133 -303.231537) (xy 335.000283 -303.261003)
			(xy 334.950706 -303.283645) (xy 334.898411 -303.299) (xy 334.844463 -303.306756) (xy 334.789961 -303.306756)
			(xy 334.736013 -303.299) (xy 334.683718 -303.283645) (xy 334.634141 -303.261003) (xy 334.588291 -303.231537)
			(xy 334.5471 -303.195846) (xy 334.511409 -303.154655) (xy 334.481943 -303.108805) (xy 334.459301 -303.059228)
			(xy 334.443946 -303.006933) (xy 334.43619 -302.952985) (xy 334.435704 -302.925734) (xy 331.987906 -302.925734)
			(xy 331.987906 -310.242712) (xy 332.67218 -310.242712) (xy 332.676251 -310.18709) (xy 332.688377 -310.132653)
			(xy 332.7083 -310.080562) (xy 332.735596 -310.031927) (xy 332.769682 -309.987784) (xy 332.809831 -309.949075)
			(xy 332.855189 -309.916624) (xy 332.904789 -309.891123) (xy 332.957573 -309.873116) (xy 333.012416 -309.862986)
			(xy 333.06815 -309.860949) (xy 333.123587 -309.867049) (xy 333.177544 -309.881155) (xy 333.228873 -309.902967)
			(xy 333.276479 -309.932021) (xy 333.319347 -309.967696) (xy 333.356564 -310.009233) (xy 333.387337 -310.055746)
			(xy 333.411009 -310.106243) (xy 333.427077 -310.15965) (xy 333.435197 -310.214826) (xy 333.435706 -310.242712)
			(xy 333.68818 -310.242712) (xy 333.692251 -310.18709) (xy 333.704377 -310.132653) (xy 333.7243 -310.080562)
			(xy 333.751596 -310.031927) (xy 333.785682 -309.987784) (xy 333.825831 -309.949075) (xy 333.871189 -309.916624)
			(xy 333.920789 -309.891123) (xy 333.973573 -309.873116) (xy 334.028416 -309.862986) (xy 334.08415 -309.860949)
			(xy 334.139587 -309.867049) (xy 334.193544 -309.881155) (xy 334.244873 -309.902967) (xy 334.292479 -309.932021)
			(xy 334.335347 -309.967696) (xy 334.372564 -310.009233) (xy 334.403337 -310.055746) (xy 334.427009 -310.106243)
			(xy 334.443077 -310.15965) (xy 334.451197 -310.214826) (xy 334.451706 -310.242712) (xy 334.70418 -310.242712)
			(xy 334.708251 -310.18709) (xy 334.720377 -310.132653) (xy 334.7403 -310.080562) (xy 334.767596 -310.031927)
			(xy 334.801682 -309.987784) (xy 334.841831 -309.949075) (xy 334.887189 -309.916624) (xy 334.936789 -309.891123)
			(xy 334.989573 -309.873116) (xy 335.044416 -309.862986) (xy 335.10015 -309.860949) (xy 335.155587 -309.867049)
			(xy 335.209544 -309.881155) (xy 335.260873 -309.902967) (xy 335.308479 -309.932021) (xy 335.351347 -309.967696)
			(xy 335.388564 -310.009233) (xy 335.419337 -310.055746) (xy 335.443009 -310.106243) (xy 335.459077 -310.15965)
			(xy 335.467197 -310.214826) (xy 335.467706 -310.242712) (xy 335.72018 -310.242712) (xy 335.724251 -310.18709)
			(xy 335.736377 -310.132653) (xy 335.7563 -310.080562) (xy 335.783596 -310.031927) (xy 335.817682 -309.987784)
			(xy 335.857831 -309.949075) (xy 335.903189 -309.916624) (xy 335.952789 -309.891123) (xy 336.005573 -309.873116)
			(xy 336.060416 -309.862986) (xy 336.11615 -309.860949) (xy 336.171587 -309.867049) (xy 336.225544 -309.881155)
			(xy 336.276873 -309.902967) (xy 336.324479 -309.932021) (xy 336.367347 -309.967696) (xy 336.404564 -310.009233)
			(xy 336.435337 -310.055746) (xy 336.459009 -310.106243) (xy 336.475077 -310.15965) (xy 336.483197 -310.214826)
			(xy 336.483706 -310.242712) (xy 336.73618 -310.242712) (xy 336.740251 -310.18709) (xy 336.752377 -310.132653)
			(xy 336.7723 -310.080562) (xy 336.799596 -310.031927) (xy 336.833682 -309.987784) (xy 336.873831 -309.949075)
			(xy 336.919189 -309.916624) (xy 336.968789 -309.891123) (xy 337.021573 -309.873116) (xy 337.076416 -309.862986)
			(xy 337.13215 -309.860949) (xy 337.187587 -309.867049) (xy 337.241544 -309.881155) (xy 337.292873 -309.902967)
			(xy 337.340479 -309.932021) (xy 337.383347 -309.967696) (xy 337.420564 -310.009233) (xy 337.451337 -310.055746)
			(xy 337.475009 -310.106243) (xy 337.491077 -310.15965) (xy 337.499197 -310.214826) (xy 337.499706 -310.242712)
			(xy 337.75218 -310.242712) (xy 337.756251 -310.18709) (xy 337.768377 -310.132653) (xy 337.7883 -310.080562)
			(xy 337.815596 -310.031927) (xy 337.849682 -309.987784) (xy 337.889831 -309.949075) (xy 337.935189 -309.916624)
			(xy 337.984789 -309.891123) (xy 338.037573 -309.873116) (xy 338.092416 -309.862986) (xy 338.14815 -309.860949)
			(xy 338.203587 -309.867049) (xy 338.257544 -309.881155) (xy 338.308873 -309.902967) (xy 338.356479 -309.932021)
			(xy 338.399347 -309.967696) (xy 338.436564 -310.009233) (xy 338.467337 -310.055746) (xy 338.491009 -310.106243)
			(xy 338.507077 -310.15965) (xy 338.515197 -310.214826) (xy 338.515706 -310.242712) (xy 338.76818 -310.242712)
			(xy 338.772251 -310.18709) (xy 338.784377 -310.132653) (xy 338.8043 -310.080562) (xy 338.831596 -310.031927)
			(xy 338.865682 -309.987784) (xy 338.905831 -309.949075) (xy 338.951189 -309.916624) (xy 339.000789 -309.891123)
			(xy 339.053573 -309.873116) (xy 339.108416 -309.862986) (xy 339.16415 -309.860949) (xy 339.219587 -309.867049)
			(xy 339.273544 -309.881155) (xy 339.324873 -309.902967) (xy 339.372479 -309.932021) (xy 339.415347 -309.967696)
			(xy 339.452564 -310.009233) (xy 339.483337 -310.055746) (xy 339.507009 -310.106243) (xy 339.523077 -310.15965)
			(xy 339.531197 -310.214826) (xy 339.531706 -310.242712) (xy 339.78418 -310.242712) (xy 339.788251 -310.18709)
			(xy 339.800377 -310.132653) (xy 339.8203 -310.080562) (xy 339.847596 -310.031927) (xy 339.881682 -309.987784)
			(xy 339.921831 -309.949075) (xy 339.967189 -309.916624) (xy 340.016789 -309.891123) (xy 340.069573 -309.873116)
			(xy 340.124416 -309.862986) (xy 340.18015 -309.860949) (xy 340.235587 -309.867049) (xy 340.289544 -309.881155)
			(xy 340.340873 -309.902967) (xy 340.388479 -309.932021) (xy 340.431347 -309.967696) (xy 340.468564 -310.009233)
			(xy 340.499337 -310.055746) (xy 340.523009 -310.106243) (xy 340.539077 -310.15965) (xy 340.547197 -310.214826)
			(xy 340.547706 -310.242712) (xy 340.80018 -310.242712) (xy 340.804251 -310.18709) (xy 340.816377 -310.132653)
			(xy 340.8363 -310.080562) (xy 340.863596 -310.031927) (xy 340.897682 -309.987784) (xy 340.937831 -309.949075)
			(xy 340.983189 -309.916624) (xy 341.032789 -309.891123) (xy 341.085573 -309.873116) (xy 341.140416 -309.862986)
			(xy 341.19615 -309.860949) (xy 341.251587 -309.867049) (xy 341.305544 -309.881155) (xy 341.356873 -309.902967)
			(xy 341.404479 -309.932021) (xy 341.447347 -309.967696) (xy 341.484564 -310.009233) (xy 341.515337 -310.055746)
			(xy 341.539009 -310.106243) (xy 341.555077 -310.15965) (xy 341.563197 -310.214826) (xy 341.563706 -310.242712)
			(xy 341.81618 -310.242712) (xy 341.820251 -310.18709) (xy 341.832377 -310.132653) (xy 341.8523 -310.080562)
			(xy 341.879596 -310.031927) (xy 341.913682 -309.987784) (xy 341.953831 -309.949075) (xy 341.999189 -309.916624)
			(xy 342.048789 -309.891123) (xy 342.101573 -309.873116) (xy 342.156416 -309.862986) (xy 342.21215 -309.860949)
			(xy 342.267587 -309.867049) (xy 342.321544 -309.881155) (xy 342.372873 -309.902967) (xy 342.420479 -309.932021)
			(xy 342.463347 -309.967696) (xy 342.500564 -310.009233) (xy 342.531337 -310.055746) (xy 342.555009 -310.106243)
			(xy 342.571077 -310.15965) (xy 342.579197 -310.214826) (xy 342.579706 -310.242712) (xy 342.579197 -310.270598)
			(xy 342.571077 -310.325774) (xy 342.555009 -310.379181) (xy 342.531337 -310.429678) (xy 342.500564 -310.476191)
			(xy 342.463347 -310.517728) (xy 342.420479 -310.553403) (xy 342.372873 -310.582457) (xy 342.321544 -310.604269)
			(xy 342.267587 -310.618375) (xy 342.21215 -310.624475) (xy 342.156416 -310.622438) (xy 342.101573 -310.612308)
			(xy 342.048789 -310.594301) (xy 341.999189 -310.5688) (xy 341.953831 -310.536349) (xy 341.913682 -310.49764)
			(xy 341.879596 -310.453497) (xy 341.8523 -310.404862) (xy 341.832377 -310.352771) (xy 341.820251 -310.298334)
			(xy 341.81618 -310.242712) (xy 341.563706 -310.242712) (xy 341.563197 -310.270598) (xy 341.555077 -310.325774)
			(xy 341.539009 -310.379181) (xy 341.515337 -310.429678) (xy 341.484564 -310.476191) (xy 341.447347 -310.517728)
			(xy 341.404479 -310.553403) (xy 341.356873 -310.582457) (xy 341.305544 -310.604269) (xy 341.251587 -310.618375)
			(xy 341.19615 -310.624475) (xy 341.140416 -310.622438) (xy 341.085573 -310.612308) (xy 341.032789 -310.594301)
			(xy 340.983189 -310.5688) (xy 340.937831 -310.536349) (xy 340.897682 -310.49764) (xy 340.863596 -310.453497)
			(xy 340.8363 -310.404862) (xy 340.816377 -310.352771) (xy 340.804251 -310.298334) (xy 340.80018 -310.242712)
			(xy 340.547706 -310.242712) (xy 340.547197 -310.270598) (xy 340.539077 -310.325774) (xy 340.523009 -310.379181)
			(xy 340.499337 -310.429678) (xy 340.468564 -310.476191) (xy 340.431347 -310.517728) (xy 340.388479 -310.553403)
			(xy 340.340873 -310.582457) (xy 340.289544 -310.604269) (xy 340.235587 -310.618375) (xy 340.18015 -310.624475)
			(xy 340.124416 -310.622438) (xy 340.069573 -310.612308) (xy 340.016789 -310.594301) (xy 339.967189 -310.5688)
			(xy 339.921831 -310.536349) (xy 339.881682 -310.49764) (xy 339.847596 -310.453497) (xy 339.8203 -310.404862)
			(xy 339.800377 -310.352771) (xy 339.788251 -310.298334) (xy 339.78418 -310.242712) (xy 339.531706 -310.242712)
			(xy 339.531197 -310.270598) (xy 339.523077 -310.325774) (xy 339.507009 -310.379181) (xy 339.483337 -310.429678)
			(xy 339.452564 -310.476191) (xy 339.415347 -310.517728) (xy 339.372479 -310.553403) (xy 339.324873 -310.582457)
			(xy 339.273544 -310.604269) (xy 339.219587 -310.618375) (xy 339.16415 -310.624475) (xy 339.108416 -310.622438)
			(xy 339.053573 -310.612308) (xy 339.000789 -310.594301) (xy 338.951189 -310.5688) (xy 338.905831 -310.536349)
			(xy 338.865682 -310.49764) (xy 338.831596 -310.453497) (xy 338.8043 -310.404862) (xy 338.784377 -310.352771)
			(xy 338.772251 -310.298334) (xy 338.76818 -310.242712) (xy 338.515706 -310.242712) (xy 338.515197 -310.270598)
			(xy 338.507077 -310.325774) (xy 338.491009 -310.379181) (xy 338.467337 -310.429678) (xy 338.436564 -310.476191)
			(xy 338.399347 -310.517728) (xy 338.356479 -310.553403) (xy 338.308873 -310.582457) (xy 338.257544 -310.604269)
			(xy 338.203587 -310.618375) (xy 338.14815 -310.624475) (xy 338.092416 -310.622438) (xy 338.037573 -310.612308)
			(xy 337.984789 -310.594301) (xy 337.935189 -310.5688) (xy 337.889831 -310.536349) (xy 337.849682 -310.49764)
			(xy 337.815596 -310.453497) (xy 337.7883 -310.404862) (xy 337.768377 -310.352771) (xy 337.756251 -310.298334)
			(xy 337.75218 -310.242712) (xy 337.499706 -310.242712) (xy 337.499197 -310.270598) (xy 337.491077 -310.325774)
			(xy 337.475009 -310.379181) (xy 337.451337 -310.429678) (xy 337.420564 -310.476191) (xy 337.383347 -310.517728)
			(xy 337.340479 -310.553403) (xy 337.292873 -310.582457) (xy 337.241544 -310.604269) (xy 337.187587 -310.618375)
			(xy 337.13215 -310.624475) (xy 337.076416 -310.622438) (xy 337.021573 -310.612308) (xy 336.968789 -310.594301)
			(xy 336.919189 -310.5688) (xy 336.873831 -310.536349) (xy 336.833682 -310.49764) (xy 336.799596 -310.453497)
			(xy 336.7723 -310.404862) (xy 336.752377 -310.352771) (xy 336.740251 -310.298334) (xy 336.73618 -310.242712)
			(xy 336.483706 -310.242712) (xy 336.483197 -310.270598) (xy 336.475077 -310.325774) (xy 336.459009 -310.379181)
			(xy 336.435337 -310.429678) (xy 336.404564 -310.476191) (xy 336.367347 -310.517728) (xy 336.324479 -310.553403)
			(xy 336.276873 -310.582457) (xy 336.225544 -310.604269) (xy 336.171587 -310.618375) (xy 336.11615 -310.624475)
			(xy 336.060416 -310.622438) (xy 336.005573 -310.612308) (xy 335.952789 -310.594301) (xy 335.903189 -310.5688)
			(xy 335.857831 -310.536349) (xy 335.817682 -310.49764) (xy 335.783596 -310.453497) (xy 335.7563 -310.404862)
			(xy 335.736377 -310.352771) (xy 335.724251 -310.298334) (xy 335.72018 -310.242712) (xy 335.467706 -310.242712)
			(xy 335.467197 -310.270598) (xy 335.459077 -310.325774) (xy 335.443009 -310.379181) (xy 335.419337 -310.429678)
			(xy 335.388564 -310.476191) (xy 335.351347 -310.517728) (xy 335.308479 -310.553403) (xy 335.260873 -310.582457)
			(xy 335.209544 -310.604269) (xy 335.155587 -310.618375) (xy 335.10015 -310.624475) (xy 335.044416 -310.622438)
			(xy 334.989573 -310.612308) (xy 334.936789 -310.594301) (xy 334.887189 -310.5688) (xy 334.841831 -310.536349)
			(xy 334.801682 -310.49764) (xy 334.767596 -310.453497) (xy 334.7403 -310.404862) (xy 334.720377 -310.352771)
			(xy 334.708251 -310.298334) (xy 334.70418 -310.242712) (xy 334.451706 -310.242712) (xy 334.451197 -310.270598)
			(xy 334.443077 -310.325774) (xy 334.427009 -310.379181) (xy 334.403337 -310.429678) (xy 334.372564 -310.476191)
			(xy 334.335347 -310.517728) (xy 334.292479 -310.553403) (xy 334.244873 -310.582457) (xy 334.193544 -310.604269)
			(xy 334.139587 -310.618375) (xy 334.08415 -310.624475) (xy 334.028416 -310.622438) (xy 333.973573 -310.612308)
			(xy 333.920789 -310.594301) (xy 333.871189 -310.5688) (xy 333.825831 -310.536349) (xy 333.785682 -310.49764)
			(xy 333.751596 -310.453497) (xy 333.7243 -310.404862) (xy 333.704377 -310.352771) (xy 333.692251 -310.298334)
			(xy 333.68818 -310.242712) (xy 333.435706 -310.242712) (xy 333.435197 -310.270598) (xy 333.427077 -310.325774)
			(xy 333.411009 -310.379181) (xy 333.387337 -310.429678) (xy 333.356564 -310.476191) (xy 333.319347 -310.517728)
			(xy 333.276479 -310.553403) (xy 333.228873 -310.582457) (xy 333.177544 -310.604269) (xy 333.123587 -310.618375)
			(xy 333.06815 -310.624475) (xy 333.012416 -310.622438) (xy 332.957573 -310.612308) (xy 332.904789 -310.594301)
			(xy 332.855189 -310.5688) (xy 332.809831 -310.536349) (xy 332.769682 -310.49764) (xy 332.735596 -310.453497)
			(xy 332.7083 -310.404862) (xy 332.688377 -310.352771) (xy 332.676251 -310.298334) (xy 332.67218 -310.242712)
			(xy 331.987906 -310.242712) (xy 331.987906 -311.258712) (xy 332.67218 -311.258712) (xy 332.676251 -311.20309)
			(xy 332.688377 -311.148653) (xy 332.7083 -311.096562) (xy 332.735596 -311.047927) (xy 332.769682 -311.003784)
			(xy 332.809831 -310.965075) (xy 332.855189 -310.932624) (xy 332.904789 -310.907123) (xy 332.957573 -310.889116)
			(xy 333.012416 -310.878986) (xy 333.06815 -310.876949) (xy 333.123587 -310.883049) (xy 333.177544 -310.897155)
			(xy 333.228873 -310.918967) (xy 333.276479 -310.948021) (xy 333.319347 -310.983696) (xy 333.356564 -311.025233)
			(xy 333.387337 -311.071746) (xy 333.411009 -311.122243) (xy 333.427077 -311.17565) (xy 333.435197 -311.230826)
			(xy 333.435706 -311.258712) (xy 333.68818 -311.258712) (xy 333.692251 -311.20309) (xy 333.704377 -311.148653)
			(xy 333.7243 -311.096562) (xy 333.751596 -311.047927) (xy 333.785682 -311.003784) (xy 333.825831 -310.965075)
			(xy 333.871189 -310.932624) (xy 333.920789 -310.907123) (xy 333.973573 -310.889116) (xy 334.028416 -310.878986)
			(xy 334.08415 -310.876949) (xy 334.139587 -310.883049) (xy 334.193544 -310.897155) (xy 334.244873 -310.918967)
			(xy 334.292479 -310.948021) (xy 334.335347 -310.983696) (xy 334.372564 -311.025233) (xy 334.403337 -311.071746)
			(xy 334.427009 -311.122243) (xy 334.443077 -311.17565) (xy 334.451197 -311.230826) (xy 334.451706 -311.258712)
			(xy 334.70418 -311.258712) (xy 334.708251 -311.20309) (xy 334.720377 -311.148653) (xy 334.7403 -311.096562)
			(xy 334.767596 -311.047927) (xy 334.801682 -311.003784) (xy 334.841831 -310.965075) (xy 334.887189 -310.932624)
			(xy 334.936789 -310.907123) (xy 334.989573 -310.889116) (xy 335.044416 -310.878986) (xy 335.10015 -310.876949)
			(xy 335.155587 -310.883049) (xy 335.209544 -310.897155) (xy 335.260873 -310.918967) (xy 335.308479 -310.948021)
			(xy 335.351347 -310.983696) (xy 335.388564 -311.025233) (xy 335.419337 -311.071746) (xy 335.443009 -311.122243)
			(xy 335.459077 -311.17565) (xy 335.467197 -311.230826) (xy 335.467706 -311.258712) (xy 335.72018 -311.258712)
			(xy 335.724251 -311.20309) (xy 335.736377 -311.148653) (xy 335.7563 -311.096562) (xy 335.783596 -311.047927)
			(xy 335.817682 -311.003784) (xy 335.857831 -310.965075) (xy 335.903189 -310.932624) (xy 335.952789 -310.907123)
			(xy 336.005573 -310.889116) (xy 336.060416 -310.878986) (xy 336.11615 -310.876949) (xy 336.171587 -310.883049)
			(xy 336.225544 -310.897155) (xy 336.276873 -310.918967) (xy 336.324479 -310.948021) (xy 336.367347 -310.983696)
			(xy 336.404564 -311.025233) (xy 336.435337 -311.071746) (xy 336.459009 -311.122243) (xy 336.475077 -311.17565)
			(xy 336.483197 -311.230826) (xy 336.483706 -311.258712) (xy 336.73618 -311.258712) (xy 336.740251 -311.20309)
			(xy 336.752377 -311.148653) (xy 336.7723 -311.096562) (xy 336.799596 -311.047927) (xy 336.833682 -311.003784)
			(xy 336.873831 -310.965075) (xy 336.919189 -310.932624) (xy 336.968789 -310.907123) (xy 337.021573 -310.889116)
			(xy 337.076416 -310.878986) (xy 337.13215 -310.876949) (xy 337.187587 -310.883049) (xy 337.241544 -310.897155)
			(xy 337.292873 -310.918967) (xy 337.340479 -310.948021) (xy 337.383347 -310.983696) (xy 337.420564 -311.025233)
			(xy 337.451337 -311.071746) (xy 337.475009 -311.122243) (xy 337.491077 -311.17565) (xy 337.499197 -311.230826)
			(xy 337.499706 -311.258712) (xy 337.75218 -311.258712) (xy 337.756251 -311.20309) (xy 337.768377 -311.148653)
			(xy 337.7883 -311.096562) (xy 337.815596 -311.047927) (xy 337.849682 -311.003784) (xy 337.889831 -310.965075)
			(xy 337.935189 -310.932624) (xy 337.984789 -310.907123) (xy 338.037573 -310.889116) (xy 338.092416 -310.878986)
			(xy 338.14815 -310.876949) (xy 338.203587 -310.883049) (xy 338.257544 -310.897155) (xy 338.308873 -310.918967)
			(xy 338.356479 -310.948021) (xy 338.399347 -310.983696) (xy 338.436564 -311.025233) (xy 338.467337 -311.071746)
			(xy 338.491009 -311.122243) (xy 338.507077 -311.17565) (xy 338.515197 -311.230826) (xy 338.515706 -311.258712)
			(xy 338.76818 -311.258712) (xy 338.772251 -311.20309) (xy 338.784377 -311.148653) (xy 338.8043 -311.096562)
			(xy 338.831596 -311.047927) (xy 338.865682 -311.003784) (xy 338.905831 -310.965075) (xy 338.951189 -310.932624)
			(xy 339.000789 -310.907123) (xy 339.053573 -310.889116) (xy 339.108416 -310.878986) (xy 339.16415 -310.876949)
			(xy 339.219587 -310.883049) (xy 339.273544 -310.897155) (xy 339.324873 -310.918967) (xy 339.372479 -310.948021)
			(xy 339.415347 -310.983696) (xy 339.452564 -311.025233) (xy 339.483337 -311.071746) (xy 339.507009 -311.122243)
			(xy 339.523077 -311.17565) (xy 339.531197 -311.230826) (xy 339.531706 -311.258712) (xy 339.78418 -311.258712)
			(xy 339.788251 -311.20309) (xy 339.800377 -311.148653) (xy 339.8203 -311.096562) (xy 339.847596 -311.047927)
			(xy 339.881682 -311.003784) (xy 339.921831 -310.965075) (xy 339.967189 -310.932624) (xy 340.016789 -310.907123)
			(xy 340.069573 -310.889116) (xy 340.124416 -310.878986) (xy 340.18015 -310.876949) (xy 340.235587 -310.883049)
			(xy 340.289544 -310.897155) (xy 340.340873 -310.918967) (xy 340.388479 -310.948021) (xy 340.431347 -310.983696)
			(xy 340.468564 -311.025233) (xy 340.499337 -311.071746) (xy 340.523009 -311.122243) (xy 340.539077 -311.17565)
			(xy 340.547197 -311.230826) (xy 340.547706 -311.258712) (xy 340.547197 -311.286598) (xy 340.539077 -311.341774)
			(xy 340.523009 -311.395181) (xy 340.499337 -311.445678) (xy 340.468564 -311.492191) (xy 340.431347 -311.533728)
			(xy 340.388479 -311.569403) (xy 340.340873 -311.598457) (xy 340.289544 -311.620269) (xy 340.235587 -311.634375)
			(xy 340.18015 -311.640475) (xy 340.124416 -311.638438) (xy 340.069573 -311.628308) (xy 340.016789 -311.610301)
			(xy 339.967189 -311.5848) (xy 339.921831 -311.552349) (xy 339.881682 -311.51364) (xy 339.847596 -311.469497)
			(xy 339.8203 -311.420862) (xy 339.800377 -311.368771) (xy 339.788251 -311.314334) (xy 339.78418 -311.258712)
			(xy 339.531706 -311.258712) (xy 339.531197 -311.286598) (xy 339.523077 -311.341774) (xy 339.507009 -311.395181)
			(xy 339.483337 -311.445678) (xy 339.452564 -311.492191) (xy 339.415347 -311.533728) (xy 339.372479 -311.569403)
			(xy 339.324873 -311.598457) (xy 339.273544 -311.620269) (xy 339.219587 -311.634375) (xy 339.16415 -311.640475)
			(xy 339.108416 -311.638438) (xy 339.053573 -311.628308) (xy 339.000789 -311.610301) (xy 338.951189 -311.5848)
			(xy 338.905831 -311.552349) (xy 338.865682 -311.51364) (xy 338.831596 -311.469497) (xy 338.8043 -311.420862)
			(xy 338.784377 -311.368771) (xy 338.772251 -311.314334) (xy 338.76818 -311.258712) (xy 338.515706 -311.258712)
			(xy 338.515197 -311.286598) (xy 338.507077 -311.341774) (xy 338.491009 -311.395181) (xy 338.467337 -311.445678)
			(xy 338.436564 -311.492191) (xy 338.399347 -311.533728) (xy 338.356479 -311.569403) (xy 338.308873 -311.598457)
			(xy 338.257544 -311.620269) (xy 338.203587 -311.634375) (xy 338.14815 -311.640475) (xy 338.092416 -311.638438)
			(xy 338.037573 -311.628308) (xy 337.984789 -311.610301) (xy 337.935189 -311.5848) (xy 337.889831 -311.552349)
			(xy 337.849682 -311.51364) (xy 337.815596 -311.469497) (xy 337.7883 -311.420862) (xy 337.768377 -311.368771)
			(xy 337.756251 -311.314334) (xy 337.75218 -311.258712) (xy 337.499706 -311.258712) (xy 337.499197 -311.286598)
			(xy 337.491077 -311.341774) (xy 337.475009 -311.395181) (xy 337.451337 -311.445678) (xy 337.420564 -311.492191)
			(xy 337.383347 -311.533728) (xy 337.340479 -311.569403) (xy 337.292873 -311.598457) (xy 337.241544 -311.620269)
			(xy 337.187587 -311.634375) (xy 337.13215 -311.640475) (xy 337.076416 -311.638438) (xy 337.021573 -311.628308)
			(xy 336.968789 -311.610301) (xy 336.919189 -311.5848) (xy 336.873831 -311.552349) (xy 336.833682 -311.51364)
			(xy 336.799596 -311.469497) (xy 336.7723 -311.420862) (xy 336.752377 -311.368771) (xy 336.740251 -311.314334)
			(xy 336.73618 -311.258712) (xy 336.483706 -311.258712) (xy 336.483197 -311.286598) (xy 336.475077 -311.341774)
			(xy 336.459009 -311.395181) (xy 336.435337 -311.445678) (xy 336.404564 -311.492191) (xy 336.367347 -311.533728)
			(xy 336.324479 -311.569403) (xy 336.276873 -311.598457) (xy 336.225544 -311.620269) (xy 336.171587 -311.634375)
			(xy 336.11615 -311.640475) (xy 336.060416 -311.638438) (xy 336.005573 -311.628308) (xy 335.952789 -311.610301)
			(xy 335.903189 -311.5848) (xy 335.857831 -311.552349) (xy 335.817682 -311.51364) (xy 335.783596 -311.469497)
			(xy 335.7563 -311.420862) (xy 335.736377 -311.368771) (xy 335.724251 -311.314334) (xy 335.72018 -311.258712)
			(xy 335.467706 -311.258712) (xy 335.467197 -311.286598) (xy 335.459077 -311.341774) (xy 335.443009 -311.395181)
			(xy 335.419337 -311.445678) (xy 335.388564 -311.492191) (xy 335.351347 -311.533728) (xy 335.308479 -311.569403)
			(xy 335.260873 -311.598457) (xy 335.209544 -311.620269) (xy 335.155587 -311.634375) (xy 335.10015 -311.640475)
			(xy 335.044416 -311.638438) (xy 334.989573 -311.628308) (xy 334.936789 -311.610301) (xy 334.887189 -311.5848)
			(xy 334.841831 -311.552349) (xy 334.801682 -311.51364) (xy 334.767596 -311.469497) (xy 334.7403 -311.420862)
			(xy 334.720377 -311.368771) (xy 334.708251 -311.314334) (xy 334.70418 -311.258712) (xy 334.451706 -311.258712)
			(xy 334.451197 -311.286598) (xy 334.443077 -311.341774) (xy 334.427009 -311.395181) (xy 334.403337 -311.445678)
			(xy 334.372564 -311.492191) (xy 334.335347 -311.533728) (xy 334.292479 -311.569403) (xy 334.244873 -311.598457)
			(xy 334.193544 -311.620269) (xy 334.139587 -311.634375) (xy 334.08415 -311.640475) (xy 334.028416 -311.638438)
			(xy 333.973573 -311.628308) (xy 333.920789 -311.610301) (xy 333.871189 -311.5848) (xy 333.825831 -311.552349)
			(xy 333.785682 -311.51364) (xy 333.751596 -311.469497) (xy 333.7243 -311.420862) (xy 333.704377 -311.368771)
			(xy 333.692251 -311.314334) (xy 333.68818 -311.258712) (xy 333.435706 -311.258712) (xy 333.435197 -311.286598)
			(xy 333.427077 -311.341774) (xy 333.411009 -311.395181) (xy 333.387337 -311.445678) (xy 333.356564 -311.492191)
			(xy 333.319347 -311.533728) (xy 333.276479 -311.569403) (xy 333.228873 -311.598457) (xy 333.177544 -311.620269)
			(xy 333.123587 -311.634375) (xy 333.06815 -311.640475) (xy 333.012416 -311.638438) (xy 332.957573 -311.628308)
			(xy 332.904789 -311.610301) (xy 332.855189 -311.5848) (xy 332.809831 -311.552349) (xy 332.769682 -311.51364)
			(xy 332.735596 -311.469497) (xy 332.7083 -311.420862) (xy 332.688377 -311.368771) (xy 332.676251 -311.314334)
			(xy 332.67218 -311.258712) (xy 331.987906 -311.258712) (xy 331.987906 -312.274712) (xy 332.67218 -312.274712)
			(xy 332.676251 -312.21909) (xy 332.688377 -312.164653) (xy 332.7083 -312.112562) (xy 332.735596 -312.063927)
			(xy 332.769682 -312.019784) (xy 332.809831 -311.981075) (xy 332.855189 -311.948624) (xy 332.904789 -311.923123)
			(xy 332.957573 -311.905116) (xy 333.012416 -311.894986) (xy 333.06815 -311.892949) (xy 333.123587 -311.899049)
			(xy 333.177544 -311.913155) (xy 333.228873 -311.934967) (xy 333.276479 -311.964021) (xy 333.319347 -311.999696)
			(xy 333.356564 -312.041233) (xy 333.387337 -312.087746) (xy 333.411009 -312.138243) (xy 333.427077 -312.19165)
			(xy 333.435197 -312.246826) (xy 333.435706 -312.274712) (xy 333.68818 -312.274712) (xy 333.692251 -312.21909)
			(xy 333.704377 -312.164653) (xy 333.7243 -312.112562) (xy 333.751596 -312.063927) (xy 333.785682 -312.019784)
			(xy 333.825831 -311.981075) (xy 333.871189 -311.948624) (xy 333.920789 -311.923123) (xy 333.973573 -311.905116)
			(xy 334.028416 -311.894986) (xy 334.08415 -311.892949) (xy 334.139587 -311.899049) (xy 334.193544 -311.913155)
			(xy 334.244873 -311.934967) (xy 334.292479 -311.964021) (xy 334.335347 -311.999696) (xy 334.372564 -312.041233)
			(xy 334.403337 -312.087746) (xy 334.427009 -312.138243) (xy 334.443077 -312.19165) (xy 334.451197 -312.246826)
			(xy 334.451706 -312.274712) (xy 334.70418 -312.274712) (xy 334.708251 -312.21909) (xy 334.720377 -312.164653)
			(xy 334.7403 -312.112562) (xy 334.767596 -312.063927) (xy 334.801682 -312.019784) (xy 334.841831 -311.981075)
			(xy 334.887189 -311.948624) (xy 334.936789 -311.923123) (xy 334.989573 -311.905116) (xy 335.044416 -311.894986)
			(xy 335.10015 -311.892949) (xy 335.155587 -311.899049) (xy 335.209544 -311.913155) (xy 335.260873 -311.934967)
			(xy 335.308479 -311.964021) (xy 335.351347 -311.999696) (xy 335.388564 -312.041233) (xy 335.419337 -312.087746)
			(xy 335.443009 -312.138243) (xy 335.459077 -312.19165) (xy 335.467197 -312.246826) (xy 335.467706 -312.274712)
			(xy 335.72018 -312.274712) (xy 335.724251 -312.21909) (xy 335.736377 -312.164653) (xy 335.7563 -312.112562)
			(xy 335.783596 -312.063927) (xy 335.817682 -312.019784) (xy 335.857831 -311.981075) (xy 335.903189 -311.948624)
			(xy 335.952789 -311.923123) (xy 336.005573 -311.905116) (xy 336.060416 -311.894986) (xy 336.11615 -311.892949)
			(xy 336.171587 -311.899049) (xy 336.225544 -311.913155) (xy 336.276873 -311.934967) (xy 336.324479 -311.964021)
			(xy 336.367347 -311.999696) (xy 336.404564 -312.041233) (xy 336.435337 -312.087746) (xy 336.459009 -312.138243)
			(xy 336.475077 -312.19165) (xy 336.483197 -312.246826) (xy 336.483706 -312.274712) (xy 336.73618 -312.274712)
			(xy 336.740251 -312.21909) (xy 336.752377 -312.164653) (xy 336.7723 -312.112562) (xy 336.799596 -312.063927)
			(xy 336.833682 -312.019784) (xy 336.873831 -311.981075) (xy 336.919189 -311.948624) (xy 336.968789 -311.923123)
			(xy 337.021573 -311.905116) (xy 337.076416 -311.894986) (xy 337.13215 -311.892949) (xy 337.187587 -311.899049)
			(xy 337.241544 -311.913155) (xy 337.292873 -311.934967) (xy 337.340479 -311.964021) (xy 337.383347 -311.999696)
			(xy 337.420564 -312.041233) (xy 337.451337 -312.087746) (xy 337.475009 -312.138243) (xy 337.491077 -312.19165)
			(xy 337.499197 -312.246826) (xy 337.499706 -312.274712) (xy 337.75218 -312.274712) (xy 337.756251 -312.21909)
			(xy 337.768377 -312.164653) (xy 337.7883 -312.112562) (xy 337.815596 -312.063927) (xy 337.849682 -312.019784)
			(xy 337.889831 -311.981075) (xy 337.935189 -311.948624) (xy 337.984789 -311.923123) (xy 338.037573 -311.905116)
			(xy 338.092416 -311.894986) (xy 338.14815 -311.892949) (xy 338.203587 -311.899049) (xy 338.257544 -311.913155)
			(xy 338.308873 -311.934967) (xy 338.356479 -311.964021) (xy 338.399347 -311.999696) (xy 338.436564 -312.041233)
			(xy 338.467337 -312.087746) (xy 338.491009 -312.138243) (xy 338.507077 -312.19165) (xy 338.515197 -312.246826)
			(xy 338.515706 -312.274712) (xy 338.76818 -312.274712) (xy 338.772251 -312.21909) (xy 338.784377 -312.164653)
			(xy 338.8043 -312.112562) (xy 338.831596 -312.063927) (xy 338.865682 -312.019784) (xy 338.905831 -311.981075)
			(xy 338.951189 -311.948624) (xy 339.000789 -311.923123) (xy 339.053573 -311.905116) (xy 339.108416 -311.894986)
			(xy 339.16415 -311.892949) (xy 339.219587 -311.899049) (xy 339.273544 -311.913155) (xy 339.324873 -311.934967)
			(xy 339.372479 -311.964021) (xy 339.415347 -311.999696) (xy 339.452564 -312.041233) (xy 339.483337 -312.087746)
			(xy 339.507009 -312.138243) (xy 339.523077 -312.19165) (xy 339.531197 -312.246826) (xy 339.531706 -312.274712)
			(xy 339.78418 -312.274712) (xy 339.788251 -312.21909) (xy 339.800377 -312.164653) (xy 339.8203 -312.112562)
			(xy 339.847596 -312.063927) (xy 339.881682 -312.019784) (xy 339.921831 -311.981075) (xy 339.967189 -311.948624)
			(xy 340.016789 -311.923123) (xy 340.069573 -311.905116) (xy 340.124416 -311.894986) (xy 340.18015 -311.892949)
			(xy 340.235587 -311.899049) (xy 340.289544 -311.913155) (xy 340.340873 -311.934967) (xy 340.388479 -311.964021)
			(xy 340.431347 -311.999696) (xy 340.468564 -312.041233) (xy 340.499337 -312.087746) (xy 340.523009 -312.138243)
			(xy 340.539077 -312.19165) (xy 340.547197 -312.246826) (xy 340.547706 -312.274712) (xy 340.80018 -312.274712)
			(xy 340.804251 -312.21909) (xy 340.816377 -312.164653) (xy 340.8363 -312.112562) (xy 340.863596 -312.063927)
			(xy 340.897682 -312.019784) (xy 340.937831 -311.981075) (xy 340.983189 -311.948624) (xy 341.032789 -311.923123)
			(xy 341.085573 -311.905116) (xy 341.140416 -311.894986) (xy 341.19615 -311.892949) (xy 341.251587 -311.899049)
			(xy 341.305544 -311.913155) (xy 341.356873 -311.934967) (xy 341.404479 -311.964021) (xy 341.447347 -311.999696)
			(xy 341.484564 -312.041233) (xy 341.515337 -312.087746) (xy 341.539009 -312.138243) (xy 341.555077 -312.19165)
			(xy 341.563197 -312.246826) (xy 341.563706 -312.274712) (xy 341.81618 -312.274712) (xy 341.820251 -312.21909)
			(xy 341.832377 -312.164653) (xy 341.8523 -312.112562) (xy 341.879596 -312.063927) (xy 341.913682 -312.019784)
			(xy 341.953831 -311.981075) (xy 341.999189 -311.948624) (xy 342.048789 -311.923123) (xy 342.101573 -311.905116)
			(xy 342.156416 -311.894986) (xy 342.21215 -311.892949) (xy 342.267587 -311.899049) (xy 342.321544 -311.913155)
			(xy 342.372873 -311.934967) (xy 342.420479 -311.964021) (xy 342.463347 -311.999696) (xy 342.500564 -312.041233)
			(xy 342.531337 -312.087746) (xy 342.555009 -312.138243) (xy 342.571077 -312.19165) (xy 342.579197 -312.246826)
			(xy 342.579706 -312.274712) (xy 342.579197 -312.302598) (xy 342.571077 -312.357774) (xy 342.555009 -312.411181)
			(xy 342.531337 -312.461678) (xy 342.500564 -312.508191) (xy 342.463347 -312.549728) (xy 342.420479 -312.585403)
			(xy 342.372873 -312.614457) (xy 342.321544 -312.636269) (xy 342.267587 -312.650375) (xy 342.21215 -312.656475)
			(xy 342.156416 -312.654438) (xy 342.101573 -312.644308) (xy 342.048789 -312.626301) (xy 341.999189 -312.6008)
			(xy 341.953831 -312.568349) (xy 341.913682 -312.52964) (xy 341.879596 -312.485497) (xy 341.8523 -312.436862)
			(xy 341.832377 -312.384771) (xy 341.820251 -312.330334) (xy 341.81618 -312.274712) (xy 341.563706 -312.274712)
			(xy 341.563197 -312.302598) (xy 341.555077 -312.357774) (xy 341.539009 -312.411181) (xy 341.515337 -312.461678)
			(xy 341.484564 -312.508191) (xy 341.447347 -312.549728) (xy 341.404479 -312.585403) (xy 341.356873 -312.614457)
			(xy 341.305544 -312.636269) (xy 341.251587 -312.650375) (xy 341.19615 -312.656475) (xy 341.140416 -312.654438)
			(xy 341.085573 -312.644308) (xy 341.032789 -312.626301) (xy 340.983189 -312.6008) (xy 340.937831 -312.568349)
			(xy 340.897682 -312.52964) (xy 340.863596 -312.485497) (xy 340.8363 -312.436862) (xy 340.816377 -312.384771)
			(xy 340.804251 -312.330334) (xy 340.80018 -312.274712) (xy 340.547706 -312.274712) (xy 340.547197 -312.302598)
			(xy 340.539077 -312.357774) (xy 340.523009 -312.411181) (xy 340.499337 -312.461678) (xy 340.468564 -312.508191)
			(xy 340.431347 -312.549728) (xy 340.388479 -312.585403) (xy 340.340873 -312.614457) (xy 340.289544 -312.636269)
			(xy 340.235587 -312.650375) (xy 340.18015 -312.656475) (xy 340.124416 -312.654438) (xy 340.069573 -312.644308)
			(xy 340.016789 -312.626301) (xy 339.967189 -312.6008) (xy 339.921831 -312.568349) (xy 339.881682 -312.52964)
			(xy 339.847596 -312.485497) (xy 339.8203 -312.436862) (xy 339.800377 -312.384771) (xy 339.788251 -312.330334)
			(xy 339.78418 -312.274712) (xy 339.531706 -312.274712) (xy 339.531197 -312.302598) (xy 339.523077 -312.357774)
			(xy 339.507009 -312.411181) (xy 339.483337 -312.461678) (xy 339.452564 -312.508191) (xy 339.415347 -312.549728)
			(xy 339.372479 -312.585403) (xy 339.324873 -312.614457) (xy 339.273544 -312.636269) (xy 339.219587 -312.650375)
			(xy 339.16415 -312.656475) (xy 339.108416 -312.654438) (xy 339.053573 -312.644308) (xy 339.000789 -312.626301)
			(xy 338.951189 -312.6008) (xy 338.905831 -312.568349) (xy 338.865682 -312.52964) (xy 338.831596 -312.485497)
			(xy 338.8043 -312.436862) (xy 338.784377 -312.384771) (xy 338.772251 -312.330334) (xy 338.76818 -312.274712)
			(xy 338.515706 -312.274712) (xy 338.515197 -312.302598) (xy 338.507077 -312.357774) (xy 338.491009 -312.411181)
			(xy 338.467337 -312.461678) (xy 338.436564 -312.508191) (xy 338.399347 -312.549728) (xy 338.356479 -312.585403)
			(xy 338.308873 -312.614457) (xy 338.257544 -312.636269) (xy 338.203587 -312.650375) (xy 338.14815 -312.656475)
			(xy 338.092416 -312.654438) (xy 338.037573 -312.644308) (xy 337.984789 -312.626301) (xy 337.935189 -312.6008)
			(xy 337.889831 -312.568349) (xy 337.849682 -312.52964) (xy 337.815596 -312.485497) (xy 337.7883 -312.436862)
			(xy 337.768377 -312.384771) (xy 337.756251 -312.330334) (xy 337.75218 -312.274712) (xy 337.499706 -312.274712)
			(xy 337.499197 -312.302598) (xy 337.491077 -312.357774) (xy 337.475009 -312.411181) (xy 337.451337 -312.461678)
			(xy 337.420564 -312.508191) (xy 337.383347 -312.549728) (xy 337.340479 -312.585403) (xy 337.292873 -312.614457)
			(xy 337.241544 -312.636269) (xy 337.187587 -312.650375) (xy 337.13215 -312.656475) (xy 337.076416 -312.654438)
			(xy 337.021573 -312.644308) (xy 336.968789 -312.626301) (xy 336.919189 -312.6008) (xy 336.873831 -312.568349)
			(xy 336.833682 -312.52964) (xy 336.799596 -312.485497) (xy 336.7723 -312.436862) (xy 336.752377 -312.384771)
			(xy 336.740251 -312.330334) (xy 336.73618 -312.274712) (xy 336.483706 -312.274712) (xy 336.483197 -312.302598)
			(xy 336.475077 -312.357774) (xy 336.459009 -312.411181) (xy 336.435337 -312.461678) (xy 336.404564 -312.508191)
			(xy 336.367347 -312.549728) (xy 336.324479 -312.585403) (xy 336.276873 -312.614457) (xy 336.225544 -312.636269)
			(xy 336.171587 -312.650375) (xy 336.11615 -312.656475) (xy 336.060416 -312.654438) (xy 336.005573 -312.644308)
			(xy 335.952789 -312.626301) (xy 335.903189 -312.6008) (xy 335.857831 -312.568349) (xy 335.817682 -312.52964)
			(xy 335.783596 -312.485497) (xy 335.7563 -312.436862) (xy 335.736377 -312.384771) (xy 335.724251 -312.330334)
			(xy 335.72018 -312.274712) (xy 335.467706 -312.274712) (xy 335.467197 -312.302598) (xy 335.459077 -312.357774)
			(xy 335.443009 -312.411181) (xy 335.419337 -312.461678) (xy 335.388564 -312.508191) (xy 335.351347 -312.549728)
			(xy 335.308479 -312.585403) (xy 335.260873 -312.614457) (xy 335.209544 -312.636269) (xy 335.155587 -312.650375)
			(xy 335.10015 -312.656475) (xy 335.044416 -312.654438) (xy 334.989573 -312.644308) (xy 334.936789 -312.626301)
			(xy 334.887189 -312.6008) (xy 334.841831 -312.568349) (xy 334.801682 -312.52964) (xy 334.767596 -312.485497)
			(xy 334.7403 -312.436862) (xy 334.720377 -312.384771) (xy 334.708251 -312.330334) (xy 334.70418 -312.274712)
			(xy 334.451706 -312.274712) (xy 334.451197 -312.302598) (xy 334.443077 -312.357774) (xy 334.427009 -312.411181)
			(xy 334.403337 -312.461678) (xy 334.372564 -312.508191) (xy 334.335347 -312.549728) (xy 334.292479 -312.585403)
			(xy 334.244873 -312.614457) (xy 334.193544 -312.636269) (xy 334.139587 -312.650375) (xy 334.08415 -312.656475)
			(xy 334.028416 -312.654438) (xy 333.973573 -312.644308) (xy 333.920789 -312.626301) (xy 333.871189 -312.6008)
			(xy 333.825831 -312.568349) (xy 333.785682 -312.52964) (xy 333.751596 -312.485497) (xy 333.7243 -312.436862)
			(xy 333.704377 -312.384771) (xy 333.692251 -312.330334) (xy 333.68818 -312.274712) (xy 333.435706 -312.274712)
			(xy 333.435197 -312.302598) (xy 333.427077 -312.357774) (xy 333.411009 -312.411181) (xy 333.387337 -312.461678)
			(xy 333.356564 -312.508191) (xy 333.319347 -312.549728) (xy 333.276479 -312.585403) (xy 333.228873 -312.614457)
			(xy 333.177544 -312.636269) (xy 333.123587 -312.650375) (xy 333.06815 -312.656475) (xy 333.012416 -312.654438)
			(xy 332.957573 -312.644308) (xy 332.904789 -312.626301) (xy 332.855189 -312.6008) (xy 332.809831 -312.568349)
			(xy 332.769682 -312.52964) (xy 332.735596 -312.485497) (xy 332.7083 -312.436862) (xy 332.688377 -312.384771)
			(xy 332.676251 -312.330334) (xy 332.67218 -312.274712) (xy 331.987906 -312.274712) (xy 331.987906 -313.290712)
			(xy 332.67218 -313.290712) (xy 332.676251 -313.23509) (xy 332.688377 -313.180653) (xy 332.7083 -313.128562)
			(xy 332.735596 -313.079927) (xy 332.769682 -313.035784) (xy 332.809831 -312.997075) (xy 332.855189 -312.964624)
			(xy 332.904789 -312.939123) (xy 332.957573 -312.921116) (xy 333.012416 -312.910986) (xy 333.06815 -312.908949)
			(xy 333.123587 -312.915049) (xy 333.177544 -312.929155) (xy 333.228873 -312.950967) (xy 333.276479 -312.980021)
			(xy 333.319347 -313.015696) (xy 333.356564 -313.057233) (xy 333.387337 -313.103746) (xy 333.411009 -313.154243)
			(xy 333.427077 -313.20765) (xy 333.435197 -313.262826) (xy 333.435706 -313.290712) (xy 333.68818 -313.290712)
			(xy 333.692251 -313.23509) (xy 333.704377 -313.180653) (xy 333.7243 -313.128562) (xy 333.751596 -313.079927)
			(xy 333.785682 -313.035784) (xy 333.825831 -312.997075) (xy 333.871189 -312.964624) (xy 333.920789 -312.939123)
			(xy 333.973573 -312.921116) (xy 334.028416 -312.910986) (xy 334.08415 -312.908949) (xy 334.139587 -312.915049)
			(xy 334.193544 -312.929155) (xy 334.244873 -312.950967) (xy 334.292479 -312.980021) (xy 334.335347 -313.015696)
			(xy 334.372564 -313.057233) (xy 334.403337 -313.103746) (xy 334.427009 -313.154243) (xy 334.443077 -313.20765)
			(xy 334.451197 -313.262826) (xy 334.451706 -313.290712) (xy 334.70418 -313.290712) (xy 334.708251 -313.23509)
			(xy 334.720377 -313.180653) (xy 334.7403 -313.128562) (xy 334.767596 -313.079927) (xy 334.801682 -313.035784)
			(xy 334.841831 -312.997075) (xy 334.887189 -312.964624) (xy 334.936789 -312.939123) (xy 334.989573 -312.921116)
			(xy 335.044416 -312.910986) (xy 335.10015 -312.908949) (xy 335.155587 -312.915049) (xy 335.209544 -312.929155)
			(xy 335.260873 -312.950967) (xy 335.308479 -312.980021) (xy 335.351347 -313.015696) (xy 335.388564 -313.057233)
			(xy 335.419337 -313.103746) (xy 335.443009 -313.154243) (xy 335.459077 -313.20765) (xy 335.467197 -313.262826)
			(xy 335.467706 -313.290712) (xy 335.72018 -313.290712) (xy 335.724251 -313.23509) (xy 335.736377 -313.180653)
			(xy 335.7563 -313.128562) (xy 335.783596 -313.079927) (xy 335.817682 -313.035784) (xy 335.857831 -312.997075)
			(xy 335.903189 -312.964624) (xy 335.952789 -312.939123) (xy 336.005573 -312.921116) (xy 336.060416 -312.910986)
			(xy 336.11615 -312.908949) (xy 336.171587 -312.915049) (xy 336.225544 -312.929155) (xy 336.276873 -312.950967)
			(xy 336.324479 -312.980021) (xy 336.367347 -313.015696) (xy 336.404564 -313.057233) (xy 336.435337 -313.103746)
			(xy 336.459009 -313.154243) (xy 336.475077 -313.20765) (xy 336.483197 -313.262826) (xy 336.483706 -313.290712)
			(xy 336.73618 -313.290712) (xy 336.740251 -313.23509) (xy 336.752377 -313.180653) (xy 336.7723 -313.128562)
			(xy 336.799596 -313.079927) (xy 336.833682 -313.035784) (xy 336.873831 -312.997075) (xy 336.919189 -312.964624)
			(xy 336.968789 -312.939123) (xy 337.021573 -312.921116) (xy 337.076416 -312.910986) (xy 337.13215 -312.908949)
			(xy 337.187587 -312.915049) (xy 337.241544 -312.929155) (xy 337.292873 -312.950967) (xy 337.340479 -312.980021)
			(xy 337.383347 -313.015696) (xy 337.420564 -313.057233) (xy 337.451337 -313.103746) (xy 337.475009 -313.154243)
			(xy 337.491077 -313.20765) (xy 337.499197 -313.262826) (xy 337.499706 -313.290712) (xy 337.75218 -313.290712)
			(xy 337.756251 -313.23509) (xy 337.768377 -313.180653) (xy 337.7883 -313.128562) (xy 337.815596 -313.079927)
			(xy 337.849682 -313.035784) (xy 337.889831 -312.997075) (xy 337.935189 -312.964624) (xy 337.984789 -312.939123)
			(xy 338.037573 -312.921116) (xy 338.092416 -312.910986) (xy 338.14815 -312.908949) (xy 338.203587 -312.915049)
			(xy 338.257544 -312.929155) (xy 338.308873 -312.950967) (xy 338.356479 -312.980021) (xy 338.399347 -313.015696)
			(xy 338.436564 -313.057233) (xy 338.467337 -313.103746) (xy 338.491009 -313.154243) (xy 338.507077 -313.20765)
			(xy 338.515197 -313.262826) (xy 338.515706 -313.290712) (xy 338.76818 -313.290712) (xy 338.772251 -313.23509)
			(xy 338.784377 -313.180653) (xy 338.8043 -313.128562) (xy 338.831596 -313.079927) (xy 338.865682 -313.035784)
			(xy 338.905831 -312.997075) (xy 338.951189 -312.964624) (xy 339.000789 -312.939123) (xy 339.053573 -312.921116)
			(xy 339.108416 -312.910986) (xy 339.16415 -312.908949) (xy 339.219587 -312.915049) (xy 339.273544 -312.929155)
			(xy 339.324873 -312.950967) (xy 339.372479 -312.980021) (xy 339.415347 -313.015696) (xy 339.452564 -313.057233)
			(xy 339.483337 -313.103746) (xy 339.507009 -313.154243) (xy 339.523077 -313.20765) (xy 339.531197 -313.262826)
			(xy 339.531706 -313.290712) (xy 339.78418 -313.290712) (xy 339.788251 -313.23509) (xy 339.800377 -313.180653)
			(xy 339.8203 -313.128562) (xy 339.847596 -313.079927) (xy 339.881682 -313.035784) (xy 339.921831 -312.997075)
			(xy 339.967189 -312.964624) (xy 340.016789 -312.939123) (xy 340.069573 -312.921116) (xy 340.124416 -312.910986)
			(xy 340.18015 -312.908949) (xy 340.235587 -312.915049) (xy 340.289544 -312.929155) (xy 340.340873 -312.950967)
			(xy 340.388479 -312.980021) (xy 340.431347 -313.015696) (xy 340.468564 -313.057233) (xy 340.499337 -313.103746)
			(xy 340.523009 -313.154243) (xy 340.539077 -313.20765) (xy 340.547197 -313.262826) (xy 340.547706 -313.290712)
			(xy 340.80018 -313.290712) (xy 340.804251 -313.23509) (xy 340.816377 -313.180653) (xy 340.8363 -313.128562)
			(xy 340.863596 -313.079927) (xy 340.897682 -313.035784) (xy 340.937831 -312.997075) (xy 340.983189 -312.964624)
			(xy 341.032789 -312.939123) (xy 341.085573 -312.921116) (xy 341.140416 -312.910986) (xy 341.19615 -312.908949)
			(xy 341.251587 -312.915049) (xy 341.305544 -312.929155) (xy 341.356873 -312.950967) (xy 341.404479 -312.980021)
			(xy 341.447347 -313.015696) (xy 341.484564 -313.057233) (xy 341.515337 -313.103746) (xy 341.539009 -313.154243)
			(xy 341.555077 -313.20765) (xy 341.563197 -313.262826) (xy 341.563706 -313.290712) (xy 341.81618 -313.290712)
			(xy 341.820251 -313.23509) (xy 341.832377 -313.180653) (xy 341.8523 -313.128562) (xy 341.879596 -313.079927)
			(xy 341.913682 -313.035784) (xy 341.953831 -312.997075) (xy 341.999189 -312.964624) (xy 342.048789 -312.939123)
			(xy 342.101573 -312.921116) (xy 342.156416 -312.910986) (xy 342.21215 -312.908949) (xy 342.267587 -312.915049)
			(xy 342.321544 -312.929155) (xy 342.372873 -312.950967) (xy 342.420479 -312.980021) (xy 342.463347 -313.015696)
			(xy 342.500564 -313.057233) (xy 342.531337 -313.103746) (xy 342.555009 -313.154243) (xy 342.571077 -313.20765)
			(xy 342.579197 -313.262826) (xy 342.579706 -313.290712) (xy 342.579197 -313.318598) (xy 342.571077 -313.373774)
			(xy 342.555009 -313.427181) (xy 342.531337 -313.477678) (xy 342.500564 -313.524191) (xy 342.463347 -313.565728)
			(xy 342.420479 -313.601403) (xy 342.372873 -313.630457) (xy 342.321544 -313.652269) (xy 342.267587 -313.666375)
			(xy 342.21215 -313.672475) (xy 342.156416 -313.670438) (xy 342.101573 -313.660308) (xy 342.048789 -313.642301)
			(xy 341.999189 -313.6168) (xy 341.953831 -313.584349) (xy 341.913682 -313.54564) (xy 341.879596 -313.501497)
			(xy 341.8523 -313.452862) (xy 341.832377 -313.400771) (xy 341.820251 -313.346334) (xy 341.81618 -313.290712)
			(xy 341.563706 -313.290712) (xy 341.563197 -313.318598) (xy 341.555077 -313.373774) (xy 341.539009 -313.427181)
			(xy 341.515337 -313.477678) (xy 341.484564 -313.524191) (xy 341.447347 -313.565728) (xy 341.404479 -313.601403)
			(xy 341.356873 -313.630457) (xy 341.305544 -313.652269) (xy 341.251587 -313.666375) (xy 341.19615 -313.672475)
			(xy 341.140416 -313.670438) (xy 341.085573 -313.660308) (xy 341.032789 -313.642301) (xy 340.983189 -313.6168)
			(xy 340.937831 -313.584349) (xy 340.897682 -313.54564) (xy 340.863596 -313.501497) (xy 340.8363 -313.452862)
			(xy 340.816377 -313.400771) (xy 340.804251 -313.346334) (xy 340.80018 -313.290712) (xy 340.547706 -313.290712)
			(xy 340.547197 -313.318598) (xy 340.539077 -313.373774) (xy 340.523009 -313.427181) (xy 340.499337 -313.477678)
			(xy 340.468564 -313.524191) (xy 340.431347 -313.565728) (xy 340.388479 -313.601403) (xy 340.340873 -313.630457)
			(xy 340.289544 -313.652269) (xy 340.235587 -313.666375) (xy 340.18015 -313.672475) (xy 340.124416 -313.670438)
			(xy 340.069573 -313.660308) (xy 340.016789 -313.642301) (xy 339.967189 -313.6168) (xy 339.921831 -313.584349)
			(xy 339.881682 -313.54564) (xy 339.847596 -313.501497) (xy 339.8203 -313.452862) (xy 339.800377 -313.400771)
			(xy 339.788251 -313.346334) (xy 339.78418 -313.290712) (xy 339.531706 -313.290712) (xy 339.531197 -313.318598)
			(xy 339.523077 -313.373774) (xy 339.507009 -313.427181) (xy 339.483337 -313.477678) (xy 339.452564 -313.524191)
			(xy 339.415347 -313.565728) (xy 339.372479 -313.601403) (xy 339.324873 -313.630457) (xy 339.273544 -313.652269)
			(xy 339.219587 -313.666375) (xy 339.16415 -313.672475) (xy 339.108416 -313.670438) (xy 339.053573 -313.660308)
			(xy 339.000789 -313.642301) (xy 338.951189 -313.6168) (xy 338.905831 -313.584349) (xy 338.865682 -313.54564)
			(xy 338.831596 -313.501497) (xy 338.8043 -313.452862) (xy 338.784377 -313.400771) (xy 338.772251 -313.346334)
			(xy 338.76818 -313.290712) (xy 338.515706 -313.290712) (xy 338.515197 -313.318598) (xy 338.507077 -313.373774)
			(xy 338.491009 -313.427181) (xy 338.467337 -313.477678) (xy 338.436564 -313.524191) (xy 338.399347 -313.565728)
			(xy 338.356479 -313.601403) (xy 338.308873 -313.630457) (xy 338.257544 -313.652269) (xy 338.203587 -313.666375)
			(xy 338.14815 -313.672475) (xy 338.092416 -313.670438) (xy 338.037573 -313.660308) (xy 337.984789 -313.642301)
			(xy 337.935189 -313.6168) (xy 337.889831 -313.584349) (xy 337.849682 -313.54564) (xy 337.815596 -313.501497)
			(xy 337.7883 -313.452862) (xy 337.768377 -313.400771) (xy 337.756251 -313.346334) (xy 337.75218 -313.290712)
			(xy 337.499706 -313.290712) (xy 337.499197 -313.318598) (xy 337.491077 -313.373774) (xy 337.475009 -313.427181)
			(xy 337.451337 -313.477678) (xy 337.420564 -313.524191) (xy 337.383347 -313.565728) (xy 337.340479 -313.601403)
			(xy 337.292873 -313.630457) (xy 337.241544 -313.652269) (xy 337.187587 -313.666375) (xy 337.13215 -313.672475)
			(xy 337.076416 -313.670438) (xy 337.021573 -313.660308) (xy 336.968789 -313.642301) (xy 336.919189 -313.6168)
			(xy 336.873831 -313.584349) (xy 336.833682 -313.54564) (xy 336.799596 -313.501497) (xy 336.7723 -313.452862)
			(xy 336.752377 -313.400771) (xy 336.740251 -313.346334) (xy 336.73618 -313.290712) (xy 336.483706 -313.290712)
			(xy 336.483197 -313.318598) (xy 336.475077 -313.373774) (xy 336.459009 -313.427181) (xy 336.435337 -313.477678)
			(xy 336.404564 -313.524191) (xy 336.367347 -313.565728) (xy 336.324479 -313.601403) (xy 336.276873 -313.630457)
			(xy 336.225544 -313.652269) (xy 336.171587 -313.666375) (xy 336.11615 -313.672475) (xy 336.060416 -313.670438)
			(xy 336.005573 -313.660308) (xy 335.952789 -313.642301) (xy 335.903189 -313.6168) (xy 335.857831 -313.584349)
			(xy 335.817682 -313.54564) (xy 335.783596 -313.501497) (xy 335.7563 -313.452862) (xy 335.736377 -313.400771)
			(xy 335.724251 -313.346334) (xy 335.72018 -313.290712) (xy 335.467706 -313.290712) (xy 335.467197 -313.318598)
			(xy 335.459077 -313.373774) (xy 335.443009 -313.427181) (xy 335.419337 -313.477678) (xy 335.388564 -313.524191)
			(xy 335.351347 -313.565728) (xy 335.308479 -313.601403) (xy 335.260873 -313.630457) (xy 335.209544 -313.652269)
			(xy 335.155587 -313.666375) (xy 335.10015 -313.672475) (xy 335.044416 -313.670438) (xy 334.989573 -313.660308)
			(xy 334.936789 -313.642301) (xy 334.887189 -313.6168) (xy 334.841831 -313.584349) (xy 334.801682 -313.54564)
			(xy 334.767596 -313.501497) (xy 334.7403 -313.452862) (xy 334.720377 -313.400771) (xy 334.708251 -313.346334)
			(xy 334.70418 -313.290712) (xy 334.451706 -313.290712) (xy 334.451197 -313.318598) (xy 334.443077 -313.373774)
			(xy 334.427009 -313.427181) (xy 334.403337 -313.477678) (xy 334.372564 -313.524191) (xy 334.335347 -313.565728)
			(xy 334.292479 -313.601403) (xy 334.244873 -313.630457) (xy 334.193544 -313.652269) (xy 334.139587 -313.666375)
			(xy 334.08415 -313.672475) (xy 334.028416 -313.670438) (xy 333.973573 -313.660308) (xy 333.920789 -313.642301)
			(xy 333.871189 -313.6168) (xy 333.825831 -313.584349) (xy 333.785682 -313.54564) (xy 333.751596 -313.501497)
			(xy 333.7243 -313.452862) (xy 333.704377 -313.400771) (xy 333.692251 -313.346334) (xy 333.68818 -313.290712)
			(xy 333.435706 -313.290712) (xy 333.435197 -313.318598) (xy 333.427077 -313.373774) (xy 333.411009 -313.427181)
			(xy 333.387337 -313.477678) (xy 333.356564 -313.524191) (xy 333.319347 -313.565728) (xy 333.276479 -313.601403)
			(xy 333.228873 -313.630457) (xy 333.177544 -313.652269) (xy 333.123587 -313.666375) (xy 333.06815 -313.672475)
			(xy 333.012416 -313.670438) (xy 332.957573 -313.660308) (xy 332.904789 -313.642301) (xy 332.855189 -313.6168)
			(xy 332.809831 -313.584349) (xy 332.769682 -313.54564) (xy 332.735596 -313.501497) (xy 332.7083 -313.452862)
			(xy 332.688377 -313.400771) (xy 332.676251 -313.346334) (xy 332.67218 -313.290712) (xy 331.987906 -313.290712)
			(xy 331.987906 -314.306712) (xy 333.68818 -314.306712) (xy 333.692251 -314.25109) (xy 333.704377 -314.196653)
			(xy 333.7243 -314.144562) (xy 333.751596 -314.095927) (xy 333.785682 -314.051784) (xy 333.825831 -314.013075)
			(xy 333.871189 -313.980624) (xy 333.920789 -313.955123) (xy 333.973573 -313.937116) (xy 334.028416 -313.926986)
			(xy 334.08415 -313.924949) (xy 334.139587 -313.931049) (xy 334.193544 -313.945155) (xy 334.244873 -313.966967)
			(xy 334.292479 -313.996021) (xy 334.335347 -314.031696) (xy 334.372564 -314.073233) (xy 334.403337 -314.119746)
			(xy 334.427009 -314.170243) (xy 334.443077 -314.22365) (xy 334.451197 -314.278826) (xy 334.451706 -314.306712)
			(xy 334.70418 -314.306712) (xy 334.708251 -314.25109) (xy 334.720377 -314.196653) (xy 334.7403 -314.144562)
			(xy 334.767596 -314.095927) (xy 334.801682 -314.051784) (xy 334.841831 -314.013075) (xy 334.887189 -313.980624)
			(xy 334.936789 -313.955123) (xy 334.989573 -313.937116) (xy 335.044416 -313.926986) (xy 335.10015 -313.924949)
			(xy 335.155587 -313.931049) (xy 335.209544 -313.945155) (xy 335.260873 -313.966967) (xy 335.308479 -313.996021)
			(xy 335.351347 -314.031696) (xy 335.388564 -314.073233) (xy 335.419337 -314.119746) (xy 335.443009 -314.170243)
			(xy 335.459077 -314.22365) (xy 335.467197 -314.278826) (xy 335.467706 -314.306712) (xy 335.72018 -314.306712)
			(xy 335.724251 -314.25109) (xy 335.736377 -314.196653) (xy 335.7563 -314.144562) (xy 335.783596 -314.095927)
			(xy 335.817682 -314.051784) (xy 335.857831 -314.013075) (xy 335.903189 -313.980624) (xy 335.952789 -313.955123)
			(xy 336.005573 -313.937116) (xy 336.060416 -313.926986) (xy 336.11615 -313.924949) (xy 336.171587 -313.931049)
			(xy 336.225544 -313.945155) (xy 336.276873 -313.966967) (xy 336.324479 -313.996021) (xy 336.367347 -314.031696)
			(xy 336.404564 -314.073233) (xy 336.435337 -314.119746) (xy 336.459009 -314.170243) (xy 336.475077 -314.22365)
			(xy 336.483197 -314.278826) (xy 336.483706 -314.306712) (xy 336.73618 -314.306712) (xy 336.740251 -314.25109)
			(xy 336.752377 -314.196653) (xy 336.7723 -314.144562) (xy 336.799596 -314.095927) (xy 336.833682 -314.051784)
			(xy 336.873831 -314.013075) (xy 336.919189 -313.980624) (xy 336.968789 -313.955123) (xy 337.021573 -313.937116)
			(xy 337.076416 -313.926986) (xy 337.13215 -313.924949) (xy 337.187587 -313.931049) (xy 337.241544 -313.945155)
			(xy 337.292873 -313.966967) (xy 337.340479 -313.996021) (xy 337.383347 -314.031696) (xy 337.420564 -314.073233)
			(xy 337.451337 -314.119746) (xy 337.475009 -314.170243) (xy 337.491077 -314.22365) (xy 337.499197 -314.278826)
			(xy 337.499706 -314.306712) (xy 337.75218 -314.306712) (xy 337.756251 -314.25109) (xy 337.768377 -314.196653)
			(xy 337.7883 -314.144562) (xy 337.815596 -314.095927) (xy 337.849682 -314.051784) (xy 337.889831 -314.013075)
			(xy 337.935189 -313.980624) (xy 337.984789 -313.955123) (xy 338.037573 -313.937116) (xy 338.092416 -313.926986)
			(xy 338.14815 -313.924949) (xy 338.203587 -313.931049) (xy 338.257544 -313.945155) (xy 338.308873 -313.966967)
			(xy 338.356479 -313.996021) (xy 338.399347 -314.031696) (xy 338.436564 -314.073233) (xy 338.467337 -314.119746)
			(xy 338.491009 -314.170243) (xy 338.507077 -314.22365) (xy 338.515197 -314.278826) (xy 338.515706 -314.306712)
			(xy 338.76818 -314.306712) (xy 338.772251 -314.25109) (xy 338.784377 -314.196653) (xy 338.8043 -314.144562)
			(xy 338.831596 -314.095927) (xy 338.865682 -314.051784) (xy 338.905831 -314.013075) (xy 338.951189 -313.980624)
			(xy 339.000789 -313.955123) (xy 339.053573 -313.937116) (xy 339.108416 -313.926986) (xy 339.16415 -313.924949)
			(xy 339.219587 -313.931049) (xy 339.273544 -313.945155) (xy 339.324873 -313.966967) (xy 339.372479 -313.996021)
			(xy 339.415347 -314.031696) (xy 339.452564 -314.073233) (xy 339.483337 -314.119746) (xy 339.507009 -314.170243)
			(xy 339.523077 -314.22365) (xy 339.531197 -314.278826) (xy 339.531706 -314.306712) (xy 339.78418 -314.306712)
			(xy 339.788251 -314.25109) (xy 339.800377 -314.196653) (xy 339.8203 -314.144562) (xy 339.847596 -314.095927)
			(xy 339.881682 -314.051784) (xy 339.921831 -314.013075) (xy 339.967189 -313.980624) (xy 340.016789 -313.955123)
			(xy 340.069573 -313.937116) (xy 340.124416 -313.926986) (xy 340.18015 -313.924949) (xy 340.235587 -313.931049)
			(xy 340.289544 -313.945155) (xy 340.340873 -313.966967) (xy 340.388479 -313.996021) (xy 340.431347 -314.031696)
			(xy 340.468564 -314.073233) (xy 340.499337 -314.119746) (xy 340.523009 -314.170243) (xy 340.539077 -314.22365)
			(xy 340.547197 -314.278826) (xy 340.547706 -314.306712) (xy 340.80018 -314.306712) (xy 340.804251 -314.25109)
			(xy 340.816377 -314.196653) (xy 340.8363 -314.144562) (xy 340.863596 -314.095927) (xy 340.897682 -314.051784)
			(xy 340.937831 -314.013075) (xy 340.983189 -313.980624) (xy 341.032789 -313.955123) (xy 341.085573 -313.937116)
			(xy 341.140416 -313.926986) (xy 341.19615 -313.924949) (xy 341.251587 -313.931049) (xy 341.305544 -313.945155)
			(xy 341.356873 -313.966967) (xy 341.404479 -313.996021) (xy 341.447347 -314.031696) (xy 341.484564 -314.073233)
			(xy 341.515337 -314.119746) (xy 341.539009 -314.170243) (xy 341.555077 -314.22365) (xy 341.563197 -314.278826)
			(xy 341.563706 -314.306712) (xy 341.81618 -314.306712) (xy 341.820251 -314.25109) (xy 341.832377 -314.196653)
			(xy 341.8523 -314.144562) (xy 341.879596 -314.095927) (xy 341.913682 -314.051784) (xy 341.953831 -314.013075)
			(xy 341.999189 -313.980624) (xy 342.048789 -313.955123) (xy 342.101573 -313.937116) (xy 342.156416 -313.926986)
			(xy 342.21215 -313.924949) (xy 342.267587 -313.931049) (xy 342.321544 -313.945155) (xy 342.372873 -313.966967)
			(xy 342.420479 -313.996021) (xy 342.463347 -314.031696) (xy 342.500564 -314.073233) (xy 342.531337 -314.119746)
			(xy 342.555009 -314.170243) (xy 342.571077 -314.22365) (xy 342.579197 -314.278826) (xy 342.579706 -314.306712)
			(xy 342.579197 -314.334598) (xy 342.571077 -314.389774) (xy 342.555009 -314.443181) (xy 342.531337 -314.493678)
			(xy 342.500564 -314.540191) (xy 342.463347 -314.581728) (xy 342.420479 -314.617403) (xy 342.372873 -314.646457)
			(xy 342.321544 -314.668269) (xy 342.267587 -314.682375) (xy 342.21215 -314.688475) (xy 342.156416 -314.686438)
			(xy 342.101573 -314.676308) (xy 342.048789 -314.658301) (xy 341.999189 -314.6328) (xy 341.953831 -314.600349)
			(xy 341.913682 -314.56164) (xy 341.879596 -314.517497) (xy 341.8523 -314.468862) (xy 341.832377 -314.416771)
			(xy 341.820251 -314.362334) (xy 341.81618 -314.306712) (xy 341.563706 -314.306712) (xy 341.563197 -314.334598)
			(xy 341.555077 -314.389774) (xy 341.539009 -314.443181) (xy 341.515337 -314.493678) (xy 341.484564 -314.540191)
			(xy 341.447347 -314.581728) (xy 341.404479 -314.617403) (xy 341.356873 -314.646457) (xy 341.305544 -314.668269)
			(xy 341.251587 -314.682375) (xy 341.19615 -314.688475) (xy 341.140416 -314.686438) (xy 341.085573 -314.676308)
			(xy 341.032789 -314.658301) (xy 340.983189 -314.6328) (xy 340.937831 -314.600349) (xy 340.897682 -314.56164)
			(xy 340.863596 -314.517497) (xy 340.8363 -314.468862) (xy 340.816377 -314.416771) (xy 340.804251 -314.362334)
			(xy 340.80018 -314.306712) (xy 340.547706 -314.306712) (xy 340.547197 -314.334598) (xy 340.539077 -314.389774)
			(xy 340.523009 -314.443181) (xy 340.499337 -314.493678) (xy 340.468564 -314.540191) (xy 340.431347 -314.581728)
			(xy 340.388479 -314.617403) (xy 340.340873 -314.646457) (xy 340.289544 -314.668269) (xy 340.235587 -314.682375)
			(xy 340.18015 -314.688475) (xy 340.124416 -314.686438) (xy 340.069573 -314.676308) (xy 340.016789 -314.658301)
			(xy 339.967189 -314.6328) (xy 339.921831 -314.600349) (xy 339.881682 -314.56164) (xy 339.847596 -314.517497)
			(xy 339.8203 -314.468862) (xy 339.800377 -314.416771) (xy 339.788251 -314.362334) (xy 339.78418 -314.306712)
			(xy 339.531706 -314.306712) (xy 339.531197 -314.334598) (xy 339.523077 -314.389774) (xy 339.507009 -314.443181)
			(xy 339.483337 -314.493678) (xy 339.452564 -314.540191) (xy 339.415347 -314.581728) (xy 339.372479 -314.617403)
			(xy 339.324873 -314.646457) (xy 339.273544 -314.668269) (xy 339.219587 -314.682375) (xy 339.16415 -314.688475)
			(xy 339.108416 -314.686438) (xy 339.053573 -314.676308) (xy 339.000789 -314.658301) (xy 338.951189 -314.6328)
			(xy 338.905831 -314.600349) (xy 338.865682 -314.56164) (xy 338.831596 -314.517497) (xy 338.8043 -314.468862)
			(xy 338.784377 -314.416771) (xy 338.772251 -314.362334) (xy 338.76818 -314.306712) (xy 338.515706 -314.306712)
			(xy 338.515197 -314.334598) (xy 338.507077 -314.389774) (xy 338.491009 -314.443181) (xy 338.467337 -314.493678)
			(xy 338.436564 -314.540191) (xy 338.399347 -314.581728) (xy 338.356479 -314.617403) (xy 338.308873 -314.646457)
			(xy 338.257544 -314.668269) (xy 338.203587 -314.682375) (xy 338.14815 -314.688475) (xy 338.092416 -314.686438)
			(xy 338.037573 -314.676308) (xy 337.984789 -314.658301) (xy 337.935189 -314.6328) (xy 337.889831 -314.600349)
			(xy 337.849682 -314.56164) (xy 337.815596 -314.517497) (xy 337.7883 -314.468862) (xy 337.768377 -314.416771)
			(xy 337.756251 -314.362334) (xy 337.75218 -314.306712) (xy 337.499706 -314.306712) (xy 337.499197 -314.334598)
			(xy 337.491077 -314.389774) (xy 337.475009 -314.443181) (xy 337.451337 -314.493678) (xy 337.420564 -314.540191)
			(xy 337.383347 -314.581728) (xy 337.340479 -314.617403) (xy 337.292873 -314.646457) (xy 337.241544 -314.668269)
			(xy 337.187587 -314.682375) (xy 337.13215 -314.688475) (xy 337.076416 -314.686438) (xy 337.021573 -314.676308)
			(xy 336.968789 -314.658301) (xy 336.919189 -314.6328) (xy 336.873831 -314.600349) (xy 336.833682 -314.56164)
			(xy 336.799596 -314.517497) (xy 336.7723 -314.468862) (xy 336.752377 -314.416771) (xy 336.740251 -314.362334)
			(xy 336.73618 -314.306712) (xy 336.483706 -314.306712) (xy 336.483197 -314.334598) (xy 336.475077 -314.389774)
			(xy 336.459009 -314.443181) (xy 336.435337 -314.493678) (xy 336.404564 -314.540191) (xy 336.367347 -314.581728)
			(xy 336.324479 -314.617403) (xy 336.276873 -314.646457) (xy 336.225544 -314.668269) (xy 336.171587 -314.682375)
			(xy 336.11615 -314.688475) (xy 336.060416 -314.686438) (xy 336.005573 -314.676308) (xy 335.952789 -314.658301)
			(xy 335.903189 -314.6328) (xy 335.857831 -314.600349) (xy 335.817682 -314.56164) (xy 335.783596 -314.517497)
			(xy 335.7563 -314.468862) (xy 335.736377 -314.416771) (xy 335.724251 -314.362334) (xy 335.72018 -314.306712)
			(xy 335.467706 -314.306712) (xy 335.467197 -314.334598) (xy 335.459077 -314.389774) (xy 335.443009 -314.443181)
			(xy 335.419337 -314.493678) (xy 335.388564 -314.540191) (xy 335.351347 -314.581728) (xy 335.308479 -314.617403)
			(xy 335.260873 -314.646457) (xy 335.209544 -314.668269) (xy 335.155587 -314.682375) (xy 335.10015 -314.688475)
			(xy 335.044416 -314.686438) (xy 334.989573 -314.676308) (xy 334.936789 -314.658301) (xy 334.887189 -314.6328)
			(xy 334.841831 -314.600349) (xy 334.801682 -314.56164) (xy 334.767596 -314.517497) (xy 334.7403 -314.468862)
			(xy 334.720377 -314.416771) (xy 334.708251 -314.362334) (xy 334.70418 -314.306712) (xy 334.451706 -314.306712)
			(xy 334.451197 -314.334598) (xy 334.443077 -314.389774) (xy 334.427009 -314.443181) (xy 334.403337 -314.493678)
			(xy 334.372564 -314.540191) (xy 334.335347 -314.581728) (xy 334.292479 -314.617403) (xy 334.244873 -314.646457)
			(xy 334.193544 -314.668269) (xy 334.139587 -314.682375) (xy 334.08415 -314.688475) (xy 334.028416 -314.686438)
			(xy 333.973573 -314.676308) (xy 333.920789 -314.658301) (xy 333.871189 -314.6328) (xy 333.825831 -314.600349)
			(xy 333.785682 -314.56164) (xy 333.751596 -314.517497) (xy 333.7243 -314.468862) (xy 333.704377 -314.416771)
			(xy 333.692251 -314.362334) (xy 333.68818 -314.306712) (xy 331.987906 -314.306712) (xy 331.987906 -315.322712)
			(xy 333.68818 -315.322712) (xy 333.692251 -315.26709) (xy 333.704377 -315.212653) (xy 333.7243 -315.160562)
			(xy 333.751596 -315.111927) (xy 333.785682 -315.067784) (xy 333.825831 -315.029075) (xy 333.871189 -314.996624)
			(xy 333.920789 -314.971123) (xy 333.973573 -314.953116) (xy 334.028416 -314.942986) (xy 334.08415 -314.940949)
			(xy 334.139587 -314.947049) (xy 334.193544 -314.961155) (xy 334.244873 -314.982967) (xy 334.292479 -315.012021)
			(xy 334.335347 -315.047696) (xy 334.372564 -315.089233) (xy 334.403337 -315.135746) (xy 334.427009 -315.186243)
			(xy 334.443077 -315.23965) (xy 334.451197 -315.294826) (xy 334.451706 -315.322712) (xy 334.70418 -315.322712)
			(xy 334.708251 -315.26709) (xy 334.720377 -315.212653) (xy 334.7403 -315.160562) (xy 334.767596 -315.111927)
			(xy 334.801682 -315.067784) (xy 334.841831 -315.029075) (xy 334.887189 -314.996624) (xy 334.936789 -314.971123)
			(xy 334.989573 -314.953116) (xy 335.044416 -314.942986) (xy 335.10015 -314.940949) (xy 335.155587 -314.947049)
			(xy 335.209544 -314.961155) (xy 335.260873 -314.982967) (xy 335.308479 -315.012021) (xy 335.351347 -315.047696)
			(xy 335.388564 -315.089233) (xy 335.419337 -315.135746) (xy 335.443009 -315.186243) (xy 335.459077 -315.23965)
			(xy 335.467197 -315.294826) (xy 335.467706 -315.322712) (xy 335.72018 -315.322712) (xy 335.724251 -315.26709)
			(xy 335.736377 -315.212653) (xy 335.7563 -315.160562) (xy 335.783596 -315.111927) (xy 335.817682 -315.067784)
			(xy 335.857831 -315.029075) (xy 335.903189 -314.996624) (xy 335.952789 -314.971123) (xy 336.005573 -314.953116)
			(xy 336.060416 -314.942986) (xy 336.11615 -314.940949) (xy 336.171587 -314.947049) (xy 336.225544 -314.961155)
			(xy 336.276873 -314.982967) (xy 336.324479 -315.012021) (xy 336.367347 -315.047696) (xy 336.404564 -315.089233)
			(xy 336.435337 -315.135746) (xy 336.459009 -315.186243) (xy 336.475077 -315.23965) (xy 336.483197 -315.294826)
			(xy 336.483706 -315.322712) (xy 336.73618 -315.322712) (xy 336.740251 -315.26709) (xy 336.752377 -315.212653)
			(xy 336.7723 -315.160562) (xy 336.799596 -315.111927) (xy 336.833682 -315.067784) (xy 336.873831 -315.029075)
			(xy 336.919189 -314.996624) (xy 336.968789 -314.971123) (xy 337.021573 -314.953116) (xy 337.076416 -314.942986)
			(xy 337.13215 -314.940949) (xy 337.187587 -314.947049) (xy 337.241544 -314.961155) (xy 337.292873 -314.982967)
			(xy 337.340479 -315.012021) (xy 337.383347 -315.047696) (xy 337.420564 -315.089233) (xy 337.451337 -315.135746)
			(xy 337.475009 -315.186243) (xy 337.491077 -315.23965) (xy 337.499197 -315.294826) (xy 337.499706 -315.322712)
			(xy 337.75218 -315.322712) (xy 337.756251 -315.26709) (xy 337.768377 -315.212653) (xy 337.7883 -315.160562)
			(xy 337.815596 -315.111927) (xy 337.849682 -315.067784) (xy 337.889831 -315.029075) (xy 337.935189 -314.996624)
			(xy 337.984789 -314.971123) (xy 338.037573 -314.953116) (xy 338.092416 -314.942986) (xy 338.14815 -314.940949)
			(xy 338.203587 -314.947049) (xy 338.257544 -314.961155) (xy 338.308873 -314.982967) (xy 338.356479 -315.012021)
			(xy 338.399347 -315.047696) (xy 338.436564 -315.089233) (xy 338.467337 -315.135746) (xy 338.491009 -315.186243)
			(xy 338.507077 -315.23965) (xy 338.515197 -315.294826) (xy 338.515706 -315.322712) (xy 338.76818 -315.322712)
			(xy 338.772251 -315.26709) (xy 338.784377 -315.212653) (xy 338.8043 -315.160562) (xy 338.831596 -315.111927)
			(xy 338.865682 -315.067784) (xy 338.905831 -315.029075) (xy 338.951189 -314.996624) (xy 339.000789 -314.971123)
			(xy 339.053573 -314.953116) (xy 339.108416 -314.942986) (xy 339.16415 -314.940949) (xy 339.219587 -314.947049)
			(xy 339.273544 -314.961155) (xy 339.324873 -314.982967) (xy 339.372479 -315.012021) (xy 339.415347 -315.047696)
			(xy 339.452564 -315.089233) (xy 339.483337 -315.135746) (xy 339.507009 -315.186243) (xy 339.523077 -315.23965)
			(xy 339.531197 -315.294826) (xy 339.531706 -315.322712) (xy 339.78418 -315.322712) (xy 339.788251 -315.26709)
			(xy 339.800377 -315.212653) (xy 339.8203 -315.160562) (xy 339.847596 -315.111927) (xy 339.881682 -315.067784)
			(xy 339.921831 -315.029075) (xy 339.967189 -314.996624) (xy 340.016789 -314.971123) (xy 340.069573 -314.953116)
			(xy 340.124416 -314.942986) (xy 340.18015 -314.940949) (xy 340.235587 -314.947049) (xy 340.289544 -314.961155)
			(xy 340.340873 -314.982967) (xy 340.388479 -315.012021) (xy 340.431347 -315.047696) (xy 340.468564 -315.089233)
			(xy 340.499337 -315.135746) (xy 340.523009 -315.186243) (xy 340.539077 -315.23965) (xy 340.547197 -315.294826)
			(xy 340.547706 -315.322712) (xy 340.80018 -315.322712) (xy 340.804251 -315.26709) (xy 340.816377 -315.212653)
			(xy 340.8363 -315.160562) (xy 340.863596 -315.111927) (xy 340.897682 -315.067784) (xy 340.937831 -315.029075)
			(xy 340.983189 -314.996624) (xy 341.032789 -314.971123) (xy 341.085573 -314.953116) (xy 341.140416 -314.942986)
			(xy 341.19615 -314.940949) (xy 341.251587 -314.947049) (xy 341.305544 -314.961155) (xy 341.356873 -314.982967)
			(xy 341.404479 -315.012021) (xy 341.447347 -315.047696) (xy 341.484564 -315.089233) (xy 341.515337 -315.135746)
			(xy 341.539009 -315.186243) (xy 341.555077 -315.23965) (xy 341.563197 -315.294826) (xy 341.563706 -315.322712)
			(xy 341.81618 -315.322712) (xy 341.820251 -315.26709) (xy 341.832377 -315.212653) (xy 341.8523 -315.160562)
			(xy 341.879596 -315.111927) (xy 341.913682 -315.067784) (xy 341.953831 -315.029075) (xy 341.999189 -314.996624)
			(xy 342.048789 -314.971123) (xy 342.101573 -314.953116) (xy 342.156416 -314.942986) (xy 342.21215 -314.940949)
			(xy 342.267587 -314.947049) (xy 342.321544 -314.961155) (xy 342.372873 -314.982967) (xy 342.420479 -315.012021)
			(xy 342.463347 -315.047696) (xy 342.500564 -315.089233) (xy 342.531337 -315.135746) (xy 342.555009 -315.186243)
			(xy 342.571077 -315.23965) (xy 342.579197 -315.294826) (xy 342.579706 -315.322712) (xy 342.579197 -315.350598)
			(xy 342.571077 -315.405774) (xy 342.555009 -315.459181) (xy 342.531337 -315.509678) (xy 342.500564 -315.556191)
			(xy 342.463347 -315.597728) (xy 342.420479 -315.633403) (xy 342.372873 -315.662457) (xy 342.321544 -315.684269)
			(xy 342.267587 -315.698375) (xy 342.21215 -315.704475) (xy 342.156416 -315.702438) (xy 342.101573 -315.692308)
			(xy 342.048789 -315.674301) (xy 341.999189 -315.6488) (xy 341.953831 -315.616349) (xy 341.913682 -315.57764)
			(xy 341.879596 -315.533497) (xy 341.8523 -315.484862) (xy 341.832377 -315.432771) (xy 341.820251 -315.378334)
			(xy 341.81618 -315.322712) (xy 341.563706 -315.322712) (xy 341.563197 -315.350598) (xy 341.555077 -315.405774)
			(xy 341.539009 -315.459181) (xy 341.515337 -315.509678) (xy 341.484564 -315.556191) (xy 341.447347 -315.597728)
			(xy 341.404479 -315.633403) (xy 341.356873 -315.662457) (xy 341.305544 -315.684269) (xy 341.251587 -315.698375)
			(xy 341.19615 -315.704475) (xy 341.140416 -315.702438) (xy 341.085573 -315.692308) (xy 341.032789 -315.674301)
			(xy 340.983189 -315.6488) (xy 340.937831 -315.616349) (xy 340.897682 -315.57764) (xy 340.863596 -315.533497)
			(xy 340.8363 -315.484862) (xy 340.816377 -315.432771) (xy 340.804251 -315.378334) (xy 340.80018 -315.322712)
			(xy 340.547706 -315.322712) (xy 340.547197 -315.350598) (xy 340.539077 -315.405774) (xy 340.523009 -315.459181)
			(xy 340.499337 -315.509678) (xy 340.468564 -315.556191) (xy 340.431347 -315.597728) (xy 340.388479 -315.633403)
			(xy 340.340873 -315.662457) (xy 340.289544 -315.684269) (xy 340.235587 -315.698375) (xy 340.18015 -315.704475)
			(xy 340.124416 -315.702438) (xy 340.069573 -315.692308) (xy 340.016789 -315.674301) (xy 339.967189 -315.6488)
			(xy 339.921831 -315.616349) (xy 339.881682 -315.57764) (xy 339.847596 -315.533497) (xy 339.8203 -315.484862)
			(xy 339.800377 -315.432771) (xy 339.788251 -315.378334) (xy 339.78418 -315.322712) (xy 339.531706 -315.322712)
			(xy 339.531197 -315.350598) (xy 339.523077 -315.405774) (xy 339.507009 -315.459181) (xy 339.483337 -315.509678)
			(xy 339.452564 -315.556191) (xy 339.415347 -315.597728) (xy 339.372479 -315.633403) (xy 339.324873 -315.662457)
			(xy 339.273544 -315.684269) (xy 339.219587 -315.698375) (xy 339.16415 -315.704475) (xy 339.108416 -315.702438)
			(xy 339.053573 -315.692308) (xy 339.000789 -315.674301) (xy 338.951189 -315.6488) (xy 338.905831 -315.616349)
			(xy 338.865682 -315.57764) (xy 338.831596 -315.533497) (xy 338.8043 -315.484862) (xy 338.784377 -315.432771)
			(xy 338.772251 -315.378334) (xy 338.76818 -315.322712) (xy 338.515706 -315.322712) (xy 338.515197 -315.350598)
			(xy 338.507077 -315.405774) (xy 338.491009 -315.459181) (xy 338.467337 -315.509678) (xy 338.436564 -315.556191)
			(xy 338.399347 -315.597728) (xy 338.356479 -315.633403) (xy 338.308873 -315.662457) (xy 338.257544 -315.684269)
			(xy 338.203587 -315.698375) (xy 338.14815 -315.704475) (xy 338.092416 -315.702438) (xy 338.037573 -315.692308)
			(xy 337.984789 -315.674301) (xy 337.935189 -315.6488) (xy 337.889831 -315.616349) (xy 337.849682 -315.57764)
			(xy 337.815596 -315.533497) (xy 337.7883 -315.484862) (xy 337.768377 -315.432771) (xy 337.756251 -315.378334)
			(xy 337.75218 -315.322712) (xy 337.499706 -315.322712) (xy 337.499197 -315.350598) (xy 337.491077 -315.405774)
			(xy 337.475009 -315.459181) (xy 337.451337 -315.509678) (xy 337.420564 -315.556191) (xy 337.383347 -315.597728)
			(xy 337.340479 -315.633403) (xy 337.292873 -315.662457) (xy 337.241544 -315.684269) (xy 337.187587 -315.698375)
			(xy 337.13215 -315.704475) (xy 337.076416 -315.702438) (xy 337.021573 -315.692308) (xy 336.968789 -315.674301)
			(xy 336.919189 -315.6488) (xy 336.873831 -315.616349) (xy 336.833682 -315.57764) (xy 336.799596 -315.533497)
			(xy 336.7723 -315.484862) (xy 336.752377 -315.432771) (xy 336.740251 -315.378334) (xy 336.73618 -315.322712)
			(xy 336.483706 -315.322712) (xy 336.483197 -315.350598) (xy 336.475077 -315.405774) (xy 336.459009 -315.459181)
			(xy 336.435337 -315.509678) (xy 336.404564 -315.556191) (xy 336.367347 -315.597728) (xy 336.324479 -315.633403)
			(xy 336.276873 -315.662457) (xy 336.225544 -315.684269) (xy 336.171587 -315.698375) (xy 336.11615 -315.704475)
			(xy 336.060416 -315.702438) (xy 336.005573 -315.692308) (xy 335.952789 -315.674301) (xy 335.903189 -315.6488)
			(xy 335.857831 -315.616349) (xy 335.817682 -315.57764) (xy 335.783596 -315.533497) (xy 335.7563 -315.484862)
			(xy 335.736377 -315.432771) (xy 335.724251 -315.378334) (xy 335.72018 -315.322712) (xy 335.467706 -315.322712)
			(xy 335.467197 -315.350598) (xy 335.459077 -315.405774) (xy 335.443009 -315.459181) (xy 335.419337 -315.509678)
			(xy 335.388564 -315.556191) (xy 335.351347 -315.597728) (xy 335.308479 -315.633403) (xy 335.260873 -315.662457)
			(xy 335.209544 -315.684269) (xy 335.155587 -315.698375) (xy 335.10015 -315.704475) (xy 335.044416 -315.702438)
			(xy 334.989573 -315.692308) (xy 334.936789 -315.674301) (xy 334.887189 -315.6488) (xy 334.841831 -315.616349)
			(xy 334.801682 -315.57764) (xy 334.767596 -315.533497) (xy 334.7403 -315.484862) (xy 334.720377 -315.432771)
			(xy 334.708251 -315.378334) (xy 334.70418 -315.322712) (xy 334.451706 -315.322712) (xy 334.451197 -315.350598)
			(xy 334.443077 -315.405774) (xy 334.427009 -315.459181) (xy 334.403337 -315.509678) (xy 334.372564 -315.556191)
			(xy 334.335347 -315.597728) (xy 334.292479 -315.633403) (xy 334.244873 -315.662457) (xy 334.193544 -315.684269)
			(xy 334.139587 -315.698375) (xy 334.08415 -315.704475) (xy 334.028416 -315.702438) (xy 333.973573 -315.692308)
			(xy 333.920789 -315.674301) (xy 333.871189 -315.6488) (xy 333.825831 -315.616349) (xy 333.785682 -315.57764)
			(xy 333.751596 -315.533497) (xy 333.7243 -315.484862) (xy 333.704377 -315.432771) (xy 333.692251 -315.378334)
			(xy 333.68818 -315.322712) (xy 331.987906 -315.322712) (xy 331.987906 -316.338712) (xy 335.72018 -316.338712)
			(xy 335.724251 -316.28309) (xy 335.736377 -316.228653) (xy 335.7563 -316.176562) (xy 335.783596 -316.127927)
			(xy 335.817682 -316.083784) (xy 335.857831 -316.045075) (xy 335.903189 -316.012624) (xy 335.952789 -315.987123)
			(xy 336.005573 -315.969116) (xy 336.060416 -315.958986) (xy 336.11615 -315.956949) (xy 336.171587 -315.963049)
			(xy 336.225544 -315.977155) (xy 336.276873 -315.998967) (xy 336.324479 -316.028021) (xy 336.367347 -316.063696)
			(xy 336.404564 -316.105233) (xy 336.435337 -316.151746) (xy 336.459009 -316.202243) (xy 336.475077 -316.25565)
			(xy 336.483197 -316.310826) (xy 336.483706 -316.338712) (xy 336.73618 -316.338712) (xy 336.740251 -316.28309)
			(xy 336.752377 -316.228653) (xy 336.7723 -316.176562) (xy 336.799596 -316.127927) (xy 336.833682 -316.083784)
			(xy 336.873831 -316.045075) (xy 336.919189 -316.012624) (xy 336.968789 -315.987123) (xy 337.021573 -315.969116)
			(xy 337.076416 -315.958986) (xy 337.13215 -315.956949) (xy 337.187587 -315.963049) (xy 337.241544 -315.977155)
			(xy 337.292873 -315.998967) (xy 337.340479 -316.028021) (xy 337.383347 -316.063696) (xy 337.420564 -316.105233)
			(xy 337.451337 -316.151746) (xy 337.475009 -316.202243) (xy 337.491077 -316.25565) (xy 337.499197 -316.310826)
			(xy 337.499706 -316.338712) (xy 337.75218 -316.338712) (xy 337.756251 -316.28309) (xy 337.768377 -316.228653)
			(xy 337.7883 -316.176562) (xy 337.815596 -316.127927) (xy 337.849682 -316.083784) (xy 337.889831 -316.045075)
			(xy 337.935189 -316.012624) (xy 337.984789 -315.987123) (xy 338.037573 -315.969116) (xy 338.092416 -315.958986)
			(xy 338.14815 -315.956949) (xy 338.203587 -315.963049) (xy 338.257544 -315.977155) (xy 338.308873 -315.998967)
			(xy 338.356479 -316.028021) (xy 338.399347 -316.063696) (xy 338.436564 -316.105233) (xy 338.467337 -316.151746)
			(xy 338.491009 -316.202243) (xy 338.507077 -316.25565) (xy 338.515197 -316.310826) (xy 338.515706 -316.338712)
			(xy 338.76818 -316.338712) (xy 338.772251 -316.28309) (xy 338.784377 -316.228653) (xy 338.8043 -316.176562)
			(xy 338.831596 -316.127927) (xy 338.865682 -316.083784) (xy 338.905831 -316.045075) (xy 338.951189 -316.012624)
			(xy 339.000789 -315.987123) (xy 339.053573 -315.969116) (xy 339.108416 -315.958986) (xy 339.16415 -315.956949)
			(xy 339.219587 -315.963049) (xy 339.273544 -315.977155) (xy 339.324873 -315.998967) (xy 339.372479 -316.028021)
			(xy 339.415347 -316.063696) (xy 339.452564 -316.105233) (xy 339.483337 -316.151746) (xy 339.507009 -316.202243)
			(xy 339.523077 -316.25565) (xy 339.531197 -316.310826) (xy 339.531706 -316.338712) (xy 339.78418 -316.338712)
			(xy 339.788251 -316.28309) (xy 339.800377 -316.228653) (xy 339.8203 -316.176562) (xy 339.847596 -316.127927)
			(xy 339.881682 -316.083784) (xy 339.921831 -316.045075) (xy 339.967189 -316.012624) (xy 340.016789 -315.987123)
			(xy 340.069573 -315.969116) (xy 340.124416 -315.958986) (xy 340.18015 -315.956949) (xy 340.235587 -315.963049)
			(xy 340.289544 -315.977155) (xy 340.340873 -315.998967) (xy 340.388479 -316.028021) (xy 340.431347 -316.063696)
			(xy 340.468564 -316.105233) (xy 340.499337 -316.151746) (xy 340.523009 -316.202243) (xy 340.539077 -316.25565)
			(xy 340.547197 -316.310826) (xy 340.547706 -316.338712) (xy 340.80018 -316.338712) (xy 340.804251 -316.28309)
			(xy 340.816377 -316.228653) (xy 340.8363 -316.176562) (xy 340.863596 -316.127927) (xy 340.897682 -316.083784)
			(xy 340.937831 -316.045075) (xy 340.983189 -316.012624) (xy 341.032789 -315.987123) (xy 341.085573 -315.969116)
			(xy 341.140416 -315.958986) (xy 341.19615 -315.956949) (xy 341.251587 -315.963049) (xy 341.305544 -315.977155)
			(xy 341.356873 -315.998967) (xy 341.404479 -316.028021) (xy 341.447347 -316.063696) (xy 341.484564 -316.105233)
			(xy 341.515337 -316.151746) (xy 341.539009 -316.202243) (xy 341.555077 -316.25565) (xy 341.563197 -316.310826)
			(xy 341.563706 -316.338712) (xy 341.81618 -316.338712) (xy 341.820251 -316.28309) (xy 341.832377 -316.228653)
			(xy 341.8523 -316.176562) (xy 341.879596 -316.127927) (xy 341.913682 -316.083784) (xy 341.953831 -316.045075)
			(xy 341.999189 -316.012624) (xy 342.048789 -315.987123) (xy 342.101573 -315.969116) (xy 342.156416 -315.958986)
			(xy 342.21215 -315.956949) (xy 342.267587 -315.963049) (xy 342.321544 -315.977155) (xy 342.372873 -315.998967)
			(xy 342.420479 -316.028021) (xy 342.463347 -316.063696) (xy 342.500564 -316.105233) (xy 342.531337 -316.151746)
			(xy 342.555009 -316.202243) (xy 342.571077 -316.25565) (xy 342.579197 -316.310826) (xy 342.579706 -316.338712)
			(xy 342.579197 -316.366598) (xy 342.571077 -316.421774) (xy 342.555009 -316.475181) (xy 342.531337 -316.525678)
			(xy 342.500564 -316.572191) (xy 342.463347 -316.613728) (xy 342.420479 -316.649403) (xy 342.372873 -316.678457)
			(xy 342.321544 -316.700269) (xy 342.267587 -316.714375) (xy 342.21215 -316.720475) (xy 342.156416 -316.718438)
			(xy 342.101573 -316.708308) (xy 342.048789 -316.690301) (xy 341.999189 -316.6648) (xy 341.953831 -316.632349)
			(xy 341.913682 -316.59364) (xy 341.879596 -316.549497) (xy 341.8523 -316.500862) (xy 341.832377 -316.448771)
			(xy 341.820251 -316.394334) (xy 341.81618 -316.338712) (xy 341.563706 -316.338712) (xy 341.563197 -316.366598)
			(xy 341.555077 -316.421774) (xy 341.539009 -316.475181) (xy 341.515337 -316.525678) (xy 341.484564 -316.572191)
			(xy 341.447347 -316.613728) (xy 341.404479 -316.649403) (xy 341.356873 -316.678457) (xy 341.305544 -316.700269)
			(xy 341.251587 -316.714375) (xy 341.19615 -316.720475) (xy 341.140416 -316.718438) (xy 341.085573 -316.708308)
			(xy 341.032789 -316.690301) (xy 340.983189 -316.6648) (xy 340.937831 -316.632349) (xy 340.897682 -316.59364)
			(xy 340.863596 -316.549497) (xy 340.8363 -316.500862) (xy 340.816377 -316.448771) (xy 340.804251 -316.394334)
			(xy 340.80018 -316.338712) (xy 340.547706 -316.338712) (xy 340.547197 -316.366598) (xy 340.539077 -316.421774)
			(xy 340.523009 -316.475181) (xy 340.499337 -316.525678) (xy 340.468564 -316.572191) (xy 340.431347 -316.613728)
			(xy 340.388479 -316.649403) (xy 340.340873 -316.678457) (xy 340.289544 -316.700269) (xy 340.235587 -316.714375)
			(xy 340.18015 -316.720475) (xy 340.124416 -316.718438) (xy 340.069573 -316.708308) (xy 340.016789 -316.690301)
			(xy 339.967189 -316.6648) (xy 339.921831 -316.632349) (xy 339.881682 -316.59364) (xy 339.847596 -316.549497)
			(xy 339.8203 -316.500862) (xy 339.800377 -316.448771) (xy 339.788251 -316.394334) (xy 339.78418 -316.338712)
			(xy 339.531706 -316.338712) (xy 339.531197 -316.366598) (xy 339.523077 -316.421774) (xy 339.507009 -316.475181)
			(xy 339.483337 -316.525678) (xy 339.452564 -316.572191) (xy 339.415347 -316.613728) (xy 339.372479 -316.649403)
			(xy 339.324873 -316.678457) (xy 339.273544 -316.700269) (xy 339.219587 -316.714375) (xy 339.16415 -316.720475)
			(xy 339.108416 -316.718438) (xy 339.053573 -316.708308) (xy 339.000789 -316.690301) (xy 338.951189 -316.6648)
			(xy 338.905831 -316.632349) (xy 338.865682 -316.59364) (xy 338.831596 -316.549497) (xy 338.8043 -316.500862)
			(xy 338.784377 -316.448771) (xy 338.772251 -316.394334) (xy 338.76818 -316.338712) (xy 338.515706 -316.338712)
			(xy 338.515197 -316.366598) (xy 338.507077 -316.421774) (xy 338.491009 -316.475181) (xy 338.467337 -316.525678)
			(xy 338.436564 -316.572191) (xy 338.399347 -316.613728) (xy 338.356479 -316.649403) (xy 338.308873 -316.678457)
			(xy 338.257544 -316.700269) (xy 338.203587 -316.714375) (xy 338.14815 -316.720475) (xy 338.092416 -316.718438)
			(xy 338.037573 -316.708308) (xy 337.984789 -316.690301) (xy 337.935189 -316.6648) (xy 337.889831 -316.632349)
			(xy 337.849682 -316.59364) (xy 337.815596 -316.549497) (xy 337.7883 -316.500862) (xy 337.768377 -316.448771)
			(xy 337.756251 -316.394334) (xy 337.75218 -316.338712) (xy 337.499706 -316.338712) (xy 337.499197 -316.366598)
			(xy 337.491077 -316.421774) (xy 337.475009 -316.475181) (xy 337.451337 -316.525678) (xy 337.420564 -316.572191)
			(xy 337.383347 -316.613728) (xy 337.340479 -316.649403) (xy 337.292873 -316.678457) (xy 337.241544 -316.700269)
			(xy 337.187587 -316.714375) (xy 337.13215 -316.720475) (xy 337.076416 -316.718438) (xy 337.021573 -316.708308)
			(xy 336.968789 -316.690301) (xy 336.919189 -316.6648) (xy 336.873831 -316.632349) (xy 336.833682 -316.59364)
			(xy 336.799596 -316.549497) (xy 336.7723 -316.500862) (xy 336.752377 -316.448771) (xy 336.740251 -316.394334)
			(xy 336.73618 -316.338712) (xy 336.483706 -316.338712) (xy 336.483197 -316.366598) (xy 336.475077 -316.421774)
			(xy 336.459009 -316.475181) (xy 336.435337 -316.525678) (xy 336.404564 -316.572191) (xy 336.367347 -316.613728)
			(xy 336.324479 -316.649403) (xy 336.276873 -316.678457) (xy 336.225544 -316.700269) (xy 336.171587 -316.714375)
			(xy 336.11615 -316.720475) (xy 336.060416 -316.718438) (xy 336.005573 -316.708308) (xy 335.952789 -316.690301)
			(xy 335.903189 -316.6648) (xy 335.857831 -316.632349) (xy 335.817682 -316.59364) (xy 335.783596 -316.549497)
			(xy 335.7563 -316.500862) (xy 335.736377 -316.448771) (xy 335.724251 -316.394334) (xy 335.72018 -316.338712)
			(xy 331.987906 -316.338712) (xy 331.987906 -320.08064) (xy 338.422996 -320.08064) (xy 338.423507 -320.051722)
			(xy 338.432232 -319.994549) (xy 338.449489 -319.939349) (xy 338.474882 -319.887386) (xy 338.507829 -319.839853)
			(xy 338.547574 -319.797838) (xy 338.570062 -319.77965) (xy 338.578847 -319.772022) (xy 338.58904 -319.751137)
			(xy 338.58962 -319.739518) (xy 338.58962 -319.659762) (xy 338.589082 -319.64813) (xy 338.578891 -319.627221)
			(xy 338.570062 -319.61963) (xy 338.547585 -319.601432) (xy 338.507851 -319.559412) (xy 338.474912 -319.511879)
			(xy 338.449523 -319.459919) (xy 338.432265 -319.404723) (xy 338.423533 -319.347555) (xy 338.422996 -319.31864)
			(xy 338.423493 -319.291388) (xy 338.431244 -319.237438) (xy 338.446595 -319.185141) (xy 338.469233 -319.13556)
			(xy 338.498698 -319.089707) (xy 338.534388 -319.048514) (xy 338.575578 -319.012819) (xy 338.621429 -318.983351)
			(xy 338.671007 -318.960708) (xy 338.723303 -318.945352) (xy 338.777252 -318.937595) (xy 338.804504 -318.937132)
			(xy 338.833422 -318.937635) (xy 338.890594 -318.946366) (xy 338.945794 -318.963626) (xy 338.997756 -318.98902)
			(xy 339.045289 -319.021967) (xy 339.087305 -319.061711) (xy 339.105494 -319.084198) (xy 339.113114 -319.092992)
			(xy 339.134005 -319.103183) (xy 339.145626 -319.103756) (xy 339.225382 -319.103756) (xy 339.237013 -319.103207)
			(xy 339.257924 -319.093027) (xy 339.265514 -319.084198) (xy 339.282267 -319.063415) (xy 339.320621 -319.026285)
			(xy 339.363775 -318.994863) (xy 339.410889 -318.969764) (xy 339.461041 -318.951478) (xy 339.513252 -318.940361)
			(xy 339.566504 -318.936631) (xy 339.619756 -318.940361) (xy 339.671967 -318.951478) (xy 339.722119 -318.969764)
			(xy 339.769233 -318.994863) (xy 339.812387 -319.026285) (xy 339.850741 -319.063415) (xy 339.867494 -319.084198)
			(xy 339.875114 -319.092992) (xy 339.896005 -319.103183) (xy 339.907626 -319.103756) (xy 339.987382 -319.103756)
			(xy 339.999013 -319.103207) (xy 340.019924 -319.093027) (xy 340.027514 -319.084198) (xy 340.044267 -319.063415)
			(xy 340.082621 -319.026285) (xy 340.125775 -318.994863) (xy 340.172889 -318.969764) (xy 340.223041 -318.951478)
			(xy 340.275252 -318.940361) (xy 340.328504 -318.936631) (xy 340.381756 -318.940361) (xy 340.433967 -318.951478)
			(xy 340.484119 -318.969764) (xy 340.531233 -318.994863) (xy 340.574387 -319.026285) (xy 340.612741 -319.063415)
			(xy 340.629494 -319.084198) (xy 340.637114 -319.092992) (xy 340.658005 -319.103183) (xy 340.669626 -319.103756)
			(xy 340.749382 -319.103756) (xy 340.761013 -319.103207) (xy 340.781924 -319.093027) (xy 340.789514 -319.084198)
			(xy 340.806267 -319.063415) (xy 340.844621 -319.026285) (xy 340.887775 -318.994863) (xy 340.934889 -318.969764)
			(xy 340.985041 -318.951478) (xy 341.037252 -318.940361) (xy 341.090504 -318.936631) (xy 341.143756 -318.940361)
			(xy 341.195967 -318.951478) (xy 341.246119 -318.969764) (xy 341.293233 -318.994863) (xy 341.336387 -319.026285)
			(xy 341.374741 -319.063415) (xy 341.391494 -319.084198) (xy 341.399114 -319.092992) (xy 341.420005 -319.103183)
			(xy 341.431626 -319.103756) (xy 341.511382 -319.103756) (xy 341.523013 -319.103207) (xy 341.543924 -319.093027)
			(xy 341.551514 -319.084198) (xy 341.568267 -319.063415) (xy 341.606621 -319.026285) (xy 341.649775 -318.994863)
			(xy 341.696889 -318.969764) (xy 341.747041 -318.951478) (xy 341.799252 -318.940361) (xy 341.852504 -318.936631)
			(xy 341.905756 -318.940361) (xy 341.957967 -318.951478) (xy 342.008119 -318.969764) (xy 342.055233 -318.994863)
			(xy 342.098387 -319.026285) (xy 342.136741 -319.063415) (xy 342.153494 -319.084198) (xy 342.161114 -319.092992)
			(xy 342.182005 -319.103183) (xy 342.193626 -319.103756) (xy 342.273382 -319.103756) (xy 342.285013 -319.103207)
			(xy 342.305924 -319.093027) (xy 342.313514 -319.084198) (xy 342.330267 -319.063415) (xy 342.368621 -319.026285)
			(xy 342.411775 -318.994863) (xy 342.458889 -318.969764) (xy 342.509041 -318.951478) (xy 342.561252 -318.940361)
			(xy 342.614504 -318.936631) (xy 342.667756 -318.940361) (xy 342.719967 -318.951478) (xy 342.770119 -318.969764)
			(xy 342.817233 -318.994863) (xy 342.860387 -319.026285) (xy 342.898741 -319.063415) (xy 342.915494 -319.084198)
			(xy 342.923114 -319.092992) (xy 342.944005 -319.103183) (xy 342.955626 -319.103756) (xy 343.035382 -319.103756)
			(xy 343.047013 -319.103207) (xy 343.067924 -319.093027) (xy 343.075514 -319.084198) (xy 343.092267 -319.063415)
			(xy 343.130621 -319.026285) (xy 343.173775 -318.994863) (xy 343.220889 -318.969764) (xy 343.271041 -318.951478)
			(xy 343.323252 -318.940361) (xy 343.376504 -318.936631) (xy 343.429756 -318.940361) (xy 343.481967 -318.951478)
			(xy 343.532119 -318.969764) (xy 343.579233 -318.994863) (xy 343.622387 -319.026285) (xy 343.660741 -319.063415)
			(xy 343.677494 -319.084198) (xy 343.685114 -319.092992) (xy 343.706005 -319.103183) (xy 343.717626 -319.103756)
			(xy 343.797382 -319.103756) (xy 343.809013 -319.103207) (xy 343.829924 -319.093027) (xy 343.837514 -319.084198)
			(xy 343.854267 -319.063415) (xy 343.892621 -319.026285) (xy 343.935775 -318.994863) (xy 343.982889 -318.969764)
			(xy 344.033041 -318.951478) (xy 344.085252 -318.940361) (xy 344.138504 -318.936631) (xy 344.191756 -318.940361)
			(xy 344.243967 -318.951478) (xy 344.294119 -318.969764) (xy 344.341233 -318.994863) (xy 344.384387 -319.026285)
			(xy 344.422741 -319.063415) (xy 344.439494 -319.084198) (xy 344.447114 -319.092992) (xy 344.468005 -319.103183)
			(xy 344.479626 -319.103756) (xy 344.559382 -319.103756) (xy 344.571013 -319.103207) (xy 344.591924 -319.093027)
			(xy 344.599514 -319.084198) (xy 344.616267 -319.063415) (xy 344.654621 -319.026285) (xy 344.697775 -318.994863)
			(xy 344.744889 -318.969764) (xy 344.795041 -318.951478) (xy 344.847252 -318.940361) (xy 344.900504 -318.936631)
			(xy 344.953756 -318.940361) (xy 345.005967 -318.951478) (xy 345.056119 -318.969764) (xy 345.103233 -318.994863)
			(xy 345.146387 -319.026285) (xy 345.184741 -319.063415) (xy 345.201494 -319.084198) (xy 345.209114 -319.092992)
			(xy 345.230005 -319.103183) (xy 345.241626 -319.103756) (xy 345.321382 -319.103756) (xy 345.333013 -319.103207)
			(xy 345.353924 -319.093027) (xy 345.361514 -319.084198) (xy 345.378267 -319.063415) (xy 345.416621 -319.026285)
			(xy 345.459775 -318.994863) (xy 345.506889 -318.969764) (xy 345.557041 -318.951478) (xy 345.609252 -318.940361)
			(xy 345.662504 -318.936631) (xy 345.715756 -318.940361) (xy 345.767967 -318.951478) (xy 345.818119 -318.969764)
			(xy 345.865233 -318.994863) (xy 345.908387 -319.026285) (xy 345.946741 -319.063415) (xy 345.963494 -319.084198)
			(xy 345.971114 -319.092992) (xy 345.992005 -319.103183) (xy 346.003626 -319.103756) (xy 346.083382 -319.103756)
			(xy 346.095013 -319.103207) (xy 346.115924 -319.093027) (xy 346.123514 -319.084198) (xy 346.140267 -319.063415)
			(xy 346.178621 -319.026285) (xy 346.221775 -318.994863) (xy 346.268889 -318.969764) (xy 346.319041 -318.951478)
			(xy 346.371252 -318.940361) (xy 346.424504 -318.936631) (xy 346.477756 -318.940361) (xy 346.529967 -318.951478)
			(xy 346.580119 -318.969764) (xy 346.627233 -318.994863) (xy 346.670387 -319.026285) (xy 346.708741 -319.063415)
			(xy 346.725494 -319.084198) (xy 346.733114 -319.092992) (xy 346.754005 -319.103183) (xy 346.765626 -319.103756)
			(xy 346.845382 -319.103756) (xy 346.857013 -319.103207) (xy 346.877924 -319.093027) (xy 346.885514 -319.084198)
			(xy 346.903697 -319.061707) (xy 346.945718 -319.021973) (xy 346.993255 -318.989035) (xy 347.045218 -318.963647)
			(xy 347.100417 -318.946393) (xy 347.157588 -318.937666) (xy 347.186504 -318.937132) (xy 347.213759 -318.937552)
			(xy 347.267713 -318.94531) (xy 347.320014 -318.960669) (xy 347.369597 -318.983315) (xy 347.415452 -319.012787)
			(xy 347.456646 -319.048485) (xy 347.49234 -319.089683) (xy 347.521806 -319.135541) (xy 347.544447 -319.185127)
			(xy 347.559799 -319.23743) (xy 347.567551 -319.291385) (xy 347.568012 -319.31864) (xy 347.567484 -319.347557)
			(xy 347.558761 -319.404729) (xy 347.541508 -319.459929) (xy 347.516118 -319.511892) (xy 347.483174 -319.559426)
			(xy 347.443432 -319.601441) (xy 347.420946 -319.61963) (xy 347.412126 -319.627224) (xy 347.401951 -319.648135)
			(xy 347.401388 -319.659762) (xy 347.401388 -319.739518) (xy 347.401935 -319.751149) (xy 347.412119 -319.772058)
			(xy 347.420946 -319.77965) (xy 347.443415 -319.797858) (xy 347.483149 -319.839875) (xy 347.516088 -319.887407)
			(xy 347.541479 -319.939365) (xy 347.558739 -319.994559) (xy 347.567474 -320.051725) (xy 347.568012 -320.08064)
			(xy 347.567559 -320.107892) (xy 347.559798 -320.161841) (xy 347.544438 -320.214136) (xy 347.521792 -320.263713)
			(xy 347.492322 -320.309563) (xy 347.456627 -320.350753) (xy 347.415434 -320.386444) (xy 347.369581 -320.415909)
			(xy 347.320002 -320.43855) (xy 347.267706 -320.453905) (xy 347.213756 -320.461662) (xy 347.186504 -320.462148)
			(xy 347.157586 -320.461646) (xy 347.100413 -320.452917) (xy 347.045213 -320.435657) (xy 346.993251 -320.410262)
			(xy 346.945718 -320.377315) (xy 346.903703 -320.33757) (xy 346.885514 -320.315082) (xy 346.877894 -320.306288)
			(xy 346.857003 -320.296098) (xy 346.845382 -320.295524) (xy 346.765626 -320.295524) (xy 346.753996 -320.296084)
			(xy 346.733086 -320.306257) (xy 346.725494 -320.315082) (xy 346.708741 -320.335865) (xy 346.670387 -320.372995)
			(xy 346.627233 -320.404417) (xy 346.580119 -320.429516) (xy 346.529967 -320.447802) (xy 346.477756 -320.458919)
			(xy 346.424504 -320.462649) (xy 346.371252 -320.458919) (xy 346.319041 -320.447802) (xy 346.268889 -320.429516)
			(xy 346.221775 -320.404417) (xy 346.178621 -320.372995) (xy 346.140267 -320.335865) (xy 346.123514 -320.315082)
			(xy 346.115894 -320.306288) (xy 346.095003 -320.296098) (xy 346.083382 -320.295524) (xy 346.003626 -320.295524)
			(xy 345.991996 -320.296084) (xy 345.971086 -320.306257) (xy 345.963494 -320.315082) (xy 345.946741 -320.335865)
			(xy 345.908387 -320.372995) (xy 345.865233 -320.404417) (xy 345.818119 -320.429516) (xy 345.767967 -320.447802)
			(xy 345.715756 -320.458919) (xy 345.662504 -320.462649) (xy 345.609252 -320.458919) (xy 345.557041 -320.447802)
			(xy 345.506889 -320.429516) (xy 345.459775 -320.404417) (xy 345.416621 -320.372995) (xy 345.378267 -320.335865)
			(xy 345.361514 -320.315082) (xy 345.353894 -320.306288) (xy 345.333003 -320.296098) (xy 345.321382 -320.295524)
			(xy 345.241626 -320.295524) (xy 345.229996 -320.296084) (xy 345.209086 -320.306257) (xy 345.201494 -320.315082)
			(xy 345.184741 -320.335865) (xy 345.146387 -320.372995) (xy 345.103233 -320.404417) (xy 345.056119 -320.429516)
			(xy 345.005967 -320.447802) (xy 344.953756 -320.458919) (xy 344.900504 -320.462649) (xy 344.847252 -320.458919)
			(xy 344.795041 -320.447802) (xy 344.744889 -320.429516) (xy 344.697775 -320.404417) (xy 344.654621 -320.372995)
			(xy 344.616267 -320.335865) (xy 344.599514 -320.315082) (xy 344.591894 -320.306288) (xy 344.571003 -320.296098)
			(xy 344.559382 -320.295524) (xy 344.479626 -320.295524) (xy 344.467996 -320.296084) (xy 344.447086 -320.306257)
			(xy 344.439494 -320.315082) (xy 344.422741 -320.335865) (xy 344.384387 -320.372995) (xy 344.341233 -320.404417)
			(xy 344.294119 -320.429516) (xy 344.243967 -320.447802) (xy 344.191756 -320.458919) (xy 344.138504 -320.462649)
			(xy 344.085252 -320.458919) (xy 344.033041 -320.447802) (xy 343.982889 -320.429516) (xy 343.935775 -320.404417)
			(xy 343.892621 -320.372995) (xy 343.854267 -320.335865) (xy 343.837514 -320.315082) (xy 343.829894 -320.306288)
			(xy 343.809003 -320.296098) (xy 343.797382 -320.295524) (xy 343.717626 -320.295524) (xy 343.705996 -320.296084)
			(xy 343.685086 -320.306257) (xy 343.677494 -320.315082) (xy 343.660741 -320.335865) (xy 343.622387 -320.372995)
			(xy 343.579233 -320.404417) (xy 343.532119 -320.429516) (xy 343.481967 -320.447802) (xy 343.429756 -320.458919)
			(xy 343.376504 -320.462649) (xy 343.323252 -320.458919) (xy 343.271041 -320.447802) (xy 343.220889 -320.429516)
			(xy 343.173775 -320.404417) (xy 343.130621 -320.372995) (xy 343.092267 -320.335865) (xy 343.075514 -320.315082)
			(xy 343.067894 -320.306288) (xy 343.047003 -320.296098) (xy 343.035382 -320.295524) (xy 342.955626 -320.295524)
			(xy 342.943996 -320.296084) (xy 342.923086 -320.306257) (xy 342.915494 -320.315082) (xy 342.898741 -320.335865)
			(xy 342.860387 -320.372995) (xy 342.817233 -320.404417) (xy 342.770119 -320.429516) (xy 342.719967 -320.447802)
			(xy 342.667756 -320.458919) (xy 342.614504 -320.462649) (xy 342.561252 -320.458919) (xy 342.509041 -320.447802)
			(xy 342.458889 -320.429516) (xy 342.411775 -320.404417) (xy 342.368621 -320.372995) (xy 342.330267 -320.335865)
			(xy 342.313514 -320.315082) (xy 342.305894 -320.306288) (xy 342.285003 -320.296098) (xy 342.273382 -320.295524)
			(xy 342.193626 -320.295524) (xy 342.181996 -320.296084) (xy 342.161086 -320.306257) (xy 342.153494 -320.315082)
			(xy 342.136741 -320.335865) (xy 342.098387 -320.372995) (xy 342.055233 -320.404417) (xy 342.008119 -320.429516)
			(xy 341.957967 -320.447802) (xy 341.905756 -320.458919) (xy 341.852504 -320.462649) (xy 341.799252 -320.458919)
			(xy 341.747041 -320.447802) (xy 341.696889 -320.429516) (xy 341.649775 -320.404417) (xy 341.606621 -320.372995)
			(xy 341.568267 -320.335865) (xy 341.551514 -320.315082) (xy 341.543894 -320.306288) (xy 341.523003 -320.296098)
			(xy 341.511382 -320.295524) (xy 341.431626 -320.295524) (xy 341.419996 -320.296084) (xy 341.399086 -320.306257)
			(xy 341.391494 -320.315082) (xy 341.374741 -320.335865) (xy 341.336387 -320.372995) (xy 341.293233 -320.404417)
			(xy 341.246119 -320.429516) (xy 341.195967 -320.447802) (xy 341.143756 -320.458919) (xy 341.090504 -320.462649)
			(xy 341.037252 -320.458919) (xy 340.985041 -320.447802) (xy 340.934889 -320.429516) (xy 340.887775 -320.404417)
			(xy 340.844621 -320.372995) (xy 340.806267 -320.335865) (xy 340.789514 -320.315082) (xy 340.781894 -320.306288)
			(xy 340.761003 -320.296098) (xy 340.749382 -320.295524) (xy 340.669626 -320.295524) (xy 340.657996 -320.296084)
			(xy 340.637086 -320.306257) (xy 340.629494 -320.315082) (xy 340.612741 -320.335865) (xy 340.574387 -320.372995)
			(xy 340.531233 -320.404417) (xy 340.484119 -320.429516) (xy 340.433967 -320.447802) (xy 340.381756 -320.458919)
			(xy 340.328504 -320.462649) (xy 340.275252 -320.458919) (xy 340.223041 -320.447802) (xy 340.172889 -320.429516)
			(xy 340.125775 -320.404417) (xy 340.082621 -320.372995) (xy 340.044267 -320.335865) (xy 340.027514 -320.315082)
			(xy 340.019894 -320.306288) (xy 339.999003 -320.296098) (xy 339.987382 -320.295524) (xy 339.907626 -320.295524)
			(xy 339.895996 -320.296084) (xy 339.875086 -320.306257) (xy 339.867494 -320.315082) (xy 339.850741 -320.335865)
			(xy 339.812387 -320.372995) (xy 339.769233 -320.404417) (xy 339.722119 -320.429516) (xy 339.671967 -320.447802)
			(xy 339.619756 -320.458919) (xy 339.566504 -320.462649) (xy 339.513252 -320.458919) (xy 339.461041 -320.447802)
			(xy 339.410889 -320.429516) (xy 339.363775 -320.404417) (xy 339.320621 -320.372995) (xy 339.282267 -320.335865)
			(xy 339.265514 -320.315082) (xy 339.257894 -320.306288) (xy 339.237003 -320.296098) (xy 339.225382 -320.295524)
			(xy 339.145626 -320.295524) (xy 339.133996 -320.296084) (xy 339.113086 -320.306257) (xy 339.105494 -320.315082)
			(xy 339.087302 -320.337565) (xy 339.045283 -320.377301) (xy 338.997748 -320.41024) (xy 338.945787 -320.435629)
			(xy 338.89059 -320.452885) (xy 338.83342 -320.461614) (xy 338.804504 -320.462148) (xy 338.777255 -320.461619)
			(xy 338.723311 -320.453864) (xy 338.671019 -320.438511) (xy 338.621445 -320.415873) (xy 338.575596 -320.386411)
			(xy 338.534407 -320.350724) (xy 338.498715 -320.309539) (xy 338.469248 -320.263694) (xy 338.446604 -320.214122)
			(xy 338.431246 -320.161832) (xy 338.423485 -320.107889) (xy 338.422996 -320.08064) (xy 331.987906 -320.08064)
			(xy 331.987906 -324.717918) (xy 331.988333 -324.727987) (xy 331.996052 -324.746586) (xy 332.002892 -324.753986)
			(xy 332.32852 -325.079614) (xy 332.335915 -325.086467) (xy 332.354514 -325.094207) (xy 332.364588 -325.0946)
			(xy 333.125318 -325.0946) (xy 333.135387 -325.095027) (xy 333.153986 -325.102746) (xy 333.161386 -325.109586)
			(xy 333.410814 -325.359014) (xy 333.417668 -325.366409) (xy 333.42541 -325.385008) (xy 333.4258 -325.395082)
			(xy 333.4258 -329.026774) (xy 334.463644 -329.026774) (xy 334.463644 -329.026266) (xy 334.464253 -328.996348)
			(xy 334.473614 -328.937248) (xy 334.4921 -328.880339) (xy 334.519257 -328.82702) (xy 334.554416 -328.778602)
			(xy 334.57515 -328.757026) (xy 334.777588 -328.554588) (xy 334.784386 -328.547249) (xy 334.792033 -328.528778)
			(xy 334.792026 -328.508786) (xy 334.784365 -328.49032) (xy 334.777588 -328.48296) (xy 334.57515 -328.280522)
			(xy 334.554414 -328.25895) (xy 334.519274 -328.21052) (xy 334.492126 -328.157199) (xy 334.473633 -328.100293)
			(xy 334.464249 -328.041199) (xy 334.463644 -328.011282) (xy 334.463644 -328.010774) (xy 334.464107 -327.98354)
			(xy 334.471862 -327.929628) (xy 334.48721 -327.877368) (xy 334.509839 -327.827824) (xy 334.539289 -327.782004)
			(xy 334.574958 -327.740841) (xy 334.616123 -327.705174) (xy 334.661945 -327.675728) (xy 334.71149 -327.653102)
			(xy 334.763751 -327.637757) (xy 334.817664 -327.630006) (xy 334.844898 -327.62952) (xy 334.845406 -327.62952)
			(xy 334.875326 -327.630091) (xy 334.934427 -327.639462) (xy 334.991336 -327.657958) (xy 335.044654 -327.685123)
			(xy 335.09307 -327.720289) (xy 335.114646 -327.741026) (xy 335.29143 -327.91781) (xy 335.298825 -327.924657)
			(xy 335.317428 -327.932372) (xy 335.327498 -327.932796) (xy 346.185236 -327.932796) (xy 346.195311 -327.932417)
			(xy 346.21391 -327.924667) (xy 346.221304 -327.91781) (xy 348.506542 -325.632826) (xy 348.513369 -325.625416)
			(xy 348.521095 -325.606824) (xy 348.521528 -325.596758) (xy 348.521528 -307.243734) (xy 348.521104 -307.233664)
			(xy 348.513384 -307.215065) (xy 348.506542 -307.207666) (xy 347.784928 -306.486306) (xy 347.764114 -306.46472)
			(xy 347.72886 -306.416216) (xy 347.701632 -306.362791) (xy 347.683101 -306.305764) (xy 347.673723 -306.246539)
			(xy 347.673168 -306.216558) (xy 347.673168 -303.936146) (xy 347.673784 -303.90617) (xy 347.683168 -303.846955)
			(xy 347.701697 -303.789937) (xy 347.728914 -303.736518) (xy 347.76415 -303.688013) (xy 347.784928 -303.666398)
			(xy 348.26194 -303.189386) (xy 348.283535 -303.168674) (xy 348.331958 -303.13353) (xy 348.385273 -303.106376)
			(xy 348.442174 -303.087877) (xy 348.501264 -303.078488) (xy 348.53118 -303.07788) (xy 348.870016 -303.07788)
			(xy 348.880087 -303.077468) (xy 348.898685 -303.069738) (xy 348.906084 -303.062894) (xy 349.096838 -302.871886)
			(xy 349.118434 -302.851175) (xy 349.166857 -302.816031) (xy 349.220172 -302.788877) (xy 349.277072 -302.770378)
			(xy 349.336163 -302.760988) (xy 349.366078 -302.76038) (xy 349.366586 -302.76038) (xy 349.393822 -302.760822)
			(xy 349.44774 -302.768573) (xy 349.500005 -302.783918) (xy 349.549554 -302.806547) (xy 349.595379 -302.835997)
			(xy 349.636545 -302.871669) (xy 349.672215 -302.912837) (xy 349.701663 -302.958663) (xy 349.724289 -303.008214)
			(xy 349.739632 -303.06048) (xy 349.74738 -303.114398) (xy 349.74784 -303.141634) (xy 349.74784 -303.142142)
			(xy 349.747241 -303.172061) (xy 349.737878 -303.231161) (xy 349.71939 -303.288071) (xy 349.692231 -303.34139)
			(xy 349.657069 -303.389806) (xy 349.636334 -303.411382) (xy 349.433896 -303.61382) (xy 349.427092 -303.621153)
			(xy 349.419448 -303.639627) (xy 349.419458 -303.65962) (xy 349.427119 -303.678087) (xy 349.433896 -303.685448)
			(xy 349.636334 -303.887886) (xy 349.657071 -303.909458) (xy 349.692211 -303.957887) (xy 349.71936 -304.011209)
			(xy 349.737853 -304.068114) (xy 349.747236 -304.127209) (xy 349.74784 -304.157126) (xy 349.74784 -304.157634)
			(xy 349.7474 -304.184869) (xy 349.739644 -304.238783) (xy 349.724294 -304.291044) (xy 349.701663 -304.34059)
			(xy 349.672211 -304.38641) (xy 349.636539 -304.427573) (xy 349.595371 -304.46324) (xy 349.549547 -304.492686)
			(xy 349.499999 -304.51531) (xy 349.447736 -304.530654) (xy 349.393821 -304.538403) (xy 349.366586 -304.538888)
			(xy 349.366078 -304.538888) (xy 349.336158 -304.538325) (xy 349.277057 -304.528951) (xy 349.220147 -304.510454)
			(xy 349.166829 -304.483287) (xy 349.118413 -304.44812) (xy 349.096838 -304.427382) (xy 348.906084 -304.236374)
			(xy 348.898687 -304.229531) (xy 348.880085 -304.221814) (xy 348.870016 -304.221388) (xy 348.868746 -304.221388)
			(xy 348.858676 -304.221814) (xy 348.840077 -304.229532) (xy 348.832678 -304.236374) (xy 348.831916 -304.23739)
			(xy 348.82526 -304.244738) (xy 348.817694 -304.263047) (xy 348.817184 -304.27295) (xy 348.817184 -305.8795)
			(xy 348.817587 -305.889572) (xy 348.825321 -305.908171) (xy 348.83217 -305.915568) (xy 349.55353 -306.636928)
			(xy 349.574239 -306.658526) (xy 349.609383 -306.706948) (xy 349.636537 -306.760263) (xy 349.655036 -306.817163)
			(xy 349.664427 -306.876253) (xy 349.665036 -306.906168) (xy 349.665036 -325.934324) (xy 349.664489 -325.964245)
			(xy 349.655114 -326.023348) (xy 349.636613 -326.080258) (xy 349.609443 -326.133576) (xy 349.57427 -326.18199)
			(xy 349.55353 -326.203564) (xy 346.792042 -328.965052) (xy 346.770437 -328.985845) (xy 346.721938 -329.021102)
			(xy 346.668518 -329.048335) (xy 346.611495 -329.066871) (xy 346.552274 -329.076254) (xy 346.522294 -329.076812)
			(xy 335.355438 -329.076812) (xy 335.345371 -329.077254) (xy 335.326772 -329.084963) (xy 335.31937 -329.091798)
			(xy 335.114646 -329.296522) (xy 335.093058 -329.317242) (xy 335.044633 -329.352384) (xy 334.991316 -329.379537)
			(xy 334.934414 -329.398034) (xy 334.875322 -329.407421) (xy 334.845406 -329.408028) (xy 334.844898 -329.408028)
			(xy 334.817662 -329.407593) (xy 334.763745 -329.39984) (xy 334.711479 -329.384493) (xy 334.661931 -329.361863)
			(xy 334.616107 -329.332412) (xy 334.574941 -329.296739) (xy 334.539271 -329.255571) (xy 334.509823 -329.209745)
			(xy 334.487197 -329.160194) (xy 334.471854 -329.107928) (xy 334.464105 -329.05401) (xy 334.463644 -329.026774)
			(xy 333.4258 -329.026774) (xy 333.4258 -329.715368) (xy 333.426236 -329.725433) (xy 333.433967 -329.744019)
			(xy 333.440786 -329.751436) (xy 335.533238 -331.844142) (xy 335.540636 -331.850989) (xy 335.559235 -331.858718)
			(xy 335.569306 -331.859128)
		)
		(stroke
			(width 0)
			(type solid)
		)
		(fill yes)
		(layer "In5.Cu")
		(net "GND")
	)
	(gr_poly
		(pts
			(xy 59.300618 -315.21019) (xy 59.309573 -315.209843) (xy 59.326396 -315.203695) (xy 59.34009 -315.192151)
			(xy 59.344814 -315.184536) (xy 59.395106 -315.095636) (xy 59.394852 -315.068458) (xy 59.38774 -315.05652)
			(xy 59.374228 -315.032678) (xy 59.354989 -314.981369) (xy 59.345199 -314.927454) (xy 59.34456 -314.900056)
			(xy 59.34456 -314.899802) (xy 59.34503 -314.87581) (xy 59.352536 -314.828416) (xy 59.367363 -314.78278)
			(xy 59.389146 -314.740024) (xy 59.417349 -314.701203) (xy 59.451277 -314.667271) (xy 59.490095 -314.639064)
			(xy 59.532848 -314.617276) (xy 59.578483 -314.602444) (xy 59.625876 -314.594933) (xy 59.649868 -314.594494)
			(xy 59.658905 -314.59454) (xy 59.676951 -314.595557) (xy 59.685936 -314.596526) (xy 59.697874 -314.59805)
			(xy 59.720226 -314.589922) (xy 59.79287 -314.513722) (xy 59.799982 -314.490862) (xy 59.79795 -314.479178)
			(xy 59.795904 -314.465811) (xy 59.793741 -314.438853) (xy 59.793632 -314.42533) (xy 59.793632 -314.354464)
			(xy 59.793064 -314.343775) (xy 59.784394 -314.324231) (xy 59.776868 -314.316618) (xy 59.71286 -314.25896)
			(xy 59.692032 -314.252356) (xy 59.681618 -314.253626) (xy 59.649868 -314.25515) (xy 59.624611 -314.254626)
			(xy 59.574786 -314.246307) (xy 59.527011 -314.229901) (xy 59.482586 -314.205856) (xy 59.442725 -314.174827)
			(xy 59.408515 -314.13766) (xy 59.380888 -314.095371) (xy 59.360598 -314.04911) (xy 59.348198 -314.000142)
			(xy 59.344027 -313.9498) (xy 59.348198 -313.899458) (xy 59.360598 -313.85049) (xy 59.380888 -313.804229)
			(xy 59.408515 -313.76194) (xy 59.442725 -313.724773) (xy 59.482586 -313.693744) (xy 59.527011 -313.669699)
			(xy 59.574786 -313.653293) (xy 59.624611 -313.644974) (xy 59.649868 -313.644534) (xy 59.681618 -313.646058)
			(xy 59.692032 -313.647328) (xy 59.71286 -313.640724) (xy 59.776868 -313.583066) (xy 59.784522 -313.575547)
			(xy 59.793191 -313.555942) (xy 59.793632 -313.54522) (xy 59.793632 -313.474608) (xy 59.79384 -313.459534)
			(xy 59.796638 -313.429516) (xy 59.79922 -313.414664) (xy 59.79922 -313.413648) (xy 59.800236 -313.408568)
			(xy 59.793124 -313.385962) (xy 59.720226 -313.309762) (xy 59.697874 -313.301634) (xy 59.685936 -313.303158)
			(xy 59.676952 -313.304141) (xy 59.658906 -313.305158) (xy 59.649868 -313.30519) (xy 59.62505 -313.304702)
			(xy 59.576067 -313.296666) (xy 59.52903 -313.280813) (xy 59.485177 -313.257559) (xy 59.445664 -313.227516)
			(xy 59.411531 -313.191477) (xy 59.383678 -313.150391) (xy 59.362839 -313.105341) (xy 59.349563 -313.057512)
			(xy 59.344199 -313.008166) (xy 59.346888 -312.958601) (xy 59.357561 -312.910125) (xy 59.375935 -312.864014)
			(xy 59.401527 -312.821483) (xy 59.433663 -312.783653) (xy 59.471495 -312.751519) (xy 59.514027 -312.725929)
			(xy 59.560139 -312.707557) (xy 59.608615 -312.696887) (xy 59.65818 -312.694199) (xy 59.707526 -312.699565)
			(xy 59.755354 -312.712844) (xy 59.800404 -312.733685) (xy 59.841488 -312.76154) (xy 59.877526 -312.795674)
			(xy 59.907566 -312.835189) (xy 59.930818 -312.879043) (xy 59.94667 -312.926081) (xy 59.954703 -312.975063)
			(xy 59.955176 -312.999882) (xy 59.955129 -313.008919) (xy 59.954112 -313.026965) (xy 59.953144 -313.03595)
			(xy 59.95162 -313.047888) (xy 59.959748 -313.07024) (xy 60.035948 -313.143138) (xy 60.058554 -313.15025)
			(xy 60.064142 -313.149234) (xy 60.07918 -313.1466) (xy 60.109582 -313.1438) (xy 60.124848 -313.143646)
			(xy 60.139985 -313.143845) (xy 60.170131 -313.146644) (xy 60.185046 -313.149234) (xy 60.186062 -313.149234)
			(xy 60.191142 -313.15025) (xy 60.213748 -313.143138) (xy 60.289948 -313.07024) (xy 60.298076 -313.047888)
			(xy 60.296552 -313.03595) (xy 60.295569 -313.026966) (xy 60.29455 -313.00892) (xy 60.29452 -312.999882)
			(xy 60.295007 -312.975064) (xy 60.30304 -312.926083) (xy 60.318891 -312.879046) (xy 60.342143 -312.835194)
			(xy 60.372182 -312.79568) (xy 60.408219 -312.761547) (xy 60.449302 -312.733694) (xy 60.494351 -312.712853)
			(xy 60.542177 -312.699575) (xy 60.591522 -312.694209) (xy 60.641085 -312.696897) (xy 60.68956 -312.707567)
			(xy 60.73567 -312.725939) (xy 60.778201 -312.751528) (xy 60.816032 -312.783661) (xy 60.848166 -312.821491)
			(xy 60.873757 -312.864021) (xy 60.89213 -312.910131) (xy 60.902802 -312.958605) (xy 60.905491 -313.008168)
			(xy 60.900127 -313.057513) (xy 60.88685 -313.10534) (xy 60.866011 -313.150389) (xy 60.838159 -313.191474)
			(xy 60.804027 -313.227511) (xy 60.764515 -313.257552) (xy 60.720663 -313.280805) (xy 60.673627 -313.296658)
			(xy 60.624646 -313.304692) (xy 60.599828 -313.30519) (xy 60.590791 -313.305144) (xy 60.572745 -313.304127)
			(xy 60.56376 -313.303158) (xy 60.551822 -313.301634) (xy 60.52947 -313.309762) (xy 60.456572 -313.385962)
			(xy 60.44946 -313.408568) (xy 60.450476 -313.414156) (xy 60.453099 -313.429131) (xy 60.455898 -313.459406)
			(xy 60.456064 -313.474608) (xy 60.456064 -313.54522) (xy 60.456629 -313.55591) (xy 60.465294 -313.57546)
			(xy 60.472828 -313.583066) (xy 60.536836 -313.640724) (xy 60.557664 -313.647328) (xy 60.568078 -313.646058)
			(xy 60.599828 -313.644534) (xy 60.623819 -313.644982) (xy 60.671208 -313.652493) (xy 60.716839 -313.667324)
			(xy 60.759589 -313.689112) (xy 60.798403 -313.717319) (xy 60.832327 -313.75125) (xy 60.860525 -313.790071)
			(xy 60.882302 -313.832825) (xy 60.897124 -313.87846) (xy 60.904623 -313.925851) (xy 60.905136 -313.949842)
			(xy 60.905003 -313.963893) (xy 60.902456 -313.991877) (xy 60.900056 -314.005722) (xy 60.89777 -314.018168)
			(xy 60.905136 -314.042298) (xy 60.982352 -314.11926) (xy 61.005974 -314.126626) (xy 61.012578 -314.125356)
			(xy 61.042616 -314.119912) (xy 61.103653 -314.119659) (xy 61.133736 -314.124848) (xy 61.134244 -314.124848)
			(xy 61.143642 -314.126626) (xy 61.167264 -314.11926) (xy 61.24448 -314.042298) (xy 61.251846 -314.018168)
			(xy 61.24956 -314.005722) (xy 61.247172 -313.991876) (xy 61.24463 -313.963892) (xy 61.24448 -313.949842)
			(xy 61.244923 -313.925846) (xy 61.252424 -313.878445) (xy 61.267249 -313.832801) (xy 61.289032 -313.790038)
			(xy 61.317237 -313.75121) (xy 61.351169 -313.717272) (xy 61.389992 -313.68906) (xy 61.432751 -313.66727)
			(xy 61.478392 -313.652437) (xy 61.525792 -313.644927) (xy 61.549788 -313.644534) (xy 61.581538 -313.646312)
			(xy 61.582046 -313.646312) (xy 61.592669 -313.646835) (xy 61.61288 -313.640284) (xy 61.621162 -313.633612)
			(xy 61.677296 -313.583066) (xy 61.684946 -313.575545) (xy 61.69361 -313.55594) (xy 61.69406 -313.54522)
			(xy 61.69406 -313.474862) (xy 61.694256 -313.459851) (xy 61.697053 -313.429958) (xy 61.699648 -313.415172)
			(xy 61.699648 -313.414156) (xy 61.700664 -313.408568) (xy 61.693552 -313.385962) (xy 61.629036 -313.318398)
			(xy 61.620397 -313.310183) (xy 61.598004 -313.302094) (xy 61.58611 -313.302904) (xy 61.577066 -313.303952)
			(xy 61.558892 -313.305095) (xy 61.549788 -313.30519) (xy 61.524969 -313.304703) (xy 61.475986 -313.296671)
			(xy 61.428947 -313.28082) (xy 61.385092 -313.257568) (xy 61.345576 -313.227528) (xy 61.311441 -313.19149)
			(xy 61.283586 -313.150405) (xy 61.262744 -313.105354) (xy 61.249465 -313.057526) (xy 61.244099 -313.008179)
			(xy 61.246787 -312.958614) (xy 61.257457 -312.910137) (xy 61.27583 -312.864025) (xy 61.301421 -312.821492)
			(xy 61.333555 -312.78366) (xy 61.371387 -312.751524) (xy 61.413919 -312.725933) (xy 61.460031 -312.707559)
			(xy 61.508508 -312.696888) (xy 61.558073 -312.694199) (xy 61.60742 -312.699564) (xy 61.655249 -312.712842)
			(xy 61.7003 -312.733683) (xy 61.741385 -312.761538) (xy 61.777424 -312.795672) (xy 61.807465 -312.835187)
			(xy 61.830718 -312.879041) (xy 61.84657 -312.92608) (xy 61.854603 -312.975063) (xy 61.855096 -312.999882)
			(xy 61.854997 -313.008986) (xy 61.853851 -313.027159) (xy 61.85281 -313.036204) (xy 61.852012 -313.048096)
			(xy 61.860098 -313.070485) (xy 61.868304 -313.07913) (xy 61.935868 -313.143646) (xy 61.958474 -313.150758)
			(xy 61.96457 -313.149742) (xy 61.979485 -313.147146) (xy 62.00963 -313.144345) (xy 62.024768 -313.144154)
			(xy 62.039779 -313.144352) (xy 62.069671 -313.147151) (xy 62.084458 -313.149742) (xy 62.085474 -313.149742)
			(xy 62.091062 -313.150758) (xy 62.113668 -313.143646) (xy 62.181232 -313.07913) (xy 62.189455 -313.070494)
			(xy 62.197553 -313.048098) (xy 62.196726 -313.036204) (xy 62.195678 -313.02716) (xy 62.194536 -313.008986)
			(xy 62.19444 -312.999882) (xy 62.194888 -312.975891) (xy 62.202397 -312.928501) (xy 62.217228 -312.882868)
			(xy 62.239015 -312.840118) (xy 62.267221 -312.801303) (xy 62.301153 -312.767378) (xy 62.339975 -312.73918)
			(xy 62.38273 -312.717402) (xy 62.428365 -312.702581) (xy 62.475757 -312.695082) (xy 62.499748 -312.694574)
			(xy 62.500002 -312.694574) (xy 62.523015 -312.695018) (xy 62.568514 -312.701966) (xy 62.612461 -312.715646)
			(xy 62.633352 -312.725308) (xy 62.641235 -312.728789) (xy 62.658339 -312.730803) (xy 62.675145 -312.727041)
			(xy 62.682628 -312.722768) (xy 62.755526 -312.677048) (xy 62.76267 -312.672214) (xy 62.77345 -312.658764)
			(xy 62.779126 -312.642488) (xy 62.779402 -312.633868) (xy 62.779402 -312.415936) (xy 62.779061 -312.407329)
			(xy 62.773366 -312.391082) (xy 62.762635 -312.377621) (xy 62.755526 -312.372756) (xy 62.682628 -312.327036)
			(xy 62.675144 -312.322763) (xy 62.658339 -312.319001) (xy 62.641235 -312.321016) (xy 62.633352 -312.324496)
			(xy 62.612474 -312.334191) (xy 62.568526 -312.34788) (xy 62.523018 -312.354796) (xy 62.500002 -312.35523)
			(xy 62.499748 -312.35523) (xy 62.474486 -312.354741) (xy 62.42465 -312.346432) (xy 62.376861 -312.330033)
			(xy 62.332424 -312.305991) (xy 62.29255 -312.274962) (xy 62.258329 -312.237793) (xy 62.230692 -312.195497)
			(xy 62.210395 -312.149229) (xy 62.197991 -312.100252) (xy 62.193818 -312.0499) (xy 62.197991 -311.999548)
			(xy 62.210395 -311.950571) (xy 62.230692 -311.904303) (xy 62.258329 -311.862007) (xy 62.29255 -311.824838)
			(xy 62.332424 -311.793809) (xy 62.376861 -311.769767) (xy 62.42465 -311.753368) (xy 62.474486 -311.745059)
			(xy 62.499748 -311.744614) (xy 62.500002 -311.744614) (xy 62.523015 -311.745059) (xy 62.568514 -311.752007)
			(xy 62.61246 -311.765688) (xy 62.633352 -311.775348) (xy 62.641236 -311.778826) (xy 62.658339 -311.780839)
			(xy 62.675145 -311.77708) (xy 62.682628 -311.772808) (xy 62.755526 -311.727088) (xy 62.762663 -311.722251)
			(xy 62.773428 -311.708799) (xy 62.779085 -311.692525) (xy 62.779402 -311.683908) (xy 62.779402 -311.465976)
			(xy 62.779051 -311.457374) (xy 62.773344 -311.441142) (xy 62.762607 -311.427696) (xy 62.755526 -311.422796)
			(xy 62.682628 -311.377076) (xy 62.675143 -311.372807) (xy 62.658339 -311.369049) (xy 62.641237 -311.371061)
			(xy 62.633352 -311.374536) (xy 62.612474 -311.38423) (xy 62.568525 -311.397917) (xy 62.523017 -311.404832)
			(xy 62.500002 -311.40527) (xy 62.499748 -311.40527) (xy 62.474491 -311.404781) (xy 62.424664 -311.396474)
			(xy 62.376885 -311.380078) (xy 62.332457 -311.356041) (xy 62.292591 -311.325018) (xy 62.258376 -311.287856)
			(xy 62.230745 -311.245569) (xy 62.210452 -311.19931) (xy 62.19805 -311.150342) (xy 62.193878 -311.1)
			(xy 62.19805 -311.049658) (xy 62.210452 -311.00069) (xy 62.230745 -310.954431) (xy 62.258376 -310.912144)
			(xy 62.292591 -310.874982) (xy 62.332457 -310.843959) (xy 62.376885 -310.819922) (xy 62.424664 -310.803526)
			(xy 62.474491 -310.795219) (xy 62.499748 -310.794654) (xy 62.500002 -310.794654) (xy 62.523015 -310.795098)
			(xy 62.568514 -310.802046) (xy 62.612461 -310.815724) (xy 62.633352 -310.825388) (xy 62.641235 -310.82887)
			(xy 62.658339 -310.830885) (xy 62.675145 -310.827122) (xy 62.682628 -310.822848) (xy 62.755526 -310.777128)
			(xy 62.762667 -310.772293) (xy 62.773442 -310.758842) (xy 62.779112 -310.742567) (xy 62.779402 -310.733948)
			(xy 62.779402 -310.515762) (xy 62.779049 -310.507161) (xy 62.773339 -310.490932) (xy 62.762601 -310.47749)
			(xy 62.755526 -310.472582) (xy 62.682628 -310.426862) (xy 62.675143 -310.422594) (xy 62.658339 -310.418837)
			(xy 62.641237 -310.420849) (xy 62.633352 -310.424322) (xy 62.612474 -310.434017) (xy 62.568525 -310.447704)
			(xy 62.523017 -310.454619) (xy 62.500002 -310.455056) (xy 62.499748 -310.455056) (xy 62.474484 -310.454567)
			(xy 62.424643 -310.446257) (xy 62.376851 -310.429857) (xy 62.33241 -310.405813) (xy 62.292533 -310.374781)
			(xy 62.258308 -310.337609) (xy 62.230669 -310.295309) (xy 62.21037 -310.249038) (xy 62.197965 -310.200056)
			(xy 62.193792 -310.1497) (xy 62.197965 -310.099344) (xy 62.21037 -310.050362) (xy 62.230669 -310.004091)
			(xy 62.258308 -309.961791) (xy 62.292533 -309.924619) (xy 62.33241 -309.893587) (xy 62.376851 -309.869543)
			(xy 62.424643 -309.853143) (xy 62.474484 -309.844833) (xy 62.499748 -309.84444) (xy 62.500002 -309.84444)
			(xy 62.523015 -309.844884) (xy 62.568514 -309.851832) (xy 62.612462 -309.865509) (xy 62.633352 -309.875174)
			(xy 62.641235 -309.878656) (xy 62.658339 -309.880672) (xy 62.675145 -309.876908) (xy 62.682628 -309.872634)
			(xy 62.755526 -309.826914) (xy 62.762666 -309.822078) (xy 62.773437 -309.808627) (xy 62.779103 -309.792352)
			(xy 62.779402 -309.783734) (xy 62.779402 -308.981856) (xy 62.778873 -308.971589) (xy 62.770744 -308.952726)
			(xy 62.763654 -308.94528) (xy 62.746159 -308.92787) (xy 62.716464 -308.888448) (xy 62.693491 -308.844766)
			(xy 62.677838 -308.797959) (xy 62.669911 -308.749246) (xy 62.669916 -308.699891) (xy 62.677853 -308.651179)
			(xy 62.693516 -308.604376) (xy 62.716498 -308.560698) (xy 62.746201 -308.521282) (xy 62.763654 -308.503828)
			(xy 62.771274 -308.496462) (xy 62.779402 -308.477666) (xy 62.779402 -308.428898) (xy 62.778978 -308.418828)
			(xy 62.771264 -308.400224) (xy 62.764416 -308.39283) (xy 62.560454 -308.188868) (xy 62.533401 -308.16091)
			(xy 62.486152 -308.099104) (xy 62.447482 -308.031598) (xy 62.432184 -307.995828) (xy 62.427358 -307.983636)
			(xy 62.406276 -307.966872) (xy 62.293246 -307.9496) (xy 62.268608 -307.958998) (xy 62.259972 -307.969412)
			(xy 62.242417 -307.989769) (xy 62.201451 -308.024565) (xy 62.155021 -308.051645) (xy 62.104565 -308.070169)
			(xy 62.051643 -308.079565) (xy 62.024768 -308.080156) (xy 61.99951 -308.079632) (xy 61.949685 -308.071313)
			(xy 61.901908 -308.054907) (xy 61.857483 -308.030861) (xy 61.817621 -307.999831) (xy 61.78341 -307.962664)
			(xy 61.755782 -307.920374) (xy 61.735492 -307.874113) (xy 61.723092 -307.825143) (xy 61.71892 -307.7748)
			(xy 61.723092 -307.724457) (xy 61.735492 -307.675487) (xy 61.755782 -307.629226) (xy 61.78341 -307.586936)
			(xy 61.817621 -307.549769) (xy 61.857483 -307.518739) (xy 61.901908 -307.494693) (xy 61.949685 -307.478287)
			(xy 61.99951 -307.469968) (xy 62.024768 -307.46954) (xy 62.051629 -307.4701) (xy 62.104526 -307.479485)
			(xy 62.154968 -307.49797) (xy 62.201403 -307.524988) (xy 62.2424 -307.559706) (xy 62.259972 -307.58003)
			(xy 62.268608 -307.590444) (xy 62.293246 -307.599842) (xy 62.392814 -307.584602) (xy 62.401424 -307.58294)
			(xy 62.416854 -307.574635) (xy 62.428566 -307.561601) (xy 62.432184 -307.553614) (xy 62.445205 -307.522905)
			(xy 62.477226 -307.464387) (xy 62.515681 -307.409882) (xy 62.560073 -307.360092) (xy 62.609828 -307.315662)
			(xy 62.664304 -307.277166) (xy 62.722797 -307.2451) (xy 62.753494 -307.23205) (xy 62.761442 -307.228379)
			(xy 62.774433 -307.216659) (xy 62.782741 -307.201263) (xy 62.784482 -307.19268) (xy 62.799976 -307.093366)
			(xy 62.790324 -307.06822) (xy 62.77991 -307.059838) (xy 62.75964 -307.04226) (xy 62.725003 -307.001292)
			(xy 62.698046 -306.954909) (xy 62.679597 -306.904534) (xy 62.67022 -306.851712) (xy 62.669674 -306.824888)
			(xy 62.670196 -306.799633) (xy 62.678509 -306.749811) (xy 62.69491 -306.702037) (xy 62.718951 -306.657614)
			(xy 62.749975 -306.617754) (xy 62.787137 -306.583544) (xy 62.829423 -306.555918) (xy 62.875679 -306.535628)
			(xy 62.924644 -306.523228) (xy 62.974982 -306.519057) (xy 63.02532 -306.523228) (xy 63.074285 -306.535628)
			(xy 63.120541 -306.555918) (xy 63.162827 -306.583544) (xy 63.199989 -306.617754) (xy 63.231013 -306.657614)
			(xy 63.255054 -306.702037) (xy 63.271455 -306.749811) (xy 63.279768 -306.799633) (xy 63.28029 -306.824888)
			(xy 63.279727 -306.851727) (xy 63.27034 -306.904579) (xy 63.251854 -306.954973) (xy 63.224838 -307.001358)
			(xy 63.190125 -307.042302) (xy 63.1698 -307.059838) (xy 63.169546 -307.060092) (xy 63.163143 -307.06595)
			(xy 63.154376 -307.080914) (xy 63.151094 -307.097944) (xy 63.15202 -307.106574) (xy 63.165228 -307.192934)
			(xy 63.166894 -307.201541) (xy 63.175205 -307.216961) (xy 63.188242 -307.228661) (xy 63.196216 -307.232304)
			(xy 63.218296 -307.241562) (xy 63.261022 -307.263177) (xy 63.28156 -307.275484) (xy 63.296546 -307.284882)
			(xy 63.331344 -307.280818) (xy 63.462154 -307.150008) (xy 63.469555 -307.143169) (xy 63.488153 -307.135453)
			(xy 63.498222 -307.135022) (xy 63.678308 -307.135022) (xy 63.688378 -307.134598) (xy 63.706983 -307.126884)
			(xy 63.714376 -307.120036) (xy 63.715646 -307.118766) (xy 63.722323 -307.111356) (xy 63.729906 -307.092929)
			(xy 63.729893 -307.073003) (xy 63.722285 -307.054587) (xy 63.715646 -307.047138) (xy 63.71463 -307.046122)
			(xy 63.697005 -307.028719) (xy 63.667073 -306.989259) (xy 63.643912 -306.94548) (xy 63.62813 -306.898533)
			(xy 63.620144 -306.849652) (xy 63.619634 -306.824888) (xy 63.620081 -306.800897) (xy 63.62759 -306.753505)
			(xy 63.64242 -306.707872) (xy 63.664206 -306.66512) (xy 63.692413 -306.626304) (xy 63.726345 -306.592378)
			(xy 63.765166 -306.564178) (xy 63.807922 -306.542399) (xy 63.853558 -306.527577) (xy 63.900951 -306.520077)
			(xy 63.924942 -306.51958) (xy 63.949667 -306.520052) (xy 63.998474 -306.528007) (xy 64.045362 -306.543718)
			(xy 64.089108 -306.566776) (xy 64.128569 -306.596578) (xy 64.162716 -306.632346) (xy 64.190656 -306.673147)
			(xy 64.201548 -306.695348) (xy 64.206821 -306.705211) (xy 64.223982 -306.719511) (xy 64.245576 -306.725232)
			(xy 64.256666 -306.723796) (xy 64.283037 -306.719252) (xy 64.336334 -306.71442) (xy 64.363092 -306.714144)
			(xy 64.557402 -306.714144) (xy 64.566775 -306.713773) (xy 64.584299 -306.70713) (xy 64.598257 -306.694625)
			(xy 64.602868 -306.686458) (xy 64.602868 -306.686204) (xy 64.614183 -306.665045) (xy 64.642391 -306.626235)
			(xy 64.676323 -306.592315) (xy 64.715142 -306.564119) (xy 64.757893 -306.542341) (xy 64.803525 -306.527518)
			(xy 64.850913 -306.520014) (xy 64.898891 -306.520014) (xy 64.946279 -306.527518) (xy 64.991911 -306.542341)
			(xy 65.034662 -306.564119) (xy 65.073481 -306.592315) (xy 65.107413 -306.626235) (xy 65.135621 -306.665045)
			(xy 65.146936 -306.686204) (xy 65.146936 -306.686458) (xy 65.151577 -306.694603) (xy 65.165527 -306.707103)
			(xy 65.183035 -306.713759) (xy 65.192402 -306.714144) (xy 65.507362 -306.714144) (xy 65.516729 -306.713763)
			(xy 65.534236 -306.707107) (xy 65.548177 -306.694598) (xy 65.552828 -306.686458) (xy 65.552828 -306.686204)
			(xy 65.564143 -306.665045) (xy 65.592351 -306.626235) (xy 65.626283 -306.592315) (xy 65.665102 -306.564119)
			(xy 65.707853 -306.542341) (xy 65.753485 -306.527518) (xy 65.800873 -306.520014) (xy 65.848851 -306.520014)
			(xy 65.896239 -306.527518) (xy 65.941871 -306.542341) (xy 65.984622 -306.564119) (xy 66.023441 -306.592315)
			(xy 66.057373 -306.626235) (xy 66.085581 -306.665045) (xy 66.096896 -306.686204) (xy 66.096896 -306.686458)
			(xy 66.101536 -306.694608) (xy 66.115484 -306.707118) (xy 66.132993 -306.713788) (xy 66.142362 -306.714144)
			(xy 66.457322 -306.714144) (xy 66.466693 -306.71377) (xy 66.484211 -306.707123) (xy 66.498163 -306.694616)
			(xy 66.502788 -306.686458) (xy 66.502788 -306.686204) (xy 66.514103 -306.665045) (xy 66.542311 -306.626235)
			(xy 66.576243 -306.592315) (xy 66.615062 -306.564119) (xy 66.657813 -306.542341) (xy 66.703445 -306.527518)
			(xy 66.750833 -306.520014) (xy 66.798811 -306.520014) (xy 66.846199 -306.527518) (xy 66.891831 -306.542341)
			(xy 66.934582 -306.564119) (xy 66.973401 -306.592315) (xy 67.007333 -306.626235) (xy 67.035541 -306.665045)
			(xy 67.046856 -306.686204) (xy 67.046856 -306.686458) (xy 67.051498 -306.694601) (xy 67.065449 -306.707095)
			(xy 67.082956 -306.713744) (xy 67.092322 -306.714144) (xy 67.407282 -306.714144) (xy 67.416657 -306.713777)
			(xy 67.434186 -306.707138) (xy 67.44815 -306.694634) (xy 67.452748 -306.686458) (xy 67.452748 -306.686204)
			(xy 67.464063 -306.665045) (xy 67.492271 -306.626235) (xy 67.526203 -306.592315) (xy 67.565022 -306.564119)
			(xy 67.607773 -306.542341) (xy 67.653405 -306.527518) (xy 67.700793 -306.520014) (xy 67.748771 -306.520014)
			(xy 67.796159 -306.527518) (xy 67.841791 -306.542341) (xy 67.884542 -306.564119) (xy 67.923361 -306.592315)
			(xy 67.957293 -306.626235) (xy 67.985501 -306.665045) (xy 67.996816 -306.686204) (xy 67.996816 -306.686458)
			(xy 68.001456 -306.694605) (xy 68.015405 -306.70711) (xy 68.032914 -306.713773) (xy 68.042282 -306.714144)
			(xy 68.357242 -306.714144) (xy 68.366611 -306.713767) (xy 68.384124 -306.707115) (xy 68.39807 -306.694607)
			(xy 68.402708 -306.686458) (xy 68.402708 -306.686204) (xy 68.414023 -306.665045) (xy 68.442231 -306.626235)
			(xy 68.476163 -306.592315) (xy 68.514982 -306.564119) (xy 68.557733 -306.542341) (xy 68.603365 -306.527518)
			(xy 68.650753 -306.520014) (xy 68.698731 -306.520014) (xy 68.746119 -306.527518) (xy 68.791751 -306.542341)
			(xy 68.834502 -306.564119) (xy 68.873321 -306.592315) (xy 68.907253 -306.626235) (xy 68.935461 -306.665045)
			(xy 68.946776 -306.686204) (xy 68.946776 -306.686458) (xy 68.951419 -306.694599) (xy 68.965371 -306.707087)
			(xy 68.982878 -306.71373) (xy 68.992242 -306.714144) (xy 69.307456 -306.714144) (xy 69.316823 -306.713764)
			(xy 69.334332 -306.70711) (xy 69.348275 -306.694601) (xy 69.352922 -306.686458) (xy 69.352922 -306.686204)
			(xy 69.364598 -306.664363) (xy 69.393916 -306.624452) (xy 69.429288 -306.589792) (xy 69.469786 -306.56129)
			(xy 69.49186 -306.55006) (xy 69.504814 -306.543964) (xy 69.520308 -306.519072) (xy 69.520308 -306.180744)
			(xy 69.504814 -306.155852) (xy 69.49186 -306.149756) (xy 69.470074 -306.138676) (xy 69.430039 -306.110642)
			(xy 69.394983 -306.076586) (xy 69.365805 -306.037377) (xy 69.34325 -305.994019) (xy 69.327894 -305.947619)
			(xy 69.320131 -305.899365) (xy 69.319648 -305.874928) (xy 69.320088 -305.851597) (xy 69.327183 -305.805479)
			(xy 69.341211 -305.760976) (xy 69.361848 -305.719127) (xy 69.388611 -305.680903) (xy 69.420878 -305.647197)
			(xy 69.457897 -305.618792) (xy 69.498807 -305.59635) (xy 69.520562 -305.587908) (xy 69.520308 -305.577494)
			(xy 69.520308 -305.576478) (xy 69.520812 -305.543637) (xy 69.528242 -305.478374) (xy 69.542918 -305.414351)
			(xy 69.564655 -305.352368) (xy 69.593182 -305.293201) (xy 69.62814 -305.237593) (xy 69.669093 -305.186239)
			(xy 69.692012 -305.162712) (xy 69.859398 -304.995326) (xy 69.882977 -304.972419) (xy 69.934393 -304.931452)
			(xy 69.990072 -304.896498) (xy 70.049313 -304.867997) (xy 70.111373 -304.846306) (xy 70.175471 -304.831699)
			(xy 70.240801 -304.824359) (xy 70.273672 -304.823876) (xy 70.28688 -304.823876) (xy 70.296148 -304.799119)
			(xy 70.321948 -304.752985) (xy 70.355301 -304.711978) (xy 70.395212 -304.677321) (xy 70.44049 -304.650046)
			(xy 70.464934 -304.63998) (xy 70.472507 -304.636726) (xy 70.4852 -304.626228) (xy 70.489826 -304.619406)
			(xy 70.50532 -304.59426) (xy 70.50959 -304.586805) (xy 70.513373 -304.570057) (xy 70.512686 -304.561494)
			(xy 70.510885 -304.544789) (xy 70.508979 -304.51124) (xy 70.508876 -304.494438) (xy 70.508876 -304.31105)
			(xy 70.508354 -304.30055) (xy 70.499958 -304.2813) (xy 70.484581 -304.266997) (xy 70.47484 -304.263044)
			(xy 70.474586 -304.263044) (xy 70.450149 -304.253978) (xy 70.404549 -304.228738) (xy 70.363893 -304.196125)
			(xy 70.329362 -304.157087) (xy 70.301956 -304.112755) (xy 70.282471 -304.064414) (xy 70.271473 -304.013469)
			(xy 70.269862 -303.987454) (xy 70.269354 -303.973992) (xy 70.254876 -303.951132) (xy 70.176136 -303.909222)
			(xy 70.168061 -303.905381) (xy 70.150364 -303.902911) (xy 70.132889 -303.906634) (xy 70.125082 -303.911)
			(xy 70.117432 -303.91583) (xy 70.101673 -303.924723) (xy 70.093586 -303.92878) (xy 70.093078 -303.92878)
			(xy 70.084442 -303.932844) (xy 70.004432 -303.969928) (xy 69.986768 -303.977792) (xy 69.949961 -303.989634)
			(xy 69.931026 -303.99355) (xy 69.926962 -304.019458) (xy 69.926962 -304.019966) (xy 69.92294 -304.043758)
			(xy 69.908381 -304.08976) (xy 69.886766 -304.132897) (xy 69.858633 -304.172097) (xy 69.824683 -304.206383)
			(xy 69.785761 -304.2349) (xy 69.742838 -304.256938) (xy 69.696982 -304.271948) (xy 69.649335 -304.279557)
			(xy 69.62521 -304.280062) (xy 69.624702 -304.280062) (xy 69.605398 -304.279554) (xy 69.602604 -304.2793)
			(xy 69.577204 -304.292762) (xy 69.516752 -304.394108) (xy 69.502373 -304.417214) (xy 69.466982 -304.458549)
			(xy 69.425025 -304.493201) (xy 69.377745 -304.520142) (xy 69.326545 -304.538572) (xy 69.272942 -304.547947)
			(xy 69.245734 -304.54854) (xy 69.05625 -304.54854) (xy 69.032814 -304.548099) (xy 68.986461 -304.541132)
			(xy 68.941653 -304.527374) (xy 68.899378 -304.507129) (xy 68.860569 -304.480843) (xy 68.826082 -304.449098)
			(xy 68.79668 -304.412593) (xy 68.78447 -304.392584) (xy 68.723002 -304.287936) (xy 68.69811 -304.274474)
			(xy 68.69557 -304.274728) (xy 68.68033 -304.275236) (xy 68.679314 -304.275236) (xy 68.664074 -304.274728)
			(xy 68.661534 -304.274474) (xy 68.636642 -304.287936) (xy 68.575174 -304.392584) (xy 68.562945 -304.412575)
			(xy 68.533512 -304.449039) (xy 68.499014 -304.480754) (xy 68.460208 -304.507023) (xy 68.417947 -304.527271)
			(xy 68.373157 -304.541051) (xy 68.326824 -304.548062) (xy 68.303394 -304.54854) (xy 68.104004 -304.54854)
			(xy 68.076799 -304.547944) (xy 68.023202 -304.53856) (xy 67.972009 -304.520123) (xy 67.924738 -304.493177)
			(xy 67.882788 -304.458523) (xy 67.847405 -304.417187) (xy 67.832986 -304.394108) (xy 67.772534 -304.292762)
			(xy 67.747134 -304.2793) (xy 67.74434 -304.279554) (xy 67.725036 -304.280062) (xy 67.724528 -304.280062)
			(xy 67.705224 -304.279554) (xy 67.70243 -304.2793) (xy 67.67703 -304.292762) (xy 67.616578 -304.394108)
			(xy 67.6022 -304.417215) (xy 67.56681 -304.458554) (xy 67.524853 -304.493209) (xy 67.477573 -304.520153)
			(xy 67.426373 -304.538588) (xy 67.372769 -304.547967) (xy 67.34556 -304.54854) (xy 67.154044 -304.54854)
			(xy 67.126837 -304.547947) (xy 67.073236 -304.538569) (xy 67.022038 -304.520136) (xy 66.974761 -304.493194)
			(xy 66.932807 -304.458541) (xy 66.897418 -304.417205) (xy 66.883026 -304.394108) (xy 66.822574 -304.292762)
			(xy 66.797174 -304.2793) (xy 66.79438 -304.279554) (xy 66.775076 -304.280062) (xy 66.774568 -304.280062)
			(xy 66.755264 -304.279554) (xy 66.75247 -304.2793) (xy 66.72707 -304.292762) (xy 66.666618 -304.394108)
			(xy 66.652241 -304.417217) (xy 66.616852 -304.45856) (xy 66.574896 -304.493221) (xy 66.527617 -304.520171)
			(xy 66.476416 -304.538612) (xy 66.42281 -304.547998) (xy 66.3956 -304.54854) (xy 66.204084 -304.54854)
			(xy 66.176875 -304.54795) (xy 66.12327 -304.538578) (xy 66.072067 -304.520149) (xy 66.024785 -304.49321)
			(xy 65.982825 -304.458559) (xy 65.947431 -304.417223) (xy 65.933066 -304.394108) (xy 65.872614 -304.292762)
			(xy 65.847214 -304.2793) (xy 65.84442 -304.279554) (xy 65.825116 -304.280062) (xy 65.824608 -304.280062)
			(xy 65.805304 -304.279554) (xy 65.80251 -304.2793) (xy 65.77711 -304.292762) (xy 65.716658 -304.394108)
			(xy 65.702279 -304.417214) (xy 65.666888 -304.45855) (xy 65.624931 -304.493203) (xy 65.577652 -304.520144)
			(xy 65.526451 -304.538576) (xy 65.472848 -304.547952) (xy 65.44564 -304.54854) (xy 65.254124 -304.54854)
			(xy 65.226918 -304.547945) (xy 65.173319 -304.538565) (xy 65.122124 -304.520129) (xy 65.074849 -304.493186)
			(xy 65.032897 -304.458532) (xy 64.997512 -304.417196) (xy 64.983106 -304.394108) (xy 64.922654 -304.292762)
			(xy 64.897254 -304.2793) (xy 64.89446 -304.279554) (xy 64.875156 -304.280062) (xy 64.874648 -304.280062)
			(xy 64.855344 -304.279554) (xy 64.85255 -304.2793) (xy 64.82715 -304.292762) (xy 64.766698 -304.394108)
			(xy 64.75232 -304.417216) (xy 64.716931 -304.458557) (xy 64.674974 -304.493215) (xy 64.627695 -304.520162)
			(xy 64.576494 -304.5386) (xy 64.522889 -304.547983) (xy 64.49568 -304.54854) (xy 64.304164 -304.54854)
			(xy 64.276956 -304.547949) (xy 64.223353 -304.538574) (xy 64.172153 -304.520143) (xy 64.124873 -304.493202)
			(xy 64.082916 -304.45855) (xy 64.047525 -304.417214) (xy 64.033146 -304.394108) (xy 63.972694 -304.292762)
			(xy 63.947294 -304.2793) (xy 63.9445 -304.279554) (xy 63.925196 -304.280062) (xy 63.924688 -304.280062)
			(xy 63.905384 -304.279554) (xy 63.90259 -304.2793) (xy 63.87719 -304.292762) (xy 63.816738 -304.394108)
			(xy 63.802359 -304.417213) (xy 63.766967 -304.458547) (xy 63.72501 -304.493197) (xy 63.67773 -304.520135)
			(xy 63.62653 -304.538564) (xy 63.572927 -304.547936) (xy 63.54572 -304.54854) (xy 63.354204 -304.54854)
			(xy 63.326999 -304.547944) (xy 63.273402 -304.53856) (xy 63.222209 -304.520123) (xy 63.174938 -304.493177)
			(xy 63.132988 -304.458523) (xy 63.097605 -304.417187) (xy 63.083186 -304.394108) (xy 63.022734 -304.292762)
			(xy 62.997334 -304.2793) (xy 62.99454 -304.279554) (xy 62.975236 -304.280062) (xy 62.974728 -304.280062)
			(xy 62.955424 -304.279554) (xy 62.95263 -304.2793) (xy 62.92723 -304.292762) (xy 62.866778 -304.394108)
			(xy 62.8524 -304.417215) (xy 62.81701 -304.458554) (xy 62.775053 -304.493209) (xy 62.727773 -304.520153)
			(xy 62.676573 -304.538588) (xy 62.622969 -304.547967) (xy 62.59576 -304.54854) (xy 62.40399 -304.54854)
			(xy 62.376781 -304.547951) (xy 62.323175 -304.53858) (xy 62.271971 -304.520151) (xy 62.224688 -304.493212)
			(xy 62.182727 -304.458561) (xy 62.147333 -304.417225) (xy 62.132972 -304.394108) (xy 62.07252 -304.292762)
			(xy 62.04712 -304.2793) (xy 62.044326 -304.279554) (xy 62.025022 -304.280062) (xy 62.024514 -304.280062)
			(xy 62.00521 -304.279554) (xy 62.002416 -304.2793) (xy 61.977016 -304.292762) (xy 61.916564 -304.394108)
			(xy 61.902186 -304.417214) (xy 61.866795 -304.458551) (xy 61.824838 -304.493205) (xy 61.777558 -304.520147)
			(xy 61.726358 -304.53858) (xy 61.672754 -304.547956) (xy 61.645546 -304.54854) (xy 61.45403 -304.54854)
			(xy 61.426824 -304.547946) (xy 61.373224 -304.538566) (xy 61.322028 -304.520131) (xy 61.274753 -304.493188)
			(xy 61.2328 -304.458535) (xy 61.197414 -304.417199) (xy 61.183012 -304.394108) (xy 61.12256 -304.292762)
			(xy 61.09716 -304.2793) (xy 61.094366 -304.279554) (xy 61.075062 -304.280062) (xy 61.074554 -304.280062)
			(xy 61.05525 -304.279554) (xy 61.052456 -304.2793) (xy 61.027056 -304.292762) (xy 60.966604 -304.394108)
			(xy 60.952226 -304.417216) (xy 60.916837 -304.458558) (xy 60.874881 -304.493217) (xy 60.827602 -304.520165)
			(xy 60.776401 -304.538604) (xy 60.722796 -304.547987) (xy 60.695586 -304.54854) (xy 60.50407 -304.54854)
			(xy 60.476862 -304.547949) (xy 60.423258 -304.538575) (xy 60.372057 -304.520145) (xy 60.324776 -304.493204)
			(xy 60.282818 -304.458552) (xy 60.247426 -304.417217) (xy 60.233052 -304.394108) (xy 60.1726 -304.292762)
			(xy 60.1472 -304.2793) (xy 60.144406 -304.279554) (xy 60.125102 -304.280062) (xy 60.124594 -304.280062)
			(xy 60.10529 -304.279554) (xy 60.102496 -304.2793) (xy 60.077096 -304.292762) (xy 60.016644 -304.394108)
			(xy 60.002265 -304.417213) (xy 59.966874 -304.458548) (xy 59.924916 -304.493199) (xy 59.877636 -304.520138)
			(xy 59.826436 -304.538568) (xy 59.772834 -304.547941) (xy 59.745626 -304.54854) (xy 58.60415 -304.54854)
			(xy 58.576943 -304.547948) (xy 58.523341 -304.538571) (xy 58.472142 -304.520138) (xy 58.424865 -304.493196)
			(xy 58.382909 -304.458544) (xy 58.34752 -304.417208) (xy 58.333132 -304.394108) (xy 58.27268 -304.292762)
			(xy 58.24728 -304.2793) (xy 58.244486 -304.279554) (xy 58.225182 -304.280062) (xy 58.224674 -304.280062)
			(xy 58.20537 -304.279554) (xy 58.202576 -304.2793) (xy 58.177176 -304.292762) (xy 58.116724 -304.394108)
			(xy 58.102345 -304.417212) (xy 58.066953 -304.458544) (xy 58.024995 -304.493193) (xy 57.977715 -304.520129)
			(xy 57.926515 -304.538555) (xy 57.872913 -304.547925) (xy 57.845706 -304.54854) (xy 57.65419 -304.54854)
			(xy 57.626981 -304.547951) (xy 57.573375 -304.53858) (xy 57.522171 -304.520151) (xy 57.474888 -304.493212)
			(xy 57.432927 -304.458561) (xy 57.397533 -304.417225) (xy 57.383172 -304.394108) (xy 57.32272 -304.292762)
			(xy 57.29732 -304.2793) (xy 57.294526 -304.279554) (xy 57.275222 -304.280062) (xy 57.274714 -304.280062)
			(xy 57.25541 -304.279554) (xy 57.252616 -304.2793) (xy 57.227216 -304.292762) (xy 57.166764 -304.394108)
			(xy 57.152386 -304.417214) (xy 57.116995 -304.458551) (xy 57.075038 -304.493205) (xy 57.027758 -304.520147)
			(xy 56.976558 -304.53858) (xy 56.922954 -304.547956) (xy 56.895746 -304.54854) (xy 56.703976 -304.54854)
			(xy 56.676768 -304.54795) (xy 56.623163 -304.538577) (xy 56.571961 -304.520147) (xy 56.52468 -304.493207)
			(xy 56.482721 -304.458555) (xy 56.447328 -304.417219) (xy 56.432958 -304.394108) (xy 56.372506 -304.292762)
			(xy 56.347106 -304.2793) (xy 56.344312 -304.279554) (xy 56.325008 -304.280062) (xy 56.3245 -304.280062)
			(xy 56.305196 -304.279554) (xy 56.302402 -304.2793) (xy 56.277002 -304.292762) (xy 56.21655 -304.394108)
			(xy 56.202171 -304.417213) (xy 56.16678 -304.458549) (xy 56.124823 -304.4932) (xy 56.077543 -304.520141)
			(xy 56.026343 -304.538571) (xy 55.97274 -304.547945) (xy 55.945532 -304.54854) (xy 55.754016 -304.54854)
			(xy 55.72681 -304.547945) (xy 55.673212 -304.538563) (xy 55.622018 -304.520127) (xy 55.574745 -304.493182)
			(xy 55.532794 -304.458528) (xy 55.497409 -304.417192) (xy 55.482998 -304.394108) (xy 55.422546 -304.292762)
			(xy 55.397146 -304.2793) (xy 55.394352 -304.279554) (xy 55.375048 -304.280062) (xy 55.37454 -304.280062)
			(xy 55.355236 -304.279554) (xy 55.352442 -304.2793) (xy 55.327042 -304.292762) (xy 55.26659 -304.394108)
			(xy 55.252212 -304.417216) (xy 55.216822 -304.458556) (xy 55.174866 -304.493212) (xy 55.127586 -304.520159)
			(xy 55.076386 -304.538595) (xy 55.022781 -304.547976) (xy 54.995572 -304.54854) (xy 54.804056 -304.54854)
			(xy 54.776848 -304.547948) (xy 54.723246 -304.538572) (xy 54.672047 -304.52014) (xy 54.624768 -304.493199)
			(xy 54.582812 -304.458546) (xy 54.547422 -304.41721) (xy 54.533038 -304.394108) (xy 54.472586 -304.292762)
			(xy 54.447186 -304.2793) (xy 54.444392 -304.279554) (xy 54.425088 -304.280062) (xy 54.42458 -304.280062)
			(xy 54.405276 -304.279554) (xy 54.402482 -304.2793) (xy 54.377082 -304.292762) (xy 54.31663 -304.394108)
			(xy 54.302251 -304.417212) (xy 54.266859 -304.458545) (xy 54.224901 -304.493194) (xy 54.177621 -304.520132)
			(xy 54.126421 -304.538559) (xy 54.072819 -304.54793) (xy 54.045612 -304.54854) (xy 53.854096 -304.54854)
			(xy 53.826891 -304.547943) (xy 53.773295 -304.538559) (xy 53.722103 -304.52012) (xy 53.674833 -304.493174)
			(xy 53.632885 -304.45852) (xy 53.597503 -304.417183) (xy 53.583078 -304.394108) (xy 53.522626 -304.292762)
			(xy 53.497226 -304.2793) (xy 53.494432 -304.279554) (xy 53.475128 -304.280062) (xy 53.47462 -304.280062)
			(xy 53.455316 -304.279554) (xy 53.452522 -304.2793) (xy 53.427122 -304.292762) (xy 53.36667 -304.394108)
			(xy 53.352292 -304.417215) (xy 53.316901 -304.458552) (xy 53.274944 -304.493206) (xy 53.227665 -304.52015)
			(xy 53.176464 -304.538583) (xy 53.12286 -304.547961) (xy 53.095652 -304.54854) (xy 52.904136 -304.54854)
			(xy 52.876929 -304.547946) (xy 52.823329 -304.538568) (xy 52.772132 -304.520133) (xy 52.724856 -304.49319)
			(xy 52.682903 -304.458537) (xy 52.647515 -304.417201) (xy 52.633118 -304.394108) (xy 52.572666 -304.292762)
			(xy 52.547266 -304.2793) (xy 52.544472 -304.279554) (xy 52.525168 -304.280062) (xy 52.52466 -304.280062)
			(xy 52.505356 -304.279554) (xy 52.502562 -304.2793) (xy 52.477162 -304.292762) (xy 52.41671 -304.394108)
			(xy 52.402332 -304.417217) (xy 52.366943 -304.458559) (xy 52.324987 -304.493218) (xy 52.277708 -304.520168)
			(xy 52.226507 -304.538608) (xy 52.172902 -304.547992) (xy 52.145692 -304.54854) (xy 51.954176 -304.54854)
			(xy 51.926968 -304.54795) (xy 51.873363 -304.538577) (xy 51.822161 -304.520147) (xy 51.77488 -304.493207)
			(xy 51.732921 -304.458555) (xy 51.697528 -304.417219) (xy 51.683158 -304.394108) (xy 51.622706 -304.292762)
			(xy 51.597306 -304.2793) (xy 51.594512 -304.279554) (xy 51.575208 -304.280062) (xy 51.5747 -304.280062)
			(xy 51.555396 -304.279554) (xy 51.552602 -304.2793) (xy 51.527202 -304.292762) (xy 51.46675 -304.394108)
			(xy 51.452371 -304.417213) (xy 51.41698 -304.458549) (xy 51.375023 -304.4932) (xy 51.327743 -304.520141)
			(xy 51.276543 -304.538571) (xy 51.22294 -304.547945) (xy 51.195732 -304.54854) (xy 51.004216 -304.54854)
			(xy 50.97701 -304.547945) (xy 50.923412 -304.538563) (xy 50.872218 -304.520127) (xy 50.824945 -304.493182)
			(xy 50.782994 -304.458528) (xy 50.747609 -304.417192) (xy 50.733198 -304.394108) (xy 50.672746 -304.292762)
			(xy 50.647346 -304.2793) (xy 50.644552 -304.279554) (xy 50.625248 -304.280062) (xy 50.62474 -304.280062)
			(xy 50.605436 -304.279554) (xy 50.602642 -304.2793) (xy 50.577242 -304.292762) (xy 50.51679 -304.394108)
			(xy 50.502412 -304.417216) (xy 50.467022 -304.458556) (xy 50.425066 -304.493212) (xy 50.377786 -304.520159)
			(xy 50.326586 -304.538595) (xy 50.272981 -304.547976) (xy 50.245772 -304.54854) (xy 50.054002 -304.54854)
			(xy 50.026797 -304.547944) (xy 49.9732 -304.53856) (xy 49.922008 -304.520122) (xy 49.874736 -304.493177)
			(xy 49.832788 -304.458522) (xy 49.797405 -304.417186) (xy 49.782984 -304.394108) (xy 49.722532 -304.292762)
			(xy 49.697132 -304.2793) (xy 49.694338 -304.279554) (xy 49.675034 -304.280062) (xy 49.674526 -304.280062)
			(xy 49.65055 -304.279571) (xy 49.603194 -304.272031) (xy 49.5576 -304.257178) (xy 49.514889 -304.23538)
			(xy 49.476111 -304.207171) (xy 49.442221 -304.173245) (xy 49.414053 -304.134438) (xy 49.392299 -304.091704)
			(xy 49.377495 -304.046094) (xy 49.370004 -303.99873) (xy 49.369472 -303.974754) (xy 49.369472 -303.973992)
			(xy 49.369609 -303.961229) (xy 49.371769 -303.935795) (xy 49.37379 -303.923192) (xy 49.374552 -303.919382)
			(xy 49.362614 -303.891696) (xy 49.28235 -303.838356) (xy 49.261144 -303.823611) (xy 49.223401 -303.788357)
			(xy 49.191913 -303.74742) (xy 49.167523 -303.701895) (xy 49.150883 -303.653003) (xy 49.14244 -303.602051)
			(xy 49.141888 -303.576228) (xy 49.141888 -303.42332) (xy 49.142427 -303.397497) (xy 49.150887 -303.346548)
			(xy 49.167534 -303.297658) (xy 49.191923 -303.252132) (xy 49.223403 -303.211189) (xy 49.261134 -303.175921)
			(xy 49.28235 -303.161192) (xy 49.362614 -303.107852) (xy 49.374552 -303.080166) (xy 49.37379 -303.076356)
			(xy 49.371761 -303.063562) (xy 49.369602 -303.037747) (xy 49.369472 -303.024794) (xy 49.369726 -303.012094)
			(xy 49.370742 -302.988726) (xy 49.36191 -302.985376) (xy 49.344625 -302.977753) (xy 49.336198 -302.973486)
			(xy 49.2506 -302.928782) (xy 49.245102 -302.925653) (xy 49.235711 -302.917182) (xy 49.232058 -302.912018)
			(xy 49.15027 -302.78959) (xy 49.150016 -302.786034) (xy 48.99914 -302.635158) (xy 48.991741 -302.628315)
			(xy 48.973142 -302.620593) (xy 48.963072 -302.620172) (xy 46.668182 -302.620172) (xy 46.641766 -302.639222)
			(xy 46.639988 -302.64481) (xy 46.636834 -302.65422) (xy 46.629462 -302.67265) (xy 46.625256 -302.68164)
			(xy 46.621163 -302.691317) (xy 46.620371 -302.71229) (xy 46.628036 -302.731828) (xy 46.642877 -302.746668)
			(xy 46.662417 -302.754331) (xy 46.68339 -302.753536) (xy 46.693074 -302.749458) (xy 46.713757 -302.740022)
			(xy 46.757216 -302.726681) (xy 46.80217 -302.719914) (xy 46.8249 -302.719486) (xy 46.849721 -302.719972)
			(xy 46.89871 -302.728003) (xy 46.945755 -302.743854) (xy 46.989615 -302.767108) (xy 47.029135 -302.79715)
			(xy 47.063274 -302.833191) (xy 47.091133 -302.87428) (xy 47.111977 -302.919335) (xy 47.125258 -302.967168)
			(xy 47.130625 -303.01652) (xy 47.130176 -303.024794) (xy 47.469056 -303.024794) (xy 47.473016 -302.97574)
			(xy 47.484793 -302.927956) (xy 47.504084 -302.88268) (xy 47.530387 -302.841084) (xy 47.563022 -302.804247)
			(xy 47.601143 -302.773122) (xy 47.643764 -302.748515) (xy 47.68978 -302.731063) (xy 47.737999 -302.721219)
			(xy 47.787174 -302.719238) (xy 47.836029 -302.72517) (xy 47.8833 -302.738862) (xy 47.927762 -302.75996)
			(xy 47.968265 -302.787916) (xy 48.003758 -302.822008) (xy 48.033323 -302.861352) (xy 48.056194 -302.904929)
			(xy 48.071778 -302.95161) (xy 48.079673 -303.000187) (xy 48.080168 -303.024794) (xy 48.079673 -303.049401)
			(xy 48.071778 -303.097978) (xy 48.056194 -303.144659) (xy 48.033323 -303.188236) (xy 48.003758 -303.22758)
			(xy 47.968265 -303.261672) (xy 47.927762 -303.289628) (xy 47.8833 -303.310726) (xy 47.836029 -303.324418)
			(xy 47.787174 -303.33035) (xy 47.737999 -303.328369) (xy 47.68978 -303.318525) (xy 47.643764 -303.301073)
			(xy 47.601143 -303.276466) (xy 47.563022 -303.245341) (xy 47.530387 -303.208504) (xy 47.504084 -303.166908)
			(xy 47.484793 -303.121632) (xy 47.473016 -303.073848) (xy 47.469056 -303.024794) (xy 47.130176 -303.024794)
			(xy 47.127937 -303.06609) (xy 47.117265 -303.114572) (xy 47.09889 -303.160689) (xy 47.073296 -303.203226)
			(xy 47.041157 -303.241062) (xy 47.003321 -303.273199) (xy 46.960784 -303.298792) (xy 46.914667 -303.317167)
			(xy 46.866184 -303.327838) (xy 46.816614 -303.330525) (xy 46.767262 -303.325157) (xy 46.719429 -303.311875)
			(xy 46.674375 -303.29103) (xy 46.633286 -303.26317) (xy 46.597246 -303.22903) (xy 46.567204 -303.18951)
			(xy 46.543952 -303.145649) (xy 46.528102 -303.098605) (xy 46.520071 -303.049615) (xy 46.519592 -303.024794)
			(xy 46.519779 -303.010612) (xy 46.522453 -302.982372) (xy 46.524926 -302.968406) (xy 46.527212 -302.95596)
			(xy 46.519846 -302.932338) (xy 46.442376 -302.854868) (xy 46.418754 -302.847502) (xy 46.406308 -302.849788)
			(xy 46.392343 -302.852274) (xy 46.364103 -302.854948) (xy 46.34992 -302.855122) (xy 46.325925 -302.854677)
			(xy 46.278527 -302.847173) (xy 46.232885 -302.832347) (xy 46.190126 -302.810563) (xy 46.1513 -302.782357)
			(xy 46.117365 -302.748426) (xy 46.089155 -302.709603) (xy 46.067366 -302.666846) (xy 46.052535 -302.621206)
			(xy 46.045025 -302.573809) (xy 46.044612 -302.549814) (xy 46.045261 -302.521574) (xy 46.05563 -302.466055)
			(xy 46.076019 -302.413384) (xy 46.090332 -302.389032) (xy 46.094396 -302.382682) (xy 46.090332 -302.347884)
			(xy 45.996098 -302.25365) (xy 45.992664 -302.250033) (xy 45.987162 -302.241715) (xy 45.985176 -302.23714)
			(xy 45.946314 -302.143414) (xy 45.944652 -302.139085) (xy 45.942741 -302.130011) (xy 45.942504 -302.12538)
			(xy 45.941234 -302.074326) (xy 45.941234 -302.073056) (xy 45.940472 -302.063658) (xy 45.936916 -302.043338)
			(xy 45.93433 -302.03202) (xy 45.920707 -302.013248) (xy 45.910754 -302.00727) (xy 45.90638 -302.005115)
			(xy 45.897207 -302.001805) (xy 45.892466 -302.000666) (xy 45.891704 -302.000412) (xy 45.804328 -301.981362)
			(xy 45.795976 -301.979171) (xy 45.781303 -301.970088) (xy 45.775626 -301.963582) (xy 45.705014 -301.87519)
			(xy 45.69873 -301.868069) (xy 45.682314 -301.858551) (xy 45.67301 -301.856648) (xy 45.595794 -301.844456)
			(xy 45.577252 -301.84852) (xy 45.569124 -301.854108) (xy 45.550258 -301.866165) (xy 45.509746 -301.885227)
			(xy 45.466888 -301.898182) (xy 45.4226 -301.904752) (xy 45.400214 -301.905162) (xy 45.39996 -301.905162)
			(xy 45.37597 -301.904713) (xy 45.328582 -301.897201) (xy 45.282953 -301.882368) (xy 45.240206 -301.86058)
			(xy 45.201393 -301.832373) (xy 45.167471 -301.798441) (xy 45.139275 -301.759621) (xy 45.117499 -301.716868)
			(xy 45.102679 -301.671234) (xy 45.09518 -301.623844) (xy 45.094652 -301.599854) (xy 45.094836 -301.585671)
			(xy 45.097504 -301.557431) (xy 45.099986 -301.543466) (xy 45.102272 -301.53102) (xy 45.094906 -301.507398)
			(xy 45.017436 -301.429928) (xy 44.993814 -301.422562) (xy 44.981368 -301.424848) (xy 44.967403 -301.427333)
			(xy 44.939163 -301.430003) (xy 44.92498 -301.430182) (xy 44.910734 -301.430006) (xy 44.882366 -301.427336)
			(xy 44.868338 -301.424848) (xy 44.855892 -301.422562) (xy 44.83227 -301.429928) (xy 44.76369 -301.498254)
			(xy 44.755533 -301.507492) (xy 44.748214 -301.530983) (xy 44.74972 -301.543212) (xy 44.74972 -301.543466)
			(xy 44.752202 -301.557431) (xy 44.754869 -301.585671) (xy 44.755054 -301.599854) (xy 44.754532 -301.625109)
			(xy 44.746219 -301.674931) (xy 44.729818 -301.722705) (xy 44.705777 -301.767128) (xy 44.674753 -301.806988)
			(xy 44.637591 -301.841198) (xy 44.595305 -301.868824) (xy 44.549049 -301.889114) (xy 44.500084 -301.901514)
			(xy 44.449746 -301.905685) (xy 44.399408 -301.901514) (xy 44.350443 -301.889114) (xy 44.304187 -301.868824)
			(xy 44.261901 -301.841198) (xy 44.224739 -301.806988) (xy 44.193715 -301.767128) (xy 44.169674 -301.722705)
			(xy 44.153273 -301.674931) (xy 44.14496 -301.625109) (xy 44.144438 -301.599854) (xy 44.144622 -301.585671)
			(xy 44.14729 -301.557431) (xy 44.149772 -301.543466) (xy 44.152058 -301.53102) (xy 44.144692 -301.507398)
			(xy 44.067222 -301.429928) (xy 44.0436 -301.422562) (xy 44.031154 -301.424848) (xy 44.017189 -301.427332)
			(xy 43.988949 -301.430001) (xy 43.974766 -301.430182) (xy 43.960583 -301.429998) (xy 43.932343 -301.427331)
			(xy 43.918378 -301.424848) (xy 43.905932 -301.422562) (xy 43.88231 -301.429928) (xy 43.80484 -301.507398)
			(xy 43.797474 -301.53102) (xy 43.79976 -301.543466) (xy 43.802243 -301.557431) (xy 43.80491 -301.585671)
			(xy 43.805094 -301.599854) (xy 43.804612 -301.624674) (xy 43.796588 -301.673662) (xy 43.780745 -301.720706)
			(xy 43.757499 -301.764568) (xy 43.727463 -301.80409) (xy 43.691429 -301.838233) (xy 43.650345 -301.866096)
			(xy 43.605295 -301.886945) (xy 43.557466 -301.900231) (xy 43.508117 -301.905604) (xy 43.458549 -301.902922)
			(xy 43.410068 -301.892256) (xy 43.363951 -301.873887) (xy 43.321413 -301.848299) (xy 43.283576 -301.816167)
			(xy 43.251436 -301.778335) (xy 43.225839 -301.735803) (xy 43.207461 -301.68969) (xy 43.196786 -301.641211)
			(xy 43.194094 -301.591643) (xy 43.199458 -301.542293) (xy 43.212734 -301.494461) (xy 43.233575 -301.449407)
			(xy 43.26143 -301.408318) (xy 43.295565 -301.372277) (xy 43.335082 -301.342234) (xy 43.378938 -301.318979)
			(xy 43.42598 -301.303126) (xy 43.474966 -301.295093) (xy 43.499786 -301.294546) (xy 43.513969 -301.294732)
			(xy 43.542208 -301.297404) (xy 43.556174 -301.29988) (xy 43.56862 -301.302166) (xy 43.592242 -301.2948)
			(xy 43.669712 -301.21733) (xy 43.677078 -301.193708) (xy 43.674792 -301.181262) (xy 43.672308 -301.167297)
			(xy 43.669639 -301.139057) (xy 43.669458 -301.124874) (xy 43.66998 -301.099619) (xy 43.678293 -301.049797)
			(xy 43.694694 -301.002023) (xy 43.718735 -300.9576) (xy 43.749759 -300.91774) (xy 43.786921 -300.88353)
			(xy 43.829207 -300.855904) (xy 43.875463 -300.835614) (xy 43.924428 -300.823214) (xy 43.974766 -300.819043)
			(xy 44.025104 -300.823214) (xy 44.074069 -300.835614) (xy 44.120325 -300.855904) (xy 44.162611 -300.88353)
			(xy 44.199773 -300.91774) (xy 44.230797 -300.9576) (xy 44.254838 -301.002023) (xy 44.271239 -301.049797)
			(xy 44.279552 -301.099619) (xy 44.280074 -301.124874) (xy 44.279889 -301.139057) (xy 44.277217 -301.167296)
			(xy 44.27474 -301.181262) (xy 44.272454 -301.193708) (xy 44.27982 -301.21733) (xy 44.35729 -301.2948)
			(xy 44.380912 -301.302166) (xy 44.393358 -301.29988) (xy 44.407323 -301.297397) (xy 44.435563 -301.29473)
			(xy 44.449746 -301.294546) (xy 44.463992 -301.294724) (xy 44.492359 -301.297396) (xy 44.506388 -301.29988)
			(xy 44.518834 -301.302166) (xy 44.542456 -301.2948) (xy 44.611036 -301.226474) (xy 44.619175 -301.217232)
			(xy 44.626457 -301.193747) (xy 44.625006 -301.181516) (xy 44.625006 -301.181262) (xy 44.622522 -301.167297)
			(xy 44.619853 -301.139057) (xy 44.619672 -301.124874) (xy 44.620194 -301.099619) (xy 44.628507 -301.049797)
			(xy 44.644908 -301.002023) (xy 44.668949 -300.9576) (xy 44.699973 -300.91774) (xy 44.737135 -300.88353)
			(xy 44.779421 -300.855904) (xy 44.825677 -300.835614) (xy 44.874642 -300.823214) (xy 44.92498 -300.819043)
			(xy 44.975318 -300.823214) (xy 45.024283 -300.835614) (xy 45.070539 -300.855904) (xy 45.112825 -300.88353)
			(xy 45.149987 -300.91774) (xy 45.181011 -300.9576) (xy 45.205052 -301.002023) (xy 45.221453 -301.049797)
			(xy 45.229766 -301.099619) (xy 45.230288 -301.124874) (xy 45.230103 -301.139057) (xy 45.227431 -301.167296)
			(xy 45.224954 -301.181262) (xy 45.222668 -301.193708) (xy 45.230034 -301.21733) (xy 45.307504 -301.2948)
			(xy 45.331126 -301.302166) (xy 45.343572 -301.29988) (xy 45.357537 -301.297393) (xy 45.385777 -301.294718)
			(xy 45.39996 -301.294546) (xy 45.400214 -301.294546) (xy 45.422603 -301.294936) (xy 45.466899 -301.301479)
			(xy 45.509759 -301.314439) (xy 45.550261 -301.333534) (xy 45.569124 -301.3456) (xy 45.577252 -301.351188)
			(xy 45.595794 -301.355252) (xy 45.67301 -301.34306) (xy 45.682351 -301.341255) (xy 45.698798 -301.331721)
			(xy 45.705014 -301.324518) (xy 45.775626 -301.236126) (xy 45.781289 -301.229603) (xy 45.795966 -301.220517)
			(xy 45.804328 -301.218346) (xy 45.89145 -301.199296) (xy 45.891958 -301.199296) (xy 45.896568 -301.198127)
			(xy 45.905483 -301.194816) (xy 45.909738 -301.192692) (xy 45.919993 -301.186747) (xy 45.934018 -301.167673)
			(xy 45.936662 -301.156116) (xy 45.940218 -301.135796) (xy 45.940218 -301.13478) (xy 45.941566 -301.122537)
			(xy 45.936179 -301.098521) (xy 45.922462 -301.078085) (xy 45.902275 -301.064003) (xy 45.890434 -301.060612)
			(xy 45.889418 -301.060358) (xy 45.79874 -301.040546) (xy 45.790396 -301.038342) (xy 45.775746 -301.029241)
			(xy 45.770038 -301.022766) (xy 45.653452 -300.87697) (xy 45.648338 -300.870046) (xy 45.642626 -300.85382)
			(xy 45.642276 -300.84522) (xy 45.642276 -300.445678) (xy 45.647864 -300.429676) (xy 45.652436 -300.423834)
			(xy 45.652436 -300.40326) (xy 45.652002 -300.394408) (xy 45.645884 -300.377788) (xy 45.640498 -300.370748)
			(xy 45.62391 -300.349968) (xy 45.597437 -300.303862) (xy 45.579348 -300.253868) (xy 45.57019 -300.201497)
			(xy 45.569632 -300.174914) (xy 45.569632 -300.17466) (xy 45.570034 -300.152379) (xy 45.57651 -300.108291)
			(xy 45.589334 -300.065614) (xy 45.608233 -300.025258) (xy 45.632803 -299.988083) (xy 45.647356 -299.971206)
			(xy 45.653198 -299.964856) (xy 45.654214 -299.928026) (xy 45.653452 -299.92701) (xy 45.648347 -299.920084)
			(xy 45.642654 -299.903858) (xy 45.642276 -299.89526) (xy 45.642276 -299.495718) (xy 45.647864 -299.479716)
			(xy 45.652436 -299.473874) (xy 45.652436 -299.4533) (xy 45.652009 -299.444445) (xy 45.645901 -299.427817)
			(xy 45.640498 -299.420788) (xy 45.623907 -299.400009) (xy 45.597428 -299.353904) (xy 45.579333 -299.30391)
			(xy 45.570168 -299.251538) (xy 45.569632 -299.224954) (xy 45.569632 -299.2247) (xy 45.570031 -299.202418)
			(xy 45.576502 -299.158327) (xy 45.589322 -299.115647) (xy 45.608217 -299.075287) (xy 45.632784 -299.038107)
			(xy 45.647356 -299.021246) (xy 45.653198 -299.014896) (xy 45.654214 -298.978066) (xy 45.653452 -298.97705)
			(xy 45.648341 -298.970126) (xy 45.642635 -298.953899) (xy 45.642276 -298.9453) (xy 45.642276 -298.545504)
			(xy 45.647864 -298.529502) (xy 45.652436 -298.52366) (xy 45.652436 -298.503086) (xy 45.652007 -298.494232)
			(xy 45.645895 -298.477607) (xy 45.640498 -298.470574) (xy 45.623908 -298.449794) (xy 45.597431 -298.403689)
			(xy 45.579338 -298.353695) (xy 45.570176 -298.301324) (xy 45.569632 -298.27474) (xy 45.569632 -298.274486)
			(xy 45.570032 -298.252204) (xy 45.576505 -298.208114) (xy 45.589326 -298.165435) (xy 45.608222 -298.125077)
			(xy 45.632791 -298.087898) (xy 45.647356 -298.071032) (xy 45.653198 -298.064682) (xy 45.654214 -298.027852)
			(xy 45.653452 -298.026836) (xy 45.648343 -298.019911) (xy 45.642642 -298.003685) (xy 45.642276 -297.995086)
			(xy 45.642276 -297.646344) (xy 45.641579 -297.633906) (xy 45.629858 -297.611954) (xy 45.619924 -297.604434)
			(xy 45.616368 -297.601894) (xy 45.611796 -297.605958) (xy 45.558456 -297.626532) (xy 45.531116 -297.636423)
			(xy 45.473983 -297.647161) (xy 45.444918 -297.647868) (xy 45.354748 -297.647868) (xy 45.331558 -297.647423)
			(xy 45.285689 -297.640555) (xy 45.241323 -297.627035) (xy 45.199419 -297.607155) (xy 45.160884 -297.581344)
			(xy 45.14342 -297.56608) (xy 45.128434 -297.552618) (xy 45.107237 -297.570682) (xy 45.059639 -297.599587)
			(xy 45.007595 -297.619397) (xy 44.952824 -297.629458) (xy 44.92498 -297.630088) (xy 44.900965 -297.629646)
			(xy 44.853528 -297.622133) (xy 44.807853 -297.60728) (xy 44.76507 -297.585454) (xy 44.745402 -297.571668)
			(xy 44.736512 -297.565318) (xy 44.723558 -297.565826) (xy 44.71501 -297.566667) (xy 44.699169 -297.573282)
			(xy 44.69257 -297.57878) (xy 44.668694 -297.599862) (xy 44.665221 -297.602817) (xy 44.657426 -297.607547)
			(xy 44.6532 -297.60926) (xy 44.608496 -297.626532) (xy 44.581157 -297.636426) (xy 44.524024 -297.647171)
			(xy 44.494958 -297.647868) (xy 44.404534 -297.647868) (xy 44.381345 -297.647422) (xy 44.335477 -297.640552)
			(xy 44.291112 -297.627031) (xy 44.249209 -297.607149) (xy 44.210675 -297.581338) (xy 44.193206 -297.56608)
			(xy 44.17822 -297.552618) (xy 44.157025 -297.570689) (xy 44.109429 -297.599607) (xy 44.057385 -297.619432)
			(xy 44.002612 -297.629507) (xy 43.974766 -297.630088) (xy 43.950752 -297.629645) (xy 43.903315 -297.62213)
			(xy 43.857642 -297.607275) (xy 43.81486 -297.585448) (xy 43.795188 -297.571668) (xy 43.78325 -297.563032)
			(xy 43.775884 -297.563286) (xy 43.767773 -297.564038) (xy 43.752624 -297.570004) (xy 43.746166 -297.57497)
			(xy 43.725677 -297.591335) (xy 43.680373 -297.617735) (xy 43.631327 -297.636279) (xy 43.57989 -297.646456)
			(xy 43.527477 -297.647985) (xy 43.475534 -297.640825) (xy 43.42549 -297.625173) (xy 43.378724 -297.601459)
			(xy 43.336524 -297.570338) (xy 43.317922 -297.551856) (xy 43.317414 -297.551348) (xy 42.939716 -297.17365)
			(xy 42.922503 -297.155805) (xy 42.893341 -297.115709) (xy 42.870814 -297.071543) (xy 42.855479 -297.024395)
			(xy 42.847712 -296.975428) (xy 42.84726 -296.950638) (xy 42.84726 -294.830246) (xy 42.847462 -294.813802)
			(xy 42.850896 -294.781094) (xy 42.854118 -294.764968) (xy 42.855694 -294.755655) (xy 42.852635 -294.737031)
			(xy 42.843036 -294.720779) (xy 42.83583 -294.714676) (xy 42.816442 -294.698749) (xy 42.782645 -294.661669)
			(xy 42.755365 -294.619561) (xy 42.735338 -294.57356) (xy 42.723102 -294.524903) (xy 42.718987 -294.4749)
			(xy 42.723102 -294.424897) (xy 42.735338 -294.37624) (xy 42.755365 -294.330239) (xy 42.782645 -294.288131)
			(xy 42.816442 -294.251051) (xy 42.83583 -294.235124) (xy 42.842942 -294.228942) (xy 42.852496 -294.21272)
			(xy 42.855565 -294.194146) (xy 42.854118 -294.184832) (xy 42.850921 -294.168702) (xy 42.847483 -294.135996)
			(xy 42.84726 -294.119554) (xy 42.84726 -293.934896) (xy 42.847564 -293.915648) (xy 42.852275 -293.877441)
			(xy 42.856658 -293.858696) (xy 42.857166 -293.856156) (xy 42.85742 -293.854886) (xy 42.85742 -293.839138)
			(xy 42.833366 -293.825759) (xy 42.789334 -293.792737) (xy 42.75091 -293.75333) (xy 42.719009 -293.708479)
			(xy 42.694393 -293.659251) (xy 42.677648 -293.606821) (xy 42.669173 -293.552438) (xy 42.66917 -293.497399)
			(xy 42.677639 -293.443016) (xy 42.694379 -293.390584) (xy 42.71899 -293.341354) (xy 42.750885 -293.296499)
			(xy 42.789305 -293.257088) (xy 42.833334 -293.224061) (xy 42.85742 -293.210742) (xy 42.85742 -293.201344)
			(xy 42.855896 -293.189406) (xy 42.852998 -293.176739) (xy 42.849058 -293.151051) (xy 42.848022 -293.138098)
			(xy 42.84726 -293.114984) (xy 42.84726 -292.930326) (xy 42.847463 -292.913882) (xy 42.850899 -292.881175)
			(xy 42.854118 -292.865048) (xy 42.85569 -292.855737) (xy 42.852625 -292.837117) (xy 42.843024 -292.820872)
			(xy 42.83583 -292.814756) (xy 42.816443 -292.79883) (xy 42.78265 -292.761749) (xy 42.755373 -292.719643)
			(xy 42.735349 -292.673643) (xy 42.723116 -292.624988) (xy 42.719002 -292.574988) (xy 42.72312 -292.524988)
			(xy 42.735357 -292.476334) (xy 42.755385 -292.430335) (xy 42.782665 -292.388231) (xy 42.816461 -292.351154)
			(xy 42.83583 -292.335204) (xy 42.842954 -292.329025) (xy 42.852534 -292.312803) (xy 42.85563 -292.294219)
			(xy 42.854118 -292.284912) (xy 42.850922 -292.268782) (xy 42.847487 -292.236076) (xy 42.84726 -292.219634)
			(xy 42.84726 -291.980112) (xy 42.847464 -291.963668) (xy 42.850901 -291.930961) (xy 42.854118 -291.914834)
			(xy 42.855687 -291.905524) (xy 42.852619 -291.886907) (xy 42.843016 -291.870666) (xy 42.83583 -291.864542)
			(xy 42.816444 -291.848616) (xy 42.782653 -291.811536) (xy 42.755379 -291.76943) (xy 42.735357 -291.723431)
			(xy 42.723125 -291.674778) (xy 42.719013 -291.624779) (xy 42.723132 -291.574781) (xy 42.73537 -291.526129)
			(xy 42.755399 -291.480133) (xy 42.782679 -291.438031) (xy 42.816475 -291.400956) (xy 42.83583 -291.38499)
			(xy 42.842952 -291.378811) (xy 42.852527 -291.362588) (xy 42.855619 -291.344006) (xy 42.854118 -291.334698)
			(xy 42.850923 -291.318568) (xy 42.847489 -291.285862) (xy 42.84726 -291.26942) (xy 42.84726 -291.030152)
			(xy 42.847462 -291.013708) (xy 42.850895 -290.981) (xy 42.854118 -290.964874) (xy 42.855695 -290.955561)
			(xy 42.852638 -290.936935) (xy 42.84304 -290.920681) (xy 42.83583 -290.914582) (xy 42.816441 -290.898655)
			(xy 42.782643 -290.861575) (xy 42.755363 -290.819467) (xy 42.735335 -290.773465) (xy 42.723098 -290.724807)
			(xy 42.718982 -290.674804) (xy 42.723097 -290.6248) (xy 42.735333 -290.576142) (xy 42.75536 -290.53014)
			(xy 42.782639 -290.488031) (xy 42.816436 -290.45095) (xy 42.83583 -290.43503) (xy 42.842943 -290.428849)
			(xy 42.852499 -290.412627) (xy 42.85557 -290.394051) (xy 42.854118 -290.384738) (xy 42.850921 -290.368608)
			(xy 42.847483 -290.335903) (xy 42.84726 -290.31946) (xy 42.84726 -290.161472) (xy 42.849292 -290.147502)
			(xy 42.85996 -290.109148) (xy 42.861992 -290.095178) (xy 42.861992 -290.07435) (xy 42.862345 -290.054443)
			(xy 42.867442 -290.014955) (xy 42.872152 -289.99561) (xy 42.872152 -289.98926) (xy 42.849336 -289.975454)
			(xy 42.808489 -289.941174) (xy 42.774216 -289.900321) (xy 42.747559 -289.854137) (xy 42.729328 -289.804025)
			(xy 42.720076 -289.751509) (xy 42.719498 -289.724846) (xy 42.72002 -289.699633) (xy 42.728312 -289.649893)
			(xy 42.744663 -289.602191) (xy 42.768628 -289.557822) (xy 42.799555 -289.517994) (xy 42.836606 -289.483787)
			(xy 42.878772 -289.456131) (xy 42.901616 -289.445446) (xy 42.910092 -289.441248) (xy 42.923491 -289.427921)
			(xy 42.931196 -289.410665) (xy 42.932096 -289.40125) (xy 42.9335 -289.377894) (xy 42.942347 -289.331949)
			(xy 42.957893 -289.287819) (xy 42.979797 -289.246474) (xy 43.007576 -289.208824) (xy 43.02379 -289.191954)
			(xy 43.02887 -289.186874) (xy 43.052746 -289.165284) (xy 43.054361 -289.154465) (xy 43.049343 -289.133194)
			(xy 43.035967 -289.115912) (xy 43.016635 -289.105721) (xy 43.005756 -289.104578) (xy 42.980772 -289.102697)
			(xy 42.931753 -289.092345) (xy 42.884856 -289.074717) (xy 42.841155 -289.050218) (xy 42.801649 -289.019407)
			(xy 42.767242 -288.982989) (xy 42.738723 -288.941799) (xy 42.716743 -288.896777) (xy 42.701805 -288.848956)
			(xy 42.694251 -288.799428) (xy 42.693844 -288.774378) (xy 42.694356 -288.748372) (xy 42.702496 -288.697001)
			(xy 42.718571 -288.647536) (xy 42.742186 -288.601195) (xy 42.77276 -288.559118) (xy 42.809539 -288.522342)
			(xy 42.851619 -288.491771) (xy 42.897962 -288.46816) (xy 42.947429 -288.452089) (xy 42.9988 -288.443954)
			(xy 43.024806 -288.443416) (xy 43.974766 -288.443416) (xy 44.000778 -288.443897) (xy 44.052161 -288.45203)
			(xy 44.101639 -288.468101) (xy 44.147995 -288.491715) (xy 44.190085 -288.52229) (xy 44.226874 -288.559072)
			(xy 44.257456 -288.601158) (xy 44.281077 -288.647509) (xy 44.297157 -288.696984) (xy 44.305299 -288.748366)
			(xy 44.305728 -288.774378) (xy 44.305719 -288.774886) (xy 44.619176 -288.774886) (xy 44.623136 -288.725832)
			(xy 44.634913 -288.678048) (xy 44.654204 -288.632772) (xy 44.680507 -288.591176) (xy 44.713142 -288.554339)
			(xy 44.751263 -288.523214) (xy 44.793884 -288.498607) (xy 44.8399 -288.481155) (xy 44.888119 -288.471311)
			(xy 44.937294 -288.46933) (xy 44.986149 -288.475262) (xy 45.03342 -288.488954) (xy 45.077882 -288.510052)
			(xy 45.118385 -288.538008) (xy 45.153878 -288.5721) (xy 45.183443 -288.611444) (xy 45.206314 -288.655021)
			(xy 45.221898 -288.701702) (xy 45.229793 -288.750279) (xy 45.230288 -288.774886) (xy 45.569136 -288.774886)
			(xy 45.573096 -288.725832) (xy 45.584873 -288.678048) (xy 45.604164 -288.632772) (xy 45.630467 -288.591176)
			(xy 45.663102 -288.554339) (xy 45.701223 -288.523214) (xy 45.743844 -288.498607) (xy 45.78986 -288.481155)
			(xy 45.838079 -288.471311) (xy 45.887254 -288.46933) (xy 45.936109 -288.475262) (xy 45.98338 -288.488954)
			(xy 46.027842 -288.510052) (xy 46.068345 -288.538008) (xy 46.103838 -288.5721) (xy 46.133403 -288.611444)
			(xy 46.156274 -288.655021) (xy 46.171858 -288.701702) (xy 46.179753 -288.750279) (xy 46.180248 -288.774886)
			(xy 46.519096 -288.774886) (xy 46.523056 -288.725832) (xy 46.534833 -288.678048) (xy 46.554124 -288.632772)
			(xy 46.580427 -288.591176) (xy 46.613062 -288.554339) (xy 46.651183 -288.523214) (xy 46.693804 -288.498607)
			(xy 46.73982 -288.481155) (xy 46.788039 -288.471311) (xy 46.837214 -288.46933) (xy 46.886069 -288.475262)
			(xy 46.93334 -288.488954) (xy 46.977802 -288.510052) (xy 47.018305 -288.538008) (xy 47.053798 -288.5721)
			(xy 47.083363 -288.611444) (xy 47.106234 -288.655021) (xy 47.121818 -288.701702) (xy 47.129713 -288.750279)
			(xy 47.130208 -288.774886) (xy 47.469056 -288.774886) (xy 47.473016 -288.725832) (xy 47.484793 -288.678048)
			(xy 47.504084 -288.632772) (xy 47.530387 -288.591176) (xy 47.563022 -288.554339) (xy 47.601143 -288.523214)
			(xy 47.643764 -288.498607) (xy 47.68978 -288.481155) (xy 47.737999 -288.471311) (xy 47.787174 -288.46933)
			(xy 47.836029 -288.475262) (xy 47.8833 -288.488954) (xy 47.927762 -288.510052) (xy 47.968265 -288.538008)
			(xy 48.003758 -288.5721) (xy 48.033323 -288.611444) (xy 48.056194 -288.655021) (xy 48.071778 -288.701702)
			(xy 48.079673 -288.750279) (xy 48.080168 -288.774886) (xy 48.079673 -288.799493) (xy 48.071778 -288.84807)
			(xy 48.056194 -288.894751) (xy 48.033323 -288.938328) (xy 48.003758 -288.977672) (xy 47.968265 -289.011764)
			(xy 47.927762 -289.03972) (xy 47.8833 -289.060818) (xy 47.836029 -289.07451) (xy 47.787174 -289.080442)
			(xy 47.737999 -289.078461) (xy 47.68978 -289.068617) (xy 47.643764 -289.051165) (xy 47.601143 -289.026558)
			(xy 47.563022 -288.995433) (xy 47.530387 -288.958596) (xy 47.504084 -288.917) (xy 47.484793 -288.871724)
			(xy 47.473016 -288.82394) (xy 47.469056 -288.774886) (xy 47.130208 -288.774886) (xy 47.129713 -288.799493)
			(xy 47.121818 -288.84807) (xy 47.106234 -288.894751) (xy 47.083363 -288.938328) (xy 47.053798 -288.977672)
			(xy 47.018305 -289.011764) (xy 46.977802 -289.03972) (xy 46.93334 -289.060818) (xy 46.886069 -289.07451)
			(xy 46.837214 -289.080442) (xy 46.788039 -289.078461) (xy 46.73982 -289.068617) (xy 46.693804 -289.051165)
			(xy 46.651183 -289.026558) (xy 46.613062 -288.995433) (xy 46.580427 -288.958596) (xy 46.554124 -288.917)
			(xy 46.534833 -288.871724) (xy 46.523056 -288.82394) (xy 46.519096 -288.774886) (xy 46.180248 -288.774886)
			(xy 46.179753 -288.799493) (xy 46.171858 -288.84807) (xy 46.156274 -288.894751) (xy 46.133403 -288.938328)
			(xy 46.103838 -288.977672) (xy 46.068345 -289.011764) (xy 46.027842 -289.03972) (xy 45.98338 -289.060818)
			(xy 45.936109 -289.07451) (xy 45.887254 -289.080442) (xy 45.838079 -289.078461) (xy 45.78986 -289.068617)
			(xy 45.743844 -289.051165) (xy 45.701223 -289.026558) (xy 45.663102 -288.995433) (xy 45.630467 -288.958596)
			(xy 45.604164 -288.917) (xy 45.584873 -288.871724) (xy 45.573096 -288.82394) (xy 45.569136 -288.774886)
			(xy 45.230288 -288.774886) (xy 45.229793 -288.799493) (xy 45.221898 -288.84807) (xy 45.206314 -288.894751)
			(xy 45.183443 -288.938328) (xy 45.153878 -288.977672) (xy 45.118385 -289.011764) (xy 45.077882 -289.03972)
			(xy 45.03342 -289.060818) (xy 44.986149 -289.07451) (xy 44.937294 -289.080442) (xy 44.888119 -289.078461)
			(xy 44.8399 -289.068617) (xy 44.793884 -289.051165) (xy 44.751263 -289.026558) (xy 44.713142 -288.995433)
			(xy 44.680507 -288.958596) (xy 44.654204 -288.917) (xy 44.634913 -288.871724) (xy 44.623136 -288.82394)
			(xy 44.619176 -288.774886) (xy 44.305719 -288.774886) (xy 44.305277 -288.798501) (xy 44.298239 -288.846233)
			(xy 44.284338 -288.892434) (xy 44.26387 -288.936125) (xy 44.237268 -288.976376) (xy 44.205099 -289.012334)
			(xy 44.186856 -289.028124) (xy 44.178815 -289.035463) (xy 44.169318 -289.055029) (xy 44.168756 -289.076771)
			(xy 44.177228 -289.096802) (xy 44.193221 -289.111542) (xy 44.203366 -289.1155) (xy 44.230645 -289.105628)
			(xy 44.287649 -289.094894) (xy 44.31665 -289.094164) (xy 44.583096 -289.094164) (xy 44.608212 -289.094666)
			(xy 44.657805 -289.102658) (xy 44.705504 -289.118409) (xy 44.750104 -289.14152) (xy 44.790478 -289.171408)
			(xy 44.825604 -289.207317) (xy 44.854596 -289.248338) (xy 44.866052 -289.270694) (xy 44.89069 -289.320732)
			(xy 44.895202 -289.329105) (xy 44.909185 -289.341977) (xy 44.926906 -289.348849) (xy 44.93641 -289.34918)
			(xy 44.9453 -289.34918) (xy 44.983908 -289.270694) (xy 44.995407 -289.248362) (xy 45.024397 -289.207344)
			(xy 45.059518 -289.171437) (xy 45.099884 -289.141546) (xy 45.144475 -289.118427) (xy 45.192165 -289.102664)
			(xy 45.241751 -289.094654) (xy 45.266864 -289.094164) (xy 45.533056 -289.094164) (xy 45.558169 -289.094671)
			(xy 45.607756 -289.102671) (xy 45.655448 -289.118428) (xy 45.700041 -289.141543) (xy 45.740407 -289.171433)
			(xy 45.775526 -289.207342) (xy 45.80451 -289.248363) (xy 45.816012 -289.270694) (xy 45.84065 -289.320732)
			(xy 45.845165 -289.329098) (xy 45.859151 -289.341954) (xy 45.876869 -289.348806) (xy 45.88637 -289.34918)
			(xy 45.89526 -289.34918) (xy 45.933868 -289.270694) (xy 45.945369 -289.248365) (xy 45.97436 -289.207353)
			(xy 46.009483 -289.171452) (xy 46.049849 -289.141569) (xy 46.09444 -289.118459) (xy 46.142129 -289.102704)
			(xy 46.191712 -289.094704) (xy 46.216824 -289.094164) (xy 46.483016 -289.094164) (xy 46.508131 -289.094668)
			(xy 46.557722 -289.102663) (xy 46.605419 -289.118415) (xy 46.650016 -289.141528) (xy 46.690387 -289.171416)
			(xy 46.725511 -289.207325) (xy 46.754501 -289.248347) (xy 46.765972 -289.270694) (xy 46.79061 -289.320732)
			(xy 46.795123 -289.329103) (xy 46.809107 -289.34197) (xy 46.826827 -289.348835) (xy 46.83633 -289.34918)
			(xy 46.84522 -289.34918) (xy 46.883828 -289.270694) (xy 46.895327 -289.248363) (xy 46.924318 -289.207347)
			(xy 46.959439 -289.171442) (xy 46.999805 -289.141554) (xy 47.044397 -289.118437) (xy 47.092087 -289.102677)
			(xy 47.141671 -289.094671) (xy 47.166784 -289.094164) (xy 47.432976 -289.094164) (xy 47.458089 -289.094673)
			(xy 47.507673 -289.102675) (xy 47.555363 -289.118434) (xy 47.599953 -289.141551) (xy 47.640316 -289.171442)
			(xy 47.675433 -289.207351) (xy 47.704415 -289.248372) (xy 47.715932 -289.270694) (xy 47.74057 -289.320732)
			(xy 47.745081 -289.329107) (xy 47.759063 -289.341985) (xy 47.776784 -289.348864) (xy 47.78629 -289.34918)
			(xy 47.79518 -289.34918) (xy 47.833788 -289.270694) (xy 47.845289 -289.248366) (xy 47.874281 -289.207356)
			(xy 47.909404 -289.171457) (xy 47.949771 -289.141577) (xy 47.994362 -289.118469) (xy 48.042051 -289.102717)
			(xy 48.091633 -289.09472) (xy 48.116744 -289.094164) (xy 48.382936 -289.094164) (xy 48.40805 -289.09467)
			(xy 48.457639 -289.102667) (xy 48.505333 -289.118422) (xy 48.549928 -289.141536) (xy 48.590297 -289.171425)
			(xy 48.625418 -289.207334) (xy 48.654405 -289.248355) (xy 48.665892 -289.270694) (xy 48.69053 -289.320732)
			(xy 48.695044 -289.329101) (xy 48.709029 -289.341962) (xy 48.726748 -289.348821) (xy 48.73625 -289.34918)
			(xy 48.74514 -289.34918) (xy 48.783748 -289.270694) (xy 48.795261 -289.248363) (xy 48.824281 -289.207352)
			(xy 48.859433 -289.171458) (xy 48.89983 -289.141589) (xy 48.94445 -289.1185) (xy 48.968152 -289.110166)
			(xy 48.973768 -289.108139) (xy 48.983917 -289.10186) (xy 48.988218 -289.09772) (xy 49.29505 -288.790888)
			(xy 49.301615 -288.784765) (xy 49.317885 -288.77721) (xy 49.3268 -288.776156) (xy 49.344326 -288.774632)
			(xy 49.370488 -288.74974) (xy 49.371504 -288.74085) (xy 49.374898 -288.715372) (xy 49.389106 -288.665979)
			(xy 49.411387 -288.619664) (xy 49.44111 -288.577735) (xy 49.477437 -288.541378) (xy 49.51934 -288.511618)
			(xy 49.565637 -288.489299) (xy 49.615017 -288.475049) (xy 49.64049 -288.47161) (xy 49.640998 -288.47161)
			(xy 49.649634 -288.470594) (xy 49.674526 -288.444432) (xy 49.67605 -288.426906) (xy 49.677209 -288.418019)
			(xy 49.684736 -288.40177) (xy 49.690782 -288.395156) (xy 49.859438 -288.2265) (xy 49.877283 -288.209287)
			(xy 49.917379 -288.180125) (xy 49.961545 -288.157598) (xy 50.008693 -288.142261) (xy 50.05766 -288.134493)
			(xy 50.08245 -288.134044) (xy 50.291492 -288.134044) (xy 50.316432 -288.134523) (xy 50.365689 -288.142382)
			(xy 50.413098 -288.15789) (xy 50.43551 -288.168842) (xy 50.44507 -288.166246) (xy 50.461335 -288.154972)
			(xy 50.472128 -288.138384) (xy 50.475846 -288.118946) (xy 50.471936 -288.099546) (xy 50.460979 -288.083065)
			(xy 50.453036 -288.077148) (xy 50.432855 -288.062807) (xy 50.396985 -288.028685) (xy 50.367088 -287.989225)
			(xy 50.343947 -287.945459) (xy 50.328168 -287.898535) (xy 50.320163 -287.849679) (xy 50.319686 -287.824926)
			(xy 50.320208 -287.799671) (xy 50.328521 -287.749849) (xy 50.344922 -287.702075) (xy 50.368963 -287.657652)
			(xy 50.399987 -287.617792) (xy 50.437149 -287.583582) (xy 50.479435 -287.555956) (xy 50.525691 -287.535666)
			(xy 50.574656 -287.523266) (xy 50.624994 -287.519095) (xy 50.675332 -287.523266) (xy 50.724297 -287.535666)
			(xy 50.770553 -287.555956) (xy 50.812839 -287.583582) (xy 50.850001 -287.617792) (xy 50.881025 -287.657652)
			(xy 50.905066 -287.702075) (xy 50.921467 -287.749849) (xy 50.92978 -287.799671) (xy 50.930302 -287.824926)
			(xy 50.929827 -287.849682) (xy 50.921844 -287.898546) (xy 50.906076 -287.945479) (xy 50.882937 -287.989251)
			(xy 50.853033 -288.028712) (xy 50.81715 -288.062827) (xy 50.796952 -288.077148) (xy 50.788986 -288.083072)
			(xy 50.777957 -288.099555) (xy 50.774006 -288.11899) (xy 50.777722 -288.138471) (xy 50.78855 -288.155086)
			(xy 50.804872 -288.166352) (xy 50.814478 -288.168842) (xy 50.83688 -288.157865) (xy 50.88429 -288.142344)
			(xy 50.933553 -288.134494) (xy 50.958496 -288.134044) (xy 51.241452 -288.134044) (xy 51.266393 -288.13452)
			(xy 51.315653 -288.142373) (xy 51.363064 -288.157876) (xy 51.38547 -288.168842) (xy 51.395021 -288.166238)
			(xy 51.411266 -288.154958) (xy 51.422045 -288.138376) (xy 51.425759 -288.11895) (xy 51.421856 -288.099562)
			(xy 51.410917 -288.083085) (xy 51.402996 -288.077148) (xy 51.382817 -288.062805) (xy 51.346952 -288.028682)
			(xy 51.317059 -287.989221) (xy 51.293921 -287.945456) (xy 51.278144 -287.898532) (xy 51.27014 -287.849678)
			(xy 51.269646 -287.824926) (xy 51.270168 -287.799671) (xy 51.278481 -287.749849) (xy 51.294882 -287.702075)
			(xy 51.318923 -287.657652) (xy 51.349947 -287.617792) (xy 51.387109 -287.583582) (xy 51.429395 -287.555956)
			(xy 51.475651 -287.535666) (xy 51.524616 -287.523266) (xy 51.574954 -287.519095) (xy 51.625292 -287.523266)
			(xy 51.674257 -287.535666) (xy 51.720513 -287.555956) (xy 51.762799 -287.583582) (xy 51.799961 -287.617792)
			(xy 51.830985 -287.657652) (xy 51.855026 -287.702075) (xy 51.871427 -287.749849) (xy 51.87974 -287.799671)
			(xy 51.880262 -287.824926) (xy 51.879787 -287.849683) (xy 51.871805 -287.898548) (xy 51.856039 -287.945484)
			(xy 51.832903 -287.989259) (xy 51.803003 -288.028724) (xy 51.767124 -288.062845) (xy 51.746912 -288.077148)
			(xy 51.738939 -288.083066) (xy 51.727897 -288.099547) (xy 51.723939 -288.118985) (xy 51.727658 -288.138471)
			(xy 51.738496 -288.155086) (xy 51.754831 -288.166341) (xy 51.764438 -288.168842) (xy 51.786841 -288.157869)
			(xy 51.834251 -288.142358) (xy 51.883514 -288.134516) (xy 51.908456 -288.134044) (xy 52.191412 -288.134044)
			(xy 52.216354 -288.134517) (xy 52.265616 -288.142364) (xy 52.31303 -288.157862) (xy 52.33543 -288.168842)
			(xy 52.344987 -288.166243) (xy 52.361245 -288.154967) (xy 52.372034 -288.138381) (xy 52.37575 -288.118947)
			(xy 52.371843 -288.099551) (xy 52.360892 -288.083072) (xy 52.352956 -288.077148) (xy 52.332779 -288.062804)
			(xy 52.296918 -288.028678) (xy 52.267029 -287.989216) (xy 52.243895 -287.945452) (xy 52.22812 -287.898529)
			(xy 52.220118 -287.849677) (xy 52.219606 -287.824926) (xy 52.220128 -287.799671) (xy 52.228441 -287.749849)
			(xy 52.244842 -287.702075) (xy 52.268883 -287.657652) (xy 52.299907 -287.617792) (xy 52.337069 -287.583582)
			(xy 52.379355 -287.555956) (xy 52.425611 -287.535666) (xy 52.474576 -287.523266) (xy 52.524914 -287.519095)
			(xy 52.575252 -287.523266) (xy 52.624217 -287.535666) (xy 52.670473 -287.555956) (xy 52.712759 -287.583582)
			(xy 52.749921 -287.617792) (xy 52.780945 -287.657652) (xy 52.804986 -287.702075) (xy 52.821387 -287.749849)
			(xy 52.8297 -287.799671) (xy 52.830222 -287.824926) (xy 52.829747 -287.849682) (xy 52.821764 -287.898547)
			(xy 52.805997 -287.945481) (xy 52.782859 -287.989254) (xy 52.752956 -288.028716) (xy 52.717075 -288.062833)
			(xy 52.696872 -288.077148) (xy 52.688903 -288.08307) (xy 52.677871 -288.099552) (xy 52.673917 -288.118988)
			(xy 52.677634 -288.138471) (xy 52.688466 -288.155086) (xy 52.704792 -288.166348) (xy 52.714398 -288.168842)
			(xy 52.7368 -288.157866) (xy 52.78421 -288.142349) (xy 52.833474 -288.134501) (xy 52.858416 -288.134044)
			(xy 53.141372 -288.134044) (xy 53.166312 -288.134521) (xy 53.215571 -288.142378) (xy 53.262981 -288.157883)
			(xy 53.28539 -288.168842) (xy 53.294953 -288.166249) (xy 53.311224 -288.154977) (xy 53.322022 -288.138386)
			(xy 53.325741 -288.118944) (xy 53.321829 -288.09954) (xy 53.310866 -288.083059) (xy 53.302916 -288.077148)
			(xy 53.282736 -288.062806) (xy 53.246868 -288.028683) (xy 53.216974 -287.989223) (xy 53.193834 -287.945457)
			(xy 53.178056 -287.898533) (xy 53.170052 -287.849679) (xy 53.169566 -287.824926) (xy 53.170088 -287.799671)
			(xy 53.178401 -287.749849) (xy 53.194802 -287.702075) (xy 53.218843 -287.657652) (xy 53.249867 -287.617792)
			(xy 53.287029 -287.583582) (xy 53.329315 -287.555956) (xy 53.375571 -287.535666) (xy 53.424536 -287.523266)
			(xy 53.474874 -287.519095) (xy 53.525212 -287.523266) (xy 53.574177 -287.535666) (xy 53.620433 -287.555956)
			(xy 53.662719 -287.583582) (xy 53.699881 -287.617792) (xy 53.730905 -287.657652) (xy 53.754946 -287.702075)
			(xy 53.771347 -287.749849) (xy 53.77966 -287.799671) (xy 53.780182 -287.824926) (xy 53.779707 -287.849682)
			(xy 53.771724 -287.898545) (xy 53.755955 -287.945478) (xy 53.732815 -287.989249) (xy 53.70291 -288.028708)
			(xy 53.667026 -288.062821) (xy 53.646832 -288.077148) (xy 53.638857 -288.083065) (xy 53.627811 -288.099544)
			(xy 53.623851 -288.118984) (xy 53.627571 -288.138471) (xy 53.638412 -288.155085) (xy 53.654751 -288.166337)
			(xy 53.664358 -288.168842) (xy 53.686761 -288.15787) (xy 53.734172 -288.142362) (xy 53.783435 -288.134524)
			(xy 53.808376 -288.134044) (xy 54.091332 -288.134044) (xy 54.116273 -288.134518) (xy 54.165534 -288.142369)
			(xy 54.212947 -288.157869) (xy 54.23535 -288.168842) (xy 54.244904 -288.166241) (xy 54.261156 -288.154963)
			(xy 54.271939 -288.138379) (xy 54.275654 -288.118949) (xy 54.27175 -288.099556) (xy 54.260804 -288.083079)
			(xy 54.252876 -288.077148) (xy 54.232698 -288.062805) (xy 54.196835 -288.02868) (xy 54.166944 -287.989219)
			(xy 54.143808 -287.945454) (xy 54.128032 -287.898531) (xy 54.120029 -287.849678) (xy 54.119526 -287.824926)
			(xy 54.120048 -287.799671) (xy 54.128361 -287.749849) (xy 54.144762 -287.702075) (xy 54.168803 -287.657652)
			(xy 54.199827 -287.617792) (xy 54.236989 -287.583582) (xy 54.279275 -287.555956) (xy 54.325531 -287.535666)
			(xy 54.374496 -287.523266) (xy 54.424834 -287.519095) (xy 54.475172 -287.523266) (xy 54.524137 -287.535666)
			(xy 54.570393 -287.555956) (xy 54.612679 -287.583582) (xy 54.649841 -287.617792) (xy 54.680865 -287.657652)
			(xy 54.704906 -287.702075) (xy 54.721307 -287.749849) (xy 54.72962 -287.799671) (xy 54.730142 -287.824926)
			(xy 54.729667 -287.849682) (xy 54.721685 -287.898547) (xy 54.705918 -287.945482) (xy 54.682781 -287.989256)
			(xy 54.65288 -288.02872) (xy 54.616999 -288.062839) (xy 54.596792 -288.077148) (xy 54.588821 -288.083068)
			(xy 54.577784 -288.099549) (xy 54.573828 -288.118987) (xy 54.577546 -288.138471) (xy 54.588381 -288.155086)
			(xy 54.604711 -288.166345) (xy 54.614318 -288.168842) (xy 54.636721 -288.157867) (xy 54.684131 -288.142353)
			(xy 54.733394 -288.134509) (xy 54.758336 -288.134044) (xy 55.041292 -288.134044) (xy 55.066232 -288.134523)
			(xy 55.115489 -288.142382) (xy 55.162898 -288.15789) (xy 55.18531 -288.168842) (xy 55.19487 -288.166246)
			(xy 55.211135 -288.154972) (xy 55.221928 -288.138384) (xy 55.225646 -288.118946) (xy 55.221736 -288.099546)
			(xy 55.210779 -288.083065) (xy 55.202836 -288.077148) (xy 55.182655 -288.062807) (xy 55.146785 -288.028685)
			(xy 55.116888 -287.989225) (xy 55.093747 -287.945459) (xy 55.077968 -287.898535) (xy 55.069963 -287.849679)
			(xy 55.069486 -287.824926) (xy 55.070008 -287.799671) (xy 55.078321 -287.749849) (xy 55.094722 -287.702075)
			(xy 55.118763 -287.657652) (xy 55.149787 -287.617792) (xy 55.186949 -287.583582) (xy 55.229235 -287.555956)
			(xy 55.275491 -287.535666) (xy 55.324456 -287.523266) (xy 55.374794 -287.519095) (xy 55.425132 -287.523266)
			(xy 55.474097 -287.535666) (xy 55.520353 -287.555956) (xy 55.562639 -287.583582) (xy 55.599801 -287.617792)
			(xy 55.630825 -287.657652) (xy 55.654866 -287.702075) (xy 55.671267 -287.749849) (xy 55.67958 -287.799671)
			(xy 55.680102 -287.824926) (xy 55.679627 -287.849682) (xy 55.671644 -287.898546) (xy 55.655876 -287.945479)
			(xy 55.632737 -287.989251) (xy 55.602833 -288.028712) (xy 55.56695 -288.062827) (xy 55.546752 -288.077148)
			(xy 55.538786 -288.083072) (xy 55.527757 -288.099555) (xy 55.523806 -288.11899) (xy 55.527522 -288.138471)
			(xy 55.53835 -288.155086) (xy 55.554672 -288.166352) (xy 55.564278 -288.168842) (xy 55.58668 -288.157865)
			(xy 55.63409 -288.142344) (xy 55.683353 -288.134494) (xy 55.708296 -288.134044) (xy 55.991252 -288.134044)
			(xy 56.016193 -288.13452) (xy 56.065453 -288.142373) (xy 56.112864 -288.157876) (xy 56.13527 -288.168842)
			(xy 56.144821 -288.166238) (xy 56.161066 -288.154958) (xy 56.171845 -288.138376) (xy 56.175559 -288.11895)
			(xy 56.171656 -288.099562) (xy 56.160717 -288.083085) (xy 56.152796 -288.077148) (xy 56.132617 -288.062805)
			(xy 56.096752 -288.028682) (xy 56.066859 -287.989221) (xy 56.043721 -287.945456) (xy 56.027944 -287.898532)
			(xy 56.01994 -287.849678) (xy 56.019446 -287.824926) (xy 56.019968 -287.799671) (xy 56.028281 -287.749849)
			(xy 56.044682 -287.702075) (xy 56.068723 -287.657652) (xy 56.099747 -287.617792) (xy 56.136909 -287.583582)
			(xy 56.179195 -287.555956) (xy 56.225451 -287.535666) (xy 56.274416 -287.523266) (xy 56.324754 -287.519095)
			(xy 56.375092 -287.523266) (xy 56.424057 -287.535666) (xy 56.470313 -287.555956) (xy 56.512599 -287.583582)
			(xy 56.549761 -287.617792) (xy 56.580785 -287.657652) (xy 56.604826 -287.702075) (xy 56.621227 -287.749849)
			(xy 56.62954 -287.799671) (xy 56.630062 -287.824926) (xy 56.629587 -287.849683) (xy 56.621605 -287.898548)
			(xy 56.605839 -287.945484) (xy 56.582703 -287.989259) (xy 56.552803 -288.028724) (xy 56.516924 -288.062845)
			(xy 56.496712 -288.077148) (xy 56.488739 -288.083066) (xy 56.477697 -288.099547) (xy 56.473739 -288.118985)
			(xy 56.477458 -288.138471) (xy 56.488296 -288.155086) (xy 56.504631 -288.166341) (xy 56.514238 -288.168842)
			(xy 56.536641 -288.157869) (xy 56.584051 -288.142358) (xy 56.633314 -288.134516) (xy 56.658256 -288.134044)
			(xy 56.941466 -288.134044) (xy 56.966407 -288.134521) (xy 57.015665 -288.142376) (xy 57.063076 -288.157881)
			(xy 57.085484 -288.168842) (xy 57.095048 -288.16625) (xy 57.111321 -288.154978) (xy 57.122121 -288.138387)
			(xy 57.12584 -288.118944) (xy 57.121927 -288.099539) (xy 57.110962 -288.083057) (xy 57.10301 -288.077148)
			(xy 57.08283 -288.062806) (xy 57.046963 -288.028683) (xy 57.017069 -287.989222) (xy 56.99393 -287.945457)
			(xy 56.978152 -287.898533) (xy 56.970148 -287.849679) (xy 56.96966 -287.824926) (xy 56.970182 -287.799671)
			(xy 56.978495 -287.749849) (xy 56.994896 -287.702075) (xy 57.018937 -287.657652) (xy 57.049961 -287.617792)
			(xy 57.087123 -287.583582) (xy 57.129409 -287.555956) (xy 57.175665 -287.535666) (xy 57.22463 -287.523266)
			(xy 57.274968 -287.519095) (xy 57.325306 -287.523266) (xy 57.374271 -287.535666) (xy 57.420527 -287.555956)
			(xy 57.462813 -287.583582) (xy 57.499975 -287.617792) (xy 57.530999 -287.657652) (xy 57.553894 -287.699958)
			(xy 57.944016 -287.699958) (xy 57.947976 -287.650904) (xy 57.959753 -287.60312) (xy 57.979044 -287.557844)
			(xy 58.005347 -287.516248) (xy 58.037982 -287.479411) (xy 58.076103 -287.448286) (xy 58.118724 -287.423679)
			(xy 58.16474 -287.406227) (xy 58.212959 -287.396383) (xy 58.262134 -287.394402) (xy 58.310989 -287.400334)
			(xy 58.35826 -287.414026) (xy 58.402722 -287.435124) (xy 58.443225 -287.46308) (xy 58.478718 -287.497172)
			(xy 58.508283 -287.536516) (xy 58.531154 -287.580093) (xy 58.546738 -287.626774) (xy 58.554633 -287.675351)
			(xy 58.555128 -287.699958) (xy 58.554633 -287.724565) (xy 58.546738 -287.773142) (xy 58.531154 -287.819823)
			(xy 58.508283 -287.8634) (xy 58.478718 -287.902744) (xy 58.443225 -287.936836) (xy 58.402722 -287.964792)
			(xy 58.35826 -287.98589) (xy 58.310989 -287.999582) (xy 58.262134 -288.005514) (xy 58.212959 -288.003533)
			(xy 58.16474 -287.993689) (xy 58.118724 -287.976237) (xy 58.076103 -287.95163) (xy 58.037982 -287.920505)
			(xy 58.005347 -287.883668) (xy 57.979044 -287.842072) (xy 57.959753 -287.796796) (xy 57.947976 -287.749012)
			(xy 57.944016 -287.699958) (xy 57.553894 -287.699958) (xy 57.55504 -287.702075) (xy 57.571441 -287.749849)
			(xy 57.579754 -287.799671) (xy 57.580276 -287.824926) (xy 57.579801 -287.849682) (xy 57.571817 -287.898545)
			(xy 57.556049 -287.945477) (xy 57.532908 -287.989248) (xy 57.503003 -288.028707) (xy 57.467119 -288.062819)
			(xy 57.446926 -288.077148) (xy 57.438951 -288.083065) (xy 57.427907 -288.099545) (xy 57.423948 -288.118984)
			(xy 57.427667 -288.138471) (xy 57.438508 -288.155085) (xy 57.454845 -288.166338) (xy 57.464452 -288.168842)
			(xy 57.486855 -288.15787) (xy 57.534266 -288.142361) (xy 57.583528 -288.134522) (xy 57.60847 -288.134044)
			(xy 57.891426 -288.134044) (xy 57.91686 -288.134524) (xy 57.967071 -288.142679) (xy 58.01532 -288.158791)
			(xy 58.060357 -288.18244) (xy 58.101012 -288.213013) (xy 58.136232 -288.249717) (xy 58.165101 -288.291599)
			(xy 58.176414 -288.314384) (xy 58.190384 -288.344102) (xy 58.194844 -288.352635) (xy 58.208857 -288.365817)
			(xy 58.226739 -288.372915) (xy 58.236358 -288.373312) (xy 58.245756 -288.373312) (xy 58.273442 -288.314384)
			(xy 58.284804 -288.291631) (xy 58.31369 -288.249778) (xy 58.348912 -288.213097) (xy 58.38956 -288.182538)
			(xy 58.434582 -288.158892) (xy 58.482812 -288.14277) (xy 58.533003 -288.134589) (xy 58.55843 -288.134044)
			(xy 59.791346 -288.134044) (xy 59.806487 -288.134175) (xy 59.836638 -288.136975) (xy 59.851544 -288.139632)
			(xy 59.860496 -288.134107) (xy 59.873305 -288.117448) (xy 59.878379 -288.097055) (xy 59.87487 -288.076336)
			(xy 59.869578 -288.067242) (xy 59.857751 -288.0485) (xy 59.83905 -288.008323) (xy 59.826356 -287.965863)
			(xy 59.819938 -287.922014) (xy 59.81954 -287.899856) (xy 59.820062 -287.874601) (xy 59.828375 -287.824779)
			(xy 59.844776 -287.777005) (xy 59.868817 -287.732582) (xy 59.899841 -287.692722) (xy 59.937003 -287.658512)
			(xy 59.979289 -287.630886) (xy 60.025545 -287.610596) (xy 60.07451 -287.598196) (xy 60.124848 -287.594025)
			(xy 60.175186 -287.598196) (xy 60.224151 -287.610596) (xy 60.270407 -287.630886) (xy 60.312693 -287.658512)
			(xy 60.349855 -287.692722) (xy 60.380879 -287.732582) (xy 60.40492 -287.777005) (xy 60.421321 -287.824779)
			(xy 60.429634 -287.874601) (xy 60.430156 -287.899856) (xy 60.429762 -287.922015) (xy 60.423353 -287.965868)
			(xy 60.410664 -288.008331) (xy 60.391962 -288.04851) (xy 60.380118 -288.067242) (xy 60.37475 -288.076317)
			(xy 60.371179 -288.097074) (xy 60.376257 -288.117514) (xy 60.389126 -288.134187) (xy 60.398152 -288.139632)
			(xy 60.413057 -288.136965) (xy 60.443209 -288.134163) (xy 60.45835 -288.134044) (xy 60.741306 -288.134044)
			(xy 60.766248 -288.134516) (xy 60.81551 -288.142363) (xy 60.862925 -288.15786) (xy 60.885324 -288.168842)
			(xy 60.894882 -288.166244) (xy 60.911142 -288.154969) (xy 60.921932 -288.138382) (xy 60.925649 -288.118947)
			(xy 60.921741 -288.099549) (xy 60.910788 -288.08307) (xy 60.90285 -288.077148) (xy 60.882673 -288.062804)
			(xy 60.846813 -288.028678) (xy 60.816925 -287.989216) (xy 60.793791 -287.945451) (xy 60.778016 -287.898529)
			(xy 60.770014 -287.849677) (xy 60.7695 -287.824926) (xy 60.770022 -287.799671) (xy 60.778335 -287.749849)
			(xy 60.794736 -287.702075) (xy 60.818777 -287.657652) (xy 60.849801 -287.617792) (xy 60.886963 -287.583582)
			(xy 60.929249 -287.555956) (xy 60.975505 -287.535666) (xy 61.02447 -287.523266) (xy 61.074808 -287.519095)
			(xy 61.125146 -287.523266) (xy 61.174111 -287.535666) (xy 61.220367 -287.555956) (xy 61.262653 -287.583582)
			(xy 61.299815 -287.617792) (xy 61.330839 -287.657652) (xy 61.35488 -287.702075) (xy 61.371281 -287.749849)
			(xy 61.379594 -287.799671) (xy 61.380116 -287.824926) (xy 61.379641 -287.849682) (xy 61.371658 -287.898546)
			(xy 61.355891 -287.94548) (xy 61.332752 -287.989253) (xy 61.302849 -288.028715) (xy 61.266967 -288.062831)
			(xy 61.246766 -288.077148) (xy 61.238798 -288.083071) (xy 61.227767 -288.099553) (xy 61.223814 -288.118989)
			(xy 61.22753 -288.138471) (xy 61.238361 -288.155086) (xy 61.254686 -288.166349) (xy 61.264292 -288.168842)
			(xy 61.286694 -288.157866) (xy 61.334104 -288.142347) (xy 61.383367 -288.134499) (xy 61.40831 -288.134044)
			(xy 61.691266 -288.134044) (xy 61.716207 -288.134521) (xy 61.765465 -288.142376) (xy 61.812876 -288.157881)
			(xy 61.835284 -288.168842) (xy 61.844848 -288.16625) (xy 61.861121 -288.154978) (xy 61.871921 -288.138387)
			(xy 61.87564 -288.118944) (xy 61.871727 -288.099539) (xy 61.860762 -288.083057) (xy 61.85281 -288.077148)
			(xy 61.83263 -288.062806) (xy 61.796763 -288.028683) (xy 61.766869 -287.989222) (xy 61.74373 -287.945457)
			(xy 61.727952 -287.898533) (xy 61.719948 -287.849679) (xy 61.71946 -287.824926) (xy 61.719982 -287.799671)
			(xy 61.728295 -287.749849) (xy 61.744696 -287.702075) (xy 61.768737 -287.657652) (xy 61.799761 -287.617792)
			(xy 61.836923 -287.583582) (xy 61.879209 -287.555956) (xy 61.925465 -287.535666) (xy 61.97443 -287.523266)
			(xy 62.024768 -287.519095) (xy 62.075106 -287.523266) (xy 62.124071 -287.535666) (xy 62.170327 -287.555956)
			(xy 62.212613 -287.583582) (xy 62.249775 -287.617792) (xy 62.280799 -287.657652) (xy 62.30484 -287.702075)
			(xy 62.321241 -287.749849) (xy 62.329554 -287.799671) (xy 62.330076 -287.824926) (xy 62.329601 -287.849682)
			(xy 62.321617 -287.898545) (xy 62.305849 -287.945477) (xy 62.282708 -287.989248) (xy 62.252803 -288.028707)
			(xy 62.216919 -288.062819) (xy 62.196726 -288.077148) (xy 62.188751 -288.083065) (xy 62.177707 -288.099545)
			(xy 62.173748 -288.118984) (xy 62.177467 -288.138471) (xy 62.188308 -288.155085) (xy 62.204645 -288.166338)
			(xy 62.214252 -288.168842) (xy 62.236655 -288.15787) (xy 62.284066 -288.142361) (xy 62.333328 -288.134522)
			(xy 62.35827 -288.134044) (xy 62.64148 -288.134044) (xy 62.66642 -288.134522) (xy 62.715678 -288.14238)
			(xy 62.763088 -288.157886) (xy 62.785498 -288.168842) (xy 62.79506 -288.166248) (xy 62.811329 -288.154975)
			(xy 62.822125 -288.138385) (xy 62.825843 -288.118945) (xy 62.821932 -288.099542) (xy 62.810971 -288.083061)
			(xy 62.803024 -288.077148) (xy 62.782843 -288.062806) (xy 62.746975 -288.028684) (xy 62.717079 -287.989224)
			(xy 62.693939 -287.945458) (xy 62.678161 -287.898534) (xy 62.670156 -287.849679) (xy 62.669674 -287.824926)
			(xy 62.670196 -287.799671) (xy 62.678509 -287.749849) (xy 62.69491 -287.702075) (xy 62.718951 -287.657652)
			(xy 62.749975 -287.617792) (xy 62.787137 -287.583582) (xy 62.829423 -287.555956) (xy 62.875679 -287.535666)
			(xy 62.924644 -287.523266) (xy 62.974982 -287.519095) (xy 63.02532 -287.523266) (xy 63.074285 -287.535666)
			(xy 63.120541 -287.555956) (xy 63.162827 -287.583582) (xy 63.199989 -287.617792) (xy 63.231013 -287.657652)
			(xy 63.255054 -287.702075) (xy 63.271455 -287.749849) (xy 63.279768 -287.799671) (xy 63.28029 -287.824926)
			(xy 63.279815 -287.849682) (xy 63.271832 -287.898545) (xy 63.256063 -287.945478) (xy 63.232923 -287.98925)
			(xy 63.203019 -288.02871) (xy 63.167136 -288.062823) (xy 63.14694 -288.077148) (xy 63.138975 -288.083073)
			(xy 63.127949 -288.099557) (xy 63.123999 -288.118991) (xy 63.127715 -288.138471) (xy 63.138541 -288.155086)
			(xy 63.15486 -288.166354) (xy 63.164466 -288.168842) (xy 63.186869 -288.157871) (xy 63.23428 -288.142364)
			(xy 63.283543 -288.134527) (xy 63.308484 -288.134044) (xy 63.59144 -288.134044) (xy 63.616381 -288.134519)
			(xy 63.665642 -288.142371) (xy 63.713054 -288.157872) (xy 63.735458 -288.168842) (xy 63.745011 -288.166239)
			(xy 63.76126 -288.154961) (xy 63.772042 -288.138378) (xy 63.775756 -288.11895) (xy 63.771852 -288.099559)
			(xy 63.760909 -288.083081) (xy 63.752984 -288.077148) (xy 63.732805 -288.062805) (xy 63.696942 -288.02868)
			(xy 63.66705 -287.989219) (xy 63.643913 -287.945454) (xy 63.628137 -287.898531) (xy 63.620133 -287.849678)
			(xy 63.619634 -287.824926) (xy 63.620156 -287.799671) (xy 63.628469 -287.749849) (xy 63.64487 -287.702075)
			(xy 63.668911 -287.657652) (xy 63.699935 -287.617792) (xy 63.737097 -287.583582) (xy 63.779383 -287.555956)
			(xy 63.825639 -287.535666) (xy 63.874604 -287.523266) (xy 63.924942 -287.519095) (xy 63.97528 -287.523266)
			(xy 64.024245 -287.535666) (xy 64.070501 -287.555956) (xy 64.112787 -287.583582) (xy 64.149949 -287.617792)
			(xy 64.180973 -287.657652) (xy 64.205014 -287.702075) (xy 64.221415 -287.749849) (xy 64.229728 -287.799671)
			(xy 64.23025 -287.824926) (xy 64.229775 -287.849682) (xy 64.221793 -287.898548) (xy 64.206027 -287.945483)
			(xy 64.18289 -287.989257) (xy 64.152989 -288.028722) (xy 64.117109 -288.062841) (xy 64.0969 -288.077148)
			(xy 64.088928 -288.083067) (xy 64.077889 -288.099548) (xy 64.073933 -288.118986) (xy 64.077651 -288.138471)
			(xy 64.088487 -288.155086) (xy 64.104819 -288.166343) (xy 64.114426 -288.168842) (xy 64.136829 -288.157868)
			(xy 64.184239 -288.142355) (xy 64.233502 -288.134512) (xy 64.258444 -288.134044) (xy 64.5414 -288.134044)
			(xy 64.566342 -288.134516) (xy 64.615605 -288.142362) (xy 64.66302 -288.157858) (xy 64.685418 -288.168842)
			(xy 64.694977 -288.166245) (xy 64.711239 -288.15497) (xy 64.72203 -288.138383) (xy 64.725747 -288.118946)
			(xy 64.721838 -288.099548) (xy 64.710884 -288.083068) (xy 64.702944 -288.077148) (xy 64.682768 -288.062803)
			(xy 64.646908 -288.028677) (xy 64.617021 -287.989215) (xy 64.593887 -287.945451) (xy 64.578113 -287.898529)
			(xy 64.570111 -287.849677) (xy 64.569594 -287.824926) (xy 64.570116 -287.799671) (xy 64.578429 -287.749849)
			(xy 64.59483 -287.702075) (xy 64.618871 -287.657652) (xy 64.649895 -287.617792) (xy 64.687057 -287.583582)
			(xy 64.729343 -287.555956) (xy 64.775599 -287.535666) (xy 64.824564 -287.523266) (xy 64.874902 -287.519095)
			(xy 64.92524 -287.523266) (xy 64.974205 -287.535666) (xy 65.020461 -287.555956) (xy 65.062747 -287.583582)
			(xy 65.099909 -287.617792) (xy 65.130933 -287.657652) (xy 65.154974 -287.702075) (xy 65.171375 -287.749849)
			(xy 65.179688 -287.799671) (xy 65.18021 -287.824926) (xy 65.179735 -287.849682) (xy 65.171752 -287.898546)
			(xy 65.155985 -287.94548) (xy 65.132846 -287.989252) (xy 65.102942 -288.028714) (xy 65.06706 -288.062829)
			(xy 65.04686 -288.077148) (xy 65.038893 -288.083071) (xy 65.027863 -288.099554) (xy 65.02391 -288.118989)
			(xy 65.027627 -288.138471) (xy 65.038456 -288.155086) (xy 65.05478 -288.166351) (xy 65.064386 -288.168842)
			(xy 65.086788 -288.157865) (xy 65.134198 -288.142346) (xy 65.183461 -288.134497) (xy 65.208404 -288.134044)
			(xy 65.49136 -288.134044) (xy 65.516301 -288.13452) (xy 65.56556 -288.142375) (xy 65.612971 -288.157879)
			(xy 65.635378 -288.168842) (xy 65.644943 -288.16625) (xy 65.661218 -288.154979) (xy 65.672019 -288.138388)
			(xy 65.675739 -288.118943) (xy 65.671825 -288.099537) (xy 65.660859 -288.083055) (xy 65.652904 -288.077148)
			(xy 65.632724 -288.062806) (xy 65.596858 -288.028682) (xy 65.566965 -287.989221) (xy 65.543826 -287.945456)
			(xy 65.528049 -287.898532) (xy 65.520045 -287.849678) (xy 65.519554 -287.824926) (xy 65.520076 -287.799671)
			(xy 65.528389 -287.749849) (xy 65.54479 -287.702075) (xy 65.568831 -287.657652) (xy 65.599855 -287.617792)
			(xy 65.637017 -287.583582) (xy 65.679303 -287.555956) (xy 65.725559 -287.535666) (xy 65.774524 -287.523266)
			(xy 65.824862 -287.519095) (xy 65.8752 -287.523266) (xy 65.924165 -287.535666) (xy 65.970421 -287.555956)
			(xy 66.012707 -287.583582) (xy 66.049869 -287.617792) (xy 66.080893 -287.657652) (xy 66.104934 -287.702075)
			(xy 66.121335 -287.749849) (xy 66.129648 -287.799671) (xy 66.13017 -287.824926) (xy 66.129695 -287.849682)
			(xy 66.121711 -287.898544) (xy 66.105942 -287.945477) (xy 66.082801 -287.989247) (xy 66.052896 -288.028706)
			(xy 66.017011 -288.062817) (xy 65.99682 -288.077148) (xy 65.988846 -288.083066) (xy 65.977803 -288.099546)
			(xy 65.973844 -288.118985) (xy 65.977563 -288.138471) (xy 65.988403 -288.155085) (xy 66.004739 -288.166339)
			(xy 66.014346 -288.168842) (xy 66.036749 -288.157869) (xy 66.084159 -288.142359) (xy 66.133422 -288.134519)
			(xy 66.158364 -288.134044) (xy 66.44132 -288.134044) (xy 66.466261 -288.134517) (xy 66.515523 -288.142366)
			(xy 66.562937 -288.157865) (xy 66.585338 -288.168842) (xy 66.594894 -288.166242) (xy 66.61115 -288.154966)
			(xy 66.621936 -288.13838) (xy 66.625652 -288.118948) (xy 66.621745 -288.099553) (xy 66.610797 -288.083075)
			(xy 66.602864 -288.077148) (xy 66.582687 -288.062804) (xy 66.546825 -288.028679) (xy 66.516935 -287.989217)
			(xy 66.4938 -287.945453) (xy 66.478025 -287.89853) (xy 66.470022 -287.849678) (xy 66.469514 -287.824926)
			(xy 66.470036 -287.799671) (xy 66.478349 -287.749849) (xy 66.49475 -287.702075) (xy 66.518791 -287.657652)
			(xy 66.549815 -287.617792) (xy 66.586977 -287.583582) (xy 66.629263 -287.555956) (xy 66.675519 -287.535666)
			(xy 66.724484 -287.523266) (xy 66.774822 -287.519095) (xy 66.82516 -287.523266) (xy 66.874125 -287.535666)
			(xy 66.920381 -287.555956) (xy 66.962667 -287.583582) (xy 66.999829 -287.617792) (xy 67.030853 -287.657652)
			(xy 67.054894 -287.702075) (xy 67.071295 -287.749849) (xy 67.079608 -287.799671) (xy 67.08013 -287.824926)
			(xy 67.079655 -287.849682) (xy 67.071673 -287.898547) (xy 67.055906 -287.945482) (xy 67.032768 -287.989255)
			(xy 67.002866 -288.028718) (xy 66.966985 -288.062835) (xy 66.94678 -288.077148) (xy 66.938811 -288.083069)
			(xy 66.927776 -288.099551) (xy 66.923821 -288.118988) (xy 66.927539 -288.138471) (xy 66.938372 -288.155086)
			(xy 66.9547 -288.166347) (xy 66.964306 -288.168842) (xy 66.986709 -288.157867) (xy 67.034118 -288.142351)
			(xy 67.083382 -288.134504) (xy 67.108324 -288.134044) (xy 67.39128 -288.134044) (xy 67.41622 -288.134522)
			(xy 67.465478 -288.14238) (xy 67.512888 -288.157886) (xy 67.535298 -288.168842) (xy 67.54486 -288.166248)
			(xy 67.561129 -288.154975) (xy 67.571925 -288.138385) (xy 67.575643 -288.118945) (xy 67.571732 -288.099542)
			(xy 67.560771 -288.083061) (xy 67.552824 -288.077148) (xy 67.532643 -288.062806) (xy 67.496775 -288.028684)
			(xy 67.466879 -287.989224) (xy 67.443739 -287.945458) (xy 67.427961 -287.898534) (xy 67.419956 -287.849679)
			(xy 67.419474 -287.824926) (xy 67.419996 -287.799671) (xy 67.428309 -287.749849) (xy 67.44471 -287.702075)
			(xy 67.468751 -287.657652) (xy 67.499775 -287.617792) (xy 67.536937 -287.583582) (xy 67.579223 -287.555956)
			(xy 67.625479 -287.535666) (xy 67.674444 -287.523266) (xy 67.724782 -287.519095) (xy 67.77512 -287.523266)
			(xy 67.824085 -287.535666) (xy 67.870341 -287.555956) (xy 67.912627 -287.583582) (xy 67.949789 -287.617792)
			(xy 67.980813 -287.657652) (xy 68.004854 -287.702075) (xy 68.021255 -287.749849) (xy 68.029568 -287.799671)
			(xy 68.03009 -287.824926) (xy 68.029615 -287.849682) (xy 68.021632 -287.898545) (xy 68.005863 -287.945478)
			(xy 67.982723 -287.98925) (xy 67.952819 -288.02871) (xy 67.916936 -288.062823) (xy 67.89674 -288.077148)
			(xy 67.888775 -288.083073) (xy 67.877749 -288.099557) (xy 67.873799 -288.118991) (xy 67.877515 -288.138471)
			(xy 67.888341 -288.155086) (xy 67.90466 -288.166354) (xy 67.914266 -288.168842) (xy 67.936669 -288.157871)
			(xy 67.98408 -288.142364) (xy 68.033343 -288.134527) (xy 68.058284 -288.134044) (xy 68.349368 -288.134044)
			(xy 68.372789 -288.135078) (xy 68.418958 -288.143206) (xy 68.463419 -288.158071) (xy 68.484496 -288.168334)
			(xy 68.495635 -288.165319) (xy 68.513744 -288.151051) (xy 68.523849 -288.130329) (xy 68.524374 -288.118804)
			(xy 68.508118 -288.087816) (xy 68.505308 -288.082822) (xy 68.497878 -288.074102) (xy 68.493386 -288.070544)
			(xy 68.474515 -288.056043) (xy 68.441082 -288.022174) (xy 68.413311 -287.983527) (xy 68.391875 -287.941038)
			(xy 68.377292 -287.895737) (xy 68.369918 -287.848721) (xy 68.369434 -287.824926) (xy 68.369956 -287.799671)
			(xy 68.378269 -287.749849) (xy 68.39467 -287.702075) (xy 68.418711 -287.657652) (xy 68.449735 -287.617792)
			(xy 68.486897 -287.583582) (xy 68.529183 -287.555956) (xy 68.575439 -287.535666) (xy 68.624404 -287.523266)
			(xy 68.674742 -287.519095) (xy 68.72508 -287.523266) (xy 68.774045 -287.535666) (xy 68.820301 -287.555956)
			(xy 68.862587 -287.583582) (xy 68.899749 -287.617792) (xy 68.930773 -287.657652) (xy 68.954814 -287.702075)
			(xy 68.971215 -287.749849) (xy 68.979528 -287.799671) (xy 68.98005 -287.824926) (xy 70.269112 -287.824926)
			(xy 70.273072 -287.775872) (xy 70.284849 -287.728088) (xy 70.30414 -287.682812) (xy 70.330443 -287.641216)
			(xy 70.363078 -287.604379) (xy 70.401199 -287.573254) (xy 70.44382 -287.548647) (xy 70.489836 -287.531195)
			(xy 70.538055 -287.521351) (xy 70.58723 -287.51937) (xy 70.636085 -287.525302) (xy 70.683356 -287.538994)
			(xy 70.727818 -287.560092) (xy 70.768321 -287.588048) (xy 70.803814 -287.62214) (xy 70.833379 -287.661484)
			(xy 70.85625 -287.705061) (xy 70.871834 -287.751742) (xy 70.879729 -287.800319) (xy 70.880224 -287.824926)
			(xy 70.879729 -287.849533) (xy 70.871834 -287.89811) (xy 70.85625 -287.944791) (xy 70.833379 -287.988368)
			(xy 70.803814 -288.027712) (xy 70.768321 -288.061804) (xy 70.727818 -288.08976) (xy 70.683356 -288.110858)
			(xy 70.636085 -288.12455) (xy 70.58723 -288.130482) (xy 70.538055 -288.128501) (xy 70.489836 -288.118657)
			(xy 70.44382 -288.101205) (xy 70.401199 -288.076598) (xy 70.363078 -288.045473) (xy 70.330443 -288.008636)
			(xy 70.30414 -287.96704) (xy 70.284849 -287.921764) (xy 70.273072 -287.87398) (xy 70.269112 -287.824926)
			(xy 68.98005 -287.824926) (xy 68.979593 -287.848721) (xy 68.972205 -287.895735) (xy 68.957614 -287.941033)
			(xy 68.936171 -287.98352) (xy 68.908396 -288.022165) (xy 68.874962 -288.056032) (xy 68.856098 -288.070544)
			(xy 68.851577 -288.074072) (xy 68.844143 -288.082799) (xy 68.841366 -288.087816) (xy 68.82511 -288.118804)
			(xy 68.825643 -288.130338) (xy 68.835701 -288.151097) (xy 68.853832 -288.165358) (xy 68.864988 -288.168334)
			(xy 68.886064 -288.158064) (xy 68.930521 -288.143183) (xy 68.976693 -288.135058) (xy 69.000116 -288.134044)
			(xy 69.992748 -288.134044) (xy 70.017539 -288.134502) (xy 70.06651 -288.142258) (xy 70.113662 -288.157586)
			(xy 70.157833 -288.180108) (xy 70.197932 -288.209268) (xy 70.21576 -288.2265) (xy 70.289166 -288.299906)
			(xy 73.593972 -288.299906) (xy 73.597932 -288.250852) (xy 73.609709 -288.203068) (xy 73.629 -288.157792)
			(xy 73.655303 -288.116196) (xy 73.687938 -288.079359) (xy 73.726059 -288.048234) (xy 73.76868 -288.023627)
			(xy 73.814696 -288.006175) (xy 73.862915 -287.996331) (xy 73.91209 -287.99435) (xy 73.960945 -288.000282)
			(xy 74.008216 -288.013974) (xy 74.052678 -288.035072) (xy 74.093181 -288.063028) (xy 74.128674 -288.09712)
			(xy 74.158239 -288.136464) (xy 74.18111 -288.180041) (xy 74.196694 -288.226722) (xy 74.204589 -288.275299)
			(xy 74.205084 -288.299906) (xy 74.544186 -288.299906) (xy 74.548146 -288.250852) (xy 74.559923 -288.203068)
			(xy 74.579214 -288.157792) (xy 74.605517 -288.116196) (xy 74.638152 -288.079359) (xy 74.676273 -288.048234)
			(xy 74.718894 -288.023627) (xy 74.76491 -288.006175) (xy 74.813129 -287.996331) (xy 74.862304 -287.99435)
			(xy 74.911159 -288.000282) (xy 74.95843 -288.013974) (xy 75.002892 -288.035072) (xy 75.043395 -288.063028)
			(xy 75.078888 -288.09712) (xy 75.108453 -288.136464) (xy 75.131324 -288.180041) (xy 75.146908 -288.226722)
			(xy 75.154803 -288.275299) (xy 75.155298 -288.299906) (xy 75.494146 -288.299906) (xy 75.498106 -288.250852)
			(xy 75.509883 -288.203068) (xy 75.529174 -288.157792) (xy 75.555477 -288.116196) (xy 75.588112 -288.079359)
			(xy 75.626233 -288.048234) (xy 75.668854 -288.023627) (xy 75.71487 -288.006175) (xy 75.763089 -287.996331)
			(xy 75.812264 -287.99435) (xy 75.861119 -288.000282) (xy 75.90839 -288.013974) (xy 75.952852 -288.035072)
			(xy 75.993355 -288.063028) (xy 76.028848 -288.09712) (xy 76.058413 -288.136464) (xy 76.081284 -288.180041)
			(xy 76.096868 -288.226722) (xy 76.104763 -288.275299) (xy 76.105258 -288.299906) (xy 76.104763 -288.324513)
			(xy 76.096868 -288.37309) (xy 76.081284 -288.419771) (xy 76.058413 -288.463348) (xy 76.028848 -288.502692)
			(xy 75.993355 -288.536784) (xy 75.952852 -288.56474) (xy 75.90839 -288.585838) (xy 75.861119 -288.59953)
			(xy 75.812264 -288.605462) (xy 75.763089 -288.603481) (xy 75.71487 -288.593637) (xy 75.668854 -288.576185)
			(xy 75.626233 -288.551578) (xy 75.588112 -288.520453) (xy 75.555477 -288.483616) (xy 75.529174 -288.44202)
			(xy 75.509883 -288.396744) (xy 75.498106 -288.34896) (xy 75.494146 -288.299906) (xy 75.155298 -288.299906)
			(xy 75.154803 -288.324513) (xy 75.146908 -288.37309) (xy 75.131324 -288.419771) (xy 75.108453 -288.463348)
			(xy 75.078888 -288.502692) (xy 75.043395 -288.536784) (xy 75.002892 -288.56474) (xy 74.95843 -288.585838)
			(xy 74.911159 -288.59953) (xy 74.862304 -288.605462) (xy 74.813129 -288.603481) (xy 74.76491 -288.593637)
			(xy 74.718894 -288.576185) (xy 74.676273 -288.551578) (xy 74.638152 -288.520453) (xy 74.605517 -288.483616)
			(xy 74.579214 -288.44202) (xy 74.559923 -288.396744) (xy 74.548146 -288.34896) (xy 74.544186 -288.299906)
			(xy 74.205084 -288.299906) (xy 74.204589 -288.324513) (xy 74.196694 -288.37309) (xy 74.18111 -288.419771)
			(xy 74.158239 -288.463348) (xy 74.128674 -288.502692) (xy 74.093181 -288.536784) (xy 74.052678 -288.56474)
			(xy 74.008216 -288.585838) (xy 73.960945 -288.59953) (xy 73.91209 -288.605462) (xy 73.862915 -288.603481)
			(xy 73.814696 -288.593637) (xy 73.76868 -288.576185) (xy 73.726059 -288.551578) (xy 73.687938 -288.520453)
			(xy 73.655303 -288.483616) (xy 73.629 -288.44202) (xy 73.609709 -288.396744) (xy 73.597932 -288.34896)
			(xy 73.593972 -288.299906) (xy 70.289166 -288.299906) (xy 70.431914 -288.442654) (xy 70.449694 -288.462212)
			(xy 70.456119 -288.469226) (xy 70.472825 -288.478295) (xy 70.491686 -288.480652) (xy 70.501002 -288.478722)
			(xy 70.51912 -288.474469) (xy 70.556054 -288.46988) (xy 70.574662 -288.469578) (xy 70.574916 -288.469578)
			(xy 70.598907 -288.47005) (xy 70.646297 -288.477558) (xy 70.69193 -288.492386) (xy 70.734682 -288.514171)
			(xy 70.773499 -288.542374) (xy 70.807427 -288.576302) (xy 70.83563 -288.61512) (xy 70.857414 -288.657872)
			(xy 70.872243 -288.703505) (xy 70.87975 -288.750895) (xy 70.880224 -288.774886) (xy 71.219072 -288.774886)
			(xy 71.223032 -288.725832) (xy 71.234809 -288.678048) (xy 71.2541 -288.632772) (xy 71.280403 -288.591176)
			(xy 71.313038 -288.554339) (xy 71.351159 -288.523214) (xy 71.39378 -288.498607) (xy 71.439796 -288.481155)
			(xy 71.488015 -288.471311) (xy 71.53719 -288.46933) (xy 71.586045 -288.475262) (xy 71.633316 -288.488954)
			(xy 71.677778 -288.510052) (xy 71.718281 -288.538008) (xy 71.753774 -288.5721) (xy 71.783339 -288.611444)
			(xy 71.80621 -288.655021) (xy 71.821794 -288.701702) (xy 71.829689 -288.750279) (xy 71.830184 -288.774886)
			(xy 72.169032 -288.774886) (xy 72.172992 -288.725832) (xy 72.184769 -288.678048) (xy 72.20406 -288.632772)
			(xy 72.230363 -288.591176) (xy 72.262998 -288.554339) (xy 72.301119 -288.523214) (xy 72.34374 -288.498607)
			(xy 72.389756 -288.481155) (xy 72.437975 -288.471311) (xy 72.48715 -288.46933) (xy 72.536005 -288.475262)
			(xy 72.583276 -288.488954) (xy 72.627738 -288.510052) (xy 72.668241 -288.538008) (xy 72.703734 -288.5721)
			(xy 72.733299 -288.611444) (xy 72.75617 -288.655021) (xy 72.771754 -288.701702) (xy 72.779649 -288.750279)
			(xy 72.780144 -288.774886) (xy 72.779649 -288.799493) (xy 72.771754 -288.84807) (xy 72.75617 -288.894751)
			(xy 72.733299 -288.938328) (xy 72.703734 -288.977672) (xy 72.668241 -289.011764) (xy 72.627738 -289.03972)
			(xy 72.583276 -289.060818) (xy 72.536005 -289.07451) (xy 72.48715 -289.080442) (xy 72.437975 -289.078461)
			(xy 72.389756 -289.068617) (xy 72.34374 -289.051165) (xy 72.301119 -289.026558) (xy 72.262998 -288.995433)
			(xy 72.230363 -288.958596) (xy 72.20406 -288.917) (xy 72.184769 -288.871724) (xy 72.172992 -288.82394)
			(xy 72.169032 -288.774886) (xy 71.830184 -288.774886) (xy 71.829689 -288.799493) (xy 71.821794 -288.84807)
			(xy 71.80621 -288.894751) (xy 71.783339 -288.938328) (xy 71.753774 -288.977672) (xy 71.718281 -289.011764)
			(xy 71.677778 -289.03972) (xy 71.633316 -289.060818) (xy 71.586045 -289.07451) (xy 71.53719 -289.080442)
			(xy 71.488015 -289.078461) (xy 71.439796 -289.068617) (xy 71.39378 -289.051165) (xy 71.351159 -289.026558)
			(xy 71.313038 -288.995433) (xy 71.280403 -288.958596) (xy 71.2541 -288.917) (xy 71.234809 -288.871724)
			(xy 71.223032 -288.82394) (xy 71.219072 -288.774886) (xy 70.880224 -288.774886) (xy 70.879749 -288.799607)
			(xy 70.871789 -288.848405) (xy 70.856077 -288.895284) (xy 70.83302 -288.939021) (xy 70.818502 -288.959036)
			(xy 70.796912 -288.987484) (xy 70.807072 -289.005264) (xy 70.814184 -289.015424) (xy 70.821296 -289.023298)
			(xy 70.827102 -289.03051) (xy 70.833609 -289.047829) (xy 70.833996 -289.05708) (xy 70.833996 -289.068256)
			(xy 70.83552 -289.080194) (xy 70.839582 -289.098337) (xy 70.843908 -289.135264) (xy 70.844156 -289.153854)
			(xy 70.844156 -289.345878) (xy 70.843897 -289.364467) (xy 70.839563 -289.401392) (xy 70.83552 -289.419538)
			(xy 70.833996 -289.431476) (xy 70.833996 -289.442652) (xy 70.833647 -289.451911) (xy 70.827137 -289.469242)
			(xy 70.821296 -289.476434) (xy 70.814184 -289.484308) (xy 70.807072 -289.494468) (xy 70.796912 -289.512248)
			(xy 70.818502 -289.540696) (xy 70.833018 -289.56071) (xy 70.856069 -289.604446) (xy 70.871777 -289.651323)
			(xy 70.879732 -289.700117) (xy 70.879729 -289.724846) (xy 71.219072 -289.724846) (xy 71.223032 -289.675792)
			(xy 71.234809 -289.628008) (xy 71.2541 -289.582732) (xy 71.280403 -289.541136) (xy 71.313038 -289.504299)
			(xy 71.351159 -289.473174) (xy 71.39378 -289.448567) (xy 71.439796 -289.431115) (xy 71.488015 -289.421271)
			(xy 71.53719 -289.41929) (xy 71.586045 -289.425222) (xy 71.633316 -289.438914) (xy 71.677778 -289.460012)
			(xy 71.718281 -289.487968) (xy 71.753774 -289.52206) (xy 71.783339 -289.561404) (xy 71.80621 -289.604981)
			(xy 71.821794 -289.651662) (xy 71.829689 -289.700239) (xy 71.830184 -289.724846) (xy 72.169032 -289.724846)
			(xy 72.172992 -289.675792) (xy 72.184769 -289.628008) (xy 72.20406 -289.582732) (xy 72.230363 -289.541136)
			(xy 72.262998 -289.504299) (xy 72.301119 -289.473174) (xy 72.34374 -289.448567) (xy 72.389756 -289.431115)
			(xy 72.437975 -289.421271) (xy 72.48715 -289.41929) (xy 72.536005 -289.425222) (xy 72.583276 -289.438914)
			(xy 72.627738 -289.460012) (xy 72.668241 -289.487968) (xy 72.703734 -289.52206) (xy 72.733299 -289.561404)
			(xy 72.75617 -289.604981) (xy 72.771754 -289.651662) (xy 72.779649 -289.700239) (xy 72.779976 -289.716507)
			(xy 73.119127 -289.716507) (xy 73.124496 -289.667166) (xy 73.137775 -289.619343) (xy 73.158617 -289.574298)
			(xy 73.186471 -289.533218) (xy 73.220603 -289.497186) (xy 73.260116 -289.46715) (xy 73.303967 -289.443902)
			(xy 73.351001 -289.428054) (xy 73.39998 -289.420024) (xy 73.424796 -289.419538) (xy 73.438979 -289.419714)
			(xy 73.467219 -289.422387) (xy 73.481184 -289.424872) (xy 73.49363 -289.427158) (xy 73.517252 -289.419792)
			(xy 73.594722 -289.342322) (xy 73.602088 -289.3187) (xy 73.599802 -289.306254) (xy 73.597323 -289.292289)
			(xy 73.594653 -289.264049) (xy 73.594468 -289.249866) (xy 73.59499 -289.224611) (xy 73.603303 -289.174789)
			(xy 73.619704 -289.127015) (xy 73.643745 -289.082592) (xy 73.674769 -289.042732) (xy 73.711931 -289.008522)
			(xy 73.754217 -288.980896) (xy 73.800473 -288.960606) (xy 73.849438 -288.948206) (xy 73.899776 -288.944035)
			(xy 73.950114 -288.948206) (xy 73.999079 -288.960606) (xy 74.045335 -288.980896) (xy 74.087621 -289.008522)
			(xy 74.124783 -289.042732) (xy 74.155807 -289.082592) (xy 74.179848 -289.127015) (xy 74.196249 -289.174789)
			(xy 74.204562 -289.224611) (xy 74.205084 -289.249866) (xy 74.204903 -289.264049) (xy 74.202234 -289.292289)
			(xy 74.19975 -289.306254) (xy 74.19975 -289.306508) (xy 74.198288 -289.318739) (xy 74.205575 -289.342226)
			(xy 74.21372 -289.351466) (xy 74.2823 -289.419792) (xy 74.305922 -289.427158) (xy 74.318368 -289.424872)
			(xy 74.332396 -289.42238) (xy 74.360764 -289.419713) (xy 74.37501 -289.419538) (xy 74.399829 -289.419989)
			(xy 74.448813 -289.42802) (xy 74.495853 -289.443871) (xy 74.539708 -289.467122) (xy 74.579225 -289.497162)
			(xy 74.613361 -289.5332) (xy 74.641217 -289.574284) (xy 74.66206 -289.619335) (xy 74.675341 -289.667163)
			(xy 74.680709 -289.71651) (xy 74.680257 -289.724846) (xy 75.969126 -289.724846) (xy 75.973086 -289.675792)
			(xy 75.984863 -289.628008) (xy 76.004154 -289.582732) (xy 76.030457 -289.541136) (xy 76.063092 -289.504299)
			(xy 76.101213 -289.473174) (xy 76.143834 -289.448567) (xy 76.18985 -289.431115) (xy 76.238069 -289.421271)
			(xy 76.287244 -289.41929) (xy 76.336099 -289.425222) (xy 76.38337 -289.438914) (xy 76.427832 -289.460012)
			(xy 76.468335 -289.487968) (xy 76.503828 -289.52206) (xy 76.533393 -289.561404) (xy 76.556264 -289.604981)
			(xy 76.571848 -289.651662) (xy 76.579743 -289.700239) (xy 76.580238 -289.724846) (xy 76.919086 -289.724846)
			(xy 76.923046 -289.675792) (xy 76.934823 -289.628008) (xy 76.954114 -289.582732) (xy 76.980417 -289.541136)
			(xy 77.013052 -289.504299) (xy 77.051173 -289.473174) (xy 77.093794 -289.448567) (xy 77.13981 -289.431115)
			(xy 77.188029 -289.421271) (xy 77.237204 -289.41929) (xy 77.286059 -289.425222) (xy 77.33333 -289.438914)
			(xy 77.377792 -289.460012) (xy 77.418295 -289.487968) (xy 77.453788 -289.52206) (xy 77.483353 -289.561404)
			(xy 77.506224 -289.604981) (xy 77.521808 -289.651662) (xy 77.529703 -289.700239) (xy 77.530198 -289.724846)
			(xy 77.869046 -289.724846) (xy 77.873006 -289.675792) (xy 77.884783 -289.628008) (xy 77.904074 -289.582732)
			(xy 77.930377 -289.541136) (xy 77.963012 -289.504299) (xy 78.001133 -289.473174) (xy 78.043754 -289.448567)
			(xy 78.08977 -289.431115) (xy 78.137989 -289.421271) (xy 78.187164 -289.41929) (xy 78.236019 -289.425222)
			(xy 78.28329 -289.438914) (xy 78.327752 -289.460012) (xy 78.368255 -289.487968) (xy 78.403748 -289.52206)
			(xy 78.433313 -289.561404) (xy 78.456184 -289.604981) (xy 78.471768 -289.651662) (xy 78.479663 -289.700239)
			(xy 78.480158 -289.724846) (xy 78.819006 -289.724846) (xy 78.822966 -289.675792) (xy 78.834743 -289.628008)
			(xy 78.854034 -289.582732) (xy 78.880337 -289.541136) (xy 78.912972 -289.504299) (xy 78.951093 -289.473174)
			(xy 78.993714 -289.448567) (xy 79.03973 -289.431115) (xy 79.087949 -289.421271) (xy 79.137124 -289.41929)
			(xy 79.185979 -289.425222) (xy 79.23325 -289.438914) (xy 79.277712 -289.460012) (xy 79.318215 -289.487968)
			(xy 79.353708 -289.52206) (xy 79.383273 -289.561404) (xy 79.406144 -289.604981) (xy 79.421728 -289.651662)
			(xy 79.429623 -289.700239) (xy 79.430118 -289.724846) (xy 79.768966 -289.724846) (xy 79.772926 -289.675792)
			(xy 79.784703 -289.628008) (xy 79.803994 -289.582732) (xy 79.830297 -289.541136) (xy 79.862932 -289.504299)
			(xy 79.901053 -289.473174) (xy 79.943674 -289.448567) (xy 79.98969 -289.431115) (xy 80.037909 -289.421271)
			(xy 80.087084 -289.41929) (xy 80.135939 -289.425222) (xy 80.18321 -289.438914) (xy 80.227672 -289.460012)
			(xy 80.268175 -289.487968) (xy 80.303668 -289.52206) (xy 80.333233 -289.561404) (xy 80.356104 -289.604981)
			(xy 80.371688 -289.651662) (xy 80.379583 -289.700239) (xy 80.380078 -289.724846) (xy 80.71918 -289.724846)
			(xy 80.72314 -289.675792) (xy 80.734917 -289.628008) (xy 80.754208 -289.582732) (xy 80.780511 -289.541136)
			(xy 80.813146 -289.504299) (xy 80.851267 -289.473174) (xy 80.893888 -289.448567) (xy 80.939904 -289.431115)
			(xy 80.988123 -289.421271) (xy 81.037298 -289.41929) (xy 81.086153 -289.425222) (xy 81.133424 -289.438914)
			(xy 81.177886 -289.460012) (xy 81.218389 -289.487968) (xy 81.253882 -289.52206) (xy 81.283447 -289.561404)
			(xy 81.306318 -289.604981) (xy 81.321902 -289.651662) (xy 81.329797 -289.700239) (xy 81.330292 -289.724846)
			(xy 81.66914 -289.724846) (xy 81.6731 -289.675792) (xy 81.684877 -289.628008) (xy 81.704168 -289.582732)
			(xy 81.730471 -289.541136) (xy 81.763106 -289.504299) (xy 81.801227 -289.473174) (xy 81.843848 -289.448567)
			(xy 81.889864 -289.431115) (xy 81.938083 -289.421271) (xy 81.987258 -289.41929) (xy 82.036113 -289.425222)
			(xy 82.083384 -289.438914) (xy 82.127846 -289.460012) (xy 82.168349 -289.487968) (xy 82.203842 -289.52206)
			(xy 82.233407 -289.561404) (xy 82.256278 -289.604981) (xy 82.271862 -289.651662) (xy 82.279757 -289.700239)
			(xy 82.280252 -289.724846) (xy 82.279757 -289.749453) (xy 82.271862 -289.79803) (xy 82.256278 -289.844711)
			(xy 82.233407 -289.888288) (xy 82.203842 -289.927632) (xy 82.168349 -289.961724) (xy 82.127846 -289.98968)
			(xy 82.083384 -290.010778) (xy 82.036113 -290.02447) (xy 81.987258 -290.030402) (xy 81.938083 -290.028421)
			(xy 81.889864 -290.018577) (xy 81.843848 -290.001125) (xy 81.801227 -289.976518) (xy 81.763106 -289.945393)
			(xy 81.730471 -289.908556) (xy 81.704168 -289.86696) (xy 81.684877 -289.821684) (xy 81.6731 -289.7739)
			(xy 81.66914 -289.724846) (xy 81.330292 -289.724846) (xy 81.329797 -289.749453) (xy 81.321902 -289.79803)
			(xy 81.306318 -289.844711) (xy 81.283447 -289.888288) (xy 81.253882 -289.927632) (xy 81.218389 -289.961724)
			(xy 81.177886 -289.98968) (xy 81.133424 -290.010778) (xy 81.086153 -290.02447) (xy 81.037298 -290.030402)
			(xy 80.988123 -290.028421) (xy 80.939904 -290.018577) (xy 80.893888 -290.001125) (xy 80.851267 -289.976518)
			(xy 80.813146 -289.945393) (xy 80.780511 -289.908556) (xy 80.754208 -289.86696) (xy 80.734917 -289.821684)
			(xy 80.72314 -289.7739) (xy 80.71918 -289.724846) (xy 80.380078 -289.724846) (xy 80.379583 -289.749453)
			(xy 80.371688 -289.79803) (xy 80.356104 -289.844711) (xy 80.333233 -289.888288) (xy 80.303668 -289.927632)
			(xy 80.268175 -289.961724) (xy 80.227672 -289.98968) (xy 80.18321 -290.010778) (xy 80.135939 -290.02447)
			(xy 80.087084 -290.030402) (xy 80.037909 -290.028421) (xy 79.98969 -290.018577) (xy 79.943674 -290.001125)
			(xy 79.901053 -289.976518) (xy 79.862932 -289.945393) (xy 79.830297 -289.908556) (xy 79.803994 -289.86696)
			(xy 79.784703 -289.821684) (xy 79.772926 -289.7739) (xy 79.768966 -289.724846) (xy 79.430118 -289.724846)
			(xy 79.429623 -289.749453) (xy 79.421728 -289.79803) (xy 79.406144 -289.844711) (xy 79.383273 -289.888288)
			(xy 79.353708 -289.927632) (xy 79.318215 -289.961724) (xy 79.277712 -289.98968) (xy 79.23325 -290.010778)
			(xy 79.185979 -290.02447) (xy 79.137124 -290.030402) (xy 79.087949 -290.028421) (xy 79.03973 -290.018577)
			(xy 78.993714 -290.001125) (xy 78.951093 -289.976518) (xy 78.912972 -289.945393) (xy 78.880337 -289.908556)
			(xy 78.854034 -289.86696) (xy 78.834743 -289.821684) (xy 78.822966 -289.7739) (xy 78.819006 -289.724846)
			(xy 78.480158 -289.724846) (xy 78.479663 -289.749453) (xy 78.471768 -289.79803) (xy 78.456184 -289.844711)
			(xy 78.433313 -289.888288) (xy 78.403748 -289.927632) (xy 78.368255 -289.961724) (xy 78.327752 -289.98968)
			(xy 78.28329 -290.010778) (xy 78.236019 -290.02447) (xy 78.187164 -290.030402) (xy 78.137989 -290.028421)
			(xy 78.08977 -290.018577) (xy 78.043754 -290.001125) (xy 78.001133 -289.976518) (xy 77.963012 -289.945393)
			(xy 77.930377 -289.908556) (xy 77.904074 -289.86696) (xy 77.884783 -289.821684) (xy 77.873006 -289.7739)
			(xy 77.869046 -289.724846) (xy 77.530198 -289.724846) (xy 77.529703 -289.749453) (xy 77.521808 -289.79803)
			(xy 77.506224 -289.844711) (xy 77.483353 -289.888288) (xy 77.453788 -289.927632) (xy 77.418295 -289.961724)
			(xy 77.377792 -289.98968) (xy 77.33333 -290.010778) (xy 77.286059 -290.02447) (xy 77.237204 -290.030402)
			(xy 77.188029 -290.028421) (xy 77.13981 -290.018577) (xy 77.093794 -290.001125) (xy 77.051173 -289.976518)
			(xy 77.013052 -289.945393) (xy 76.980417 -289.908556) (xy 76.954114 -289.86696) (xy 76.934823 -289.821684)
			(xy 76.923046 -289.7739) (xy 76.919086 -289.724846) (xy 76.580238 -289.724846) (xy 76.579743 -289.749453)
			(xy 76.571848 -289.79803) (xy 76.556264 -289.844711) (xy 76.533393 -289.888288) (xy 76.503828 -289.927632)
			(xy 76.468335 -289.961724) (xy 76.427832 -289.98968) (xy 76.38337 -290.010778) (xy 76.336099 -290.02447)
			(xy 76.287244 -290.030402) (xy 76.238069 -290.028421) (xy 76.18985 -290.018577) (xy 76.143834 -290.001125)
			(xy 76.101213 -289.976518) (xy 76.063092 -289.945393) (xy 76.030457 -289.908556) (xy 76.004154 -289.86696)
			(xy 75.984863 -289.821684) (xy 75.973086 -289.7739) (xy 75.969126 -289.724846) (xy 74.680257 -289.724846)
			(xy 74.678023 -289.766076) (xy 74.667354 -289.814554) (xy 74.648983 -289.860667) (xy 74.623394 -289.903201)
			(xy 74.591261 -289.941035) (xy 74.553431 -289.973173) (xy 74.510899 -289.998767) (xy 74.464788 -290.017143)
			(xy 74.416311 -290.027818) (xy 74.366746 -290.03051) (xy 74.317399 -290.025147) (xy 74.269568 -290.011873)
			(xy 74.224516 -289.991035) (xy 74.183428 -289.963183) (xy 74.147387 -289.929051) (xy 74.117342 -289.889539)
			(xy 74.094085 -289.845686) (xy 74.078229 -289.798648) (xy 74.070192 -289.749665) (xy 74.069702 -289.724846)
			(xy 74.069885 -289.710663) (xy 74.072553 -289.682423) (xy 74.075036 -289.668458) (xy 74.075036 -289.668204)
			(xy 74.076466 -289.655972) (xy 74.069197 -289.632491) (xy 74.061066 -289.623246) (xy 73.992486 -289.55492)
			(xy 73.968864 -289.547554) (xy 73.956418 -289.54984) (xy 73.942388 -289.55232) (xy 73.914022 -289.554995)
			(xy 73.899776 -289.555174) (xy 73.885593 -289.555001) (xy 73.857353 -289.552327) (xy 73.843388 -289.54984)
			(xy 73.830942 -289.547554) (xy 73.80732 -289.55492) (xy 73.72985 -289.63239) (xy 73.722484 -289.656012)
			(xy 73.72477 -289.668458) (xy 73.72725 -289.682423) (xy 73.72992 -289.710663) (xy 73.730104 -289.724846)
			(xy 73.729573 -289.749662) (xy 73.721536 -289.79864) (xy 73.705682 -289.845672) (xy 73.682427 -289.88952)
			(xy 73.652386 -289.929028) (xy 73.616349 -289.963156) (xy 73.575265 -289.991004) (xy 73.530218 -290.011839)
			(xy 73.482393 -290.025112) (xy 73.433051 -290.030474) (xy 73.383491 -290.027782) (xy 73.33502 -290.017108)
			(xy 73.288914 -289.998733) (xy 73.246388 -289.973142) (xy 73.208562 -289.941008) (xy 73.176434 -289.903178)
			(xy 73.150848 -289.860648) (xy 73.13248 -289.81454) (xy 73.121812 -289.766067) (xy 73.119127 -289.716507)
			(xy 72.779976 -289.716507) (xy 72.780144 -289.724846) (xy 72.779649 -289.749453) (xy 72.771754 -289.79803)
			(xy 72.75617 -289.844711) (xy 72.733299 -289.888288) (xy 72.703734 -289.927632) (xy 72.668241 -289.961724)
			(xy 72.627738 -289.98968) (xy 72.583276 -290.010778) (xy 72.536005 -290.02447) (xy 72.48715 -290.030402)
			(xy 72.437975 -290.028421) (xy 72.389756 -290.018577) (xy 72.34374 -290.001125) (xy 72.301119 -289.976518)
			(xy 72.262998 -289.945393) (xy 72.230363 -289.908556) (xy 72.20406 -289.86696) (xy 72.184769 -289.821684)
			(xy 72.172992 -289.7739) (xy 72.169032 -289.724846) (xy 71.830184 -289.724846) (xy 71.829689 -289.749453)
			(xy 71.821794 -289.79803) (xy 71.80621 -289.844711) (xy 71.783339 -289.888288) (xy 71.753774 -289.927632)
			(xy 71.718281 -289.961724) (xy 71.677778 -289.98968) (xy 71.633316 -290.010778) (xy 71.586045 -290.02447)
			(xy 71.53719 -290.030402) (xy 71.488015 -290.028421) (xy 71.439796 -290.018577) (xy 71.39378 -290.001125)
			(xy 71.351159 -289.976518) (xy 71.313038 -289.945393) (xy 71.280403 -289.908556) (xy 71.2541 -289.86696)
			(xy 71.234809 -289.821684) (xy 71.223032 -289.7739) (xy 71.219072 -289.724846) (xy 70.879729 -289.724846)
			(xy 70.879726 -289.749556) (xy 70.87176 -289.798349) (xy 70.85604 -289.845222) (xy 70.832979 -289.888952)
			(xy 70.818502 -289.908996) (xy 70.796912 -289.937444) (xy 70.807072 -289.955224) (xy 70.814184 -289.965384)
			(xy 70.821296 -289.973258) (xy 70.827107 -289.980469) (xy 70.833628 -289.997787) (xy 70.833996 -290.00704)
			(xy 70.833996 -290.018216) (xy 70.83552 -290.030154) (xy 70.839584 -290.048296) (xy 70.843915 -290.085223)
			(xy 70.844156 -290.103814) (xy 70.844156 -290.295838) (xy 70.8439 -290.314427) (xy 70.83957 -290.351353)
			(xy 70.83552 -290.369498) (xy 70.833996 -290.381436) (xy 70.833996 -290.392612) (xy 70.833636 -290.401867)
			(xy 70.827111 -290.419183) (xy 70.821296 -290.426394) (xy 70.814184 -290.434268) (xy 70.807072 -290.444428)
			(xy 70.796912 -290.462208) (xy 70.818502 -290.490656) (xy 70.833021 -290.51067) (xy 70.856079 -290.554407)
			(xy 70.871793 -290.601286) (xy 70.879754 -290.650083) (xy 70.879753 -290.674806) (xy 71.219072 -290.674806)
			(xy 71.223032 -290.625752) (xy 71.234809 -290.577968) (xy 71.2541 -290.532692) (xy 71.280403 -290.491096)
			(xy 71.313038 -290.454259) (xy 71.351159 -290.423134) (xy 71.39378 -290.398527) (xy 71.439796 -290.381075)
			(xy 71.488015 -290.371231) (xy 71.53719 -290.36925) (xy 71.586045 -290.375182) (xy 71.633316 -290.388874)
			(xy 71.677778 -290.409972) (xy 71.718281 -290.437928) (xy 71.753774 -290.47202) (xy 71.783339 -290.511364)
			(xy 71.80621 -290.554941) (xy 71.821794 -290.601622) (xy 71.829689 -290.650199) (xy 71.830184 -290.674806)
			(xy 72.169032 -290.674806) (xy 72.172992 -290.625752) (xy 72.184769 -290.577968) (xy 72.20406 -290.532692)
			(xy 72.230363 -290.491096) (xy 72.262998 -290.454259) (xy 72.301119 -290.423134) (xy 72.34374 -290.398527)
			(xy 72.389756 -290.381075) (xy 72.437975 -290.371231) (xy 72.48715 -290.36925) (xy 72.536005 -290.375182)
			(xy 72.583276 -290.388874) (xy 72.627738 -290.409972) (xy 72.668241 -290.437928) (xy 72.703734 -290.47202)
			(xy 72.733299 -290.511364) (xy 72.75617 -290.554941) (xy 72.771754 -290.601622) (xy 72.779649 -290.650199)
			(xy 72.780144 -290.674806) (xy 73.118992 -290.674806) (xy 73.122952 -290.625752) (xy 73.134729 -290.577968)
			(xy 73.15402 -290.532692) (xy 73.180323 -290.491096) (xy 73.212958 -290.454259) (xy 73.251079 -290.423134)
			(xy 73.2937 -290.398527) (xy 73.339716 -290.381075) (xy 73.387935 -290.371231) (xy 73.43711 -290.36925)
			(xy 73.485965 -290.375182) (xy 73.533236 -290.388874) (xy 73.577698 -290.409972) (xy 73.618201 -290.437928)
			(xy 73.653694 -290.47202) (xy 73.683259 -290.511364) (xy 73.70613 -290.554941) (xy 73.721714 -290.601622)
			(xy 73.729609 -290.650199) (xy 73.730104 -290.674806) (xy 74.068952 -290.674806) (xy 74.072912 -290.625752)
			(xy 74.084689 -290.577968) (xy 74.10398 -290.532692) (xy 74.130283 -290.491096) (xy 74.162918 -290.454259)
			(xy 74.201039 -290.423134) (xy 74.24366 -290.398527) (xy 74.289676 -290.381075) (xy 74.337895 -290.371231)
			(xy 74.38707 -290.36925) (xy 74.435925 -290.375182) (xy 74.483196 -290.388874) (xy 74.527658 -290.409972)
			(xy 74.568161 -290.437928) (xy 74.603654 -290.47202) (xy 74.633219 -290.511364) (xy 74.65609 -290.554941)
			(xy 74.671674 -290.601622) (xy 74.679569 -290.650199) (xy 74.680064 -290.674806) (xy 75.019166 -290.674806)
			(xy 75.023126 -290.625752) (xy 75.034903 -290.577968) (xy 75.054194 -290.532692) (xy 75.080497 -290.491096)
			(xy 75.113132 -290.454259) (xy 75.151253 -290.423134) (xy 75.193874 -290.398527) (xy 75.23989 -290.381075)
			(xy 75.288109 -290.371231) (xy 75.337284 -290.36925) (xy 75.386139 -290.375182) (xy 75.43341 -290.388874)
			(xy 75.477872 -290.409972) (xy 75.518375 -290.437928) (xy 75.553868 -290.47202) (xy 75.583433 -290.511364)
			(xy 75.606304 -290.554941) (xy 75.621888 -290.601622) (xy 75.629783 -290.650199) (xy 75.630278 -290.674806)
			(xy 75.969126 -290.674806) (xy 75.973086 -290.625752) (xy 75.984863 -290.577968) (xy 76.004154 -290.532692)
			(xy 76.030457 -290.491096) (xy 76.063092 -290.454259) (xy 76.101213 -290.423134) (xy 76.143834 -290.398527)
			(xy 76.18985 -290.381075) (xy 76.238069 -290.371231) (xy 76.287244 -290.36925) (xy 76.336099 -290.375182)
			(xy 76.38337 -290.388874) (xy 76.427832 -290.409972) (xy 76.468335 -290.437928) (xy 76.503828 -290.47202)
			(xy 76.533393 -290.511364) (xy 76.556264 -290.554941) (xy 76.571848 -290.601622) (xy 76.579743 -290.650199)
			(xy 76.580238 -290.674806) (xy 76.919086 -290.674806) (xy 76.923046 -290.625752) (xy 76.934823 -290.577968)
			(xy 76.954114 -290.532692) (xy 76.980417 -290.491096) (xy 77.013052 -290.454259) (xy 77.051173 -290.423134)
			(xy 77.093794 -290.398527) (xy 77.13981 -290.381075) (xy 77.188029 -290.371231) (xy 77.237204 -290.36925)
			(xy 77.286059 -290.375182) (xy 77.33333 -290.388874) (xy 77.377792 -290.409972) (xy 77.418295 -290.437928)
			(xy 77.453788 -290.47202) (xy 77.483353 -290.511364) (xy 77.506224 -290.554941) (xy 77.521808 -290.601622)
			(xy 77.529703 -290.650199) (xy 77.530198 -290.674806) (xy 77.869046 -290.674806) (xy 77.873006 -290.625752)
			(xy 77.884783 -290.577968) (xy 77.904074 -290.532692) (xy 77.930377 -290.491096) (xy 77.963012 -290.454259)
			(xy 78.001133 -290.423134) (xy 78.043754 -290.398527) (xy 78.08977 -290.381075) (xy 78.137989 -290.371231)
			(xy 78.187164 -290.36925) (xy 78.236019 -290.375182) (xy 78.28329 -290.388874) (xy 78.327752 -290.409972)
			(xy 78.368255 -290.437928) (xy 78.403748 -290.47202) (xy 78.433313 -290.511364) (xy 78.456184 -290.554941)
			(xy 78.471768 -290.601622) (xy 78.479663 -290.650199) (xy 78.480158 -290.674806) (xy 78.819006 -290.674806)
			(xy 78.822966 -290.625752) (xy 78.834743 -290.577968) (xy 78.854034 -290.532692) (xy 78.880337 -290.491096)
			(xy 78.912972 -290.454259) (xy 78.951093 -290.423134) (xy 78.993714 -290.398527) (xy 79.03973 -290.381075)
			(xy 79.087949 -290.371231) (xy 79.137124 -290.36925) (xy 79.185979 -290.375182) (xy 79.23325 -290.388874)
			(xy 79.277712 -290.409972) (xy 79.318215 -290.437928) (xy 79.353708 -290.47202) (xy 79.383273 -290.511364)
			(xy 79.406144 -290.554941) (xy 79.421728 -290.601622) (xy 79.429623 -290.650199) (xy 79.430118 -290.674806)
			(xy 79.768966 -290.674806) (xy 79.772926 -290.625752) (xy 79.784703 -290.577968) (xy 79.803994 -290.532692)
			(xy 79.830297 -290.491096) (xy 79.862932 -290.454259) (xy 79.901053 -290.423134) (xy 79.943674 -290.398527)
			(xy 79.98969 -290.381075) (xy 80.037909 -290.371231) (xy 80.087084 -290.36925) (xy 80.135939 -290.375182)
			(xy 80.18321 -290.388874) (xy 80.227672 -290.409972) (xy 80.268175 -290.437928) (xy 80.303668 -290.47202)
			(xy 80.333233 -290.511364) (xy 80.356104 -290.554941) (xy 80.371688 -290.601622) (xy 80.379583 -290.650199)
			(xy 80.380078 -290.674806) (xy 80.71918 -290.674806) (xy 80.72314 -290.625752) (xy 80.734917 -290.577968)
			(xy 80.754208 -290.532692) (xy 80.780511 -290.491096) (xy 80.813146 -290.454259) (xy 80.851267 -290.423134)
			(xy 80.893888 -290.398527) (xy 80.939904 -290.381075) (xy 80.988123 -290.371231) (xy 81.037298 -290.36925)
			(xy 81.086153 -290.375182) (xy 81.133424 -290.388874) (xy 81.177886 -290.409972) (xy 81.218389 -290.437928)
			(xy 81.253882 -290.47202) (xy 81.283447 -290.511364) (xy 81.306318 -290.554941) (xy 81.321902 -290.601622)
			(xy 81.329797 -290.650199) (xy 81.330292 -290.674806) (xy 81.66914 -290.674806) (xy 81.6731 -290.625752)
			(xy 81.684877 -290.577968) (xy 81.704168 -290.532692) (xy 81.730471 -290.491096) (xy 81.763106 -290.454259)
			(xy 81.801227 -290.423134) (xy 81.843848 -290.398527) (xy 81.889864 -290.381075) (xy 81.938083 -290.371231)
			(xy 81.987258 -290.36925) (xy 82.036113 -290.375182) (xy 82.083384 -290.388874) (xy 82.127846 -290.409972)
			(xy 82.168349 -290.437928) (xy 82.203842 -290.47202) (xy 82.233407 -290.511364) (xy 82.256278 -290.554941)
			(xy 82.271862 -290.601622) (xy 82.279757 -290.650199) (xy 82.280252 -290.674806) (xy 82.279757 -290.699413)
			(xy 82.271862 -290.74799) (xy 82.256278 -290.794671) (xy 82.233407 -290.838248) (xy 82.203842 -290.877592)
			(xy 82.168349 -290.911684) (xy 82.127846 -290.93964) (xy 82.083384 -290.960738) (xy 82.036113 -290.97443)
			(xy 81.987258 -290.980362) (xy 81.938083 -290.978381) (xy 81.889864 -290.968537) (xy 81.843848 -290.951085)
			(xy 81.801227 -290.926478) (xy 81.763106 -290.895353) (xy 81.730471 -290.858516) (xy 81.704168 -290.81692)
			(xy 81.684877 -290.771644) (xy 81.6731 -290.72386) (xy 81.66914 -290.674806) (xy 81.330292 -290.674806)
			(xy 81.329797 -290.699413) (xy 81.321902 -290.74799) (xy 81.306318 -290.794671) (xy 81.283447 -290.838248)
			(xy 81.253882 -290.877592) (xy 81.218389 -290.911684) (xy 81.177886 -290.93964) (xy 81.133424 -290.960738)
			(xy 81.086153 -290.97443) (xy 81.037298 -290.980362) (xy 80.988123 -290.978381) (xy 80.939904 -290.968537)
			(xy 80.893888 -290.951085) (xy 80.851267 -290.926478) (xy 80.813146 -290.895353) (xy 80.780511 -290.858516)
			(xy 80.754208 -290.81692) (xy 80.734917 -290.771644) (xy 80.72314 -290.72386) (xy 80.71918 -290.674806)
			(xy 80.380078 -290.674806) (xy 80.379583 -290.699413) (xy 80.371688 -290.74799) (xy 80.356104 -290.794671)
			(xy 80.333233 -290.838248) (xy 80.303668 -290.877592) (xy 80.268175 -290.911684) (xy 80.227672 -290.93964)
			(xy 80.18321 -290.960738) (xy 80.135939 -290.97443) (xy 80.087084 -290.980362) (xy 80.037909 -290.978381)
			(xy 79.98969 -290.968537) (xy 79.943674 -290.951085) (xy 79.901053 -290.926478) (xy 79.862932 -290.895353)
			(xy 79.830297 -290.858516) (xy 79.803994 -290.81692) (xy 79.784703 -290.771644) (xy 79.772926 -290.72386)
			(xy 79.768966 -290.674806) (xy 79.430118 -290.674806) (xy 79.429623 -290.699413) (xy 79.421728 -290.74799)
			(xy 79.406144 -290.794671) (xy 79.383273 -290.838248) (xy 79.353708 -290.877592) (xy 79.318215 -290.911684)
			(xy 79.277712 -290.93964) (xy 79.23325 -290.960738) (xy 79.185979 -290.97443) (xy 79.137124 -290.980362)
			(xy 79.087949 -290.978381) (xy 79.03973 -290.968537) (xy 78.993714 -290.951085) (xy 78.951093 -290.926478)
			(xy 78.912972 -290.895353) (xy 78.880337 -290.858516) (xy 78.854034 -290.81692) (xy 78.834743 -290.771644)
			(xy 78.822966 -290.72386) (xy 78.819006 -290.674806) (xy 78.480158 -290.674806) (xy 78.479663 -290.699413)
			(xy 78.471768 -290.74799) (xy 78.456184 -290.794671) (xy 78.433313 -290.838248) (xy 78.403748 -290.877592)
			(xy 78.368255 -290.911684) (xy 78.327752 -290.93964) (xy 78.28329 -290.960738) (xy 78.236019 -290.97443)
			(xy 78.187164 -290.980362) (xy 78.137989 -290.978381) (xy 78.08977 -290.968537) (xy 78.043754 -290.951085)
			(xy 78.001133 -290.926478) (xy 77.963012 -290.895353) (xy 77.930377 -290.858516) (xy 77.904074 -290.81692)
			(xy 77.884783 -290.771644) (xy 77.873006 -290.72386) (xy 77.869046 -290.674806) (xy 77.530198 -290.674806)
			(xy 77.529703 -290.699413) (xy 77.521808 -290.74799) (xy 77.506224 -290.794671) (xy 77.483353 -290.838248)
			(xy 77.453788 -290.877592) (xy 77.418295 -290.911684) (xy 77.377792 -290.93964) (xy 77.33333 -290.960738)
			(xy 77.286059 -290.97443) (xy 77.237204 -290.980362) (xy 77.188029 -290.978381) (xy 77.13981 -290.968537)
			(xy 77.093794 -290.951085) (xy 77.051173 -290.926478) (xy 77.013052 -290.895353) (xy 76.980417 -290.858516)
			(xy 76.954114 -290.81692) (xy 76.934823 -290.771644) (xy 76.923046 -290.72386) (xy 76.919086 -290.674806)
			(xy 76.580238 -290.674806) (xy 76.579743 -290.699413) (xy 76.571848 -290.74799) (xy 76.556264 -290.794671)
			(xy 76.533393 -290.838248) (xy 76.503828 -290.877592) (xy 76.468335 -290.911684) (xy 76.427832 -290.93964)
			(xy 76.38337 -290.960738) (xy 76.336099 -290.97443) (xy 76.287244 -290.980362) (xy 76.238069 -290.978381)
			(xy 76.18985 -290.968537) (xy 76.143834 -290.951085) (xy 76.101213 -290.926478) (xy 76.063092 -290.895353)
			(xy 76.030457 -290.858516) (xy 76.004154 -290.81692) (xy 75.984863 -290.771644) (xy 75.973086 -290.72386)
			(xy 75.969126 -290.674806) (xy 75.630278 -290.674806) (xy 75.629783 -290.699413) (xy 75.621888 -290.74799)
			(xy 75.606304 -290.794671) (xy 75.583433 -290.838248) (xy 75.553868 -290.877592) (xy 75.518375 -290.911684)
			(xy 75.477872 -290.93964) (xy 75.43341 -290.960738) (xy 75.386139 -290.97443) (xy 75.337284 -290.980362)
			(xy 75.288109 -290.978381) (xy 75.23989 -290.968537) (xy 75.193874 -290.951085) (xy 75.151253 -290.926478)
			(xy 75.113132 -290.895353) (xy 75.080497 -290.858516) (xy 75.054194 -290.81692) (xy 75.034903 -290.771644)
			(xy 75.023126 -290.72386) (xy 75.019166 -290.674806) (xy 74.680064 -290.674806) (xy 74.679569 -290.699413)
			(xy 74.671674 -290.74799) (xy 74.65609 -290.794671) (xy 74.633219 -290.838248) (xy 74.603654 -290.877592)
			(xy 74.568161 -290.911684) (xy 74.527658 -290.93964) (xy 74.483196 -290.960738) (xy 74.435925 -290.97443)
			(xy 74.38707 -290.980362) (xy 74.337895 -290.978381) (xy 74.289676 -290.968537) (xy 74.24366 -290.951085)
			(xy 74.201039 -290.926478) (xy 74.162918 -290.895353) (xy 74.130283 -290.858516) (xy 74.10398 -290.81692)
			(xy 74.084689 -290.771644) (xy 74.072912 -290.72386) (xy 74.068952 -290.674806) (xy 73.730104 -290.674806)
			(xy 73.729609 -290.699413) (xy 73.721714 -290.74799) (xy 73.70613 -290.794671) (xy 73.683259 -290.838248)
			(xy 73.653694 -290.877592) (xy 73.618201 -290.911684) (xy 73.577698 -290.93964) (xy 73.533236 -290.960738)
			(xy 73.485965 -290.97443) (xy 73.43711 -290.980362) (xy 73.387935 -290.978381) (xy 73.339716 -290.968537)
			(xy 73.2937 -290.951085) (xy 73.251079 -290.926478) (xy 73.212958 -290.895353) (xy 73.180323 -290.858516)
			(xy 73.15402 -290.81692) (xy 73.134729 -290.771644) (xy 73.122952 -290.72386) (xy 73.118992 -290.674806)
			(xy 72.780144 -290.674806) (xy 72.779649 -290.699413) (xy 72.771754 -290.74799) (xy 72.75617 -290.794671)
			(xy 72.733299 -290.838248) (xy 72.703734 -290.877592) (xy 72.668241 -290.911684) (xy 72.627738 -290.93964)
			(xy 72.583276 -290.960738) (xy 72.536005 -290.97443) (xy 72.48715 -290.980362) (xy 72.437975 -290.978381)
			(xy 72.389756 -290.968537) (xy 72.34374 -290.951085) (xy 72.301119 -290.926478) (xy 72.262998 -290.895353)
			(xy 72.230363 -290.858516) (xy 72.20406 -290.81692) (xy 72.184769 -290.771644) (xy 72.172992 -290.72386)
			(xy 72.169032 -290.674806) (xy 71.830184 -290.674806) (xy 71.829689 -290.699413) (xy 71.821794 -290.74799)
			(xy 71.80621 -290.794671) (xy 71.783339 -290.838248) (xy 71.753774 -290.877592) (xy 71.718281 -290.911684)
			(xy 71.677778 -290.93964) (xy 71.633316 -290.960738) (xy 71.586045 -290.97443) (xy 71.53719 -290.980362)
			(xy 71.488015 -290.978381) (xy 71.439796 -290.968537) (xy 71.39378 -290.951085) (xy 71.351159 -290.926478)
			(xy 71.313038 -290.895353) (xy 71.280403 -290.858516) (xy 71.2541 -290.81692) (xy 71.234809 -290.771644)
			(xy 71.223032 -290.72386) (xy 71.219072 -290.674806) (xy 70.879753 -290.674806) (xy 70.879753 -290.699526)
			(xy 70.871791 -290.748323) (xy 70.856075 -290.795202) (xy 70.833016 -290.838938) (xy 70.818502 -290.858956)
			(xy 70.796912 -290.887404) (xy 70.807072 -290.905184) (xy 70.814184 -290.915344) (xy 70.821296 -290.923218)
			(xy 70.827099 -290.930431) (xy 70.833599 -290.94775) (xy 70.833996 -290.957) (xy 70.833996 -290.968176)
			(xy 70.83552 -290.980114) (xy 70.839581 -290.998257) (xy 70.843905 -291.035184) (xy 70.844156 -291.053774)
			(xy 70.844156 -291.245798) (xy 70.843902 -291.264388) (xy 70.839577 -291.301315) (xy 70.83552 -291.319458)
			(xy 70.833996 -291.331396) (xy 70.833996 -291.342572) (xy 70.833643 -291.35183) (xy 70.827128 -291.369156)
			(xy 70.821296 -291.376354) (xy 70.814184 -291.384228) (xy 70.807072 -291.394388) (xy 70.796912 -291.412168)
			(xy 70.818502 -291.440616) (xy 70.833025 -291.46063) (xy 70.856089 -291.504368) (xy 70.871809 -291.551249)
			(xy 70.879775 -291.60005) (xy 70.879777 -291.624766) (xy 71.219072 -291.624766) (xy 71.223032 -291.575712)
			(xy 71.234809 -291.527928) (xy 71.2541 -291.482652) (xy 71.280403 -291.441056) (xy 71.313038 -291.404219)
			(xy 71.351159 -291.373094) (xy 71.39378 -291.348487) (xy 71.439796 -291.331035) (xy 71.488015 -291.321191)
			(xy 71.53719 -291.31921) (xy 71.586045 -291.325142) (xy 71.633316 -291.338834) (xy 71.677778 -291.359932)
			(xy 71.718281 -291.387888) (xy 71.753774 -291.42198) (xy 71.783339 -291.461324) (xy 71.80621 -291.504901)
			(xy 71.821794 -291.551582) (xy 71.829689 -291.600159) (xy 71.830184 -291.624766) (xy 72.169032 -291.624766)
			(xy 72.172992 -291.575712) (xy 72.184769 -291.527928) (xy 72.20406 -291.482652) (xy 72.230363 -291.441056)
			(xy 72.262998 -291.404219) (xy 72.301119 -291.373094) (xy 72.34374 -291.348487) (xy 72.389756 -291.331035)
			(xy 72.437975 -291.321191) (xy 72.48715 -291.31921) (xy 72.536005 -291.325142) (xy 72.583276 -291.338834)
			(xy 72.627738 -291.359932) (xy 72.668241 -291.387888) (xy 72.703734 -291.42198) (xy 72.733299 -291.461324)
			(xy 72.75617 -291.504901) (xy 72.771754 -291.551582) (xy 72.779649 -291.600159) (xy 72.780144 -291.624766)
			(xy 73.118992 -291.624766) (xy 73.122952 -291.575712) (xy 73.134729 -291.527928) (xy 73.15402 -291.482652)
			(xy 73.180323 -291.441056) (xy 73.212958 -291.404219) (xy 73.251079 -291.373094) (xy 73.2937 -291.348487)
			(xy 73.339716 -291.331035) (xy 73.387935 -291.321191) (xy 73.43711 -291.31921) (xy 73.485965 -291.325142)
			(xy 73.533236 -291.338834) (xy 73.577698 -291.359932) (xy 73.618201 -291.387888) (xy 73.653694 -291.42198)
			(xy 73.683259 -291.461324) (xy 73.70613 -291.504901) (xy 73.721714 -291.551582) (xy 73.729609 -291.600159)
			(xy 73.730104 -291.624766) (xy 74.069206 -291.624766) (xy 74.073166 -291.575712) (xy 74.084943 -291.527928)
			(xy 74.104234 -291.482652) (xy 74.130537 -291.441056) (xy 74.163172 -291.404219) (xy 74.201293 -291.373094)
			(xy 74.243914 -291.348487) (xy 74.28993 -291.331035) (xy 74.338149 -291.321191) (xy 74.387324 -291.31921)
			(xy 74.436179 -291.325142) (xy 74.48345 -291.338834) (xy 74.527912 -291.359932) (xy 74.568415 -291.387888)
			(xy 74.603908 -291.42198) (xy 74.633473 -291.461324) (xy 74.656344 -291.504901) (xy 74.671928 -291.551582)
			(xy 74.679823 -291.600159) (xy 74.680318 -291.624766) (xy 75.969126 -291.624766) (xy 75.973086 -291.575712)
			(xy 75.984863 -291.527928) (xy 76.004154 -291.482652) (xy 76.030457 -291.441056) (xy 76.063092 -291.404219)
			(xy 76.101213 -291.373094) (xy 76.143834 -291.348487) (xy 76.18985 -291.331035) (xy 76.238069 -291.321191)
			(xy 76.287244 -291.31921) (xy 76.336099 -291.325142) (xy 76.38337 -291.338834) (xy 76.427832 -291.359932)
			(xy 76.468335 -291.387888) (xy 76.503828 -291.42198) (xy 76.533393 -291.461324) (xy 76.556264 -291.504901)
			(xy 76.571848 -291.551582) (xy 76.579743 -291.600159) (xy 76.580238 -291.624766) (xy 76.919086 -291.624766)
			(xy 76.923046 -291.575712) (xy 76.934823 -291.527928) (xy 76.954114 -291.482652) (xy 76.980417 -291.441056)
			(xy 77.013052 -291.404219) (xy 77.051173 -291.373094) (xy 77.093794 -291.348487) (xy 77.13981 -291.331035)
			(xy 77.188029 -291.321191) (xy 77.237204 -291.31921) (xy 77.286059 -291.325142) (xy 77.33333 -291.338834)
			(xy 77.377792 -291.359932) (xy 77.418295 -291.387888) (xy 77.453788 -291.42198) (xy 77.483353 -291.461324)
			(xy 77.506224 -291.504901) (xy 77.521808 -291.551582) (xy 77.529703 -291.600159) (xy 77.530198 -291.624766)
			(xy 77.869046 -291.624766) (xy 77.873006 -291.575712) (xy 77.884783 -291.527928) (xy 77.904074 -291.482652)
			(xy 77.930377 -291.441056) (xy 77.963012 -291.404219) (xy 78.001133 -291.373094) (xy 78.043754 -291.348487)
			(xy 78.08977 -291.331035) (xy 78.137989 -291.321191) (xy 78.187164 -291.31921) (xy 78.236019 -291.325142)
			(xy 78.28329 -291.338834) (xy 78.327752 -291.359932) (xy 78.368255 -291.387888) (xy 78.403748 -291.42198)
			(xy 78.433313 -291.461324) (xy 78.456184 -291.504901) (xy 78.471768 -291.551582) (xy 78.479663 -291.600159)
			(xy 78.480158 -291.624766) (xy 78.819006 -291.624766) (xy 78.822966 -291.575712) (xy 78.834743 -291.527928)
			(xy 78.854034 -291.482652) (xy 78.880337 -291.441056) (xy 78.912972 -291.404219) (xy 78.951093 -291.373094)
			(xy 78.993714 -291.348487) (xy 79.03973 -291.331035) (xy 79.087949 -291.321191) (xy 79.137124 -291.31921)
			(xy 79.185979 -291.325142) (xy 79.23325 -291.338834) (xy 79.277712 -291.359932) (xy 79.318215 -291.387888)
			(xy 79.353708 -291.42198) (xy 79.383273 -291.461324) (xy 79.406144 -291.504901) (xy 79.421728 -291.551582)
			(xy 79.429623 -291.600159) (xy 79.430118 -291.624766) (xy 79.768966 -291.624766) (xy 79.772926 -291.575712)
			(xy 79.784703 -291.527928) (xy 79.803994 -291.482652) (xy 79.830297 -291.441056) (xy 79.862932 -291.404219)
			(xy 79.901053 -291.373094) (xy 79.943674 -291.348487) (xy 79.98969 -291.331035) (xy 80.037909 -291.321191)
			(xy 80.087084 -291.31921) (xy 80.135939 -291.325142) (xy 80.18321 -291.338834) (xy 80.227672 -291.359932)
			(xy 80.268175 -291.387888) (xy 80.303668 -291.42198) (xy 80.333233 -291.461324) (xy 80.356104 -291.504901)
			(xy 80.371688 -291.551582) (xy 80.379583 -291.600159) (xy 80.380078 -291.624766) (xy 80.71918 -291.624766)
			(xy 80.72314 -291.575712) (xy 80.734917 -291.527928) (xy 80.754208 -291.482652) (xy 80.780511 -291.441056)
			(xy 80.813146 -291.404219) (xy 80.851267 -291.373094) (xy 80.893888 -291.348487) (xy 80.939904 -291.331035)
			(xy 80.988123 -291.321191) (xy 81.037298 -291.31921) (xy 81.086153 -291.325142) (xy 81.133424 -291.338834)
			(xy 81.177886 -291.359932) (xy 81.218389 -291.387888) (xy 81.253882 -291.42198) (xy 81.283447 -291.461324)
			(xy 81.306318 -291.504901) (xy 81.321902 -291.551582) (xy 81.329797 -291.600159) (xy 81.330292 -291.624766)
			(xy 81.66914 -291.624766) (xy 81.6731 -291.575712) (xy 81.684877 -291.527928) (xy 81.704168 -291.482652)
			(xy 81.730471 -291.441056) (xy 81.763106 -291.404219) (xy 81.801227 -291.373094) (xy 81.843848 -291.348487)
			(xy 81.889864 -291.331035) (xy 81.938083 -291.321191) (xy 81.987258 -291.31921) (xy 82.036113 -291.325142)
			(xy 82.083384 -291.338834) (xy 82.127846 -291.359932) (xy 82.168349 -291.387888) (xy 82.203842 -291.42198)
			(xy 82.233407 -291.461324) (xy 82.256278 -291.504901) (xy 82.271862 -291.551582) (xy 82.279757 -291.600159)
			(xy 82.280252 -291.624766) (xy 82.279757 -291.649373) (xy 82.271862 -291.69795) (xy 82.256278 -291.744631)
			(xy 82.233407 -291.788208) (xy 82.203842 -291.827552) (xy 82.168349 -291.861644) (xy 82.127846 -291.8896)
			(xy 82.083384 -291.910698) (xy 82.036113 -291.92439) (xy 81.987258 -291.930322) (xy 81.938083 -291.928341)
			(xy 81.889864 -291.918497) (xy 81.843848 -291.901045) (xy 81.801227 -291.876438) (xy 81.763106 -291.845313)
			(xy 81.730471 -291.808476) (xy 81.704168 -291.76688) (xy 81.684877 -291.721604) (xy 81.6731 -291.67382)
			(xy 81.66914 -291.624766) (xy 81.330292 -291.624766) (xy 81.329797 -291.649373) (xy 81.321902 -291.69795)
			(xy 81.306318 -291.744631) (xy 81.283447 -291.788208) (xy 81.253882 -291.827552) (xy 81.218389 -291.861644)
			(xy 81.177886 -291.8896) (xy 81.133424 -291.910698) (xy 81.086153 -291.92439) (xy 81.037298 -291.930322)
			(xy 80.988123 -291.928341) (xy 80.939904 -291.918497) (xy 80.893888 -291.901045) (xy 80.851267 -291.876438)
			(xy 80.813146 -291.845313) (xy 80.780511 -291.808476) (xy 80.754208 -291.76688) (xy 80.734917 -291.721604)
			(xy 80.72314 -291.67382) (xy 80.71918 -291.624766) (xy 80.380078 -291.624766) (xy 80.379583 -291.649373)
			(xy 80.371688 -291.69795) (xy 80.356104 -291.744631) (xy 80.333233 -291.788208) (xy 80.303668 -291.827552)
			(xy 80.268175 -291.861644) (xy 80.227672 -291.8896) (xy 80.18321 -291.910698) (xy 80.135939 -291.92439)
			(xy 80.087084 -291.930322) (xy 80.037909 -291.928341) (xy 79.98969 -291.918497) (xy 79.943674 -291.901045)
			(xy 79.901053 -291.876438) (xy 79.862932 -291.845313) (xy 79.830297 -291.808476) (xy 79.803994 -291.76688)
			(xy 79.784703 -291.721604) (xy 79.772926 -291.67382) (xy 79.768966 -291.624766) (xy 79.430118 -291.624766)
			(xy 79.429623 -291.649373) (xy 79.421728 -291.69795) (xy 79.406144 -291.744631) (xy 79.383273 -291.788208)
			(xy 79.353708 -291.827552) (xy 79.318215 -291.861644) (xy 79.277712 -291.8896) (xy 79.23325 -291.910698)
			(xy 79.185979 -291.92439) (xy 79.137124 -291.930322) (xy 79.087949 -291.928341) (xy 79.03973 -291.918497)
			(xy 78.993714 -291.901045) (xy 78.951093 -291.876438) (xy 78.912972 -291.845313) (xy 78.880337 -291.808476)
			(xy 78.854034 -291.76688) (xy 78.834743 -291.721604) (xy 78.822966 -291.67382) (xy 78.819006 -291.624766)
			(xy 78.480158 -291.624766) (xy 78.479663 -291.649373) (xy 78.471768 -291.69795) (xy 78.456184 -291.744631)
			(xy 78.433313 -291.788208) (xy 78.403748 -291.827552) (xy 78.368255 -291.861644) (xy 78.327752 -291.8896)
			(xy 78.28329 -291.910698) (xy 78.236019 -291.92439) (xy 78.187164 -291.930322) (xy 78.137989 -291.928341)
			(xy 78.08977 -291.918497) (xy 78.043754 -291.901045) (xy 78.001133 -291.876438) (xy 77.963012 -291.845313)
			(xy 77.930377 -291.808476) (xy 77.904074 -291.76688) (xy 77.884783 -291.721604) (xy 77.873006 -291.67382)
			(xy 77.869046 -291.624766) (xy 77.530198 -291.624766) (xy 77.529703 -291.649373) (xy 77.521808 -291.69795)
			(xy 77.506224 -291.744631) (xy 77.483353 -291.788208) (xy 77.453788 -291.827552) (xy 77.418295 -291.861644)
			(xy 77.377792 -291.8896) (xy 77.33333 -291.910698) (xy 77.286059 -291.92439) (xy 77.237204 -291.930322)
			(xy 77.188029 -291.928341) (xy 77.13981 -291.918497) (xy 77.093794 -291.901045) (xy 77.051173 -291.876438)
			(xy 77.013052 -291.845313) (xy 76.980417 -291.808476) (xy 76.954114 -291.76688) (xy 76.934823 -291.721604)
			(xy 76.923046 -291.67382) (xy 76.919086 -291.624766) (xy 76.580238 -291.624766) (xy 76.579743 -291.649373)
			(xy 76.571848 -291.69795) (xy 76.556264 -291.744631) (xy 76.533393 -291.788208) (xy 76.503828 -291.827552)
			(xy 76.468335 -291.861644) (xy 76.427832 -291.8896) (xy 76.38337 -291.910698) (xy 76.336099 -291.92439)
			(xy 76.287244 -291.930322) (xy 76.238069 -291.928341) (xy 76.18985 -291.918497) (xy 76.143834 -291.901045)
			(xy 76.101213 -291.876438) (xy 76.063092 -291.845313) (xy 76.030457 -291.808476) (xy 76.004154 -291.76688)
			(xy 75.984863 -291.721604) (xy 75.973086 -291.67382) (xy 75.969126 -291.624766) (xy 74.680318 -291.624766)
			(xy 74.679823 -291.649373) (xy 74.671928 -291.69795) (xy 74.656344 -291.744631) (xy 74.633473 -291.788208)
			(xy 74.603908 -291.827552) (xy 74.568415 -291.861644) (xy 74.527912 -291.8896) (xy 74.48345 -291.910698)
			(xy 74.436179 -291.92439) (xy 74.387324 -291.930322) (xy 74.338149 -291.928341) (xy 74.28993 -291.918497)
			(xy 74.243914 -291.901045) (xy 74.201293 -291.876438) (xy 74.163172 -291.845313) (xy 74.130537 -291.808476)
			(xy 74.104234 -291.76688) (xy 74.084943 -291.721604) (xy 74.073166 -291.67382) (xy 74.069206 -291.624766)
			(xy 73.730104 -291.624766) (xy 73.729609 -291.649373) (xy 73.721714 -291.69795) (xy 73.70613 -291.744631)
			(xy 73.683259 -291.788208) (xy 73.653694 -291.827552) (xy 73.618201 -291.861644) (xy 73.577698 -291.8896)
			(xy 73.533236 -291.910698) (xy 73.485965 -291.92439) (xy 73.43711 -291.930322) (xy 73.387935 -291.928341)
			(xy 73.339716 -291.918497) (xy 73.2937 -291.901045) (xy 73.251079 -291.876438) (xy 73.212958 -291.845313)
			(xy 73.180323 -291.808476) (xy 73.15402 -291.76688) (xy 73.134729 -291.721604) (xy 73.122952 -291.67382)
			(xy 73.118992 -291.624766) (xy 72.780144 -291.624766) (xy 72.779649 -291.649373) (xy 72.771754 -291.69795)
			(xy 72.75617 -291.744631) (xy 72.733299 -291.788208) (xy 72.703734 -291.827552) (xy 72.668241 -291.861644)
			(xy 72.627738 -291.8896) (xy 72.583276 -291.910698) (xy 72.536005 -291.92439) (xy 72.48715 -291.930322)
			(xy 72.437975 -291.928341) (xy 72.389756 -291.918497) (xy 72.34374 -291.901045) (xy 72.301119 -291.876438)
			(xy 72.262998 -291.845313) (xy 72.230363 -291.808476) (xy 72.20406 -291.76688) (xy 72.184769 -291.721604)
			(xy 72.172992 -291.67382) (xy 72.169032 -291.624766) (xy 71.830184 -291.624766) (xy 71.829689 -291.649373)
			(xy 71.821794 -291.69795) (xy 71.80621 -291.744631) (xy 71.783339 -291.788208) (xy 71.753774 -291.827552)
			(xy 71.718281 -291.861644) (xy 71.677778 -291.8896) (xy 71.633316 -291.910698) (xy 71.586045 -291.92439)
			(xy 71.53719 -291.930322) (xy 71.488015 -291.928341) (xy 71.439796 -291.918497) (xy 71.39378 -291.901045)
			(xy 71.351159 -291.876438) (xy 71.313038 -291.845313) (xy 71.280403 -291.808476) (xy 71.2541 -291.76688)
			(xy 71.234809 -291.721604) (xy 71.223032 -291.67382) (xy 71.219072 -291.624766) (xy 70.879777 -291.624766)
			(xy 70.879779 -291.649496) (xy 70.871822 -291.698298) (xy 70.85611 -291.745182) (xy 70.833054 -291.788924)
			(xy 70.818502 -291.808916) (xy 70.796912 -291.837364) (xy 70.807072 -291.855144) (xy 70.814184 -291.865304)
			(xy 70.821296 -291.873178) (xy 70.827105 -291.88039) (xy 70.833618 -291.897708) (xy 70.833996 -291.90696)
			(xy 70.833996 -291.918136) (xy 70.83552 -291.930074) (xy 70.839583 -291.948217) (xy 70.843912 -291.985144)
			(xy 70.844156 -292.003734) (xy 70.844156 -292.196012) (xy 70.843901 -292.214602) (xy 70.839575 -292.251528)
			(xy 70.83552 -292.269672) (xy 70.833996 -292.28161) (xy 70.833996 -292.292786) (xy 70.833641 -292.302043)
			(xy 70.827122 -292.319365) (xy 70.821296 -292.326568) (xy 70.814184 -292.334442) (xy 70.807072 -292.344602)
			(xy 70.796912 -292.362382) (xy 70.818502 -292.39083) (xy 70.833023 -292.410844) (xy 70.856085 -292.454582)
			(xy 70.871803 -292.501462) (xy 70.879768 -292.550261) (xy 70.879769 -292.574726) (xy 71.219072 -292.574726)
			(xy 71.223032 -292.525672) (xy 71.234809 -292.477888) (xy 71.2541 -292.432612) (xy 71.280403 -292.391016)
			(xy 71.313038 -292.354179) (xy 71.351159 -292.323054) (xy 71.39378 -292.298447) (xy 71.439796 -292.280995)
			(xy 71.488015 -292.271151) (xy 71.53719 -292.26917) (xy 71.586045 -292.275102) (xy 71.633316 -292.288794)
			(xy 71.677778 -292.309892) (xy 71.718281 -292.337848) (xy 71.753774 -292.37194) (xy 71.783339 -292.411284)
			(xy 71.80621 -292.454861) (xy 71.821794 -292.501542) (xy 71.829689 -292.550119) (xy 71.830184 -292.574726)
			(xy 72.169032 -292.574726) (xy 72.172992 -292.525672) (xy 72.184769 -292.477888) (xy 72.20406 -292.432612)
			(xy 72.230363 -292.391016) (xy 72.262998 -292.354179) (xy 72.301119 -292.323054) (xy 72.34374 -292.298447)
			(xy 72.389756 -292.280995) (xy 72.437975 -292.271151) (xy 72.48715 -292.26917) (xy 72.536005 -292.275102)
			(xy 72.583276 -292.288794) (xy 72.627738 -292.309892) (xy 72.668241 -292.337848) (xy 72.703734 -292.37194)
			(xy 72.733299 -292.411284) (xy 72.75617 -292.454861) (xy 72.771754 -292.501542) (xy 72.779649 -292.550119)
			(xy 72.780144 -292.574726) (xy 73.118992 -292.574726) (xy 73.122952 -292.525672) (xy 73.134729 -292.477888)
			(xy 73.15402 -292.432612) (xy 73.180323 -292.391016) (xy 73.212958 -292.354179) (xy 73.251079 -292.323054)
			(xy 73.2937 -292.298447) (xy 73.339716 -292.280995) (xy 73.387935 -292.271151) (xy 73.43711 -292.26917)
			(xy 73.485965 -292.275102) (xy 73.533236 -292.288794) (xy 73.577698 -292.309892) (xy 73.618201 -292.337848)
			(xy 73.653694 -292.37194) (xy 73.683259 -292.411284) (xy 73.70613 -292.454861) (xy 73.721714 -292.501542)
			(xy 73.729609 -292.550119) (xy 73.730104 -292.574726) (xy 74.068952 -292.574726) (xy 74.072912 -292.525672)
			(xy 74.084689 -292.477888) (xy 74.10398 -292.432612) (xy 74.130283 -292.391016) (xy 74.162918 -292.354179)
			(xy 74.201039 -292.323054) (xy 74.24366 -292.298447) (xy 74.289676 -292.280995) (xy 74.337895 -292.271151)
			(xy 74.38707 -292.26917) (xy 74.435925 -292.275102) (xy 74.483196 -292.288794) (xy 74.527658 -292.309892)
			(xy 74.568161 -292.337848) (xy 74.603654 -292.37194) (xy 74.633219 -292.411284) (xy 74.65609 -292.454861)
			(xy 74.671674 -292.501542) (xy 74.679569 -292.550119) (xy 74.680064 -292.574726) (xy 75.019166 -292.574726)
			(xy 75.023126 -292.525672) (xy 75.034903 -292.477888) (xy 75.054194 -292.432612) (xy 75.080497 -292.391016)
			(xy 75.113132 -292.354179) (xy 75.151253 -292.323054) (xy 75.193874 -292.298447) (xy 75.23989 -292.280995)
			(xy 75.288109 -292.271151) (xy 75.337284 -292.26917) (xy 75.386139 -292.275102) (xy 75.43341 -292.288794)
			(xy 75.477872 -292.309892) (xy 75.518375 -292.337848) (xy 75.553868 -292.37194) (xy 75.583433 -292.411284)
			(xy 75.606304 -292.454861) (xy 75.621888 -292.501542) (xy 75.629783 -292.550119) (xy 75.630278 -292.574726)
			(xy 75.969126 -292.574726) (xy 75.973086 -292.525672) (xy 75.984863 -292.477888) (xy 76.004154 -292.432612)
			(xy 76.030457 -292.391016) (xy 76.063092 -292.354179) (xy 76.101213 -292.323054) (xy 76.143834 -292.298447)
			(xy 76.18985 -292.280995) (xy 76.238069 -292.271151) (xy 76.287244 -292.26917) (xy 76.336099 -292.275102)
			(xy 76.38337 -292.288794) (xy 76.427832 -292.309892) (xy 76.468335 -292.337848) (xy 76.503828 -292.37194)
			(xy 76.533393 -292.411284) (xy 76.556264 -292.454861) (xy 76.571848 -292.501542) (xy 76.579743 -292.550119)
			(xy 76.580238 -292.574726) (xy 76.919086 -292.574726) (xy 76.923046 -292.525672) (xy 76.934823 -292.477888)
			(xy 76.954114 -292.432612) (xy 76.980417 -292.391016) (xy 77.013052 -292.354179) (xy 77.051173 -292.323054)
			(xy 77.093794 -292.298447) (xy 77.13981 -292.280995) (xy 77.188029 -292.271151) (xy 77.237204 -292.26917)
			(xy 77.286059 -292.275102) (xy 77.33333 -292.288794) (xy 77.377792 -292.309892) (xy 77.418295 -292.337848)
			(xy 77.453788 -292.37194) (xy 77.483353 -292.411284) (xy 77.506224 -292.454861) (xy 77.521808 -292.501542)
			(xy 77.529703 -292.550119) (xy 77.530198 -292.574726) (xy 77.869046 -292.574726) (xy 77.873006 -292.525672)
			(xy 77.884783 -292.477888) (xy 77.904074 -292.432612) (xy 77.930377 -292.391016) (xy 77.963012 -292.354179)
			(xy 78.001133 -292.323054) (xy 78.043754 -292.298447) (xy 78.08977 -292.280995) (xy 78.137989 -292.271151)
			(xy 78.187164 -292.26917) (xy 78.236019 -292.275102) (xy 78.28329 -292.288794) (xy 78.327752 -292.309892)
			(xy 78.368255 -292.337848) (xy 78.403748 -292.37194) (xy 78.433313 -292.411284) (xy 78.456184 -292.454861)
			(xy 78.471768 -292.501542) (xy 78.479663 -292.550119) (xy 78.480158 -292.574726) (xy 78.819006 -292.574726)
			(xy 78.822966 -292.525672) (xy 78.834743 -292.477888) (xy 78.854034 -292.432612) (xy 78.880337 -292.391016)
			(xy 78.912972 -292.354179) (xy 78.951093 -292.323054) (xy 78.993714 -292.298447) (xy 79.03973 -292.280995)
			(xy 79.087949 -292.271151) (xy 79.137124 -292.26917) (xy 79.185979 -292.275102) (xy 79.23325 -292.288794)
			(xy 79.277712 -292.309892) (xy 79.318215 -292.337848) (xy 79.353708 -292.37194) (xy 79.383273 -292.411284)
			(xy 79.406144 -292.454861) (xy 79.421728 -292.501542) (xy 79.429623 -292.550119) (xy 79.430118 -292.574726)
			(xy 79.768966 -292.574726) (xy 79.772926 -292.525672) (xy 79.784703 -292.477888) (xy 79.803994 -292.432612)
			(xy 79.830297 -292.391016) (xy 79.862932 -292.354179) (xy 79.901053 -292.323054) (xy 79.943674 -292.298447)
			(xy 79.98969 -292.280995) (xy 80.037909 -292.271151) (xy 80.087084 -292.26917) (xy 80.135939 -292.275102)
			(xy 80.18321 -292.288794) (xy 80.227672 -292.309892) (xy 80.268175 -292.337848) (xy 80.303668 -292.37194)
			(xy 80.333233 -292.411284) (xy 80.356104 -292.454861) (xy 80.371688 -292.501542) (xy 80.379583 -292.550119)
			(xy 80.380078 -292.574726) (xy 80.71918 -292.574726) (xy 80.72314 -292.525672) (xy 80.734917 -292.477888)
			(xy 80.754208 -292.432612) (xy 80.780511 -292.391016) (xy 80.813146 -292.354179) (xy 80.851267 -292.323054)
			(xy 80.893888 -292.298447) (xy 80.939904 -292.280995) (xy 80.988123 -292.271151) (xy 81.037298 -292.26917)
			(xy 81.086153 -292.275102) (xy 81.133424 -292.288794) (xy 81.177886 -292.309892) (xy 81.218389 -292.337848)
			(xy 81.253882 -292.37194) (xy 81.283447 -292.411284) (xy 81.306318 -292.454861) (xy 81.321902 -292.501542)
			(xy 81.329797 -292.550119) (xy 81.330292 -292.574726) (xy 81.330287 -292.57498) (xy 81.66914 -292.57498)
			(xy 81.6731 -292.525926) (xy 81.684877 -292.478142) (xy 81.704168 -292.432866) (xy 81.730471 -292.39127)
			(xy 81.763106 -292.354433) (xy 81.801227 -292.323308) (xy 81.843848 -292.298701) (xy 81.889864 -292.281249)
			(xy 81.938083 -292.271405) (xy 81.987258 -292.269424) (xy 82.036113 -292.275356) (xy 82.083384 -292.289048)
			(xy 82.127846 -292.310146) (xy 82.168349 -292.338102) (xy 82.203842 -292.372194) (xy 82.233407 -292.411538)
			(xy 82.256278 -292.455115) (xy 82.271862 -292.501796) (xy 82.279757 -292.550373) (xy 82.280252 -292.57498)
			(xy 82.279757 -292.599587) (xy 82.271862 -292.648164) (xy 82.256278 -292.694845) (xy 82.233407 -292.738422)
			(xy 82.203842 -292.777766) (xy 82.168349 -292.811858) (xy 82.127846 -292.839814) (xy 82.083384 -292.860912)
			(xy 82.036113 -292.874604) (xy 81.987258 -292.880536) (xy 81.938083 -292.878555) (xy 81.889864 -292.868711)
			(xy 81.843848 -292.851259) (xy 81.801227 -292.826652) (xy 81.763106 -292.795527) (xy 81.730471 -292.75869)
			(xy 81.704168 -292.717094) (xy 81.684877 -292.671818) (xy 81.6731 -292.624034) (xy 81.66914 -292.57498)
			(xy 81.330287 -292.57498) (xy 81.329797 -292.599333) (xy 81.321902 -292.64791) (xy 81.306318 -292.694591)
			(xy 81.283447 -292.738168) (xy 81.253882 -292.777512) (xy 81.218389 -292.811604) (xy 81.177886 -292.83956)
			(xy 81.133424 -292.860658) (xy 81.086153 -292.87435) (xy 81.037298 -292.880282) (xy 80.988123 -292.878301)
			(xy 80.939904 -292.868457) (xy 80.893888 -292.851005) (xy 80.851267 -292.826398) (xy 80.813146 -292.795273)
			(xy 80.780511 -292.758436) (xy 80.754208 -292.71684) (xy 80.734917 -292.671564) (xy 80.72314 -292.62378)
			(xy 80.71918 -292.574726) (xy 80.380078 -292.574726) (xy 80.379583 -292.599333) (xy 80.371688 -292.64791)
			(xy 80.356104 -292.694591) (xy 80.333233 -292.738168) (xy 80.303668 -292.777512) (xy 80.268175 -292.811604)
			(xy 80.227672 -292.83956) (xy 80.18321 -292.860658) (xy 80.135939 -292.87435) (xy 80.087084 -292.880282)
			(xy 80.037909 -292.878301) (xy 79.98969 -292.868457) (xy 79.943674 -292.851005) (xy 79.901053 -292.826398)
			(xy 79.862932 -292.795273) (xy 79.830297 -292.758436) (xy 79.803994 -292.71684) (xy 79.784703 -292.671564)
			(xy 79.772926 -292.62378) (xy 79.768966 -292.574726) (xy 79.430118 -292.574726) (xy 79.429623 -292.599333)
			(xy 79.421728 -292.64791) (xy 79.406144 -292.694591) (xy 79.383273 -292.738168) (xy 79.353708 -292.777512)
			(xy 79.318215 -292.811604) (xy 79.277712 -292.83956) (xy 79.23325 -292.860658) (xy 79.185979 -292.87435)
			(xy 79.137124 -292.880282) (xy 79.087949 -292.878301) (xy 79.03973 -292.868457) (xy 78.993714 -292.851005)
			(xy 78.951093 -292.826398) (xy 78.912972 -292.795273) (xy 78.880337 -292.758436) (xy 78.854034 -292.71684)
			(xy 78.834743 -292.671564) (xy 78.822966 -292.62378) (xy 78.819006 -292.574726) (xy 78.480158 -292.574726)
			(xy 78.479663 -292.599333) (xy 78.471768 -292.64791) (xy 78.456184 -292.694591) (xy 78.433313 -292.738168)
			(xy 78.403748 -292.777512) (xy 78.368255 -292.811604) (xy 78.327752 -292.83956) (xy 78.28329 -292.860658)
			(xy 78.236019 -292.87435) (xy 78.187164 -292.880282) (xy 78.137989 -292.878301) (xy 78.08977 -292.868457)
			(xy 78.043754 -292.851005) (xy 78.001133 -292.826398) (xy 77.963012 -292.795273) (xy 77.930377 -292.758436)
			(xy 77.904074 -292.71684) (xy 77.884783 -292.671564) (xy 77.873006 -292.62378) (xy 77.869046 -292.574726)
			(xy 77.530198 -292.574726) (xy 77.529703 -292.599333) (xy 77.521808 -292.64791) (xy 77.506224 -292.694591)
			(xy 77.483353 -292.738168) (xy 77.453788 -292.777512) (xy 77.418295 -292.811604) (xy 77.377792 -292.83956)
			(xy 77.33333 -292.860658) (xy 77.286059 -292.87435) (xy 77.237204 -292.880282) (xy 77.188029 -292.878301)
			(xy 77.13981 -292.868457) (xy 77.093794 -292.851005) (xy 77.051173 -292.826398) (xy 77.013052 -292.795273)
			(xy 76.980417 -292.758436) (xy 76.954114 -292.71684) (xy 76.934823 -292.671564) (xy 76.923046 -292.62378)
			(xy 76.919086 -292.574726) (xy 76.580238 -292.574726) (xy 76.579743 -292.599333) (xy 76.571848 -292.64791)
			(xy 76.556264 -292.694591) (xy 76.533393 -292.738168) (xy 76.503828 -292.777512) (xy 76.468335 -292.811604)
			(xy 76.427832 -292.83956) (xy 76.38337 -292.860658) (xy 76.336099 -292.87435) (xy 76.287244 -292.880282)
			(xy 76.238069 -292.878301) (xy 76.18985 -292.868457) (xy 76.143834 -292.851005) (xy 76.101213 -292.826398)
			(xy 76.063092 -292.795273) (xy 76.030457 -292.758436) (xy 76.004154 -292.71684) (xy 75.984863 -292.671564)
			(xy 75.973086 -292.62378) (xy 75.969126 -292.574726) (xy 75.630278 -292.574726) (xy 75.629783 -292.599333)
			(xy 75.621888 -292.64791) (xy 75.606304 -292.694591) (xy 75.583433 -292.738168) (xy 75.553868 -292.777512)
			(xy 75.518375 -292.811604) (xy 75.477872 -292.83956) (xy 75.43341 -292.860658) (xy 75.386139 -292.87435)
			(xy 75.337284 -292.880282) (xy 75.288109 -292.878301) (xy 75.23989 -292.868457) (xy 75.193874 -292.851005)
			(xy 75.151253 -292.826398) (xy 75.113132 -292.795273) (xy 75.080497 -292.758436) (xy 75.054194 -292.71684)
			(xy 75.034903 -292.671564) (xy 75.023126 -292.62378) (xy 75.019166 -292.574726) (xy 74.680064 -292.574726)
			(xy 74.679569 -292.599333) (xy 74.671674 -292.64791) (xy 74.65609 -292.694591) (xy 74.633219 -292.738168)
			(xy 74.603654 -292.777512) (xy 74.568161 -292.811604) (xy 74.527658 -292.83956) (xy 74.483196 -292.860658)
			(xy 74.435925 -292.87435) (xy 74.38707 -292.880282) (xy 74.337895 -292.878301) (xy 74.289676 -292.868457)
			(xy 74.24366 -292.851005) (xy 74.201039 -292.826398) (xy 74.162918 -292.795273) (xy 74.130283 -292.758436)
			(xy 74.10398 -292.71684) (xy 74.084689 -292.671564) (xy 74.072912 -292.62378) (xy 74.068952 -292.574726)
			(xy 73.730104 -292.574726) (xy 73.729609 -292.599333) (xy 73.721714 -292.64791) (xy 73.70613 -292.694591)
			(xy 73.683259 -292.738168) (xy 73.653694 -292.777512) (xy 73.618201 -292.811604) (xy 73.577698 -292.83956)
			(xy 73.533236 -292.860658) (xy 73.485965 -292.87435) (xy 73.43711 -292.880282) (xy 73.387935 -292.878301)
			(xy 73.339716 -292.868457) (xy 73.2937 -292.851005) (xy 73.251079 -292.826398) (xy 73.212958 -292.795273)
			(xy 73.180323 -292.758436) (xy 73.15402 -292.71684) (xy 73.134729 -292.671564) (xy 73.122952 -292.62378)
			(xy 73.118992 -292.574726) (xy 72.780144 -292.574726) (xy 72.779649 -292.599333) (xy 72.771754 -292.64791)
			(xy 72.75617 -292.694591) (xy 72.733299 -292.738168) (xy 72.703734 -292.777512) (xy 72.668241 -292.811604)
			(xy 72.627738 -292.83956) (xy 72.583276 -292.860658) (xy 72.536005 -292.87435) (xy 72.48715 -292.880282)
			(xy 72.437975 -292.878301) (xy 72.389756 -292.868457) (xy 72.34374 -292.851005) (xy 72.301119 -292.826398)
			(xy 72.262998 -292.795273) (xy 72.230363 -292.758436) (xy 72.20406 -292.71684) (xy 72.184769 -292.671564)
			(xy 72.172992 -292.62378) (xy 72.169032 -292.574726) (xy 71.830184 -292.574726) (xy 71.829689 -292.599333)
			(xy 71.821794 -292.64791) (xy 71.80621 -292.694591) (xy 71.783339 -292.738168) (xy 71.753774 -292.777512)
			(xy 71.718281 -292.811604) (xy 71.677778 -292.83956) (xy 71.633316 -292.860658) (xy 71.586045 -292.87435)
			(xy 71.53719 -292.880282) (xy 71.488015 -292.878301) (xy 71.439796 -292.868457) (xy 71.39378 -292.851005)
			(xy 71.351159 -292.826398) (xy 71.313038 -292.795273) (xy 71.280403 -292.758436) (xy 71.2541 -292.71684)
			(xy 71.234809 -292.671564) (xy 71.223032 -292.62378) (xy 71.219072 -292.574726) (xy 70.879769 -292.574726)
			(xy 70.87977 -292.599707) (xy 70.871811 -292.648507) (xy 70.856098 -292.695389) (xy 70.833041 -292.739129)
			(xy 70.818502 -292.75913) (xy 70.796912 -292.787578) (xy 70.807072 -292.805358) (xy 70.814184 -292.815518)
			(xy 70.821296 -292.823392) (xy 70.827103 -292.830604) (xy 70.833612 -292.847923) (xy 70.833996 -292.857174)
			(xy 70.833996 -292.86835) (xy 70.83552 -292.880288) (xy 70.839582 -292.898431) (xy 70.843909 -292.935358)
			(xy 70.844156 -292.953948) (xy 70.844156 -293.145972) (xy 70.843898 -293.164561) (xy 70.839564 -293.201486)
			(xy 70.83552 -293.219632) (xy 70.833996 -293.23157) (xy 70.833996 -293.242746) (xy 70.833648 -293.252005)
			(xy 70.827139 -293.269337) (xy 70.821296 -293.276528) (xy 70.814184 -293.284402) (xy 70.807072 -293.294562)
			(xy 70.796912 -293.312342) (xy 70.818502 -293.34079) (xy 70.833019 -293.360804) (xy 70.856071 -293.40454)
			(xy 70.87178 -293.451417) (xy 70.879735 -293.500212) (xy 70.879732 -293.52494) (xy 71.219072 -293.52494)
			(xy 71.223032 -293.475886) (xy 71.234809 -293.428102) (xy 71.2541 -293.382826) (xy 71.280403 -293.34123)
			(xy 71.313038 -293.304393) (xy 71.351159 -293.273268) (xy 71.39378 -293.248661) (xy 71.439796 -293.231209)
			(xy 71.488015 -293.221365) (xy 71.53719 -293.219384) (xy 71.586045 -293.225316) (xy 71.633316 -293.239008)
			(xy 71.677778 -293.260106) (xy 71.718281 -293.288062) (xy 71.753774 -293.322154) (xy 71.783339 -293.361498)
			(xy 71.80621 -293.405075) (xy 71.821794 -293.451756) (xy 71.829689 -293.500333) (xy 71.830184 -293.52494)
			(xy 72.169032 -293.52494) (xy 72.172992 -293.475886) (xy 72.184769 -293.428102) (xy 72.20406 -293.382826)
			(xy 72.230363 -293.34123) (xy 72.262998 -293.304393) (xy 72.301119 -293.273268) (xy 72.34374 -293.248661)
			(xy 72.389756 -293.231209) (xy 72.437975 -293.221365) (xy 72.48715 -293.219384) (xy 72.536005 -293.225316)
			(xy 72.583276 -293.239008) (xy 72.627738 -293.260106) (xy 72.668241 -293.288062) (xy 72.703734 -293.322154)
			(xy 72.733299 -293.361498) (xy 72.75617 -293.405075) (xy 72.771754 -293.451756) (xy 72.779649 -293.500333)
			(xy 72.780144 -293.52494) (xy 73.118992 -293.52494) (xy 73.122952 -293.475886) (xy 73.134729 -293.428102)
			(xy 73.15402 -293.382826) (xy 73.180323 -293.34123) (xy 73.212958 -293.304393) (xy 73.251079 -293.273268)
			(xy 73.2937 -293.248661) (xy 73.339716 -293.231209) (xy 73.387935 -293.221365) (xy 73.43711 -293.219384)
			(xy 73.485965 -293.225316) (xy 73.533236 -293.239008) (xy 73.577698 -293.260106) (xy 73.618201 -293.288062)
			(xy 73.653694 -293.322154) (xy 73.683259 -293.361498) (xy 73.70613 -293.405075) (xy 73.721714 -293.451756)
			(xy 73.729609 -293.500333) (xy 73.730104 -293.52494) (xy 74.069206 -293.52494) (xy 74.073166 -293.475886)
			(xy 74.084943 -293.428102) (xy 74.104234 -293.382826) (xy 74.130537 -293.34123) (xy 74.163172 -293.304393)
			(xy 74.201293 -293.273268) (xy 74.243914 -293.248661) (xy 74.28993 -293.231209) (xy 74.338149 -293.221365)
			(xy 74.387324 -293.219384) (xy 74.436179 -293.225316) (xy 74.48345 -293.239008) (xy 74.527912 -293.260106)
			(xy 74.568415 -293.288062) (xy 74.603908 -293.322154) (xy 74.633473 -293.361498) (xy 74.656344 -293.405075)
			(xy 74.671928 -293.451756) (xy 74.679823 -293.500333) (xy 74.680318 -293.52494) (xy 75.019166 -293.52494)
			(xy 75.023126 -293.475886) (xy 75.034903 -293.428102) (xy 75.054194 -293.382826) (xy 75.080497 -293.34123)
			(xy 75.113132 -293.304393) (xy 75.151253 -293.273268) (xy 75.193874 -293.248661) (xy 75.23989 -293.231209)
			(xy 75.288109 -293.221365) (xy 75.337284 -293.219384) (xy 75.386139 -293.225316) (xy 75.43341 -293.239008)
			(xy 75.477872 -293.260106) (xy 75.518375 -293.288062) (xy 75.553868 -293.322154) (xy 75.583433 -293.361498)
			(xy 75.606304 -293.405075) (xy 75.621888 -293.451756) (xy 75.629783 -293.500333) (xy 75.630278 -293.52494)
			(xy 75.969126 -293.52494) (xy 75.973086 -293.475886) (xy 75.984863 -293.428102) (xy 76.004154 -293.382826)
			(xy 76.030457 -293.34123) (xy 76.063092 -293.304393) (xy 76.101213 -293.273268) (xy 76.143834 -293.248661)
			(xy 76.18985 -293.231209) (xy 76.238069 -293.221365) (xy 76.287244 -293.219384) (xy 76.336099 -293.225316)
			(xy 76.38337 -293.239008) (xy 76.427832 -293.260106) (xy 76.468335 -293.288062) (xy 76.503828 -293.322154)
			(xy 76.533393 -293.361498) (xy 76.556264 -293.405075) (xy 76.571848 -293.451756) (xy 76.579743 -293.500333)
			(xy 76.580238 -293.52494) (xy 76.919086 -293.52494) (xy 76.923046 -293.475886) (xy 76.934823 -293.428102)
			(xy 76.954114 -293.382826) (xy 76.980417 -293.34123) (xy 77.013052 -293.304393) (xy 77.051173 -293.273268)
			(xy 77.093794 -293.248661) (xy 77.13981 -293.231209) (xy 77.188029 -293.221365) (xy 77.237204 -293.219384)
			(xy 77.286059 -293.225316) (xy 77.33333 -293.239008) (xy 77.377792 -293.260106) (xy 77.418295 -293.288062)
			(xy 77.453788 -293.322154) (xy 77.483353 -293.361498) (xy 77.506224 -293.405075) (xy 77.521808 -293.451756)
			(xy 77.529703 -293.500333) (xy 77.530198 -293.52494) (xy 77.869046 -293.52494) (xy 77.873006 -293.475886)
			(xy 77.884783 -293.428102) (xy 77.904074 -293.382826) (xy 77.930377 -293.34123) (xy 77.963012 -293.304393)
			(xy 78.001133 -293.273268) (xy 78.043754 -293.248661) (xy 78.08977 -293.231209) (xy 78.137989 -293.221365)
			(xy 78.187164 -293.219384) (xy 78.236019 -293.225316) (xy 78.28329 -293.239008) (xy 78.327752 -293.260106)
			(xy 78.368255 -293.288062) (xy 78.403748 -293.322154) (xy 78.433313 -293.361498) (xy 78.456184 -293.405075)
			(xy 78.471768 -293.451756) (xy 78.479663 -293.500333) (xy 78.480158 -293.52494) (xy 78.819006 -293.52494)
			(xy 78.822966 -293.475886) (xy 78.834743 -293.428102) (xy 78.854034 -293.382826) (xy 78.880337 -293.34123)
			(xy 78.912972 -293.304393) (xy 78.951093 -293.273268) (xy 78.993714 -293.248661) (xy 79.03973 -293.231209)
			(xy 79.087949 -293.221365) (xy 79.137124 -293.219384) (xy 79.185979 -293.225316) (xy 79.23325 -293.239008)
			(xy 79.277712 -293.260106) (xy 79.318215 -293.288062) (xy 79.353708 -293.322154) (xy 79.383273 -293.361498)
			(xy 79.406144 -293.405075) (xy 79.421728 -293.451756) (xy 79.429623 -293.500333) (xy 79.430118 -293.52494)
			(xy 79.768966 -293.52494) (xy 79.772926 -293.475886) (xy 79.784703 -293.428102) (xy 79.803994 -293.382826)
			(xy 79.830297 -293.34123) (xy 79.862932 -293.304393) (xy 79.901053 -293.273268) (xy 79.943674 -293.248661)
			(xy 79.98969 -293.231209) (xy 80.037909 -293.221365) (xy 80.087084 -293.219384) (xy 80.135939 -293.225316)
			(xy 80.18321 -293.239008) (xy 80.227672 -293.260106) (xy 80.268175 -293.288062) (xy 80.303668 -293.322154)
			(xy 80.333233 -293.361498) (xy 80.356104 -293.405075) (xy 80.371688 -293.451756) (xy 80.379583 -293.500333)
			(xy 80.380078 -293.52494) (xy 80.71918 -293.52494) (xy 80.72314 -293.475886) (xy 80.734917 -293.428102)
			(xy 80.754208 -293.382826) (xy 80.780511 -293.34123) (xy 80.813146 -293.304393) (xy 80.851267 -293.273268)
			(xy 80.893888 -293.248661) (xy 80.939904 -293.231209) (xy 80.988123 -293.221365) (xy 81.037298 -293.219384)
			(xy 81.086153 -293.225316) (xy 81.133424 -293.239008) (xy 81.177886 -293.260106) (xy 81.218389 -293.288062)
			(xy 81.253882 -293.322154) (xy 81.283447 -293.361498) (xy 81.306318 -293.405075) (xy 81.321902 -293.451756)
			(xy 81.329797 -293.500333) (xy 81.330292 -293.52494) (xy 81.66914 -293.52494) (xy 81.6731 -293.475886)
			(xy 81.684877 -293.428102) (xy 81.704168 -293.382826) (xy 81.730471 -293.34123) (xy 81.763106 -293.304393)
			(xy 81.801227 -293.273268) (xy 81.843848 -293.248661) (xy 81.889864 -293.231209) (xy 81.938083 -293.221365)
			(xy 81.987258 -293.219384) (xy 82.036113 -293.225316) (xy 82.083384 -293.239008) (xy 82.127846 -293.260106)
			(xy 82.168349 -293.288062) (xy 82.203842 -293.322154) (xy 82.233407 -293.361498) (xy 82.256278 -293.405075)
			(xy 82.271862 -293.451756) (xy 82.279757 -293.500333) (xy 82.280252 -293.52494) (xy 82.279757 -293.549547)
			(xy 82.271862 -293.598124) (xy 82.256278 -293.644805) (xy 82.233407 -293.688382) (xy 82.203842 -293.727726)
			(xy 82.168349 -293.761818) (xy 82.127846 -293.789774) (xy 82.083384 -293.810872) (xy 82.036113 -293.824564)
			(xy 81.987258 -293.830496) (xy 81.938083 -293.828515) (xy 81.889864 -293.818671) (xy 81.843848 -293.801219)
			(xy 81.801227 -293.776612) (xy 81.763106 -293.745487) (xy 81.730471 -293.70865) (xy 81.704168 -293.667054)
			(xy 81.684877 -293.621778) (xy 81.6731 -293.573994) (xy 81.66914 -293.52494) (xy 81.330292 -293.52494)
			(xy 81.329797 -293.549547) (xy 81.321902 -293.598124) (xy 81.306318 -293.644805) (xy 81.283447 -293.688382)
			(xy 81.253882 -293.727726) (xy 81.218389 -293.761818) (xy 81.177886 -293.789774) (xy 81.133424 -293.810872)
			(xy 81.086153 -293.824564) (xy 81.037298 -293.830496) (xy 80.988123 -293.828515) (xy 80.939904 -293.818671)
			(xy 80.893888 -293.801219) (xy 80.851267 -293.776612) (xy 80.813146 -293.745487) (xy 80.780511 -293.70865)
			(xy 80.754208 -293.667054) (xy 80.734917 -293.621778) (xy 80.72314 -293.573994) (xy 80.71918 -293.52494)
			(xy 80.380078 -293.52494) (xy 80.379583 -293.549547) (xy 80.371688 -293.598124) (xy 80.356104 -293.644805)
			(xy 80.333233 -293.688382) (xy 80.303668 -293.727726) (xy 80.268175 -293.761818) (xy 80.227672 -293.789774)
			(xy 80.18321 -293.810872) (xy 80.135939 -293.824564) (xy 80.087084 -293.830496) (xy 80.037909 -293.828515)
			(xy 79.98969 -293.818671) (xy 79.943674 -293.801219) (xy 79.901053 -293.776612) (xy 79.862932 -293.745487)
			(xy 79.830297 -293.70865) (xy 79.803994 -293.667054) (xy 79.784703 -293.621778) (xy 79.772926 -293.573994)
			(xy 79.768966 -293.52494) (xy 79.430118 -293.52494) (xy 79.429623 -293.549547) (xy 79.421728 -293.598124)
			(xy 79.406144 -293.644805) (xy 79.383273 -293.688382) (xy 79.353708 -293.727726) (xy 79.318215 -293.761818)
			(xy 79.277712 -293.789774) (xy 79.23325 -293.810872) (xy 79.185979 -293.824564) (xy 79.137124 -293.830496)
			(xy 79.087949 -293.828515) (xy 79.03973 -293.818671) (xy 78.993714 -293.801219) (xy 78.951093 -293.776612)
			(xy 78.912972 -293.745487) (xy 78.880337 -293.70865) (xy 78.854034 -293.667054) (xy 78.834743 -293.621778)
			(xy 78.822966 -293.573994) (xy 78.819006 -293.52494) (xy 78.480158 -293.52494) (xy 78.479663 -293.549547)
			(xy 78.471768 -293.598124) (xy 78.456184 -293.644805) (xy 78.433313 -293.688382) (xy 78.403748 -293.727726)
			(xy 78.368255 -293.761818) (xy 78.327752 -293.789774) (xy 78.28329 -293.810872) (xy 78.236019 -293.824564)
			(xy 78.187164 -293.830496) (xy 78.137989 -293.828515) (xy 78.08977 -293.818671) (xy 78.043754 -293.801219)
			(xy 78.001133 -293.776612) (xy 77.963012 -293.745487) (xy 77.930377 -293.70865) (xy 77.904074 -293.667054)
			(xy 77.884783 -293.621778) (xy 77.873006 -293.573994) (xy 77.869046 -293.52494) (xy 77.530198 -293.52494)
			(xy 77.529703 -293.549547) (xy 77.521808 -293.598124) (xy 77.506224 -293.644805) (xy 77.483353 -293.688382)
			(xy 77.453788 -293.727726) (xy 77.418295 -293.761818) (xy 77.377792 -293.789774) (xy 77.33333 -293.810872)
			(xy 77.286059 -293.824564) (xy 77.237204 -293.830496) (xy 77.188029 -293.828515) (xy 77.13981 -293.818671)
			(xy 77.093794 -293.801219) (xy 77.051173 -293.776612) (xy 77.013052 -293.745487) (xy 76.980417 -293.70865)
			(xy 76.954114 -293.667054) (xy 76.934823 -293.621778) (xy 76.923046 -293.573994) (xy 76.919086 -293.52494)
			(xy 76.580238 -293.52494) (xy 76.579743 -293.549547) (xy 76.571848 -293.598124) (xy 76.556264 -293.644805)
			(xy 76.533393 -293.688382) (xy 76.503828 -293.727726) (xy 76.468335 -293.761818) (xy 76.427832 -293.789774)
			(xy 76.38337 -293.810872) (xy 76.336099 -293.824564) (xy 76.287244 -293.830496) (xy 76.238069 -293.828515)
			(xy 76.18985 -293.818671) (xy 76.143834 -293.801219) (xy 76.101213 -293.776612) (xy 76.063092 -293.745487)
			(xy 76.030457 -293.70865) (xy 76.004154 -293.667054) (xy 75.984863 -293.621778) (xy 75.973086 -293.573994)
			(xy 75.969126 -293.52494) (xy 75.630278 -293.52494) (xy 75.629783 -293.549547) (xy 75.621888 -293.598124)
			(xy 75.606304 -293.644805) (xy 75.583433 -293.688382) (xy 75.553868 -293.727726) (xy 75.518375 -293.761818)
			(xy 75.477872 -293.789774) (xy 75.43341 -293.810872) (xy 75.386139 -293.824564) (xy 75.337284 -293.830496)
			(xy 75.288109 -293.828515) (xy 75.23989 -293.818671) (xy 75.193874 -293.801219) (xy 75.151253 -293.776612)
			(xy 75.113132 -293.745487) (xy 75.080497 -293.70865) (xy 75.054194 -293.667054) (xy 75.034903 -293.621778)
			(xy 75.023126 -293.573994) (xy 75.019166 -293.52494) (xy 74.680318 -293.52494) (xy 74.679823 -293.549547)
			(xy 74.671928 -293.598124) (xy 74.656344 -293.644805) (xy 74.633473 -293.688382) (xy 74.603908 -293.727726)
			(xy 74.568415 -293.761818) (xy 74.527912 -293.789774) (xy 74.48345 -293.810872) (xy 74.436179 -293.824564)
			(xy 74.387324 -293.830496) (xy 74.338149 -293.828515) (xy 74.28993 -293.818671) (xy 74.243914 -293.801219)
			(xy 74.201293 -293.776612) (xy 74.163172 -293.745487) (xy 74.130537 -293.70865) (xy 74.104234 -293.667054)
			(xy 74.084943 -293.621778) (xy 74.073166 -293.573994) (xy 74.069206 -293.52494) (xy 73.730104 -293.52494)
			(xy 73.729609 -293.549547) (xy 73.721714 -293.598124) (xy 73.70613 -293.644805) (xy 73.683259 -293.688382)
			(xy 73.653694 -293.727726) (xy 73.618201 -293.761818) (xy 73.577698 -293.789774) (xy 73.533236 -293.810872)
			(xy 73.485965 -293.824564) (xy 73.43711 -293.830496) (xy 73.387935 -293.828515) (xy 73.339716 -293.818671)
			(xy 73.2937 -293.801219) (xy 73.251079 -293.776612) (xy 73.212958 -293.745487) (xy 73.180323 -293.70865)
			(xy 73.15402 -293.667054) (xy 73.134729 -293.621778) (xy 73.122952 -293.573994) (xy 73.118992 -293.52494)
			(xy 72.780144 -293.52494) (xy 72.779649 -293.549547) (xy 72.771754 -293.598124) (xy 72.75617 -293.644805)
			(xy 72.733299 -293.688382) (xy 72.703734 -293.727726) (xy 72.668241 -293.761818) (xy 72.627738 -293.789774)
			(xy 72.583276 -293.810872) (xy 72.536005 -293.824564) (xy 72.48715 -293.830496) (xy 72.437975 -293.828515)
			(xy 72.389756 -293.818671) (xy 72.34374 -293.801219) (xy 72.301119 -293.776612) (xy 72.262998 -293.745487)
			(xy 72.230363 -293.70865) (xy 72.20406 -293.667054) (xy 72.184769 -293.621778) (xy 72.172992 -293.573994)
			(xy 72.169032 -293.52494) (xy 71.830184 -293.52494) (xy 71.829689 -293.549547) (xy 71.821794 -293.598124)
			(xy 71.80621 -293.644805) (xy 71.783339 -293.688382) (xy 71.753774 -293.727726) (xy 71.718281 -293.761818)
			(xy 71.677778 -293.789774) (xy 71.633316 -293.810872) (xy 71.586045 -293.824564) (xy 71.53719 -293.830496)
			(xy 71.488015 -293.828515) (xy 71.439796 -293.818671) (xy 71.39378 -293.801219) (xy 71.351159 -293.776612)
			(xy 71.313038 -293.745487) (xy 71.280403 -293.70865) (xy 71.2541 -293.667054) (xy 71.234809 -293.621778)
			(xy 71.223032 -293.573994) (xy 71.219072 -293.52494) (xy 70.879732 -293.52494) (xy 70.87973 -293.549652)
			(xy 70.871764 -293.598445) (xy 70.856046 -293.645319) (xy 70.832984 -293.68905) (xy 70.818502 -293.70909)
			(xy 70.796912 -293.737538) (xy 70.807072 -293.755318) (xy 70.814184 -293.765478) (xy 70.821296 -293.773352)
			(xy 70.827108 -293.780562) (xy 70.833631 -293.797881) (xy 70.833996 -293.807134) (xy 70.833996 -293.81831)
			(xy 70.83552 -293.830248) (xy 70.839585 -293.84839) (xy 70.843916 -293.885317) (xy 70.844156 -293.903908)
			(xy 70.844156 -294.095932) (xy 70.8439 -294.114522) (xy 70.839571 -294.151447) (xy 70.83552 -294.169592)
			(xy 70.833996 -294.18153) (xy 70.833996 -294.192706) (xy 70.833637 -294.201961) (xy 70.827114 -294.219279)
			(xy 70.821296 -294.226488) (xy 70.814184 -294.234362) (xy 70.807072 -294.244522) (xy 70.796912 -294.262302)
			(xy 70.818502 -294.29075) (xy 70.833022 -294.310764) (xy 70.85608 -294.354501) (xy 70.871795 -294.40138)
			(xy 70.879757 -294.450178) (xy 70.879757 -294.4749) (xy 71.219072 -294.4749) (xy 71.223032 -294.425846)
			(xy 71.234809 -294.378062) (xy 71.2541 -294.332786) (xy 71.280403 -294.29119) (xy 71.313038 -294.254353)
			(xy 71.351159 -294.223228) (xy 71.39378 -294.198621) (xy 71.439796 -294.181169) (xy 71.488015 -294.171325)
			(xy 71.53719 -294.169344) (xy 71.586045 -294.175276) (xy 71.633316 -294.188968) (xy 71.677778 -294.210066)
			(xy 71.718281 -294.238022) (xy 71.753774 -294.272114) (xy 71.783339 -294.311458) (xy 71.80621 -294.355035)
			(xy 71.821794 -294.401716) (xy 71.829689 -294.450293) (xy 71.830184 -294.4749) (xy 72.169032 -294.4749)
			(xy 72.172992 -294.425846) (xy 72.184769 -294.378062) (xy 72.20406 -294.332786) (xy 72.230363 -294.29119)
			(xy 72.262998 -294.254353) (xy 72.301119 -294.223228) (xy 72.34374 -294.198621) (xy 72.389756 -294.181169)
			(xy 72.437975 -294.171325) (xy 72.48715 -294.169344) (xy 72.536005 -294.175276) (xy 72.583276 -294.188968)
			(xy 72.627738 -294.210066) (xy 72.668241 -294.238022) (xy 72.703734 -294.272114) (xy 72.733299 -294.311458)
			(xy 72.75617 -294.355035) (xy 72.771754 -294.401716) (xy 72.779649 -294.450293) (xy 72.780144 -294.4749)
			(xy 73.118992 -294.4749) (xy 73.122952 -294.425846) (xy 73.134729 -294.378062) (xy 73.15402 -294.332786)
			(xy 73.180323 -294.29119) (xy 73.212958 -294.254353) (xy 73.251079 -294.223228) (xy 73.2937 -294.198621)
			(xy 73.339716 -294.181169) (xy 73.387935 -294.171325) (xy 73.43711 -294.169344) (xy 73.485965 -294.175276)
			(xy 73.533236 -294.188968) (xy 73.577698 -294.210066) (xy 73.618201 -294.238022) (xy 73.653694 -294.272114)
			(xy 73.683259 -294.311458) (xy 73.70613 -294.355035) (xy 73.721714 -294.401716) (xy 73.729609 -294.450293)
			(xy 73.730104 -294.4749) (xy 74.068952 -294.4749) (xy 74.072912 -294.425846) (xy 74.084689 -294.378062)
			(xy 74.10398 -294.332786) (xy 74.130283 -294.29119) (xy 74.162918 -294.254353) (xy 74.201039 -294.223228)
			(xy 74.24366 -294.198621) (xy 74.289676 -294.181169) (xy 74.337895 -294.171325) (xy 74.38707 -294.169344)
			(xy 74.435925 -294.175276) (xy 74.483196 -294.188968) (xy 74.527658 -294.210066) (xy 74.568161 -294.238022)
			(xy 74.603654 -294.272114) (xy 74.633219 -294.311458) (xy 74.65609 -294.355035) (xy 74.671674 -294.401716)
			(xy 74.679569 -294.450293) (xy 74.680064 -294.4749) (xy 75.019166 -294.4749) (xy 75.023126 -294.425846)
			(xy 75.034903 -294.378062) (xy 75.054194 -294.332786) (xy 75.080497 -294.29119) (xy 75.113132 -294.254353)
			(xy 75.151253 -294.223228) (xy 75.193874 -294.198621) (xy 75.23989 -294.181169) (xy 75.288109 -294.171325)
			(xy 75.337284 -294.169344) (xy 75.386139 -294.175276) (xy 75.43341 -294.188968) (xy 75.477872 -294.210066)
			(xy 75.518375 -294.238022) (xy 75.553868 -294.272114) (xy 75.583433 -294.311458) (xy 75.606304 -294.355035)
			(xy 75.621888 -294.401716) (xy 75.629783 -294.450293) (xy 75.630278 -294.4749) (xy 75.969126 -294.4749)
			(xy 75.973086 -294.425846) (xy 75.984863 -294.378062) (xy 76.004154 -294.332786) (xy 76.030457 -294.29119)
			(xy 76.063092 -294.254353) (xy 76.101213 -294.223228) (xy 76.143834 -294.198621) (xy 76.18985 -294.181169)
			(xy 76.238069 -294.171325) (xy 76.287244 -294.169344) (xy 76.336099 -294.175276) (xy 76.38337 -294.188968)
			(xy 76.427832 -294.210066) (xy 76.468335 -294.238022) (xy 76.503828 -294.272114) (xy 76.533393 -294.311458)
			(xy 76.556264 -294.355035) (xy 76.571848 -294.401716) (xy 76.579743 -294.450293) (xy 76.580238 -294.4749)
			(xy 76.919086 -294.4749) (xy 76.923046 -294.425846) (xy 76.934823 -294.378062) (xy 76.954114 -294.332786)
			(xy 76.980417 -294.29119) (xy 77.013052 -294.254353) (xy 77.051173 -294.223228) (xy 77.093794 -294.198621)
			(xy 77.13981 -294.181169) (xy 77.188029 -294.171325) (xy 77.237204 -294.169344) (xy 77.286059 -294.175276)
			(xy 77.33333 -294.188968) (xy 77.377792 -294.210066) (xy 77.418295 -294.238022) (xy 77.453788 -294.272114)
			(xy 77.483353 -294.311458) (xy 77.506224 -294.355035) (xy 77.521808 -294.401716) (xy 77.529703 -294.450293)
			(xy 77.530198 -294.4749) (xy 77.869046 -294.4749) (xy 77.873006 -294.425846) (xy 77.884783 -294.378062)
			(xy 77.904074 -294.332786) (xy 77.930377 -294.29119) (xy 77.963012 -294.254353) (xy 78.001133 -294.223228)
			(xy 78.043754 -294.198621) (xy 78.08977 -294.181169) (xy 78.137989 -294.171325) (xy 78.187164 -294.169344)
			(xy 78.236019 -294.175276) (xy 78.28329 -294.188968) (xy 78.327752 -294.210066) (xy 78.368255 -294.238022)
			(xy 78.403748 -294.272114) (xy 78.433313 -294.311458) (xy 78.456184 -294.355035) (xy 78.471768 -294.401716)
			(xy 78.479663 -294.450293) (xy 78.480158 -294.4749) (xy 78.819006 -294.4749) (xy 78.822966 -294.425846)
			(xy 78.834743 -294.378062) (xy 78.854034 -294.332786) (xy 78.880337 -294.29119) (xy 78.912972 -294.254353)
			(xy 78.951093 -294.223228) (xy 78.993714 -294.198621) (xy 79.03973 -294.181169) (xy 79.087949 -294.171325)
			(xy 79.137124 -294.169344) (xy 79.185979 -294.175276) (xy 79.23325 -294.188968) (xy 79.277712 -294.210066)
			(xy 79.318215 -294.238022) (xy 79.353708 -294.272114) (xy 79.383273 -294.311458) (xy 79.406144 -294.355035)
			(xy 79.421728 -294.401716) (xy 79.429623 -294.450293) (xy 79.430118 -294.4749) (xy 79.768966 -294.4749)
			(xy 79.772926 -294.425846) (xy 79.784703 -294.378062) (xy 79.803994 -294.332786) (xy 79.830297 -294.29119)
			(xy 79.862932 -294.254353) (xy 79.901053 -294.223228) (xy 79.943674 -294.198621) (xy 79.98969 -294.181169)
			(xy 80.037909 -294.171325) (xy 80.087084 -294.169344) (xy 80.135939 -294.175276) (xy 80.18321 -294.188968)
			(xy 80.227672 -294.210066) (xy 80.268175 -294.238022) (xy 80.303668 -294.272114) (xy 80.333233 -294.311458)
			(xy 80.356104 -294.355035) (xy 80.371688 -294.401716) (xy 80.379583 -294.450293) (xy 80.380078 -294.4749)
			(xy 80.71918 -294.4749) (xy 80.72314 -294.425846) (xy 80.734917 -294.378062) (xy 80.754208 -294.332786)
			(xy 80.780511 -294.29119) (xy 80.813146 -294.254353) (xy 80.851267 -294.223228) (xy 80.893888 -294.198621)
			(xy 80.939904 -294.181169) (xy 80.988123 -294.171325) (xy 81.037298 -294.169344) (xy 81.086153 -294.175276)
			(xy 81.133424 -294.188968) (xy 81.177886 -294.210066) (xy 81.218389 -294.238022) (xy 81.253882 -294.272114)
			(xy 81.283447 -294.311458) (xy 81.306318 -294.355035) (xy 81.321902 -294.401716) (xy 81.329797 -294.450293)
			(xy 81.330292 -294.4749) (xy 81.66914 -294.4749) (xy 81.6731 -294.425846) (xy 81.684877 -294.378062)
			(xy 81.704168 -294.332786) (xy 81.730471 -294.29119) (xy 81.763106 -294.254353) (xy 81.801227 -294.223228)
			(xy 81.843848 -294.198621) (xy 81.889864 -294.181169) (xy 81.938083 -294.171325) (xy 81.987258 -294.169344)
			(xy 82.036113 -294.175276) (xy 82.083384 -294.188968) (xy 82.127846 -294.210066) (xy 82.168349 -294.238022)
			(xy 82.203842 -294.272114) (xy 82.233407 -294.311458) (xy 82.256278 -294.355035) (xy 82.271862 -294.401716)
			(xy 82.279757 -294.450293) (xy 82.280252 -294.4749) (xy 82.279757 -294.499507) (xy 82.271862 -294.548084)
			(xy 82.256278 -294.594765) (xy 82.233407 -294.638342) (xy 82.203842 -294.677686) (xy 82.168349 -294.711778)
			(xy 82.127846 -294.739734) (xy 82.083384 -294.760832) (xy 82.036113 -294.774524) (xy 81.987258 -294.780456)
			(xy 81.938083 -294.778475) (xy 81.889864 -294.768631) (xy 81.843848 -294.751179) (xy 81.801227 -294.726572)
			(xy 81.763106 -294.695447) (xy 81.730471 -294.65861) (xy 81.704168 -294.617014) (xy 81.684877 -294.571738)
			(xy 81.6731 -294.523954) (xy 81.66914 -294.4749) (xy 81.330292 -294.4749) (xy 81.329797 -294.499507)
			(xy 81.321902 -294.548084) (xy 81.306318 -294.594765) (xy 81.283447 -294.638342) (xy 81.253882 -294.677686)
			(xy 81.218389 -294.711778) (xy 81.177886 -294.739734) (xy 81.133424 -294.760832) (xy 81.086153 -294.774524)
			(xy 81.037298 -294.780456) (xy 80.988123 -294.778475) (xy 80.939904 -294.768631) (xy 80.893888 -294.751179)
			(xy 80.851267 -294.726572) (xy 80.813146 -294.695447) (xy 80.780511 -294.65861) (xy 80.754208 -294.617014)
			(xy 80.734917 -294.571738) (xy 80.72314 -294.523954) (xy 80.71918 -294.4749) (xy 80.380078 -294.4749)
			(xy 80.379583 -294.499507) (xy 80.371688 -294.548084) (xy 80.356104 -294.594765) (xy 80.333233 -294.638342)
			(xy 80.303668 -294.677686) (xy 80.268175 -294.711778) (xy 80.227672 -294.739734) (xy 80.18321 -294.760832)
			(xy 80.135939 -294.774524) (xy 80.087084 -294.780456) (xy 80.037909 -294.778475) (xy 79.98969 -294.768631)
			(xy 79.943674 -294.751179) (xy 79.901053 -294.726572) (xy 79.862932 -294.695447) (xy 79.830297 -294.65861)
			(xy 79.803994 -294.617014) (xy 79.784703 -294.571738) (xy 79.772926 -294.523954) (xy 79.768966 -294.4749)
			(xy 79.430118 -294.4749) (xy 79.429623 -294.499507) (xy 79.421728 -294.548084) (xy 79.406144 -294.594765)
			(xy 79.383273 -294.638342) (xy 79.353708 -294.677686) (xy 79.318215 -294.711778) (xy 79.277712 -294.739734)
			(xy 79.23325 -294.760832) (xy 79.185979 -294.774524) (xy 79.137124 -294.780456) (xy 79.087949 -294.778475)
			(xy 79.03973 -294.768631) (xy 78.993714 -294.751179) (xy 78.951093 -294.726572) (xy 78.912972 -294.695447)
			(xy 78.880337 -294.65861) (xy 78.854034 -294.617014) (xy 78.834743 -294.571738) (xy 78.822966 -294.523954)
			(xy 78.819006 -294.4749) (xy 78.480158 -294.4749) (xy 78.479663 -294.499507) (xy 78.471768 -294.548084)
			(xy 78.456184 -294.594765) (xy 78.433313 -294.638342) (xy 78.403748 -294.677686) (xy 78.368255 -294.711778)
			(xy 78.327752 -294.739734) (xy 78.28329 -294.760832) (xy 78.236019 -294.774524) (xy 78.187164 -294.780456)
			(xy 78.137989 -294.778475) (xy 78.08977 -294.768631) (xy 78.043754 -294.751179) (xy 78.001133 -294.726572)
			(xy 77.963012 -294.695447) (xy 77.930377 -294.65861) (xy 77.904074 -294.617014) (xy 77.884783 -294.571738)
			(xy 77.873006 -294.523954) (xy 77.869046 -294.4749) (xy 77.530198 -294.4749) (xy 77.529703 -294.499507)
			(xy 77.521808 -294.548084) (xy 77.506224 -294.594765) (xy 77.483353 -294.638342) (xy 77.453788 -294.677686)
			(xy 77.418295 -294.711778) (xy 77.377792 -294.739734) (xy 77.33333 -294.760832) (xy 77.286059 -294.774524)
			(xy 77.237204 -294.780456) (xy 77.188029 -294.778475) (xy 77.13981 -294.768631) (xy 77.093794 -294.751179)
			(xy 77.051173 -294.726572) (xy 77.013052 -294.695447) (xy 76.980417 -294.65861) (xy 76.954114 -294.617014)
			(xy 76.934823 -294.571738) (xy 76.923046 -294.523954) (xy 76.919086 -294.4749) (xy 76.580238 -294.4749)
			(xy 76.579743 -294.499507) (xy 76.571848 -294.548084) (xy 76.556264 -294.594765) (xy 76.533393 -294.638342)
			(xy 76.503828 -294.677686) (xy 76.468335 -294.711778) (xy 76.427832 -294.739734) (xy 76.38337 -294.760832)
			(xy 76.336099 -294.774524) (xy 76.287244 -294.780456) (xy 76.238069 -294.778475) (xy 76.18985 -294.768631)
			(xy 76.143834 -294.751179) (xy 76.101213 -294.726572) (xy 76.063092 -294.695447) (xy 76.030457 -294.65861)
			(xy 76.004154 -294.617014) (xy 75.984863 -294.571738) (xy 75.973086 -294.523954) (xy 75.969126 -294.4749)
			(xy 75.630278 -294.4749) (xy 75.629783 -294.499507) (xy 75.621888 -294.548084) (xy 75.606304 -294.594765)
			(xy 75.583433 -294.638342) (xy 75.553868 -294.677686) (xy 75.518375 -294.711778) (xy 75.477872 -294.739734)
			(xy 75.43341 -294.760832) (xy 75.386139 -294.774524) (xy 75.337284 -294.780456) (xy 75.288109 -294.778475)
			(xy 75.23989 -294.768631) (xy 75.193874 -294.751179) (xy 75.151253 -294.726572) (xy 75.113132 -294.695447)
			(xy 75.080497 -294.65861) (xy 75.054194 -294.617014) (xy 75.034903 -294.571738) (xy 75.023126 -294.523954)
			(xy 75.019166 -294.4749) (xy 74.680064 -294.4749) (xy 74.679569 -294.499507) (xy 74.671674 -294.548084)
			(xy 74.65609 -294.594765) (xy 74.633219 -294.638342) (xy 74.603654 -294.677686) (xy 74.568161 -294.711778)
			(xy 74.527658 -294.739734) (xy 74.483196 -294.760832) (xy 74.435925 -294.774524) (xy 74.38707 -294.780456)
			(xy 74.337895 -294.778475) (xy 74.289676 -294.768631) (xy 74.24366 -294.751179) (xy 74.201039 -294.726572)
			(xy 74.162918 -294.695447) (xy 74.130283 -294.65861) (xy 74.10398 -294.617014) (xy 74.084689 -294.571738)
			(xy 74.072912 -294.523954) (xy 74.068952 -294.4749) (xy 73.730104 -294.4749) (xy 73.729609 -294.499507)
			(xy 73.721714 -294.548084) (xy 73.70613 -294.594765) (xy 73.683259 -294.638342) (xy 73.653694 -294.677686)
			(xy 73.618201 -294.711778) (xy 73.577698 -294.739734) (xy 73.533236 -294.760832) (xy 73.485965 -294.774524)
			(xy 73.43711 -294.780456) (xy 73.387935 -294.778475) (xy 73.339716 -294.768631) (xy 73.2937 -294.751179)
			(xy 73.251079 -294.726572) (xy 73.212958 -294.695447) (xy 73.180323 -294.65861) (xy 73.15402 -294.617014)
			(xy 73.134729 -294.571738) (xy 73.122952 -294.523954) (xy 73.118992 -294.4749) (xy 72.780144 -294.4749)
			(xy 72.779649 -294.499507) (xy 72.771754 -294.548084) (xy 72.75617 -294.594765) (xy 72.733299 -294.638342)
			(xy 72.703734 -294.677686) (xy 72.668241 -294.711778) (xy 72.627738 -294.739734) (xy 72.583276 -294.760832)
			(xy 72.536005 -294.774524) (xy 72.48715 -294.780456) (xy 72.437975 -294.778475) (xy 72.389756 -294.768631)
			(xy 72.34374 -294.751179) (xy 72.301119 -294.726572) (xy 72.262998 -294.695447) (xy 72.230363 -294.65861)
			(xy 72.20406 -294.617014) (xy 72.184769 -294.571738) (xy 72.172992 -294.523954) (xy 72.169032 -294.4749)
			(xy 71.830184 -294.4749) (xy 71.829689 -294.499507) (xy 71.821794 -294.548084) (xy 71.80621 -294.594765)
			(xy 71.783339 -294.638342) (xy 71.753774 -294.677686) (xy 71.718281 -294.711778) (xy 71.677778 -294.739734)
			(xy 71.633316 -294.760832) (xy 71.586045 -294.774524) (xy 71.53719 -294.780456) (xy 71.488015 -294.778475)
			(xy 71.439796 -294.768631) (xy 71.39378 -294.751179) (xy 71.351159 -294.726572) (xy 71.313038 -294.695447)
			(xy 71.280403 -294.65861) (xy 71.2541 -294.617014) (xy 71.234809 -294.571738) (xy 71.223032 -294.523954)
			(xy 71.219072 -294.4749) (xy 70.879757 -294.4749) (xy 70.879757 -294.499622) (xy 70.871795 -294.54842)
			(xy 70.85608 -294.595299) (xy 70.833022 -294.639036) (xy 70.818502 -294.65905) (xy 70.796912 -294.687498)
			(xy 70.807072 -294.705278) (xy 70.814184 -294.715438) (xy 70.821296 -294.723312) (xy 70.8271 -294.730525)
			(xy 70.833602 -294.747844) (xy 70.833996 -294.757094) (xy 70.833996 -294.76827) (xy 70.83552 -294.780208)
			(xy 70.839581 -294.798351) (xy 70.843906 -294.835278) (xy 70.844156 -294.853868) (xy 70.844156 -295.995852)
			(xy 70.843899 -296.014441) (xy 70.839568 -296.051367) (xy 70.83552 -296.069512) (xy 70.833996 -296.08145)
			(xy 70.833996 -296.092626) (xy 70.833634 -296.10188) (xy 70.827105 -296.119193) (xy 70.821296 -296.126408)
			(xy 70.814184 -296.134282) (xy 70.807072 -296.144442) (xy 70.796912 -296.162222) (xy 70.818502 -296.19067)
			(xy 70.83302 -296.210684) (xy 70.856076 -296.254421) (xy 70.871788 -296.301299) (xy 70.879746 -296.350095)
			(xy 70.879744 -296.37482) (xy 71.219072 -296.37482) (xy 71.223032 -296.325766) (xy 71.234809 -296.277982)
			(xy 71.2541 -296.232706) (xy 71.280403 -296.19111) (xy 71.313038 -296.154273) (xy 71.351159 -296.123148)
			(xy 71.39378 -296.098541) (xy 71.439796 -296.081089) (xy 71.488015 -296.071245) (xy 71.53719 -296.069264)
			(xy 71.586045 -296.075196) (xy 71.633316 -296.088888) (xy 71.677778 -296.109986) (xy 71.718281 -296.137942)
			(xy 71.753774 -296.172034) (xy 71.783339 -296.211378) (xy 71.80621 -296.254955) (xy 71.821794 -296.301636)
			(xy 71.829689 -296.350213) (xy 71.830184 -296.37482) (xy 72.169032 -296.37482) (xy 72.172992 -296.325766)
			(xy 72.184769 -296.277982) (xy 72.20406 -296.232706) (xy 72.230363 -296.19111) (xy 72.262998 -296.154273)
			(xy 72.301119 -296.123148) (xy 72.34374 -296.098541) (xy 72.389756 -296.081089) (xy 72.437975 -296.071245)
			(xy 72.48715 -296.069264) (xy 72.536005 -296.075196) (xy 72.583276 -296.088888) (xy 72.627738 -296.109986)
			(xy 72.668241 -296.137942) (xy 72.703734 -296.172034) (xy 72.733299 -296.211378) (xy 72.75617 -296.254955)
			(xy 72.771754 -296.301636) (xy 72.779649 -296.350213) (xy 72.780144 -296.37482) (xy 73.118992 -296.37482)
			(xy 73.122952 -296.325766) (xy 73.134729 -296.277982) (xy 73.15402 -296.232706) (xy 73.180323 -296.19111)
			(xy 73.212958 -296.154273) (xy 73.251079 -296.123148) (xy 73.2937 -296.098541) (xy 73.339716 -296.081089)
			(xy 73.387935 -296.071245) (xy 73.43711 -296.069264) (xy 73.485965 -296.075196) (xy 73.533236 -296.088888)
			(xy 73.577698 -296.109986) (xy 73.618201 -296.137942) (xy 73.653694 -296.172034) (xy 73.683259 -296.211378)
			(xy 73.70613 -296.254955) (xy 73.721714 -296.301636) (xy 73.729609 -296.350213) (xy 73.730104 -296.37482)
			(xy 74.068952 -296.37482) (xy 74.072912 -296.325766) (xy 74.084689 -296.277982) (xy 74.10398 -296.232706)
			(xy 74.130283 -296.19111) (xy 74.162918 -296.154273) (xy 74.201039 -296.123148) (xy 74.24366 -296.098541)
			(xy 74.289676 -296.081089) (xy 74.337895 -296.071245) (xy 74.38707 -296.069264) (xy 74.435925 -296.075196)
			(xy 74.483196 -296.088888) (xy 74.527658 -296.109986) (xy 74.568161 -296.137942) (xy 74.603654 -296.172034)
			(xy 74.633219 -296.211378) (xy 74.65609 -296.254955) (xy 74.671674 -296.301636) (xy 74.679569 -296.350213)
			(xy 74.680064 -296.37482) (xy 75.019166 -296.37482) (xy 75.023126 -296.325766) (xy 75.034903 -296.277982)
			(xy 75.054194 -296.232706) (xy 75.080497 -296.19111) (xy 75.113132 -296.154273) (xy 75.151253 -296.123148)
			(xy 75.193874 -296.098541) (xy 75.23989 -296.081089) (xy 75.288109 -296.071245) (xy 75.337284 -296.069264)
			(xy 75.386139 -296.075196) (xy 75.43341 -296.088888) (xy 75.477872 -296.109986) (xy 75.518375 -296.137942)
			(xy 75.553868 -296.172034) (xy 75.583433 -296.211378) (xy 75.606304 -296.254955) (xy 75.621888 -296.301636)
			(xy 75.629783 -296.350213) (xy 75.630278 -296.37482) (xy 75.969126 -296.37482) (xy 75.973086 -296.325766)
			(xy 75.984863 -296.277982) (xy 76.004154 -296.232706) (xy 76.030457 -296.19111) (xy 76.063092 -296.154273)
			(xy 76.101213 -296.123148) (xy 76.143834 -296.098541) (xy 76.18985 -296.081089) (xy 76.238069 -296.071245)
			(xy 76.287244 -296.069264) (xy 76.336099 -296.075196) (xy 76.38337 -296.088888) (xy 76.427832 -296.109986)
			(xy 76.468335 -296.137942) (xy 76.503828 -296.172034) (xy 76.533393 -296.211378) (xy 76.556264 -296.254955)
			(xy 76.571848 -296.301636) (xy 76.579743 -296.350213) (xy 76.580238 -296.37482) (xy 76.919086 -296.37482)
			(xy 76.923046 -296.325766) (xy 76.934823 -296.277982) (xy 76.954114 -296.232706) (xy 76.980417 -296.19111)
			(xy 77.013052 -296.154273) (xy 77.051173 -296.123148) (xy 77.093794 -296.098541) (xy 77.13981 -296.081089)
			(xy 77.188029 -296.071245) (xy 77.237204 -296.069264) (xy 77.286059 -296.075196) (xy 77.33333 -296.088888)
			(xy 77.377792 -296.109986) (xy 77.418295 -296.137942) (xy 77.453788 -296.172034) (xy 77.483353 -296.211378)
			(xy 77.506224 -296.254955) (xy 77.521808 -296.301636) (xy 77.529703 -296.350213) (xy 77.530198 -296.37482)
			(xy 77.869046 -296.37482) (xy 77.873006 -296.325766) (xy 77.884783 -296.277982) (xy 77.904074 -296.232706)
			(xy 77.930377 -296.19111) (xy 77.963012 -296.154273) (xy 78.001133 -296.123148) (xy 78.043754 -296.098541)
			(xy 78.08977 -296.081089) (xy 78.137989 -296.071245) (xy 78.187164 -296.069264) (xy 78.236019 -296.075196)
			(xy 78.28329 -296.088888) (xy 78.327752 -296.109986) (xy 78.368255 -296.137942) (xy 78.403748 -296.172034)
			(xy 78.433313 -296.211378) (xy 78.456184 -296.254955) (xy 78.471768 -296.301636) (xy 78.479663 -296.350213)
			(xy 78.480158 -296.37482) (xy 78.819006 -296.37482) (xy 78.822966 -296.325766) (xy 78.834743 -296.277982)
			(xy 78.854034 -296.232706) (xy 78.880337 -296.19111) (xy 78.912972 -296.154273) (xy 78.951093 -296.123148)
			(xy 78.993714 -296.098541) (xy 79.03973 -296.081089) (xy 79.087949 -296.071245) (xy 79.137124 -296.069264)
			(xy 79.185979 -296.075196) (xy 79.23325 -296.088888) (xy 79.277712 -296.109986) (xy 79.318215 -296.137942)
			(xy 79.353708 -296.172034) (xy 79.383273 -296.211378) (xy 79.406144 -296.254955) (xy 79.421728 -296.301636)
			(xy 79.429623 -296.350213) (xy 79.430118 -296.37482) (xy 79.768966 -296.37482) (xy 79.772926 -296.325766)
			(xy 79.784703 -296.277982) (xy 79.803994 -296.232706) (xy 79.830297 -296.19111) (xy 79.862932 -296.154273)
			(xy 79.901053 -296.123148) (xy 79.943674 -296.098541) (xy 79.98969 -296.081089) (xy 80.037909 -296.071245)
			(xy 80.087084 -296.069264) (xy 80.135939 -296.075196) (xy 80.18321 -296.088888) (xy 80.227672 -296.109986)
			(xy 80.268175 -296.137942) (xy 80.303668 -296.172034) (xy 80.333233 -296.211378) (xy 80.356104 -296.254955)
			(xy 80.371688 -296.301636) (xy 80.379583 -296.350213) (xy 80.380078 -296.37482) (xy 80.71918 -296.37482)
			(xy 80.72314 -296.325766) (xy 80.734917 -296.277982) (xy 80.754208 -296.232706) (xy 80.780511 -296.19111)
			(xy 80.813146 -296.154273) (xy 80.851267 -296.123148) (xy 80.893888 -296.098541) (xy 80.939904 -296.081089)
			(xy 80.988123 -296.071245) (xy 81.037298 -296.069264) (xy 81.086153 -296.075196) (xy 81.133424 -296.088888)
			(xy 81.177886 -296.109986) (xy 81.218389 -296.137942) (xy 81.253882 -296.172034) (xy 81.283447 -296.211378)
			(xy 81.306318 -296.254955) (xy 81.321902 -296.301636) (xy 81.329797 -296.350213) (xy 81.330292 -296.37482)
			(xy 81.66914 -296.37482) (xy 81.6731 -296.325766) (xy 81.684877 -296.277982) (xy 81.704168 -296.232706)
			(xy 81.730471 -296.19111) (xy 81.763106 -296.154273) (xy 81.801227 -296.123148) (xy 81.843848 -296.098541)
			(xy 81.889864 -296.081089) (xy 81.938083 -296.071245) (xy 81.987258 -296.069264) (xy 82.036113 -296.075196)
			(xy 82.083384 -296.088888) (xy 82.127846 -296.109986) (xy 82.168349 -296.137942) (xy 82.203842 -296.172034)
			(xy 82.233407 -296.211378) (xy 82.256278 -296.254955) (xy 82.271862 -296.301636) (xy 82.279757 -296.350213)
			(xy 82.280252 -296.37482) (xy 82.279757 -296.399427) (xy 82.271862 -296.448004) (xy 82.256278 -296.494685)
			(xy 82.233407 -296.538262) (xy 82.203842 -296.577606) (xy 82.168349 -296.611698) (xy 82.127846 -296.639654)
			(xy 82.083384 -296.660752) (xy 82.036113 -296.674444) (xy 81.987258 -296.680376) (xy 81.938083 -296.678395)
			(xy 81.889864 -296.668551) (xy 81.843848 -296.651099) (xy 81.801227 -296.626492) (xy 81.763106 -296.595367)
			(xy 81.730471 -296.55853) (xy 81.704168 -296.516934) (xy 81.684877 -296.471658) (xy 81.6731 -296.423874)
			(xy 81.66914 -296.37482) (xy 81.330292 -296.37482) (xy 81.329797 -296.399427) (xy 81.321902 -296.448004)
			(xy 81.306318 -296.494685) (xy 81.283447 -296.538262) (xy 81.253882 -296.577606) (xy 81.218389 -296.611698)
			(xy 81.177886 -296.639654) (xy 81.133424 -296.660752) (xy 81.086153 -296.674444) (xy 81.037298 -296.680376)
			(xy 80.988123 -296.678395) (xy 80.939904 -296.668551) (xy 80.893888 -296.651099) (xy 80.851267 -296.626492)
			(xy 80.813146 -296.595367) (xy 80.780511 -296.55853) (xy 80.754208 -296.516934) (xy 80.734917 -296.471658)
			(xy 80.72314 -296.423874) (xy 80.71918 -296.37482) (xy 80.380078 -296.37482) (xy 80.379583 -296.399427)
			(xy 80.371688 -296.448004) (xy 80.356104 -296.494685) (xy 80.333233 -296.538262) (xy 80.303668 -296.577606)
			(xy 80.268175 -296.611698) (xy 80.227672 -296.639654) (xy 80.18321 -296.660752) (xy 80.135939 -296.674444)
			(xy 80.087084 -296.680376) (xy 80.037909 -296.678395) (xy 79.98969 -296.668551) (xy 79.943674 -296.651099)
			(xy 79.901053 -296.626492) (xy 79.862932 -296.595367) (xy 79.830297 -296.55853) (xy 79.803994 -296.516934)
			(xy 79.784703 -296.471658) (xy 79.772926 -296.423874) (xy 79.768966 -296.37482) (xy 79.430118 -296.37482)
			(xy 79.429623 -296.399427) (xy 79.421728 -296.448004) (xy 79.406144 -296.494685) (xy 79.383273 -296.538262)
			(xy 79.353708 -296.577606) (xy 79.318215 -296.611698) (xy 79.277712 -296.639654) (xy 79.23325 -296.660752)
			(xy 79.185979 -296.674444) (xy 79.137124 -296.680376) (xy 79.087949 -296.678395) (xy 79.03973 -296.668551)
			(xy 78.993714 -296.651099) (xy 78.951093 -296.626492) (xy 78.912972 -296.595367) (xy 78.880337 -296.55853)
			(xy 78.854034 -296.516934) (xy 78.834743 -296.471658) (xy 78.822966 -296.423874) (xy 78.819006 -296.37482)
			(xy 78.480158 -296.37482) (xy 78.479663 -296.399427) (xy 78.471768 -296.448004) (xy 78.456184 -296.494685)
			(xy 78.433313 -296.538262) (xy 78.403748 -296.577606) (xy 78.368255 -296.611698) (xy 78.327752 -296.639654)
			(xy 78.28329 -296.660752) (xy 78.236019 -296.674444) (xy 78.187164 -296.680376) (xy 78.137989 -296.678395)
			(xy 78.08977 -296.668551) (xy 78.043754 -296.651099) (xy 78.001133 -296.626492) (xy 77.963012 -296.595367)
			(xy 77.930377 -296.55853) (xy 77.904074 -296.516934) (xy 77.884783 -296.471658) (xy 77.873006 -296.423874)
			(xy 77.869046 -296.37482) (xy 77.530198 -296.37482) (xy 77.529703 -296.399427) (xy 77.521808 -296.448004)
			(xy 77.506224 -296.494685) (xy 77.483353 -296.538262) (xy 77.453788 -296.577606) (xy 77.418295 -296.611698)
			(xy 77.377792 -296.639654) (xy 77.33333 -296.660752) (xy 77.286059 -296.674444) (xy 77.237204 -296.680376)
			(xy 77.188029 -296.678395) (xy 77.13981 -296.668551) (xy 77.093794 -296.651099) (xy 77.051173 -296.626492)
			(xy 77.013052 -296.595367) (xy 76.980417 -296.55853) (xy 76.954114 -296.516934) (xy 76.934823 -296.471658)
			(xy 76.923046 -296.423874) (xy 76.919086 -296.37482) (xy 76.580238 -296.37482) (xy 76.579743 -296.399427)
			(xy 76.571848 -296.448004) (xy 76.556264 -296.494685) (xy 76.533393 -296.538262) (xy 76.503828 -296.577606)
			(xy 76.468335 -296.611698) (xy 76.427832 -296.639654) (xy 76.38337 -296.660752) (xy 76.336099 -296.674444)
			(xy 76.287244 -296.680376) (xy 76.238069 -296.678395) (xy 76.18985 -296.668551) (xy 76.143834 -296.651099)
			(xy 76.101213 -296.626492) (xy 76.063092 -296.595367) (xy 76.030457 -296.55853) (xy 76.004154 -296.516934)
			(xy 75.984863 -296.471658) (xy 75.973086 -296.423874) (xy 75.969126 -296.37482) (xy 75.630278 -296.37482)
			(xy 75.629783 -296.399427) (xy 75.621888 -296.448004) (xy 75.606304 -296.494685) (xy 75.583433 -296.538262)
			(xy 75.553868 -296.577606) (xy 75.518375 -296.611698) (xy 75.477872 -296.639654) (xy 75.43341 -296.660752)
			(xy 75.386139 -296.674444) (xy 75.337284 -296.680376) (xy 75.288109 -296.678395) (xy 75.23989 -296.668551)
			(xy 75.193874 -296.651099) (xy 75.151253 -296.626492) (xy 75.113132 -296.595367) (xy 75.080497 -296.55853)
			(xy 75.054194 -296.516934) (xy 75.034903 -296.471658) (xy 75.023126 -296.423874) (xy 75.019166 -296.37482)
			(xy 74.680064 -296.37482) (xy 74.679569 -296.399427) (xy 74.671674 -296.448004) (xy 74.65609 -296.494685)
			(xy 74.633219 -296.538262) (xy 74.603654 -296.577606) (xy 74.568161 -296.611698) (xy 74.527658 -296.639654)
			(xy 74.483196 -296.660752) (xy 74.435925 -296.674444) (xy 74.38707 -296.680376) (xy 74.337895 -296.678395)
			(xy 74.289676 -296.668551) (xy 74.24366 -296.651099) (xy 74.201039 -296.626492) (xy 74.162918 -296.595367)
			(xy 74.130283 -296.55853) (xy 74.10398 -296.516934) (xy 74.084689 -296.471658) (xy 74.072912 -296.423874)
			(xy 74.068952 -296.37482) (xy 73.730104 -296.37482) (xy 73.729609 -296.399427) (xy 73.721714 -296.448004)
			(xy 73.70613 -296.494685) (xy 73.683259 -296.538262) (xy 73.653694 -296.577606) (xy 73.618201 -296.611698)
			(xy 73.577698 -296.639654) (xy 73.533236 -296.660752) (xy 73.485965 -296.674444) (xy 73.43711 -296.680376)
			(xy 73.387935 -296.678395) (xy 73.339716 -296.668551) (xy 73.2937 -296.651099) (xy 73.251079 -296.626492)
			(xy 73.212958 -296.595367) (xy 73.180323 -296.55853) (xy 73.15402 -296.516934) (xy 73.134729 -296.471658)
			(xy 73.122952 -296.423874) (xy 73.118992 -296.37482) (xy 72.780144 -296.37482) (xy 72.779649 -296.399427)
			(xy 72.771754 -296.448004) (xy 72.75617 -296.494685) (xy 72.733299 -296.538262) (xy 72.703734 -296.577606)
			(xy 72.668241 -296.611698) (xy 72.627738 -296.639654) (xy 72.583276 -296.660752) (xy 72.536005 -296.674444)
			(xy 72.48715 -296.680376) (xy 72.437975 -296.678395) (xy 72.389756 -296.668551) (xy 72.34374 -296.651099)
			(xy 72.301119 -296.626492) (xy 72.262998 -296.595367) (xy 72.230363 -296.55853) (xy 72.20406 -296.516934)
			(xy 72.184769 -296.471658) (xy 72.172992 -296.423874) (xy 72.169032 -296.37482) (xy 71.830184 -296.37482)
			(xy 71.829689 -296.399427) (xy 71.821794 -296.448004) (xy 71.80621 -296.494685) (xy 71.783339 -296.538262)
			(xy 71.753774 -296.577606) (xy 71.718281 -296.611698) (xy 71.677778 -296.639654) (xy 71.633316 -296.660752)
			(xy 71.586045 -296.674444) (xy 71.53719 -296.680376) (xy 71.488015 -296.678395) (xy 71.439796 -296.668551)
			(xy 71.39378 -296.651099) (xy 71.351159 -296.626492) (xy 71.313038 -296.595367) (xy 71.280403 -296.55853)
			(xy 71.2541 -296.516934) (xy 71.234809 -296.471658) (xy 71.223032 -296.423874) (xy 71.219072 -296.37482)
			(xy 70.879744 -296.37482) (xy 70.879743 -296.399537) (xy 70.87178 -296.448332) (xy 70.856063 -296.495209)
			(xy 70.833003 -296.538943) (xy 70.818502 -296.55897) (xy 70.796912 -296.587418) (xy 70.807072 -296.605198)
			(xy 70.814184 -296.615358) (xy 70.821296 -296.623232) (xy 70.827112 -296.630441) (xy 70.833641 -296.64776)
			(xy 70.833996 -296.657014) (xy 70.833996 -296.66819) (xy 70.83552 -296.680128) (xy 70.839586 -296.69827)
			(xy 70.84392 -296.735197) (xy 70.844156 -296.753788) (xy 70.844156 -296.945812) (xy 70.843901 -296.964402)
			(xy 70.839575 -297.001328) (xy 70.83552 -297.019472) (xy 70.833996 -297.03141) (xy 70.833996 -297.042586)
			(xy 70.833641 -297.051843) (xy 70.827122 -297.069165) (xy 70.821296 -297.076368) (xy 70.814184 -297.084242)
			(xy 70.807072 -297.094402) (xy 70.796912 -297.112182) (xy 70.818502 -297.14063) (xy 70.833023 -297.160644)
			(xy 70.856085 -297.20438) (xy 70.871803 -297.25126) (xy 70.879767 -297.300058) (xy 70.880224 -297.32478)
			(xy 71.219072 -297.32478) (xy 71.223032 -297.275726) (xy 71.234809 -297.227942) (xy 71.2541 -297.182666)
			(xy 71.280403 -297.14107) (xy 71.313038 -297.104233) (xy 71.351159 -297.073108) (xy 71.39378 -297.048501)
			(xy 71.439796 -297.031049) (xy 71.488015 -297.021205) (xy 71.53719 -297.019224) (xy 71.586045 -297.025156)
			(xy 71.633316 -297.038848) (xy 71.677778 -297.059946) (xy 71.718281 -297.087902) (xy 71.753774 -297.121994)
			(xy 71.783339 -297.161338) (xy 71.80621 -297.204915) (xy 71.821794 -297.251596) (xy 71.829689 -297.300173)
			(xy 71.830184 -297.32478) (xy 72.169032 -297.32478) (xy 72.172992 -297.275726) (xy 72.184769 -297.227942)
			(xy 72.20406 -297.182666) (xy 72.230363 -297.14107) (xy 72.262998 -297.104233) (xy 72.301119 -297.073108)
			(xy 72.34374 -297.048501) (xy 72.389756 -297.031049) (xy 72.437975 -297.021205) (xy 72.48715 -297.019224)
			(xy 72.536005 -297.025156) (xy 72.583276 -297.038848) (xy 72.627738 -297.059946) (xy 72.668241 -297.087902)
			(xy 72.703734 -297.121994) (xy 72.733299 -297.161338) (xy 72.75617 -297.204915) (xy 72.771754 -297.251596)
			(xy 72.779649 -297.300173) (xy 72.780144 -297.32478) (xy 72.779649 -297.349387) (xy 72.771754 -297.397964)
			(xy 72.75617 -297.444645) (xy 72.733299 -297.488222) (xy 72.703734 -297.527566) (xy 72.668241 -297.561658)
			(xy 72.627738 -297.589614) (xy 72.583276 -297.610712) (xy 72.536005 -297.624404) (xy 72.48715 -297.630336)
			(xy 72.437975 -297.628355) (xy 72.389756 -297.618511) (xy 72.34374 -297.601059) (xy 72.301119 -297.576452)
			(xy 72.262998 -297.545327) (xy 72.230363 -297.50849) (xy 72.20406 -297.466894) (xy 72.184769 -297.421618)
			(xy 72.172992 -297.373834) (xy 72.169032 -297.32478) (xy 71.830184 -297.32478) (xy 71.829689 -297.349387)
			(xy 71.821794 -297.397964) (xy 71.80621 -297.444645) (xy 71.783339 -297.488222) (xy 71.753774 -297.527566)
			(xy 71.718281 -297.561658) (xy 71.677778 -297.589614) (xy 71.633316 -297.610712) (xy 71.586045 -297.624404)
			(xy 71.53719 -297.630336) (xy 71.488015 -297.628355) (xy 71.439796 -297.618511) (xy 71.39378 -297.601059)
			(xy 71.351159 -297.576452) (xy 71.313038 -297.545327) (xy 71.280403 -297.50849) (xy 71.2541 -297.466894)
			(xy 71.234809 -297.421618) (xy 71.223032 -297.373834) (xy 71.219072 -297.32478) (xy 70.880224 -297.32478)
			(xy 70.879779 -297.348775) (xy 70.872275 -297.396173) (xy 70.857449 -297.441815) (xy 70.835665 -297.484575)
			(xy 70.80746 -297.523401) (xy 70.773528 -297.557336) (xy 70.734706 -297.585546) (xy 70.691948 -297.607335)
			(xy 70.646309 -297.622167) (xy 70.598911 -297.629676) (xy 70.574916 -297.630088) (xy 70.55149 -297.629611)
			(xy 70.505195 -297.622406) (xy 70.460541 -297.608223) (xy 70.418574 -297.587394) (xy 70.380274 -297.560408)
			(xy 70.36308 -297.54449) (xy 70.332092 -297.514772) (xy 70.329298 -297.516042) (xy 70.323964 -297.520106)
			(xy 70.317181 -297.524858) (xy 70.301505 -297.530172) (xy 70.29323 -297.53052) (xy 70.286626 -297.53052)
			(xy 70.266975 -297.53532) (xy 70.226843 -297.540411) (xy 70.206616 -297.54068) (xy 69.993256 -297.54068)
			(xy 69.974475 -297.540459) (xy 69.937166 -297.536131) (xy 69.918834 -297.532044) (xy 69.906896 -297.53052)
			(xy 69.871844 -297.53052) (xy 69.862118 -297.530994) (xy 69.844082 -297.538292) (xy 69.836792 -297.544744)
			(xy 69.819603 -297.560652) (xy 69.781288 -297.587582) (xy 69.739311 -297.60835) (xy 69.694658 -297.62247)
			(xy 69.648372 -297.62961) (xy 69.624956 -297.630088) (xy 69.601529 -297.629614) (xy 69.555231 -297.622414)
			(xy 69.510573 -297.608236) (xy 69.468601 -297.587411) (xy 69.430297 -297.560427) (xy 69.41312 -297.54449)
			(xy 69.382132 -297.514772) (xy 69.379338 -297.516042) (xy 69.374004 -297.520106) (xy 69.367223 -297.524864)
			(xy 69.351546 -297.53019) (xy 69.34327 -297.53052) (xy 69.336666 -297.53052) (xy 69.317015 -297.535322)
			(xy 69.276884 -297.540418) (xy 69.256656 -297.54068) (xy 69.043042 -297.54068) (xy 69.024261 -297.540458)
			(xy 68.986952 -297.536129) (xy 68.96862 -297.532044) (xy 68.956682 -297.53052) (xy 68.92163 -297.53052)
			(xy 68.911905 -297.530996) (xy 68.893873 -297.538298) (xy 68.886578 -297.544744) (xy 68.869389 -297.560651)
			(xy 68.831073 -297.58758) (xy 68.789097 -297.608346) (xy 68.744443 -297.622463) (xy 68.698158 -297.629601)
			(xy 68.674742 -297.630088) (xy 68.659848 -297.629896) (xy 68.630204 -297.626969) (xy 68.61556 -297.624246)
			(xy 68.615306 -297.624246) (xy 68.60418 -297.622698) (xy 68.582441 -297.628249) (xy 68.573396 -297.634914)
			(xy 68.52285 -297.676316) (xy 68.514479 -297.683935) (xy 68.504837 -297.70438) (xy 68.504308 -297.715686)
			(xy 68.504308 -297.883834) (xy 68.504919 -297.895119) (xy 68.514546 -297.915536) (xy 68.52285 -297.923204)
			(xy 68.573396 -297.964606) (xy 68.582429 -297.97129) (xy 68.604178 -297.976831) (xy 68.615306 -297.975274)
			(xy 68.61556 -297.975274) (xy 68.630204 -297.972551) (xy 68.659848 -297.969625) (xy 68.674742 -297.969432)
			(xy 68.699992 -297.969957) (xy 68.749802 -297.978275) (xy 68.797563 -297.994677) (xy 68.841974 -298.018717)
			(xy 68.881823 -298.049737) (xy 68.916023 -298.086893) (xy 68.943641 -298.129171) (xy 68.963925 -298.175418)
			(xy 68.976321 -298.224373) (xy 68.980491 -298.2747) (xy 68.980488 -298.27474) (xy 69.319152 -298.27474)
			(xy 69.323112 -298.225686) (xy 69.334889 -298.177902) (xy 69.35418 -298.132626) (xy 69.380483 -298.09103)
			(xy 69.413118 -298.054193) (xy 69.451239 -298.023068) (xy 69.49386 -297.998461) (xy 69.539876 -297.981009)
			(xy 69.588095 -297.971165) (xy 69.63727 -297.969184) (xy 69.686125 -297.975116) (xy 69.733396 -297.988808)
			(xy 69.777858 -298.009906) (xy 69.818361 -298.037862) (xy 69.853854 -298.071954) (xy 69.883419 -298.111298)
			(xy 69.90629 -298.154875) (xy 69.921874 -298.201556) (xy 69.929769 -298.250133) (xy 69.930264 -298.27474)
			(xy 70.269112 -298.27474) (xy 70.273072 -298.225686) (xy 70.284849 -298.177902) (xy 70.30414 -298.132626)
			(xy 70.330443 -298.09103) (xy 70.363078 -298.054193) (xy 70.401199 -298.023068) (xy 70.44382 -297.998461)
			(xy 70.489836 -297.981009) (xy 70.538055 -297.971165) (xy 70.58723 -297.969184) (xy 70.636085 -297.975116)
			(xy 70.683356 -297.988808) (xy 70.727818 -298.009906) (xy 70.768321 -298.037862) (xy 70.803814 -298.071954)
			(xy 70.833379 -298.111298) (xy 70.85625 -298.154875) (xy 70.871834 -298.201556) (xy 70.879729 -298.250133)
			(xy 70.880224 -298.27474) (xy 71.219072 -298.27474) (xy 71.223032 -298.225686) (xy 71.234809 -298.177902)
			(xy 71.2541 -298.132626) (xy 71.280403 -298.09103) (xy 71.313038 -298.054193) (xy 71.351159 -298.023068)
			(xy 71.39378 -297.998461) (xy 71.439796 -297.981009) (xy 71.488015 -297.971165) (xy 71.53719 -297.969184)
			(xy 71.586045 -297.975116) (xy 71.633316 -297.988808) (xy 71.677778 -298.009906) (xy 71.718281 -298.037862)
			(xy 71.753774 -298.071954) (xy 71.783339 -298.111298) (xy 71.80621 -298.154875) (xy 71.821794 -298.201556)
			(xy 71.829689 -298.250133) (xy 71.830184 -298.27474) (xy 72.169032 -298.27474) (xy 72.172992 -298.225686)
			(xy 72.184769 -298.177902) (xy 72.20406 -298.132626) (xy 72.230363 -298.09103) (xy 72.262998 -298.054193)
			(xy 72.301119 -298.023068) (xy 72.34374 -297.998461) (xy 72.389756 -297.981009) (xy 72.437975 -297.971165)
			(xy 72.48715 -297.969184) (xy 72.536005 -297.975116) (xy 72.583276 -297.988808) (xy 72.627738 -298.009906)
			(xy 72.668241 -298.037862) (xy 72.703734 -298.071954) (xy 72.733299 -298.111298) (xy 72.75617 -298.154875)
			(xy 72.771754 -298.201556) (xy 72.779649 -298.250133) (xy 72.780144 -298.27474) (xy 72.779649 -298.299347)
			(xy 72.771754 -298.347924) (xy 72.75617 -298.394605) (xy 72.733299 -298.438182) (xy 72.703734 -298.477526)
			(xy 72.668241 -298.511618) (xy 72.627738 -298.539574) (xy 72.583276 -298.560672) (xy 72.536005 -298.574364)
			(xy 72.48715 -298.580296) (xy 72.437975 -298.578315) (xy 72.389756 -298.568471) (xy 72.34374 -298.551019)
			(xy 72.301119 -298.526412) (xy 72.262998 -298.495287) (xy 72.230363 -298.45845) (xy 72.20406 -298.416854)
			(xy 72.184769 -298.371578) (xy 72.172992 -298.323794) (xy 72.169032 -298.27474) (xy 71.830184 -298.27474)
			(xy 71.829689 -298.299347) (xy 71.821794 -298.347924) (xy 71.80621 -298.394605) (xy 71.783339 -298.438182)
			(xy 71.753774 -298.477526) (xy 71.718281 -298.511618) (xy 71.677778 -298.539574) (xy 71.633316 -298.560672)
			(xy 71.586045 -298.574364) (xy 71.53719 -298.580296) (xy 71.488015 -298.578315) (xy 71.439796 -298.568471)
			(xy 71.39378 -298.551019) (xy 71.351159 -298.526412) (xy 71.313038 -298.495287) (xy 71.280403 -298.45845)
			(xy 71.2541 -298.416854) (xy 71.234809 -298.371578) (xy 71.223032 -298.323794) (xy 71.219072 -298.27474)
			(xy 70.880224 -298.27474) (xy 70.879729 -298.299347) (xy 70.871834 -298.347924) (xy 70.85625 -298.394605)
			(xy 70.833379 -298.438182) (xy 70.803814 -298.477526) (xy 70.768321 -298.511618) (xy 70.727818 -298.539574)
			(xy 70.683356 -298.560672) (xy 70.636085 -298.574364) (xy 70.58723 -298.580296) (xy 70.538055 -298.578315)
			(xy 70.489836 -298.568471) (xy 70.44382 -298.551019) (xy 70.401199 -298.526412) (xy 70.363078 -298.495287)
			(xy 70.330443 -298.45845) (xy 70.30414 -298.416854) (xy 70.284849 -298.371578) (xy 70.273072 -298.323794)
			(xy 70.269112 -298.27474) (xy 69.930264 -298.27474) (xy 69.929769 -298.299347) (xy 69.921874 -298.347924)
			(xy 69.90629 -298.394605) (xy 69.883419 -298.438182) (xy 69.853854 -298.477526) (xy 69.818361 -298.511618)
			(xy 69.777858 -298.539574) (xy 69.733396 -298.560672) (xy 69.686125 -298.574364) (xy 69.63727 -298.580296)
			(xy 69.588095 -298.578315) (xy 69.539876 -298.568471) (xy 69.49386 -298.551019) (xy 69.451239 -298.526412)
			(xy 69.413118 -298.495287) (xy 69.380483 -298.45845) (xy 69.35418 -298.416854) (xy 69.334889 -298.371578)
			(xy 69.323112 -298.323794) (xy 69.319152 -298.27474) (xy 68.980488 -298.27474) (xy 68.976321 -298.325027)
			(xy 68.963925 -298.373982) (xy 68.943641 -298.420229) (xy 68.916023 -298.462507) (xy 68.881823 -298.499663)
			(xy 68.841974 -298.530683) (xy 68.797563 -298.554723) (xy 68.749802 -298.571125) (xy 68.699992 -298.579443)
			(xy 68.674742 -298.580048) (xy 68.659848 -298.579856) (xy 68.630204 -298.576928) (xy 68.61556 -298.574206)
			(xy 68.615306 -298.574206) (xy 68.60418 -298.572658) (xy 68.582444 -298.578213) (xy 68.573396 -298.584874)
			(xy 68.52285 -298.626276) (xy 68.514489 -298.633899) (xy 68.504871 -298.654344) (xy 68.504308 -298.665646)
			(xy 68.504308 -298.834048) (xy 68.504922 -298.845332) (xy 68.514552 -298.865744) (xy 68.52285 -298.873418)
			(xy 68.573396 -298.91482) (xy 68.582426 -298.921513) (xy 68.604178 -298.927064) (xy 68.615306 -298.925488)
			(xy 68.61556 -298.925488) (xy 68.630204 -298.922765) (xy 68.659848 -298.919839) (xy 68.674742 -298.919646)
			(xy 68.699999 -298.920171) (xy 68.749823 -298.928491) (xy 68.797598 -298.944898) (xy 68.842021 -298.968944)
			(xy 68.881881 -298.999974) (xy 68.916091 -299.03714) (xy 68.943718 -299.07943) (xy 68.964007 -299.12569)
			(xy 68.976406 -299.174659) (xy 68.980574 -299.224954) (xy 69.319152 -299.224954) (xy 69.323112 -299.1759)
			(xy 69.334889 -299.128116) (xy 69.35418 -299.08284) (xy 69.380483 -299.041244) (xy 69.413118 -299.004407)
			(xy 69.451239 -298.973282) (xy 69.49386 -298.948675) (xy 69.539876 -298.931223) (xy 69.588095 -298.921379)
			(xy 69.63727 -298.919398) (xy 69.686125 -298.92533) (xy 69.733396 -298.939022) (xy 69.777858 -298.96012)
			(xy 69.818361 -298.988076) (xy 69.853854 -299.022168) (xy 69.883419 -299.061512) (xy 69.90629 -299.105089)
			(xy 69.921874 -299.15177) (xy 69.929769 -299.200347) (xy 69.930264 -299.224954) (xy 70.269112 -299.224954)
			(xy 70.273072 -299.1759) (xy 70.284849 -299.128116) (xy 70.30414 -299.08284) (xy 70.330443 -299.041244)
			(xy 70.363078 -299.004407) (xy 70.401199 -298.973282) (xy 70.44382 -298.948675) (xy 70.489836 -298.931223)
			(xy 70.538055 -298.921379) (xy 70.58723 -298.919398) (xy 70.636085 -298.92533) (xy 70.683356 -298.939022)
			(xy 70.727818 -298.96012) (xy 70.768321 -298.988076) (xy 70.803814 -299.022168) (xy 70.833379 -299.061512)
			(xy 70.85625 -299.105089) (xy 70.871834 -299.15177) (xy 70.879729 -299.200347) (xy 70.880224 -299.224954)
			(xy 71.219072 -299.224954) (xy 71.223032 -299.1759) (xy 71.234809 -299.128116) (xy 71.2541 -299.08284)
			(xy 71.280403 -299.041244) (xy 71.313038 -299.004407) (xy 71.351159 -298.973282) (xy 71.39378 -298.948675)
			(xy 71.439796 -298.931223) (xy 71.488015 -298.921379) (xy 71.53719 -298.919398) (xy 71.586045 -298.92533)
			(xy 71.633316 -298.939022) (xy 71.677778 -298.96012) (xy 71.718281 -298.988076) (xy 71.753774 -299.022168)
			(xy 71.783339 -299.061512) (xy 71.80621 -299.105089) (xy 71.821794 -299.15177) (xy 71.829689 -299.200347)
			(xy 71.830184 -299.224954) (xy 71.829689 -299.249561) (xy 71.821794 -299.298138) (xy 71.80621 -299.344819)
			(xy 71.783339 -299.388396) (xy 71.753774 -299.42774) (xy 71.718281 -299.461832) (xy 71.677778 -299.489788)
			(xy 71.633316 -299.510886) (xy 71.586045 -299.524578) (xy 71.53719 -299.53051) (xy 71.488015 -299.528529)
			(xy 71.439796 -299.518685) (xy 71.39378 -299.501233) (xy 71.351159 -299.476626) (xy 71.313038 -299.445501)
			(xy 71.280403 -299.408664) (xy 71.2541 -299.367068) (xy 71.234809 -299.321792) (xy 71.223032 -299.274008)
			(xy 71.219072 -299.224954) (xy 70.880224 -299.224954) (xy 70.879729 -299.249561) (xy 70.871834 -299.298138)
			(xy 70.85625 -299.344819) (xy 70.833379 -299.388396) (xy 70.803814 -299.42774) (xy 70.768321 -299.461832)
			(xy 70.727818 -299.489788) (xy 70.683356 -299.510886) (xy 70.636085 -299.524578) (xy 70.58723 -299.53051)
			(xy 70.538055 -299.528529) (xy 70.489836 -299.518685) (xy 70.44382 -299.501233) (xy 70.401199 -299.476626)
			(xy 70.363078 -299.445501) (xy 70.330443 -299.408664) (xy 70.30414 -299.367068) (xy 70.284849 -299.321792)
			(xy 70.273072 -299.274008) (xy 70.269112 -299.224954) (xy 69.930264 -299.224954) (xy 69.929769 -299.249561)
			(xy 69.921874 -299.298138) (xy 69.90629 -299.344819) (xy 69.883419 -299.388396) (xy 69.853854 -299.42774)
			(xy 69.818361 -299.461832) (xy 69.777858 -299.489788) (xy 69.733396 -299.510886) (xy 69.686125 -299.524578)
			(xy 69.63727 -299.53051) (xy 69.588095 -299.528529) (xy 69.539876 -299.518685) (xy 69.49386 -299.501233)
			(xy 69.451239 -299.476626) (xy 69.413118 -299.445501) (xy 69.380483 -299.408664) (xy 69.35418 -299.367068)
			(xy 69.334889 -299.321792) (xy 69.323112 -299.274008) (xy 69.319152 -299.224954) (xy 68.980574 -299.224954)
			(xy 68.980578 -299.225) (xy 68.976406 -299.275341) (xy 68.964007 -299.32431) (xy 68.943718 -299.37057)
			(xy 68.916091 -299.41286) (xy 68.881881 -299.450026) (xy 68.842021 -299.481056) (xy 68.797598 -299.505102)
			(xy 68.749823 -299.521509) (xy 68.699999 -299.529829) (xy 68.674742 -299.530262) (xy 68.659848 -299.53007)
			(xy 68.630204 -299.527142) (xy 68.61556 -299.52442) (xy 68.615306 -299.52442) (xy 68.604179 -299.522872)
			(xy 68.582439 -299.52842) (xy 68.573396 -299.535088) (xy 68.52285 -299.57649) (xy 68.514491 -299.584114)
			(xy 68.504879 -299.604559) (xy 68.504308 -299.61586) (xy 68.504308 -300.287944) (xy 68.504804 -300.297945)
			(xy 68.512471 -300.316421) (xy 68.526623 -300.330558) (xy 68.545106 -300.338206) (xy 68.555108 -300.338744)
			(xy 69.233034 -300.338744) (xy 69.244166 -300.338118) (xy 69.264318 -300.328634) (xy 69.271896 -300.320456)
			(xy 69.320918 -300.26229) (xy 69.326506 -300.240446) (xy 69.324474 -300.22927) (xy 69.322221 -300.215922)
			(xy 69.319808 -300.188958) (xy 69.319648 -300.175422) (xy 69.319648 -300.174914) (xy 69.32017 -300.149659)
			(xy 69.328483 -300.099837) (xy 69.344884 -300.052063) (xy 69.368925 -300.00764) (xy 69.399949 -299.96778)
			(xy 69.437111 -299.93357) (xy 69.479397 -299.905944) (xy 69.525653 -299.885654) (xy 69.574618 -299.873254)
			(xy 69.624956 -299.869083) (xy 69.675294 -299.873254) (xy 69.724259 -299.885654) (xy 69.770515 -299.905944)
			(xy 69.812801 -299.93357) (xy 69.849963 -299.96778) (xy 69.880987 -300.00764) (xy 69.905028 -300.052063)
			(xy 69.921429 -300.099837) (xy 69.929742 -300.149659) (xy 69.930264 -300.174914) (xy 70.269112 -300.174914)
			(xy 70.273072 -300.12586) (xy 70.284849 -300.078076) (xy 70.30414 -300.0328) (xy 70.330443 -299.991204)
			(xy 70.363078 -299.954367) (xy 70.401199 -299.923242) (xy 70.44382 -299.898635) (xy 70.489836 -299.881183)
			(xy 70.538055 -299.871339) (xy 70.58723 -299.869358) (xy 70.636085 -299.87529) (xy 70.683356 -299.888982)
			(xy 70.727818 -299.91008) (xy 70.768321 -299.938036) (xy 70.803814 -299.972128) (xy 70.833379 -300.011472)
			(xy 70.85625 -300.055049) (xy 70.871834 -300.10173) (xy 70.879729 -300.150307) (xy 70.880224 -300.174914)
			(xy 70.879729 -300.199521) (xy 70.871834 -300.248098) (xy 70.85625 -300.294779) (xy 70.833379 -300.338356)
			(xy 70.803814 -300.3777) (xy 70.768321 -300.411792) (xy 70.727818 -300.439748) (xy 70.683356 -300.460846)
			(xy 70.636085 -300.474538) (xy 70.58723 -300.48047) (xy 70.538055 -300.478489) (xy 70.489836 -300.468645)
			(xy 70.44382 -300.451193) (xy 70.401199 -300.426586) (xy 70.363078 -300.395461) (xy 70.330443 -300.358624)
			(xy 70.30414 -300.317028) (xy 70.284849 -300.271752) (xy 70.273072 -300.223968) (xy 70.269112 -300.174914)
			(xy 69.930264 -300.174914) (xy 69.929734 -300.200327) (xy 69.921272 -300.250443) (xy 69.904635 -300.298469)
			(xy 69.880281 -300.343081) (xy 69.864986 -300.363382) (xy 69.859775 -300.370604) (xy 69.854187 -300.387497)
			(xy 69.854064 -300.396402) (xy 69.854572 -300.411896) (xy 69.855322 -300.421493) (xy 69.863025 -300.439117)
			(xy 69.869558 -300.446186) (xy 70.178168 -300.754796) (xy 70.198228 -300.775822) (xy 70.231074 -300.823751)
			(xy 70.243446 -300.850046) (xy 70.248774 -300.86059) (xy 70.266904 -300.875695) (xy 70.278244 -300.879002)
			(xy 70.354698 -300.897036) (xy 70.37705 -300.891956) (xy 70.386194 -300.884844) (xy 70.406519 -300.869529)
			(xy 70.451195 -300.845162) (xy 70.499288 -300.82853) (xy 70.549472 -300.82009) (xy 70.574916 -300.819566)
			(xy 70.599311 -300.820044) (xy 70.647479 -300.827803) (xy 70.693802 -300.84312) (xy 70.737101 -300.865607)
			(xy 70.776274 -300.894691) (xy 70.810325 -300.929632) (xy 70.838389 -300.969542) (xy 70.84949 -300.99127)
			(xy 70.853808 -301.00016) (xy 70.868286 -301.013368) (xy 70.944232 -301.041054) (xy 70.95361 -301.043967)
			(xy 70.973213 -301.043175) (xy 70.982332 -301.03953) (xy 71.010591 -301.027311) (xy 71.069119 -301.008196)
			(xy 71.129331 -300.995335) (xy 71.190561 -300.988871) (xy 71.221346 -300.988476) (xy 71.222108 -300.988476)
			(xy 71.230714 -300.988129) (xy 71.246956 -300.98243) (xy 71.260418 -300.971704) (xy 71.265288 -300.9646)
			(xy 71.265288 -300.964346) (xy 71.278692 -300.943578) (xy 71.311118 -300.906273) (xy 71.349124 -300.874673)
			(xy 71.39172 -300.849601) (xy 71.437796 -300.831711) (xy 71.461884 -300.82617) (xy 71.472371 -300.823481)
			(xy 71.489853 -300.810746) (xy 71.50053 -300.791936) (xy 71.502016 -300.781212) (xy 71.505719 -300.747762)
			(xy 71.519826 -300.681955) (xy 71.541383 -300.618199) (xy 71.570108 -300.557335) (xy 71.605621 -300.500165)
			(xy 71.647454 -300.447444) (xy 71.670926 -300.423326) (xy 71.848726 -300.245526) (xy 71.874139 -300.220872)
			(xy 71.929875 -300.177204) (xy 71.990463 -300.140563) (xy 72.055021 -300.111484) (xy 72.122611 -300.090388)
			(xy 72.157336 -300.083474) (xy 72.169534 -300.080592) (xy 72.189108 -300.064989) (xy 72.194674 -300.053756)
			(xy 72.204269 -300.032662) (xy 72.228882 -299.993401) (xy 72.259141 -299.958306) (xy 72.294353 -299.928182)
			(xy 72.3138 -299.91558) (xy 72.320939 -299.910742) (xy 72.331712 -299.89729) (xy 72.337389 -299.881018)
			(xy 72.337676 -299.8724) (xy 72.337676 -299.795438) (xy 72.338213 -299.760474) (xy 72.3466 -299.691049)
			(xy 72.363199 -299.623118) (xy 72.375014 -299.590206) (xy 72.377933 -299.581125) (xy 72.377556 -299.562068)
			(xy 72.374252 -299.553122) (xy 72.362568 -299.524166) (xy 72.358701 -299.515897) (xy 72.346209 -299.502605)
			(xy 72.338184 -299.498258) (xy 72.316793 -299.487009) (xy 72.277547 -299.458805) (xy 72.243225 -299.424781)
			(xy 72.214681 -299.385782) (xy 72.192625 -299.34278) (xy 72.177606 -299.296844) (xy 72.169997 -299.249118)
			(xy 72.169528 -299.224954) (xy 72.170002 -299.200966) (xy 72.177514 -299.153582) (xy 72.192346 -299.107957)
			(xy 72.214133 -299.065213) (xy 72.242337 -299.026404) (xy 72.276266 -298.992484) (xy 72.315083 -298.96429)
			(xy 72.357832 -298.942515) (xy 72.403462 -298.927695) (xy 72.450848 -298.920196) (xy 72.474836 -298.919646)
			(xy 72.498838 -298.920096) (xy 72.54625 -298.927615) (xy 72.591901 -298.942463) (xy 72.634665 -298.964273)
			(xy 72.673488 -298.992507) (xy 72.707414 -299.02647) (xy 72.735605 -299.065325) (xy 72.74687 -299.086524)
			(xy 72.75139 -299.094508) (xy 72.764926 -299.106874) (xy 72.773286 -299.110654) (xy 72.802242 -299.122084)
			(xy 72.811238 -299.125236) (xy 72.830286 -299.125363) (xy 72.839326 -299.122338) (xy 72.873108 -299.109883)
			(xy 72.942945 -299.092365) (xy 73.0144 -299.083521) (xy 73.0504 -299.082968) (xy 73.12533 -299.082968)
			(xy 73.133815 -299.082657) (xy 73.149846 -299.077097) (xy 73.163156 -299.066573) (xy 73.168002 -299.0596)
			(xy 73.181848 -299.039047) (xy 73.215092 -299.002298) (xy 73.253825 -298.971387) (xy 73.297033 -298.947123)
			(xy 73.320148 -298.938188) (xy 73.329752 -298.934176) (xy 73.344888 -298.919919) (xy 73.353138 -298.900832)
			(xy 73.353676 -298.890436) (xy 73.353676 -298.609258) (xy 73.353189 -298.598848) (xy 73.344944 -298.579732)
			(xy 73.329787 -298.56546) (xy 73.320148 -298.561506) (xy 73.298406 -298.5531) (xy 73.257559 -298.530647)
			(xy 73.220598 -298.502248) (xy 73.18838 -298.468562) (xy 73.161655 -298.430373) (xy 73.141043 -298.388566)
			(xy 73.127023 -298.344113) (xy 73.119919 -298.298046) (xy 73.119488 -298.27474) (xy 73.120011 -298.249064)
			(xy 73.12859 -298.198434) (xy 73.145513 -298.149951) (xy 73.170303 -298.10498) (xy 73.202263 -298.064786)
			(xy 73.240494 -298.030502) (xy 73.283918 -298.003091) (xy 73.331314 -297.983327) (xy 73.356216 -297.977052)
			(xy 73.368261 -297.97362) (xy 73.387174 -297.957244) (xy 73.392284 -297.94581) (xy 73.403644 -297.917246)
			(xy 73.431527 -297.862456) (xy 73.464993 -297.810887) (xy 73.503675 -297.763105) (xy 73.525126 -297.741086)
			(xy 73.565004 -297.701208) (xy 73.571715 -297.693775) (xy 73.579342 -297.67528) (xy 73.579332 -297.655274)
			(xy 73.571689 -297.636786) (xy 73.565004 -297.629326) (xy 73.565004 -297.629072) (xy 73.55821 -297.622876)
			(xy 73.541439 -297.615373) (xy 73.523098 -297.614288) (xy 73.514204 -297.616626) (xy 73.492385 -297.622898)
			(xy 73.447494 -297.629664) (xy 73.424796 -297.630088) (xy 73.399977 -297.629602) (xy 73.350994 -297.621571)
			(xy 73.303954 -297.605721) (xy 73.260099 -297.58247) (xy 73.220583 -297.552431) (xy 73.186447 -297.516394)
			(xy 73.158591 -297.47531) (xy 73.137748 -297.43026) (xy 73.124469 -297.382432) (xy 73.119101 -297.333085)
			(xy 73.121788 -297.28352) (xy 73.132458 -297.235043) (xy 73.15083 -297.18893) (xy 73.17642 -297.146397)
			(xy 73.208553 -297.108565) (xy 73.246384 -297.076429) (xy 73.288916 -297.050837) (xy 73.335028 -297.032462)
			(xy 73.383504 -297.02179) (xy 73.433069 -297.019101) (xy 73.482416 -297.024466) (xy 73.530245 -297.037743)
			(xy 73.575296 -297.058583) (xy 73.616382 -297.086437) (xy 73.65242 -297.120571) (xy 73.682462 -297.160086)
			(xy 73.705715 -297.20394) (xy 73.721567 -297.250978) (xy 73.729601 -297.299961) (xy 73.730104 -297.32478)
			(xy 73.729667 -297.347478) (xy 73.722904 -297.392367) (xy 73.716642 -297.414188) (xy 73.714304 -297.423079)
			(xy 73.715412 -297.441415) (xy 73.722901 -297.458189) (xy 73.729088 -297.464988) (xy 73.729342 -297.464988)
			(xy 73.736708 -297.471828) (xy 73.755241 -297.47957) (xy 73.775325 -297.47957) (xy 73.793858 -297.471828)
			(xy 73.801224 -297.464988) (xy 73.880726 -297.385486) (xy 73.906281 -297.360643) (xy 73.962392 -297.316694)
			(xy 74.023422 -297.279879) (xy 74.055732 -297.264836) (xy 74.065452 -297.259979) (xy 74.079917 -297.243791)
			(xy 74.083672 -297.233594) (xy 74.091341 -297.210638) (xy 74.112901 -297.167307) (xy 74.141026 -297.12792)
			(xy 74.175012 -297.093463) (xy 74.214007 -297.064797) (xy 74.257036 -297.042642) (xy 74.303021 -297.027551)
			(xy 74.350811 -297.019903) (xy 74.37501 -297.019472) (xy 74.398998 -297.019943) (xy 74.446383 -297.027445)
			(xy 74.492013 -297.042264) (xy 74.534764 -297.064036) (xy 74.573586 -297.092223) (xy 74.607523 -297.126134)
			(xy 74.63574 -297.164934) (xy 74.647044 -297.186096) (xy 74.647044 -297.18635) (xy 74.651685 -297.194495)
			(xy 74.665635 -297.206995) (xy 74.683143 -297.21365) (xy 74.69251 -297.214036) (xy 75.00747 -297.214036)
			(xy 75.016836 -297.213654) (xy 75.03434 -297.206995) (xy 75.048277 -297.194485) (xy 75.052936 -297.18635)
			(xy 75.052936 -297.186096) (xy 75.064251 -297.164937) (xy 75.092459 -297.126127) (xy 75.126391 -297.092207)
			(xy 75.16521 -297.064011) (xy 75.207961 -297.042233) (xy 75.253593 -297.02741) (xy 75.300981 -297.019906)
			(xy 75.348959 -297.019906) (xy 75.396347 -297.02741) (xy 75.441979 -297.042233) (xy 75.48473 -297.064011)
			(xy 75.523549 -297.092207) (xy 75.557481 -297.126127) (xy 75.585689 -297.164937) (xy 75.597004 -297.186096)
			(xy 75.597004 -297.18635) (xy 75.601643 -297.1945) (xy 75.615591 -297.20701) (xy 75.633101 -297.213678)
			(xy 75.64247 -297.214036) (xy 75.95743 -297.214036) (xy 75.9668 -297.213661) (xy 75.984315 -297.207011)
			(xy 75.998263 -297.194503) (xy 76.002896 -297.18635) (xy 76.002896 -297.186096) (xy 76.014211 -297.164937)
			(xy 76.042419 -297.126127) (xy 76.076351 -297.092207) (xy 76.11517 -297.064011) (xy 76.157921 -297.042233)
			(xy 76.203553 -297.02741) (xy 76.250941 -297.019906) (xy 76.298919 -297.019906) (xy 76.346307 -297.02741)
			(xy 76.391939 -297.042233) (xy 76.43469 -297.064011) (xy 76.473509 -297.092207) (xy 76.507441 -297.126127)
			(xy 76.535649 -297.164937) (xy 76.546964 -297.186096) (xy 76.546964 -297.18635) (xy 76.551606 -297.194493)
			(xy 76.565557 -297.206987) (xy 76.583064 -297.213635) (xy 76.59243 -297.214036) (xy 76.90739 -297.214036)
			(xy 76.916764 -297.213667) (xy 76.93429 -297.207026) (xy 76.94825 -297.19452) (xy 76.952856 -297.18635)
			(xy 76.952856 -297.186096) (xy 76.964171 -297.164937) (xy 76.992379 -297.126127) (xy 77.026311 -297.092207)
			(xy 77.06513 -297.064011) (xy 77.107881 -297.042233) (xy 77.153513 -297.02741) (xy 77.200901 -297.019906)
			(xy 77.248879 -297.019906) (xy 77.296267 -297.02741) (xy 77.341899 -297.042233) (xy 77.38465 -297.064011)
			(xy 77.423469 -297.092207) (xy 77.457401 -297.126127) (xy 77.485609 -297.164937) (xy 77.496924 -297.186096)
			(xy 77.496924 -297.18635) (xy 77.501564 -297.194498) (xy 77.515513 -297.207002) (xy 77.533022 -297.213664)
			(xy 77.54239 -297.214036) (xy 77.85735 -297.214036) (xy 77.866718 -297.213657) (xy 77.884228 -297.207003)
			(xy 77.89817 -297.194494) (xy 77.902816 -297.18635) (xy 77.902816 -297.186096) (xy 77.914131 -297.164937)
			(xy 77.942339 -297.126127) (xy 77.976271 -297.092207) (xy 78.01509 -297.064011) (xy 78.057841 -297.042233)
			(xy 78.103473 -297.02741) (xy 78.150861 -297.019906) (xy 78.198839 -297.019906) (xy 78.246227 -297.02741)
			(xy 78.291859 -297.042233) (xy 78.33461 -297.064011) (xy 78.373429 -297.092207) (xy 78.407361 -297.126127)
			(xy 78.435569 -297.164937) (xy 78.446884 -297.186096) (xy 78.446884 -297.18635) (xy 78.451522 -297.194502)
			(xy 78.465469 -297.207017) (xy 78.482979 -297.213692) (xy 78.49235 -297.214036) (xy 78.80731 -297.214036)
			(xy 78.816682 -297.213664) (xy 78.834203 -297.207019) (xy 78.848157 -297.194512) (xy 78.852776 -297.18635)
			(xy 78.852776 -297.186096) (xy 78.864091 -297.164937) (xy 78.892299 -297.126127) (xy 78.926231 -297.092207)
			(xy 78.96505 -297.064011) (xy 79.007801 -297.042233) (xy 79.053433 -297.02741) (xy 79.100821 -297.019906)
			(xy 79.148799 -297.019906) (xy 79.196187 -297.02741) (xy 79.241819 -297.042233) (xy 79.28457 -297.064011)
			(xy 79.323389 -297.092207) (xy 79.357321 -297.126127) (xy 79.385529 -297.164937) (xy 79.396844 -297.186096)
			(xy 79.396844 -297.18635) (xy 79.401485 -297.194495) (xy 79.415435 -297.206995) (xy 79.432943 -297.21365)
			(xy 79.44231 -297.214036) (xy 79.75727 -297.214036) (xy 79.766636 -297.213654) (xy 79.78414 -297.206995)
			(xy 79.798077 -297.194485) (xy 79.802736 -297.18635) (xy 79.802736 -297.186096) (xy 79.814051 -297.164937)
			(xy 79.842259 -297.126127) (xy 79.876191 -297.092207) (xy 79.91501 -297.064011) (xy 79.957761 -297.042233)
			(xy 80.003393 -297.02741) (xy 80.050781 -297.019906) (xy 80.098759 -297.019906) (xy 80.146147 -297.02741)
			(xy 80.191779 -297.042233) (xy 80.23453 -297.064011) (xy 80.273349 -297.092207) (xy 80.307281 -297.126127)
			(xy 80.335489 -297.164937) (xy 80.346804 -297.186096) (xy 80.346804 -297.18635) (xy 80.351443 -297.1945)
			(xy 80.365391 -297.20701) (xy 80.382901 -297.213678) (xy 80.39227 -297.214036) (xy 80.707484 -297.214036)
			(xy 80.716858 -297.213668) (xy 80.734386 -297.207029) (xy 80.748348 -297.194523) (xy 80.75295 -297.18635)
			(xy 80.75295 -297.186096) (xy 80.764265 -297.164937) (xy 80.792473 -297.126127) (xy 80.826405 -297.092207)
			(xy 80.865224 -297.064011) (xy 80.907975 -297.042233) (xy 80.953607 -297.02741) (xy 81.000995 -297.019906)
			(xy 81.048973 -297.019906) (xy 81.096361 -297.02741) (xy 81.141993 -297.042233) (xy 81.184744 -297.064011)
			(xy 81.223563 -297.092207) (xy 81.257495 -297.126127) (xy 81.285703 -297.164937) (xy 81.297018 -297.186096)
			(xy 81.297018 -297.18635) (xy 81.301658 -297.194498) (xy 81.315606 -297.207004) (xy 81.333115 -297.213668)
			(xy 81.342484 -297.214036) (xy 81.657444 -297.214036) (xy 81.666812 -297.213658) (xy 81.684324 -297.207006)
			(xy 81.698268 -297.194497) (xy 81.70291 -297.18635) (xy 81.70291 -297.186096) (xy 81.714225 -297.164937)
			(xy 81.742433 -297.126127) (xy 81.776365 -297.092207) (xy 81.815184 -297.064011) (xy 81.857935 -297.042233)
			(xy 81.903567 -297.02741) (xy 81.950955 -297.019906) (xy 81.998933 -297.019906) (xy 82.046321 -297.02741)
			(xy 82.091953 -297.042233) (xy 82.134704 -297.064011) (xy 82.173523 -297.092207) (xy 82.207455 -297.126127)
			(xy 82.235663 -297.164937) (xy 82.246978 -297.186096) (xy 82.246978 -297.18635) (xy 82.251621 -297.194492)
			(xy 82.265572 -297.206981) (xy 82.283079 -297.213625) (xy 82.292444 -297.214036) (xy 82.607404 -297.214036)
			(xy 82.616776 -297.213665) (xy 82.634299 -297.207021) (xy 82.648255 -297.194514) (xy 82.65287 -297.18635)
			(xy 82.65287 -297.186096) (xy 82.664162 -297.164925) (xy 82.692371 -297.126112) (xy 82.726305 -297.092192)
			(xy 82.765128 -297.063998) (xy 82.807885 -297.042227) (xy 82.853521 -297.027413) (xy 82.900914 -297.019922)
			(xy 82.924904 -297.019472) (xy 82.925158 -297.019472) (xy 82.941936 -297.019689) (xy 82.975288 -297.023378)
			(xy 82.991706 -297.026838) (xy 83.004406 -297.029632) (xy 83.029298 -297.02252) (xy 83.172046 -296.879772)
			(xy 83.178894 -296.872374) (xy 83.186626 -296.853776) (xy 83.187032 -296.843704) (xy 83.187032 -296.748708)
			(xy 83.186357 -296.736066) (xy 83.174356 -296.713813) (xy 83.164172 -296.70629) (xy 83.093052 -296.659554)
			(xy 83.082187 -296.653189) (xy 83.057139 -296.650941) (xy 83.0453 -296.655236) (xy 83.026205 -296.663074)
			(xy 82.986436 -296.674129) (xy 82.945542 -296.679742) (xy 82.924904 -296.680128) (xy 82.899644 -296.679636)
			(xy 82.849814 -296.671321) (xy 82.802032 -296.654918) (xy 82.757602 -296.630874) (xy 82.717735 -296.599845)
			(xy 82.683519 -296.562677) (xy 82.655887 -296.520384) (xy 82.635594 -296.47412) (xy 82.623192 -296.425147)
			(xy 82.61902 -296.3748) (xy 82.623192 -296.324453) (xy 82.635594 -296.27548) (xy 82.655887 -296.229216)
			(xy 82.683519 -296.186923) (xy 82.717735 -296.149755) (xy 82.757602 -296.118726) (xy 82.802032 -296.094682)
			(xy 82.849814 -296.078279) (xy 82.899644 -296.069964) (xy 82.924904 -296.069512) (xy 82.945544 -296.06987)
			(xy 82.986441 -296.075476) (xy 83.026206 -296.086558) (xy 83.0453 -296.094404) (xy 83.057238 -296.099484)
			(xy 83.082384 -296.097198) (xy 83.164172 -296.04335) (xy 83.174359 -296.035832) (xy 83.186357 -296.013574)
			(xy 83.187032 -296.000932) (xy 83.187032 -294.848788) (xy 83.186353 -294.836149) (xy 83.174346 -294.813903)
			(xy 83.164172 -294.80637) (xy 83.093052 -294.759634) (xy 83.082187 -294.753271) (xy 83.05714 -294.751024)
			(xy 83.0453 -294.755316) (xy 83.026205 -294.763155) (xy 82.986436 -294.77421) (xy 82.945542 -294.779823)
			(xy 82.924904 -294.780208) (xy 82.899646 -294.779716) (xy 82.849819 -294.771402) (xy 82.80204 -294.755)
			(xy 82.757613 -294.730957) (xy 82.717748 -294.69993) (xy 82.683535 -294.662764) (xy 82.655905 -294.620474)
			(xy 82.635613 -294.574213) (xy 82.623212 -294.525243) (xy 82.61904 -294.4749) (xy 82.623212 -294.424557)
			(xy 82.635613 -294.375587) (xy 82.655905 -294.329326) (xy 82.683535 -294.287036) (xy 82.717748 -294.24987)
			(xy 82.757613 -294.218843) (xy 82.80204 -294.1948) (xy 82.849819 -294.178398) (xy 82.899646 -294.170084)
			(xy 82.924904 -294.169592) (xy 82.945544 -294.16995) (xy 82.986441 -294.175558) (xy 83.026204 -294.186643)
			(xy 83.0453 -294.194484) (xy 83.057238 -294.199564) (xy 83.082384 -294.197278) (xy 83.164172 -294.14343)
			(xy 83.174356 -294.135911) (xy 83.186345 -294.113653) (xy 83.187032 -294.101012) (xy 83.187032 -293.898828)
			(xy 83.186362 -293.886184) (xy 83.174365 -293.863923) (xy 83.164172 -293.85641) (xy 83.093052 -293.809674)
			(xy 83.082185 -293.803317) (xy 83.057141 -293.801072) (xy 83.0453 -293.805356) (xy 83.026205 -293.813194)
			(xy 82.986436 -293.824248) (xy 82.945542 -293.82986) (xy 82.924904 -293.830248) (xy 82.899643 -293.829756)
			(xy 82.849809 -293.82144) (xy 82.802024 -293.805036) (xy 82.757591 -293.780991) (xy 82.717721 -293.749959)
			(xy 82.683503 -293.712789) (xy 82.65587 -293.670493) (xy 82.635575 -293.624226) (xy 82.623172 -293.57525)
			(xy 82.619 -293.5249) (xy 82.623172 -293.47455) (xy 82.635575 -293.425574) (xy 82.65587 -293.379307)
			(xy 82.683503 -293.337011) (xy 82.717721 -293.299841) (xy 82.757591 -293.268809) (xy 82.802024 -293.244764)
			(xy 82.849809 -293.22836) (xy 82.899643 -293.220044) (xy 82.924904 -293.219632) (xy 82.945544 -293.21999)
			(xy 82.986441 -293.225597) (xy 83.026205 -293.236679) (xy 83.0453 -293.244524) (xy 83.057238 -293.249604)
			(xy 83.082384 -293.247318) (xy 83.164172 -293.19347) (xy 83.174363 -293.185954) (xy 83.186369 -293.163696)
			(xy 83.187032 -293.151052) (xy 83.187032 -292.948868) (xy 83.186348 -292.936231) (xy 83.174337 -292.913993)
			(xy 83.164172 -292.90645) (xy 83.093052 -292.859714) (xy 83.082186 -292.853353) (xy 83.05714 -292.851107)
			(xy 83.0453 -292.855396) (xy 83.026205 -292.863235) (xy 82.986436 -292.874291) (xy 82.945542 -292.879904)
			(xy 82.924904 -292.880288) (xy 82.899648 -292.879796) (xy 82.849824 -292.871482) (xy 82.802048 -292.855081)
			(xy 82.757623 -292.83104) (xy 82.717762 -292.800015) (xy 82.68355 -292.762852) (xy 82.655922 -292.720565)
			(xy 82.635632 -292.674307) (xy 82.623231 -292.62534) (xy 82.61906 -292.575) (xy 82.623231 -292.52466)
			(xy 82.635632 -292.475693) (xy 82.655922 -292.429435) (xy 82.68355 -292.387148) (xy 82.717762 -292.349985)
			(xy 82.757623 -292.31896) (xy 82.802048 -292.294919) (xy 82.849824 -292.278518) (xy 82.899648 -292.270204)
			(xy 82.924904 -292.269672) (xy 82.945544 -292.27003) (xy 82.986441 -292.275638) (xy 83.026205 -292.286722)
			(xy 83.0453 -292.294564) (xy 83.057238 -292.299644) (xy 83.082384 -292.297358) (xy 83.164172 -292.24351)
			(xy 83.174352 -292.23599) (xy 83.186333 -292.213731) (xy 83.187032 -292.201092) (xy 83.187032 -291.998654)
			(xy 83.186367 -291.986006) (xy 83.174376 -291.963736) (xy 83.164172 -291.956236) (xy 83.093052 -291.9095)
			(xy 83.082186 -291.90314) (xy 83.05714 -291.900895) (xy 83.0453 -291.905182) (xy 83.026205 -291.913021)
			(xy 82.986436 -291.924078) (xy 82.945542 -291.929691) (xy 82.924904 -291.930074) (xy 82.899649 -291.929582)
			(xy 82.849827 -291.921269) (xy 82.802054 -291.904868) (xy 82.757631 -291.880829) (xy 82.717771 -291.849805)
			(xy 82.683561 -291.812644) (xy 82.655935 -291.770358) (xy 82.635645 -291.724102) (xy 82.623245 -291.675138)
			(xy 82.619074 -291.6248) (xy 82.623245 -291.574462) (xy 82.635645 -291.525498) (xy 82.655935 -291.479242)
			(xy 82.683561 -291.436956) (xy 82.717771 -291.399795) (xy 82.757631 -291.368771) (xy 82.802054 -291.344732)
			(xy 82.849827 -291.328331) (xy 82.899649 -291.320018) (xy 82.924904 -291.319458) (xy 82.945544 -291.319816)
			(xy 82.986441 -291.325423) (xy 83.026205 -291.336507) (xy 83.0453 -291.34435) (xy 83.057238 -291.34943)
			(xy 83.082384 -291.347144) (xy 83.164172 -291.293296) (xy 83.17435 -291.285775) (xy 83.186325 -291.263516)
			(xy 83.187032 -291.250878) (xy 83.187032 -291.048694) (xy 83.186354 -291.036054) (xy 83.174349 -291.013806)
			(xy 83.164172 -291.006276) (xy 83.093052 -290.95954) (xy 83.082187 -290.953177) (xy 83.057139 -290.950929)
			(xy 83.0453 -290.955222) (xy 83.026205 -290.96306) (xy 82.986436 -290.974116) (xy 82.945542 -290.979728)
			(xy 82.924904 -290.980114) (xy 82.899646 -290.979622) (xy 82.849818 -290.971307) (xy 82.802038 -290.954905)
			(xy 82.757609 -290.930862) (xy 82.717744 -290.899834) (xy 82.68353 -290.862668) (xy 82.655899 -290.820377)
			(xy 82.635607 -290.774115) (xy 82.623206 -290.725144) (xy 82.619034 -290.6748) (xy 82.623206 -290.624456)
			(xy 82.635607 -290.575485) (xy 82.655899 -290.529223) (xy 82.68353 -290.486932) (xy 82.717744 -290.449766)
			(xy 82.757609 -290.418738) (xy 82.802038 -290.394695) (xy 82.849818 -290.378293) (xy 82.899646 -290.369978)
			(xy 82.924904 -290.369498) (xy 82.945544 -290.369856) (xy 82.986441 -290.375462) (xy 83.026206 -290.386544)
			(xy 83.0453 -290.39439) (xy 83.057238 -290.39947) (xy 83.082384 -290.397184) (xy 83.164172 -290.343336)
			(xy 83.174357 -290.335817) (xy 83.186349 -290.313559) (xy 83.187032 -290.300918) (xy 83.187032 -290.098734)
			(xy 83.186363 -290.086089) (xy 83.174367 -290.063826) (xy 83.164172 -290.056316) (xy 83.093052 -290.00958)
			(xy 83.082185 -290.003222) (xy 83.057141 -290.000978) (xy 83.0453 -290.005262) (xy 83.026205 -290.0131)
			(xy 82.986436 -290.024154) (xy 82.945542 -290.029766) (xy 82.924904 -290.030154) (xy 82.899642 -290.029661)
			(xy 82.849808 -290.021346) (xy 82.802022 -290.004942) (xy 82.757587 -289.980896) (xy 82.717717 -289.949864)
			(xy 82.683498 -289.912693) (xy 82.655864 -289.870396) (xy 82.635569 -289.824128) (xy 82.623166 -289.775151)
			(xy 82.618994 -289.7248) (xy 82.623166 -289.674449) (xy 82.635569 -289.625472) (xy 82.655864 -289.579204)
			(xy 82.683498 -289.536907) (xy 82.717717 -289.499736) (xy 82.757587 -289.468704) (xy 82.802022 -289.444658)
			(xy 82.849808 -289.428254) (xy 82.899642 -289.419939) (xy 82.924904 -289.419538) (xy 82.945544 -289.419896)
			(xy 82.986441 -289.425503) (xy 83.026205 -289.436586) (xy 83.0453 -289.44443) (xy 83.057238 -289.44951)
			(xy 83.082384 -289.447224) (xy 83.164172 -289.393376) (xy 83.174364 -289.38586) (xy 83.186373 -289.363603)
			(xy 83.187032 -289.350958) (xy 83.187032 -289.310826) (xy 83.17357 -289.287712) (xy 83.164426 -289.282378)
			(xy 83.163156 -289.281616) (xy 83.159823 -289.279736) (xy 83.153696 -289.275151) (xy 83.150964 -289.272472)
			(xy 82.972402 -289.09391) (xy 82.963258 -289.086798) (xy 82.959702 -289.08502) (xy 82.947002 -289.07994)
			(xy 82.93735 -289.07994) (xy 82.924904 -289.080194) (xy 82.924396 -289.080194) (xy 82.900858 -289.079736)
			(xy 82.854347 -289.072465) (xy 82.809502 -289.058143) (xy 82.767385 -289.037109) (xy 82.728996 -289.009862)
			(xy 82.695242 -288.977046) (xy 82.666925 -288.939439) (xy 82.65541 -288.918904) (xy 82.648806 -288.906458)
			(xy 82.62493 -288.89198) (xy 82.274664 -288.89198) (xy 82.250788 -288.906458) (xy 82.244184 -288.918904)
			(xy 82.232691 -288.939476) (xy 82.204353 -288.977124) (xy 82.170566 -289.00997) (xy 82.132132 -289.037233)
			(xy 82.089966 -289.058266) (xy 82.045068 -289.072569) (xy 81.998505 -289.079802) (xy 81.974944 -289.080194)
			(xy 81.97469 -289.080194) (xy 81.951132 -289.079757) (xy 81.904576 -289.072519) (xy 81.859683 -289.058217)
			(xy 81.81752 -289.03719) (xy 81.779086 -289.009937) (xy 81.745294 -288.977104) (xy 81.716945 -288.939471)
			(xy 81.70545 -288.918904) (xy 81.698846 -288.906458) (xy 81.67497 -288.89198) (xy 81.345024 -288.89198)
			(xy 81.333605 -288.892438) (xy 81.312973 -288.902217) (xy 81.3054 -288.910776) (xy 81.285842 -288.934398)
			(xy 81.281778 -288.939986) (xy 81.269707 -288.958091) (xy 81.24125 -288.991009) (xy 81.208403 -289.019549)
			(xy 81.190338 -289.03168) (xy 81.18475 -289.035744) (xy 81.151697 -289.063659) (xy 81.081443 -289.11416)
			(xy 81.006976 -289.158214) (xy 80.928888 -289.195473) (xy 80.847796 -289.225641) (xy 80.764343 -289.248481)
			(xy 80.67919 -289.263809) (xy 80.593011 -289.271506) (xy 80.54975 -289.271964) (xy 80.28432 -289.271964)
			(xy 80.234169 -289.271352) (xy 80.134399 -289.261049) (xy 80.085184 -289.25139) (xy 80.080019 -289.250443)
			(xy 80.069521 -289.250443) (xy 80.064356 -289.25139) (xy 80.015139 -289.261039) (xy 79.91537 -289.271347)
			(xy 79.86522 -289.271964) (xy 79.59979 -289.271964) (xy 79.556531 -289.271478) (xy 79.470357 -289.263765)
			(xy 79.385209 -289.248427) (xy 79.301761 -289.225585) (xy 79.220671 -289.19542) (xy 79.142582 -289.158172)
			(xy 79.068111 -289.114133) (xy 78.997846 -289.063653) (xy 78.96479 -289.035744) (xy 78.959202 -289.03168)
			(xy 78.93511 -289.015305) (xy 78.893035 -288.975032) (xy 78.875636 -288.95167) (xy 78.867762 -288.94024)
			(xy 78.863698 -288.934398) (xy 78.835334 -288.900711) (xy 78.784131 -288.829054) (xy 78.739619 -288.753061)
			(xy 78.720442 -288.713418) (xy 78.716408 -288.705781) (xy 78.704201 -288.693579) (xy 78.696566 -288.689542)
			(xy 78.65872 -288.669984) (xy 78.657958 -288.669476) (xy 78.654402 -288.667698) (xy 78.641702 -288.66211)
			(xy 78.63713 -288.661094) (xy 78.628494 -288.661348) (xy 78.624107 -288.661697) (xy 78.615547 -288.66374)
			(xy 78.611476 -288.665412) (xy 78.584806 -288.681414) (xy 78.584298 -288.681414) (xy 78.524862 -288.718244)
			(xy 78.521373 -288.721126) (xy 78.515367 -288.727897) (xy 78.512924 -288.731706) (xy 78.511146 -288.735008)
			(xy 78.509622 -288.738056) (xy 78.507332 -288.743482) (xy 78.505018 -288.755027) (xy 78.50505 -288.760916)
			(xy 78.505304 -288.763964) (xy 78.505558 -288.773108) (xy 78.505558 -288.774886) (xy 78.50505 -288.800881)
			(xy 78.496923 -288.852232) (xy 78.480866 -288.90168) (xy 78.457275 -288.94801) (xy 78.42673 -288.990081)
			(xy 78.389982 -289.026858) (xy 78.347935 -289.057437) (xy 78.301625 -289.081065) (xy 78.252189 -289.097161)
			(xy 78.200845 -289.105329) (xy 78.17485 -289.105848) (xy 77.224636 -289.105848) (xy 77.198625 -289.105367)
			(xy 77.147244 -289.097234) (xy 77.097767 -289.081163) (xy 77.051415 -289.057548) (xy 77.009327 -289.026973)
			(xy 76.972541 -288.99019) (xy 76.941963 -288.948104) (xy 76.918346 -288.901753) (xy 76.902271 -288.852278)
			(xy 76.894134 -288.800897) (xy 76.893674 -288.774886) (xy 76.893863 -288.759811) (xy 76.896664 -288.729792)
			(xy 76.899262 -288.714942) (xy 76.899262 -288.713926) (xy 76.900278 -288.708592) (xy 76.893166 -288.685986)
			(xy 76.820268 -288.609786) (xy 76.797916 -288.601658) (xy 76.785978 -288.603182) (xy 76.776994 -288.604163)
			(xy 76.758948 -288.605177) (xy 76.74991 -288.605214) (xy 76.725088 -288.604729) (xy 76.676099 -288.596699)
			(xy 76.629054 -288.580849) (xy 76.585193 -288.557597) (xy 76.545671 -288.527555) (xy 76.511531 -288.491515)
			(xy 76.483671 -288.450427) (xy 76.462825 -288.405372) (xy 76.449543 -288.357539) (xy 76.444175 -288.308187)
			(xy 76.446862 -288.258616) (xy 76.457533 -288.210133) (xy 76.475908 -288.164016) (xy 76.501501 -288.121478)
			(xy 76.533639 -288.083642) (xy 76.571475 -288.051503) (xy 76.614012 -288.02591) (xy 76.66013 -288.007535)
			(xy 76.708612 -287.996863) (xy 76.758183 -287.994175) (xy 76.807535 -287.999543) (xy 76.855369 -288.012824)
			(xy 76.900423 -288.033669) (xy 76.941512 -288.061528) (xy 76.977553 -288.095668) (xy 77.007595 -288.135189)
			(xy 77.030848 -288.17905) (xy 77.046698 -288.226095) (xy 77.054729 -288.275084) (xy 77.055218 -288.299906)
			(xy 77.055178 -288.309007) (xy 77.054161 -288.32718) (xy 77.053186 -288.336228) (xy 77.051662 -288.348166)
			(xy 77.05979 -288.370518) (xy 77.135736 -288.443416) (xy 77.158342 -288.450528) (xy 77.162914 -288.449766)
			(xy 77.178198 -288.44703) (xy 77.20911 -288.444103) (xy 77.224636 -288.443924) (xy 77.295248 -288.443924)
			(xy 77.305938 -288.443357) (xy 77.325489 -288.434695) (xy 77.333094 -288.42716) (xy 77.38364 -288.371026)
			(xy 77.390422 -288.362804) (xy 77.396992 -288.342549) (xy 77.39634 -288.33191) (xy 77.39634 -288.331656)
			(xy 77.394562 -288.299906) (xy 77.395032 -288.275914) (xy 77.402537 -288.228519) (xy 77.417364 -288.182883)
			(xy 77.439147 -288.140127) (xy 77.467349 -288.101305) (xy 77.501278 -288.067373) (xy 77.540096 -288.039165)
			(xy 77.582849 -288.017378) (xy 77.628484 -288.002546) (xy 77.675878 -287.995035) (xy 77.69987 -287.994598)
			(xy 77.713984 -287.994721) (xy 77.742097 -287.997268) (xy 77.756004 -287.999678) (xy 77.768196 -288.001964)
			(xy 77.792326 -287.994598) (xy 77.869288 -287.917636) (xy 77.876654 -287.893506) (xy 77.874368 -287.881314)
			(xy 77.872336 -287.86836) (xy 77.870558 -287.855406) (xy 77.869034 -287.824926) (xy 77.869241 -287.808996)
			(xy 77.872549 -287.777309) (xy 77.875638 -287.76168) (xy 77.875638 -287.760664) (xy 77.876654 -287.756346)
			(xy 77.869034 -287.732216) (xy 77.792326 -287.655254) (xy 77.768196 -287.647888) (xy 77.75575 -287.650174)
			(xy 77.741904 -287.652564) (xy 77.71392 -287.655109) (xy 77.69987 -287.655254) (xy 77.675879 -287.654781)
			(xy 77.628488 -287.647272) (xy 77.582855 -287.632442) (xy 77.540103 -287.610658) (xy 77.501285 -287.582455)
			(xy 77.467356 -287.548527) (xy 77.439151 -287.50971) (xy 77.417364 -287.46696) (xy 77.402532 -287.421327)
			(xy 77.39502 -287.373937) (xy 77.394562 -287.349946) (xy 77.39634 -287.317942) (xy 77.39634 -287.317434)
			(xy 77.397356 -287.30702) (xy 77.390752 -287.2867) (xy 77.333094 -287.222184) (xy 77.325579 -287.21452)
			(xy 77.305974 -287.205831) (xy 77.295248 -287.20542) (xy 77.224636 -287.20542) (xy 77.20937 -287.205262)
			(xy 77.178968 -287.202463) (xy 77.16393 -287.199832) (xy 77.162406 -287.199578) (xy 77.158342 -287.198816)
			(xy 77.135736 -287.205928) (xy 77.059536 -287.27908) (xy 77.051408 -287.301432) (xy 77.052932 -287.31337)
			(xy 77.053987 -287.322477) (xy 77.055132 -287.340778) (xy 77.055218 -287.349946) (xy 77.054728 -287.374767)
			(xy 77.04669 -287.423754) (xy 77.030833 -287.470795) (xy 77.007574 -287.514651) (xy 76.977526 -287.554167)
			(xy 76.941482 -287.588301) (xy 76.90039 -287.616154) (xy 76.855334 -287.636993) (xy 76.807499 -287.650268)
			(xy 76.758148 -287.65563) (xy 76.708579 -287.652937) (xy 76.660098 -287.64226) (xy 76.613984 -287.623881)
			(xy 76.57145 -287.598284) (xy 76.533618 -287.566142) (xy 76.501484 -287.528304) (xy 76.475894 -287.485766)
			(xy 76.457524 -287.439648) (xy 76.446856 -287.391166) (xy 76.444172 -287.341596) (xy 76.449542 -287.292245)
			(xy 76.462826 -287.244414) (xy 76.483673 -287.199361) (xy 76.511534 -287.158274) (xy 76.545675 -287.122236)
			(xy 76.585196 -287.092196) (xy 76.629056 -287.068945) (xy 76.676101 -287.053096) (xy 76.725089 -287.045067)
			(xy 76.74991 -287.044638) (xy 76.758951 -287.044743) (xy 76.776996 -287.045888) (xy 76.785978 -287.046924)
			(xy 76.786486 -287.046924) (xy 76.79817 -287.048194) (xy 76.820522 -287.040066) (xy 76.89342 -286.963866)
			(xy 76.900278 -286.94126) (xy 76.899262 -286.934402) (xy 76.896743 -286.919609) (xy 76.894072 -286.889717)
			(xy 76.893928 -286.874712) (xy 76.894087 -286.859446) (xy 76.896889 -286.829045) (xy 76.899516 -286.814006)
			(xy 76.89977 -286.812482) (xy 76.900532 -286.808418) (xy 76.89342 -286.785812) (xy 76.820522 -286.709866)
			(xy 76.79817 -286.701738) (xy 76.786232 -286.703262) (xy 76.777185 -286.70425) (xy 76.759011 -286.705266)
			(xy 76.74991 -286.705294) (xy 76.72509 -286.704809) (xy 76.676105 -286.69678) (xy 76.629063 -286.680932)
			(xy 76.585206 -286.657682) (xy 76.545687 -286.627643) (xy 76.511549 -286.591606) (xy 76.483691 -286.550521)
			(xy 76.462846 -286.50547) (xy 76.449564 -286.457641) (xy 76.444195 -286.408293) (xy 76.446881 -286.358726)
			(xy 76.45755 -286.310247) (xy 76.475922 -286.264132) (xy 76.501512 -286.221598) (xy 76.533646 -286.183763)
			(xy 76.571478 -286.151626) (xy 76.614011 -286.126032) (xy 76.660124 -286.107657) (xy 76.708602 -286.096984)
			(xy 76.758169 -286.094295) (xy 76.807517 -286.09966) (xy 76.855348 -286.112938) (xy 76.9004 -286.133779)
			(xy 76.941487 -286.161634) (xy 76.977526 -286.195769) (xy 77.007569 -286.235285) (xy 77.030822 -286.279141)
			(xy 77.046674 -286.326181) (xy 77.054707 -286.375166) (xy 77.055218 -286.399986) (xy 77.055179 -286.409087)
			(xy 77.054163 -286.42726) (xy 77.053186 -286.436308) (xy 77.051662 -286.448246) (xy 77.05979 -286.470598)
			(xy 77.135736 -286.543496) (xy 77.158342 -286.550608) (xy 77.163168 -286.549846) (xy 77.178388 -286.547117)
			(xy 77.209174 -286.544189) (xy 77.224636 -286.544004) (xy 77.295248 -286.544004) (xy 77.305938 -286.543436)
			(xy 77.325486 -286.534771) (xy 77.333094 -286.52724) (xy 77.38364 -286.471106) (xy 77.390419 -286.462884)
			(xy 77.396981 -286.442629) (xy 77.39634 -286.43199) (xy 77.39634 -286.431736) (xy 77.394562 -286.399986)
			(xy 77.395034 -286.375995) (xy 77.402541 -286.328603) (xy 77.41737 -286.282969) (xy 77.439153 -286.240216)
			(xy 77.467356 -286.201397) (xy 77.501285 -286.167467) (xy 77.540102 -286.139262) (xy 77.582854 -286.117476)
			(xy 77.628487 -286.102645) (xy 77.675879 -286.095135) (xy 77.69987 -286.094678) (xy 77.713925 -286.094885)
			(xy 77.74191 -286.097555) (xy 77.75575 -286.100012) (xy 77.756258 -286.100012) (xy 77.768491 -286.101509)
			(xy 77.791987 -286.094209) (xy 77.801216 -286.086042) (xy 77.869542 -286.017462) (xy 77.876908 -285.99384)
			(xy 77.875638 -285.986728) (xy 77.871787 -285.966318) (xy 77.868978 -285.924879) (xy 77.871792 -285.883441)
			(xy 77.875638 -285.86303) (xy 77.875638 -285.862014) (xy 77.876908 -285.855918) (xy 77.869542 -285.832296)
			(xy 77.79258 -285.75508) (xy 77.76845 -285.747714) (xy 77.756004 -285.75) (xy 77.742095 -285.7524)
			(xy 77.713984 -285.754947) (xy 77.69987 -285.75508) (xy 77.675881 -285.754607) (xy 77.628495 -285.747097)
			(xy 77.582866 -285.732267) (xy 77.54012 -285.710481) (xy 77.501308 -285.682277) (xy 77.467386 -285.648348)
			(xy 77.439189 -285.60953) (xy 77.417411 -285.56678) (xy 77.402589 -285.521149) (xy 77.395088 -285.473761)
			(xy 77.394562 -285.449772) (xy 77.39634 -285.418022) (xy 77.39634 -285.417514) (xy 77.396856 -285.406893)
			(xy 77.390296 -285.386691) (xy 77.38364 -285.378398) (xy 77.333094 -285.322264) (xy 77.325578 -285.314602)
			(xy 77.305973 -285.305916) (xy 77.295248 -285.3055) (xy 77.224636 -285.3055) (xy 77.20937 -285.305342)
			(xy 77.178968 -285.302543) (xy 77.16393 -285.299912) (xy 77.162406 -285.299658) (xy 77.158342 -285.298896)
			(xy 77.135736 -285.306008) (xy 77.068172 -285.370778) (xy 77.060179 -285.379308) (xy 77.052248 -285.401271)
			(xy 77.052932 -285.412942) (xy 77.052932 -285.41345) (xy 77.053981 -285.422494) (xy 77.055127 -285.440668)
			(xy 77.055218 -285.449772) (xy 77.054734 -285.474594) (xy 77.046707 -285.523586) (xy 77.030859 -285.570633)
			(xy 77.007609 -285.614496) (xy 76.977568 -285.65402) (xy 76.941529 -285.688164) (xy 76.90044 -285.716026)
			(xy 76.855385 -285.736874) (xy 76.807551 -285.750158) (xy 76.758198 -285.755528) (xy 76.708626 -285.752843)
			(xy 76.660141 -285.742173) (xy 76.614022 -285.7238) (xy 76.571482 -285.698207) (xy 76.533644 -285.666069)
			(xy 76.501504 -285.628232) (xy 76.475908 -285.585694) (xy 76.457532 -285.539576) (xy 76.446859 -285.491092)
			(xy 76.444171 -285.44152) (xy 76.449538 -285.392167) (xy 76.46282 -285.344332) (xy 76.483665 -285.299276)
			(xy 76.511525 -285.258185) (xy 76.545666 -285.222144) (xy 76.585188 -285.192101) (xy 76.629051 -285.168848)
			(xy 76.676097 -285.152997) (xy 76.725088 -285.144967) (xy 76.74991 -285.144464) (xy 76.759011 -285.144504)
			(xy 76.777184 -285.145521) (xy 76.786232 -285.146496) (xy 76.79817 -285.14802) (xy 76.820522 -285.139892)
			(xy 76.89342 -285.063692) (xy 76.900532 -285.041086) (xy 76.899516 -285.03499) (xy 76.896922 -285.020075)
			(xy 76.894125 -284.989929) (xy 76.893928 -284.974792) (xy 76.894123 -284.959781) (xy 76.896918 -284.929888)
			(xy 76.899516 -284.915102) (xy 76.899516 -284.914086) (xy 76.900532 -284.908498) (xy 76.89342 -284.885892)
			(xy 76.820522 -284.809692) (xy 76.79817 -284.801564) (xy 76.786232 -284.803088) (xy 76.777185 -284.804077)
			(xy 76.759011 -284.805092) (xy 76.74991 -284.80512) (xy 76.725088 -284.804635) (xy 76.676097 -284.796605)
			(xy 76.629051 -284.780755) (xy 76.585189 -284.757502) (xy 76.545667 -284.727459) (xy 76.511526 -284.691418)
			(xy 76.483665 -284.650329) (xy 76.462819 -284.605273) (xy 76.449537 -284.557438) (xy 76.444169 -284.508085)
			(xy 76.446857 -284.458513) (xy 76.457528 -284.410029) (xy 76.475904 -284.363911) (xy 76.501498 -284.321373)
			(xy 76.533637 -284.283536) (xy 76.571474 -284.251397) (xy 76.614013 -284.225803) (xy 76.660131 -284.207428)
			(xy 76.708615 -284.196756) (xy 76.758187 -284.194069) (xy 76.80754 -284.199438) (xy 76.855375 -284.21272)
			(xy 76.90043 -284.233566) (xy 76.94152 -284.261427) (xy 76.977561 -284.295568) (xy 77.007603 -284.335091)
			(xy 77.030855 -284.378953) (xy 77.046705 -284.425999) (xy 77.054735 -284.47499) (xy 77.055218 -284.499812)
			(xy 77.055113 -284.508853) (xy 77.053967 -284.526898) (xy 77.052932 -284.53588) (xy 77.052932 -284.536642)
			(xy 77.052231 -284.548312) (xy 77.060182 -284.570269) (xy 77.068172 -284.578806) (xy 77.135736 -284.643576)
			(xy 77.158342 -284.650688) (xy 77.163168 -284.649926) (xy 77.178389 -284.647197) (xy 77.209174 -284.644269)
			(xy 77.224636 -284.644084) (xy 77.295248 -284.644084) (xy 77.305937 -284.643515) (xy 77.325483 -284.634849)
			(xy 77.333094 -284.62732) (xy 77.38364 -284.571186) (xy 77.390433 -284.562967) (xy 77.397027 -284.542709)
			(xy 77.39634 -284.53207) (xy 77.39634 -284.531816) (xy 77.394562 -284.499812) (xy 77.395032 -284.475819)
			(xy 77.402536 -284.428424) (xy 77.417362 -284.382787) (xy 77.439145 -284.34003) (xy 77.467347 -284.301208)
			(xy 77.501276 -284.267274) (xy 77.540094 -284.239067) (xy 77.582848 -284.217278) (xy 77.628483 -284.202446)
			(xy 77.675877 -284.194935) (xy 77.69987 -284.194504) (xy 77.713984 -284.194627) (xy 77.742097 -284.197174)
			(xy 77.756004 -284.199584) (xy 77.76845 -284.20187) (xy 77.79258 -284.194504) (xy 77.869542 -284.117288)
			(xy 77.876908 -284.093666) (xy 77.875638 -284.087062) (xy 77.87176 -284.066612) (xy 77.868928 -284.025086)
			(xy 77.871764 -283.983561) (xy 77.875638 -283.96311) (xy 77.875638 -283.962094) (xy 77.876908 -283.955998)
			(xy 77.869542 -283.932376) (xy 77.79258 -283.85516) (xy 77.76845 -283.847794) (xy 77.756004 -283.85008)
			(xy 77.742095 -283.85248) (xy 77.713984 -283.855028) (xy 77.69987 -283.85516) (xy 77.67588 -283.854712)
			(xy 77.628491 -283.847201) (xy 77.58286 -283.832369) (xy 77.540112 -283.810581) (xy 77.501298 -283.782374)
			(xy 77.467375 -283.748443) (xy 77.439178 -283.709622) (xy 77.417401 -283.666868) (xy 77.402581 -283.621233)
			(xy 77.395082 -283.573842) (xy 77.394562 -283.549852) (xy 77.39634 -283.518102) (xy 77.39634 -283.517594)
			(xy 77.396852 -283.506975) (xy 77.390286 -283.486777) (xy 77.38364 -283.478478) (xy 77.333094 -283.422344)
			(xy 77.325577 -283.414684) (xy 77.305972 -283.406003) (xy 77.295248 -283.40558) (xy 77.224636 -283.40558)
			(xy 77.20937 -283.405422) (xy 77.178968 -283.402623) (xy 77.16393 -283.399992) (xy 77.162406 -283.399738)
			(xy 77.158342 -283.398976) (xy 77.135736 -283.406088) (xy 77.068172 -283.470858) (xy 77.060175 -283.479387)
			(xy 77.052236 -283.501351) (xy 77.052932 -283.513022) (xy 77.052932 -283.51353) (xy 77.053982 -283.522574)
			(xy 77.055128 -283.540748) (xy 77.055218 -283.549852) (xy 77.054736 -283.574675) (xy 77.046712 -283.623667)
			(xy 77.030867 -283.670716) (xy 77.007618 -283.714582) (xy 76.977579 -283.754108) (xy 76.941541 -283.788253)
			(xy 76.900454 -283.816119) (xy 76.855399 -283.836969) (xy 76.807565 -283.850256) (xy 76.758211 -283.855628)
			(xy 76.708638 -283.852945) (xy 76.660153 -283.842277) (xy 76.614032 -283.823905) (xy 76.571491 -283.798313)
			(xy 76.533651 -283.766176) (xy 76.501509 -283.72834) (xy 76.475912 -283.685802) (xy 76.457534 -283.639684)
			(xy 76.44686 -283.591199) (xy 76.444171 -283.541627) (xy 76.449537 -283.492273) (xy 76.462818 -283.444437)
			(xy 76.483663 -283.399379) (xy 76.511523 -283.358288) (xy 76.545664 -283.322246) (xy 76.585186 -283.292202)
			(xy 76.629049 -283.268949) (xy 76.676096 -283.253098) (xy 76.725087 -283.245067) (xy 76.74991 -283.244544)
			(xy 76.759011 -283.244584) (xy 76.777184 -283.245601) (xy 76.786232 -283.246576) (xy 76.79817 -283.2481)
			(xy 76.820522 -283.239972) (xy 76.89342 -283.163772) (xy 76.900532 -283.141166) (xy 76.899516 -283.13507)
			(xy 76.896923 -283.120155) (xy 76.894127 -283.090009) (xy 76.893928 -283.074872) (xy 76.894124 -283.059861)
			(xy 76.89692 -283.029968) (xy 76.899516 -283.015182) (xy 76.899516 -283.014166) (xy 76.900532 -283.008578)
			(xy 76.89342 -282.985972) (xy 76.820522 -282.909772) (xy 76.79817 -282.901644) (xy 76.786232 -282.903168)
			(xy 76.777185 -282.904157) (xy 76.759011 -282.905172) (xy 76.74991 -282.9052) (xy 76.72509 -282.904715)
			(xy 76.676103 -282.896686) (xy 76.62906 -282.880837) (xy 76.585202 -282.857586) (xy 76.545682 -282.827546)
			(xy 76.511543 -282.791509) (xy 76.483685 -282.750423) (xy 76.46284 -282.705371) (xy 76.449558 -282.65754)
			(xy 76.444189 -282.608191) (xy 76.446875 -282.558623) (xy 76.457545 -282.510143) (xy 76.475918 -282.464027)
			(xy 76.501509 -282.421492) (xy 76.533644 -282.383657) (xy 76.571477 -282.351519) (xy 76.614011 -282.325926)
			(xy 76.660126 -282.30755) (xy 76.708605 -282.296878) (xy 76.758173 -282.294189) (xy 76.807522 -282.299555)
			(xy 76.855354 -282.312833) (xy 76.900407 -282.333676) (xy 76.941495 -282.361532) (xy 76.977534 -282.395669)
			(xy 77.007577 -282.435187) (xy 77.03083 -282.479044) (xy 77.046681 -282.526085) (xy 77.054713 -282.575072)
			(xy 77.055218 -282.599892) (xy 77.055113 -282.608933) (xy 77.053969 -282.626978) (xy 77.052932 -282.63596)
			(xy 77.052932 -282.636722) (xy 77.052226 -282.648394) (xy 77.060172 -282.670357) (xy 77.068172 -282.678886)
			(xy 77.135736 -282.743656) (xy 77.158342 -282.750768) (xy 77.163168 -282.750006) (xy 77.178389 -282.747277)
			(xy 77.209174 -282.744349) (xy 77.224636 -282.744164) (xy 77.295248 -282.744164) (xy 77.305937 -282.743595)
			(xy 77.325481 -282.734926) (xy 77.333094 -282.7274) (xy 77.38364 -282.671266) (xy 77.39043 -282.663046)
			(xy 77.397015 -282.642789) (xy 77.39634 -282.63215) (xy 77.39634 -282.631896) (xy 77.394562 -282.599892)
			(xy 77.395033 -282.5759) (xy 77.40254 -282.528508) (xy 77.417368 -282.482873) (xy 77.439151 -282.440119)
			(xy 77.467354 -282.401299) (xy 77.501282 -282.367369) (xy 77.5401 -282.339163) (xy 77.582853 -282.317376)
			(xy 77.628486 -282.302545) (xy 77.675878 -282.295035) (xy 77.69987 -282.294584) (xy 77.713984 -282.294707)
			(xy 77.742097 -282.297253) (xy 77.756004 -282.299664) (xy 77.76845 -282.30195) (xy 77.79258 -282.294584)
			(xy 77.869542 -282.217368) (xy 77.876908 -282.193746) (xy 77.875638 -282.187142) (xy 77.870116 -282.156918)
			(xy 77.869853 -282.095489) (xy 77.87513 -282.065222) (xy 77.87513 -282.064714) (xy 77.876908 -282.055824)
			(xy 77.869542 -282.032202) (xy 77.801216 -281.963622) (xy 77.791979 -281.955467) (xy 77.768488 -281.948157)
			(xy 77.756258 -281.949652) (xy 77.756004 -281.949652) (xy 77.742039 -281.952138) (xy 77.713799 -281.954812)
			(xy 77.699616 -281.954986) (xy 77.674359 -281.954495) (xy 77.624534 -281.946183) (xy 77.576757 -281.929783)
			(xy 77.532331 -281.905743) (xy 77.492468 -281.874718) (xy 77.458255 -281.837555) (xy 77.430626 -281.795267)
			(xy 77.410334 -281.749009) (xy 77.397934 -281.700041) (xy 77.393762 -281.6497) (xy 77.397934 -281.599359)
			(xy 77.410334 -281.550391) (xy 77.430626 -281.504133) (xy 77.458255 -281.461845) (xy 77.492468 -281.424682)
			(xy 77.532331 -281.393657) (xy 77.576757 -281.369617) (xy 77.624534 -281.353217) (xy 77.674359 -281.344905)
			(xy 77.699616 -281.34437) (xy 77.713215 -281.344519) (xy 77.740307 -281.346935) (xy 77.753718 -281.349196)
			(xy 77.766164 -281.351482) (xy 77.789786 -281.344116) (xy 77.866494 -281.2669) (xy 77.87386 -281.243278)
			(xy 77.871574 -281.230832) (xy 77.868205 -281.210825) (xy 77.866161 -281.170304) (xy 77.86751 -281.15006)
			(xy 77.872336 -281.116024) (xy 77.872336 -281.115516) (xy 77.874114 -281.106372) (xy 77.866748 -281.08275)
			(xy 77.79004 -281.005534) (xy 77.766164 -280.997914) (xy 77.753972 -281.0002) (xy 77.740561 -281.002461)
			(xy 77.713469 -281.004874) (xy 77.69987 -281.005026) (xy 77.674615 -281.004502) (xy 77.624794 -280.996184)
			(xy 77.577022 -280.979779) (xy 77.532601 -280.955736) (xy 77.492742 -280.92471) (xy 77.458534 -280.887546)
			(xy 77.430909 -280.84526) (xy 77.410621 -280.799003) (xy 77.398222 -280.750038) (xy 77.394051 -280.6997)
			(xy 77.398222 -280.649362) (xy 77.410621 -280.600397) (xy 77.430909 -280.55414) (xy 77.458534 -280.511854)
			(xy 77.492742 -280.47469) (xy 77.532601 -280.443664) (xy 77.577022 -280.419621) (xy 77.624794 -280.403216)
			(xy 77.674615 -280.394898) (xy 77.69987 -280.39441) (xy 77.713469 -280.394561) (xy 77.74056 -280.396982)
			(xy 77.753972 -280.399236) (xy 77.766418 -280.401522) (xy 77.79004 -280.394156) (xy 77.866748 -280.31694)
			(xy 77.874114 -280.293318) (xy 77.87259 -280.285698) (xy 77.869835 -280.270866) (xy 77.86691 -280.240839)
			(xy 77.866748 -280.225754) (xy 77.866748 -280.2255) (xy 77.866937 -280.210606) (xy 77.869862 -280.180961)
			(xy 77.87259 -280.166318) (xy 77.87259 -280.16581) (xy 77.874368 -280.156158) (xy 77.867002 -280.132536)
			(xy 77.790294 -280.05532) (xy 77.766418 -280.0477) (xy 77.754226 -280.049986) (xy 77.740878 -280.052242)
			(xy 77.713914 -280.05466) (xy 77.700378 -280.054812) (xy 77.69987 -280.054812) (xy 77.674616 -280.054288)
			(xy 77.624797 -280.04597) (xy 77.577027 -280.029567) (xy 77.532608 -280.005524) (xy 77.492752 -279.974499)
			(xy 77.458545 -279.937338) (xy 77.430922 -279.895053) (xy 77.410634 -279.848798) (xy 77.398236 -279.799836)
			(xy 77.394065 -279.7495) (xy 77.398236 -279.699164) (xy 77.410634 -279.650202) (xy 77.430922 -279.603947)
			(xy 77.458545 -279.561662) (xy 77.492752 -279.524501) (xy 77.532608 -279.493476) (xy 77.577027 -279.469433)
			(xy 77.624797 -279.45303) (xy 77.674616 -279.444712) (xy 77.69987 -279.444196) (xy 77.713984 -279.444319)
			(xy 77.742097 -279.446866) (xy 77.756004 -279.449276) (xy 77.768196 -279.451562) (xy 77.792326 -279.444196)
			(xy 77.869288 -279.367234) (xy 77.876654 -279.343104) (xy 77.874368 -279.330912) (xy 77.871511 -279.314115)
			(xy 77.869094 -279.280127) (xy 77.869542 -279.263094) (xy 77.870151 -279.25049) (xy 77.873203 -279.225438)
			(xy 77.875638 -279.213056) (xy 77.875638 -279.21204) (xy 77.876908 -279.205944) (xy 77.869542 -279.182322)
			(xy 77.79258 -279.105106) (xy 77.76845 -279.09774) (xy 77.756004 -279.100026) (xy 77.742095 -279.102425)
			(xy 77.713984 -279.104973) (xy 77.69987 -279.105106) (xy 77.67588 -279.104633) (xy 77.628492 -279.097123)
			(xy 77.582863 -279.082293) (xy 77.540114 -279.060508) (xy 77.5013 -279.032304) (xy 77.467375 -278.998376)
			(xy 77.439175 -278.959558) (xy 77.417395 -278.916808) (xy 77.402569 -278.871176) (xy 77.395064 -278.823788)
			(xy 77.394562 -278.799798) (xy 77.394667 -278.790757) (xy 77.395812 -278.772712) (xy 77.396848 -278.76373)
			(xy 77.396848 -278.763222) (xy 77.398118 -278.751538) (xy 77.38999 -278.729186) (xy 77.31379 -278.656288)
			(xy 77.291184 -278.649176) (xy 77.282294 -278.6507) (xy 77.267997 -278.653068) (xy 77.239127 -278.655614)
			(xy 77.224636 -278.65578) (xy 77.224382 -278.65578) (xy 77.209053 -278.65563) (xy 77.178524 -278.652827)
			(xy 77.163422 -278.650192) (xy 77.161898 -278.649938) (xy 77.158088 -278.649176) (xy 77.135482 -278.656288)
			(xy 77.059536 -278.729186) (xy 77.051408 -278.751538) (xy 77.052932 -278.763476) (xy 77.05392 -278.772523)
			(xy 77.054935 -278.790697) (xy 77.054964 -278.799798) (xy 77.054478 -278.824615) (xy 77.046449 -278.873594)
			(xy 77.030602 -278.920629) (xy 77.007354 -278.964481) (xy 76.977319 -279.003994) (xy 76.941286 -279.038128)
			(xy 76.900207 -279.065983) (xy 76.855162 -279.086825) (xy 76.807338 -279.100106) (xy 76.757996 -279.105474)
			(xy 76.708436 -279.10279) (xy 76.659962 -279.092123) (xy 76.613853 -279.073755) (xy 76.571323 -279.048169)
			(xy 76.533492 -279.01604) (xy 76.501357 -278.978214) (xy 76.475765 -278.935688) (xy 76.45739 -278.889582)
			(xy 76.446716 -278.84111) (xy 76.444024 -278.79155) (xy 76.449386 -278.742207) (xy 76.462659 -278.694382)
			(xy 76.483494 -278.649334) (xy 76.511343 -278.60825) (xy 76.545471 -278.572212) (xy 76.58498 -278.54217)
			(xy 76.628829 -278.518916) (xy 76.675861 -278.503062) (xy 76.72484 -278.495025) (xy 76.749656 -278.49449)
			(xy 76.758693 -278.494536) (xy 76.776739 -278.495552) (xy 76.785724 -278.496522) (xy 76.797662 -278.498046)
			(xy 76.820014 -278.489918) (xy 76.892912 -278.413718) (xy 76.900024 -278.391112) (xy 76.899008 -278.38527)
			(xy 76.896403 -278.370293) (xy 76.893606 -278.340019) (xy 76.89342 -278.324818) (xy 76.89342 -278.25446)
			(xy 76.892854 -278.243769) (xy 76.884194 -278.224217) (xy 76.876656 -278.216614) (xy 76.812648 -278.158956)
			(xy 76.79182 -278.152352) (xy 76.781406 -278.153622) (xy 76.749656 -278.155146) (xy 76.725666 -278.154672)
			(xy 76.678277 -278.147161) (xy 76.632647 -278.13233) (xy 76.589897 -278.110545) (xy 76.551082 -278.082341)
			(xy 76.517155 -278.048414) (xy 76.488952 -278.009597) (xy 76.467168 -277.966848) (xy 76.452338 -277.921217)
			(xy 76.444827 -277.873828) (xy 76.444348 -277.849838) (xy 76.444533 -277.835655) (xy 76.447202 -277.807415)
			(xy 76.449682 -277.79345) (xy 76.451968 -277.781004) (xy 76.444602 -277.757382) (xy 76.367132 -277.679912)
			(xy 76.34351 -277.672546) (xy 76.336906 -277.673816) (xy 76.32446 -277.676252) (xy 76.299281 -277.679302)
			(xy 76.286614 -277.679912) (xy 76.269517 -277.680394) (xy 76.2354 -277.677974) (xy 76.218542 -277.675086)
			(xy 76.206096 -277.6728) (xy 76.181966 -277.680166) (xy 76.105004 -277.757382) (xy 76.097638 -277.781004)
			(xy 76.099924 -277.79345) (xy 76.102408 -277.807415) (xy 76.105077 -277.835655) (xy 76.105258 -277.849838)
			(xy 76.104785 -277.873829) (xy 76.097274 -277.921219) (xy 76.082444 -277.966851) (xy 76.060659 -278.009602)
			(xy 76.032456 -278.048419) (xy 75.998529 -278.082348) (xy 75.959712 -278.110553) (xy 75.916962 -278.132339)
			(xy 75.87133 -278.147171) (xy 75.823941 -278.154684) (xy 75.79995 -278.155146) (xy 75.7682 -278.153368)
			(xy 75.767692 -278.153368) (xy 75.757073 -278.152857) (xy 75.736877 -278.159424) (xy 75.728576 -278.166068)
			(xy 75.672442 -278.216614) (xy 75.664784 -278.224132) (xy 75.656105 -278.243737) (xy 75.655678 -278.25446)
			(xy 75.655678 -278.299418) (xy 75.655424 -278.306022) (xy 75.655424 -278.324818) (xy 75.655206 -278.339702)
			(xy 75.652408 -278.369339) (xy 75.649836 -278.384) (xy 75.649836 -278.385524) (xy 75.64882 -278.391366)
			(xy 75.655932 -278.413972) (xy 75.720448 -278.481536) (xy 75.72909 -278.489597) (xy 75.751325 -278.497525)
			(xy 75.76312 -278.496776) (xy 75.763374 -278.496776) (xy 75.772482 -278.495721) (xy 75.790782 -278.494576)
			(xy 75.79995 -278.49449) (xy 75.82477 -278.49498) (xy 75.873755 -278.503019) (xy 75.920795 -278.518876)
			(xy 75.964649 -278.542134) (xy 76.004163 -278.572181) (xy 76.038296 -278.608224) (xy 76.066148 -278.649315)
			(xy 76.086986 -278.69437) (xy 76.10026 -278.742203) (xy 76.105622 -278.791553) (xy 76.102929 -278.84112)
			(xy 76.092253 -278.889599) (xy 76.073874 -278.935711) (xy 76.048278 -278.978244) (xy 76.016138 -279.016075)
			(xy 75.978302 -279.048208) (xy 75.935765 -279.073797) (xy 75.889649 -279.092168) (xy 75.841168 -279.102836)
			(xy 75.7916 -279.10552) (xy 75.742251 -279.100151) (xy 75.694421 -279.086868) (xy 75.64937 -279.066023)
			(xy 75.608284 -279.038163) (xy 75.572246 -279.004024) (xy 75.542206 -278.964505) (xy 75.518955 -278.920647)
			(xy 75.503106 -278.873605) (xy 75.495076 -278.824618) (xy 75.494642 -278.799798) (xy 75.494747 -278.790757)
			(xy 75.495892 -278.772712) (xy 75.496928 -278.76373) (xy 75.496928 -278.763222) (xy 75.498198 -278.751538)
			(xy 75.49007 -278.729186) (xy 75.41387 -278.656288) (xy 75.391264 -278.649176) (xy 75.382374 -278.6507)
			(xy 75.368077 -278.653067) (xy 75.339207 -278.655611) (xy 75.324716 -278.65578) (xy 75.324462 -278.65578)
			(xy 75.309133 -278.655634) (xy 75.278602 -278.652838) (xy 75.263502 -278.650192) (xy 75.261978 -278.649938)
			(xy 75.258168 -278.649176) (xy 75.235562 -278.656288) (xy 75.159616 -278.729186) (xy 75.151488 -278.751538)
			(xy 75.153012 -278.763476) (xy 75.154 -278.772523) (xy 75.155015 -278.790697) (xy 75.155044 -278.799798)
			(xy 75.154558 -278.824622) (xy 75.146526 -278.873617) (xy 75.130673 -278.920667) (xy 75.107417 -278.964532)
			(xy 75.07737 -279.004057) (xy 75.041325 -279.0382) (xy 75.00023 -279.066062) (xy 74.95517 -279.086908)
			(xy 74.90733 -279.100189) (xy 74.857972 -279.105555) (xy 74.808396 -279.102865) (xy 74.759909 -279.09219)
			(xy 74.713787 -279.073811) (xy 74.671246 -279.048213) (xy 74.633407 -279.016069) (xy 74.601268 -278.978226)
			(xy 74.575674 -278.935683) (xy 74.5573 -278.889559) (xy 74.54663 -278.84107) (xy 74.543946 -278.791494)
			(xy 74.549318 -278.742136) (xy 74.562604 -278.694298) (xy 74.583455 -278.64924) (xy 74.611321 -278.608149)
			(xy 74.645468 -278.572107) (xy 74.684996 -278.542065) (xy 74.728864 -278.518814) (xy 74.775916 -278.502966)
			(xy 74.824912 -278.494939) (xy 74.849736 -278.49449) (xy 74.858773 -278.494535) (xy 74.876819 -278.49555)
			(xy 74.885804 -278.496522) (xy 74.897742 -278.498046) (xy 74.920094 -278.489918) (xy 74.992992 -278.413718)
			(xy 75.000104 -278.391112) (xy 74.999088 -278.38527) (xy 74.996483 -278.370293) (xy 74.993686 -278.340019)
			(xy 74.9935 -278.324818) (xy 74.9935 -278.25446) (xy 74.992933 -278.24377) (xy 74.98427 -278.224219)
			(xy 74.976736 -278.216614) (xy 74.912728 -278.158956) (xy 74.8919 -278.152352) (xy 74.881486 -278.153622)
			(xy 74.849736 -278.155146) (xy 74.825742 -278.154678) (xy 74.778344 -278.147177) (xy 74.732702 -278.132353)
			(xy 74.689942 -278.110572) (xy 74.651115 -278.08237) (xy 74.617178 -278.048441) (xy 74.588967 -278.009621)
			(xy 74.567175 -277.966866) (xy 74.552341 -277.921229) (xy 74.544828 -277.873832) (xy 74.544428 -277.849838)
			(xy 74.544628 -277.835719) (xy 74.547302 -277.807608) (xy 74.549762 -277.793704) (xy 74.549762 -277.793196)
			(xy 74.551272 -277.78096) (xy 74.543983 -277.75745) (xy 74.535792 -277.748238) (xy 74.467212 -277.679912)
			(xy 74.44359 -277.672546) (xy 74.434446 -277.674324) (xy 74.407268 -277.678388) (xy 74.40676 -277.678388)
			(xy 74.384645 -277.680394) (xy 74.340272 -277.678734) (xy 74.318368 -277.675086) (xy 74.305922 -277.6728)
			(xy 74.281792 -277.680166) (xy 74.20483 -277.757382) (xy 74.197464 -277.781004) (xy 74.19975 -277.79345)
			(xy 74.202234 -277.807415) (xy 74.204902 -277.835655) (xy 74.205084 -277.849838) (xy 74.204611 -277.873827)
			(xy 74.1971 -277.921212) (xy 74.182268 -277.96684) (xy 74.160483 -278.009585) (xy 74.132278 -278.048397)
			(xy 74.09835 -278.082318) (xy 74.059532 -278.110515) (xy 74.016782 -278.132292) (xy 73.971152 -278.147114)
			(xy 73.923765 -278.154615) (xy 73.899776 -278.155146) (xy 73.86828 -278.153368) (xy 73.867772 -278.153368)
			(xy 73.857154 -278.152861) (xy 73.836963 -278.159434) (xy 73.828656 -278.166068) (xy 73.772522 -278.216614)
			(xy 73.764867 -278.224133) (xy 73.756192 -278.243738) (xy 73.755758 -278.25446) (xy 73.755758 -278.299418)
			(xy 73.755504 -278.306022) (xy 73.755504 -278.324818) (xy 73.755286 -278.339702) (xy 73.752488 -278.369339)
			(xy 73.749916 -278.384) (xy 73.749916 -278.385524) (xy 73.7489 -278.391366) (xy 73.756012 -278.413972)
			(xy 73.820528 -278.481536) (xy 73.829169 -278.489601) (xy 73.851404 -278.497537) (xy 73.8632 -278.496776)
			(xy 73.863454 -278.496776) (xy 73.872498 -278.495727) (xy 73.890672 -278.494582) (xy 73.899776 -278.49449)
			(xy 73.924598 -278.494974) (xy 73.973587 -278.503002) (xy 74.020632 -278.518849) (xy 74.064494 -278.542099)
			(xy 74.104017 -278.572139) (xy 74.138158 -278.608178) (xy 74.16602 -278.649265) (xy 74.186867 -278.694318)
			(xy 74.200151 -278.742151) (xy 74.20552 -278.791503) (xy 74.202835 -278.841073) (xy 74.192166 -278.889556)
			(xy 74.173793 -278.935674) (xy 74.148201 -278.978212) (xy 74.116064 -279.016049) (xy 74.07823 -279.048188)
			(xy 74.035693 -279.073783) (xy 73.989577 -279.092159) (xy 73.941095 -279.102832) (xy 73.891525 -279.105521)
			(xy 73.842173 -279.100155) (xy 73.794339 -279.086875) (xy 73.749284 -279.066031) (xy 73.708195 -279.038172)
			(xy 73.672154 -279.004033) (xy 73.642111 -278.964513) (xy 73.618858 -278.920653) (xy 73.603007 -278.873608)
			(xy 73.594976 -278.824619) (xy 73.594468 -278.799798) (xy 73.594573 -278.790757) (xy 73.595718 -278.772712)
			(xy 73.596754 -278.76373) (xy 73.596754 -278.763222) (xy 73.598024 -278.751538) (xy 73.589896 -278.729186)
			(xy 73.513696 -278.656288) (xy 73.49109 -278.64943) (xy 73.482708 -278.6507) (xy 73.468474 -278.653058)
			(xy 73.439731 -278.655603) (xy 73.425304 -278.65578) (xy 73.424542 -278.65578) (xy 73.409467 -278.655593)
			(xy 73.379447 -278.652797) (xy 73.364598 -278.650192) (xy 73.363582 -278.650192) (xy 73.358248 -278.649176)
			(xy 73.335642 -278.656288) (xy 73.259442 -278.729186) (xy 73.251314 -278.751538) (xy 73.252838 -278.763476)
			(xy 73.253826 -278.772523) (xy 73.254841 -278.790697) (xy 73.25487 -278.799798) (xy 73.254384 -278.824615)
			(xy 73.246355 -278.873596) (xy 73.230507 -278.920632) (xy 73.207259 -278.964485) (xy 73.177223 -279.003999)
			(xy 73.141189 -279.038134) (xy 73.100108 -279.065989) (xy 73.055062 -279.086831) (xy 73.007238 -279.100112)
			(xy 72.957894 -279.10548) (xy 72.908333 -279.102796) (xy 72.859858 -279.092128) (xy 72.813748 -279.073759)
			(xy 72.771217 -279.048173) (xy 72.733386 -279.016042) (xy 72.701251 -278.978215) (xy 72.675659 -278.935688)
			(xy 72.657284 -278.88958) (xy 72.64661 -278.841107) (xy 72.643918 -278.791546) (xy 72.649281 -278.742202)
			(xy 72.662555 -278.694375) (xy 72.683391 -278.649327) (xy 72.711241 -278.608242) (xy 72.745371 -278.572204)
			(xy 72.784881 -278.542162) (xy 72.828731 -278.518908) (xy 72.875765 -278.503055) (xy 72.924745 -278.495019)
			(xy 72.949562 -278.49449) (xy 72.958663 -278.494528) (xy 72.976836 -278.495542) (xy 72.985884 -278.496522)
			(xy 72.997822 -278.498046) (xy 73.020174 -278.489918) (xy 73.093072 -278.413718) (xy 73.100184 -278.391112)
			(xy 73.099168 -278.38527) (xy 73.096562 -278.370293) (xy 73.093765 -278.340019) (xy 73.09358 -278.324818)
			(xy 73.09358 -278.25446) (xy 73.093013 -278.24377) (xy 73.084348 -278.224222) (xy 73.076816 -278.216614)
			(xy 73.020682 -278.166068) (xy 73.012463 -278.159275) (xy 72.992205 -278.152681) (xy 72.981566 -278.153368)
			(xy 72.981312 -278.153368) (xy 72.949562 -278.155146) (xy 72.925572 -278.154673) (xy 72.878182 -278.147162)
			(xy 72.832551 -278.132332) (xy 72.789801 -278.110547) (xy 72.750984 -278.082343) (xy 72.717057 -278.048416)
			(xy 72.688853 -278.009599) (xy 72.667068 -277.966849) (xy 72.652238 -277.921218) (xy 72.644727 -277.873828)
			(xy 72.644254 -277.849838) (xy 72.644439 -277.835655) (xy 72.647108 -277.807415) (xy 72.649588 -277.79345)
			(xy 72.651874 -277.781004) (xy 72.644508 -277.757382) (xy 72.567038 -277.679912) (xy 72.543416 -277.672546)
			(xy 72.536812 -277.673816) (xy 72.524366 -277.676253) (xy 72.499187 -277.679303) (xy 72.48652 -277.679912)
			(xy 72.469423 -277.680395) (xy 72.435306 -277.677975) (xy 72.418448 -277.675086) (xy 72.406002 -277.6728)
			(xy 72.381872 -277.680166) (xy 72.30491 -277.757382) (xy 72.297544 -277.781004) (xy 72.29983 -277.79345)
			(xy 72.302314 -277.807415) (xy 72.304983 -277.835655) (xy 72.305164 -277.849838) (xy 72.304715 -277.873828)
			(xy 72.297203 -277.921216) (xy 72.282371 -277.966846) (xy 72.260583 -278.009594) (xy 72.232376 -278.048407)
			(xy 72.198444 -278.082329) (xy 72.159624 -278.110526) (xy 72.11687 -278.132302) (xy 72.071236 -278.147122)
			(xy 72.023846 -278.154621) (xy 71.999856 -278.155146) (xy 71.968106 -278.153368) (xy 71.967598 -278.153368)
			(xy 71.956978 -278.152855) (xy 71.936781 -278.159421) (xy 71.928482 -278.166068) (xy 71.872348 -278.216614)
			(xy 71.864689 -278.224131) (xy 71.85601 -278.243736) (xy 71.855584 -278.25446) (xy 71.855584 -278.30907)
			(xy 71.85533 -278.322532) (xy 71.855076 -278.324056) (xy 71.855076 -278.327866) (xy 71.854894 -278.338378)
			(xy 71.853367 -278.359348) (xy 71.852028 -278.369776) (xy 71.852028 -278.370284) (xy 71.850758 -278.379174)
			(xy 71.848726 -278.391112) (xy 71.855838 -278.413972) (xy 71.928736 -278.490172) (xy 71.951088 -278.4983)
			(xy 71.963026 -278.496776) (xy 71.972197 -278.495715) (xy 71.990624 -278.494572) (xy 71.999856 -278.49449)
			(xy 72.024678 -278.494972) (xy 72.073669 -278.502997) (xy 72.120716 -278.518842) (xy 72.164579 -278.54209)
			(xy 72.204104 -278.572128) (xy 72.238248 -278.608165) (xy 72.266112 -278.649251) (xy 72.286962 -278.694304)
			(xy 72.300248 -278.742137) (xy 72.30562 -278.791489) (xy 72.302937 -278.84106) (xy 72.292269 -278.889544)
			(xy 72.273898 -278.935663) (xy 72.248307 -278.978203) (xy 72.216171 -279.016042) (xy 72.178337 -279.048183)
			(xy 72.135801 -279.073779) (xy 72.089684 -279.092157) (xy 72.041202 -279.102831) (xy 71.991631 -279.105521)
			(xy 71.942278 -279.100156) (xy 71.894444 -279.086876) (xy 71.849388 -279.066033) (xy 71.808298 -279.038175)
			(xy 71.772256 -279.004035) (xy 71.742213 -278.964515) (xy 71.718959 -278.920654) (xy 71.703107 -278.873609)
			(xy 71.695076 -278.82462) (xy 71.694548 -278.799798) (xy 71.694653 -278.790757) (xy 71.695798 -278.772712)
			(xy 71.696834 -278.76373) (xy 71.696834 -278.763222) (xy 71.698104 -278.751538) (xy 71.689976 -278.729186)
			(xy 71.613776 -278.656288) (xy 71.59117 -278.649176) (xy 71.582026 -278.6507) (xy 71.567729 -278.65307)
			(xy 71.538859 -278.655616) (xy 71.524368 -278.65578) (xy 71.509102 -278.655624) (xy 71.478699 -278.652827)
			(xy 71.463662 -278.650192) (xy 71.462138 -278.649938) (xy 71.458074 -278.649176) (xy 71.435468 -278.656288)
			(xy 71.359522 -278.729186) (xy 71.351394 -278.751538) (xy 71.352918 -278.763476) (xy 71.353906 -278.772523)
			(xy 71.354921 -278.790697) (xy 71.35495 -278.799798) (xy 71.354464 -278.824623) (xy 71.346432 -278.873619)
			(xy 71.330578 -278.92067) (xy 71.307321 -278.964536) (xy 71.277274 -279.004062) (xy 71.241228 -279.038205)
			(xy 71.200132 -279.066067) (xy 71.15507 -279.086914) (xy 71.10723 -279.100195) (xy 71.05787 -279.105561)
			(xy 71.008293 -279.102871) (xy 70.959805 -279.092195) (xy 70.913682 -279.073816) (xy 70.87114 -279.048216)
			(xy 70.833301 -279.016071) (xy 70.801161 -278.978227) (xy 70.775567 -278.935682) (xy 70.757193 -278.889557)
			(xy 70.746524 -278.841067) (xy 70.74384 -278.79149) (xy 70.749213 -278.742131) (xy 70.7625 -278.694292)
			(xy 70.783352 -278.649233) (xy 70.81122 -278.608141) (xy 70.845368 -278.572099) (xy 70.884898 -278.542057)
			(xy 70.928767 -278.518806) (xy 70.97582 -278.502959) (xy 71.024817 -278.494933) (xy 71.049642 -278.49449)
			(xy 71.058743 -278.494531) (xy 71.076915 -278.495549) (xy 71.085964 -278.496522) (xy 71.097902 -278.498046)
			(xy 71.120254 -278.489918) (xy 71.193152 -278.413972) (xy 71.200264 -278.391366) (xy 71.199502 -278.38654)
			(xy 71.196787 -278.371382) (xy 71.193859 -278.340724) (xy 71.19366 -278.325326) (xy 71.19366 -278.25446)
			(xy 71.193092 -278.243771) (xy 71.184424 -278.224225) (xy 71.176896 -278.216614) (xy 71.120762 -278.166068)
			(xy 71.112542 -278.159279) (xy 71.092285 -278.152693) (xy 71.081646 -278.153368) (xy 71.081392 -278.153368)
			(xy 71.049642 -278.155146) (xy 71.025646 -278.154703) (xy 70.978243 -278.147202) (xy 70.932597 -278.132377)
			(xy 70.889832 -278.110595) (xy 70.851002 -278.082391) (xy 70.817061 -278.048459) (xy 70.788847 -278.009636)
			(xy 70.767053 -277.966877) (xy 70.752217 -277.921235) (xy 70.744703 -277.873834) (xy 70.744334 -277.849838)
			(xy 70.744519 -277.835655) (xy 70.747188 -277.807415) (xy 70.749668 -277.79345) (xy 70.751954 -277.781004)
			(xy 70.744588 -277.757382) (xy 70.667118 -277.679912) (xy 70.643496 -277.672546) (xy 70.636892 -277.673816)
			(xy 70.624446 -277.676252) (xy 70.599267 -277.6793) (xy 70.5866 -277.679912) (xy 70.569504 -277.680394)
			(xy 70.535386 -277.677972) (xy 70.518528 -277.675086) (xy 70.506082 -277.6728) (xy 70.481952 -277.680166)
			(xy 70.40499 -277.757382) (xy 70.397624 -277.781004) (xy 70.39991 -277.79345) (xy 70.402393 -277.807415)
			(xy 70.405061 -277.835655) (xy 70.405244 -277.849838) (xy 70.404771 -277.873828) (xy 70.39726 -277.921218)
			(xy 70.38243 -277.966849) (xy 70.360645 -278.009599) (xy 70.332441 -278.048415) (xy 70.298514 -278.082343)
			(xy 70.259697 -278.110546) (xy 70.216947 -278.13233) (xy 70.171316 -278.14716) (xy 70.123926 -278.154671)
			(xy 70.099936 -278.155146) (xy 70.068186 -278.153368) (xy 70.067678 -278.153368) (xy 70.05706 -278.152859)
			(xy 70.036867 -278.159431) (xy 70.028562 -278.166068) (xy 69.972428 -278.216614) (xy 69.964772 -278.224133)
			(xy 69.956096 -278.243737) (xy 69.955664 -278.25446) (xy 69.955664 -278.30907) (xy 69.95541 -278.322532)
			(xy 69.955156 -278.324056) (xy 69.955156 -278.327866) (xy 69.954974 -278.338378) (xy 69.953447 -278.359348)
			(xy 69.952108 -278.369776) (xy 69.952108 -278.370284) (xy 69.950838 -278.379174) (xy 69.948806 -278.391112)
			(xy 69.955918 -278.413972) (xy 70.028816 -278.490172) (xy 70.051168 -278.4983) (xy 70.063106 -278.496776)
			(xy 70.072277 -278.495714) (xy 70.090704 -278.49457) (xy 70.099936 -278.49449) (xy 70.124756 -278.494979)
			(xy 70.173742 -278.503015) (xy 70.220783 -278.518871) (xy 70.264639 -278.542128) (xy 70.304154 -278.572173)
			(xy 70.338289 -278.608216) (xy 70.366143 -278.649305) (xy 70.386982 -278.69436) (xy 70.400259 -278.742193)
			(xy 70.405622 -278.791543) (xy 70.40293 -278.841111) (xy 70.392255 -278.88959) (xy 70.373878 -278.935704)
			(xy 70.348282 -278.978238) (xy 70.316143 -279.01607) (xy 70.278307 -279.048205) (xy 70.23577 -279.073795)
			(xy 70.189654 -279.092166) (xy 70.141173 -279.102835) (xy 70.091605 -279.10552) (xy 70.042255 -279.100151)
			(xy 69.994424 -279.086869) (xy 69.949372 -279.066024) (xy 69.908286 -279.038165) (xy 69.872248 -279.004026)
			(xy 69.842207 -278.964507) (xy 69.818956 -278.920648) (xy 69.803106 -278.873605) (xy 69.795076 -278.824618)
			(xy 69.794628 -278.799798) (xy 69.794733 -278.790757) (xy 69.795878 -278.772712) (xy 69.796914 -278.76373)
			(xy 69.796914 -278.763222) (xy 69.798184 -278.751538) (xy 69.790056 -278.729186) (xy 69.713856 -278.656288)
			(xy 69.69125 -278.649176) (xy 69.682106 -278.6507) (xy 69.667809 -278.653069) (xy 69.638939 -278.655613)
			(xy 69.624448 -278.65578) (xy 69.609182 -278.655623) (xy 69.57878 -278.652824) (xy 69.563742 -278.650192)
			(xy 69.562218 -278.649938) (xy 69.558154 -278.649176) (xy 69.535548 -278.656288) (xy 69.459602 -278.729186)
			(xy 69.451474 -278.751538) (xy 69.452998 -278.763476) (xy 69.453986 -278.772523) (xy 69.455002 -278.790697)
			(xy 69.45503 -278.799798) (xy 69.454544 -278.824621) (xy 69.446513 -278.873613) (xy 69.43066 -278.92066)
			(xy 69.407406 -278.964523) (xy 69.377361 -279.004046) (xy 69.341318 -279.038188) (xy 69.300226 -279.066048)
			(xy 69.255168 -279.086893) (xy 69.207332 -279.100174) (xy 69.157976 -279.105541) (xy 69.108403 -279.102852)
			(xy 69.059918 -279.092179) (xy 69.013798 -279.073802) (xy 68.97126 -279.048205) (xy 68.933422 -279.016064)
			(xy 68.901283 -278.978224) (xy 68.87569 -278.935684) (xy 68.857315 -278.889563) (xy 68.846645 -278.841077)
			(xy 68.84396 -278.791504) (xy 68.84933 -278.742149) (xy 68.862614 -278.694313) (xy 68.883462 -278.649256)
			(xy 68.911325 -278.608166) (xy 68.945469 -278.572126) (xy 68.984993 -278.542083) (xy 69.028858 -278.518832)
			(xy 69.075906 -278.502983) (xy 69.124899 -278.494954) (xy 69.149722 -278.49449) (xy 69.158823 -278.49453)
			(xy 69.176995 -278.495548) (xy 69.186044 -278.496522) (xy 69.197982 -278.498046) (xy 69.220334 -278.489918)
			(xy 69.293232 -278.413972) (xy 69.300344 -278.391366) (xy 69.299582 -278.38654) (xy 69.296867 -278.371382)
			(xy 69.293939 -278.340724) (xy 69.29374 -278.325326) (xy 69.29374 -278.25446) (xy 69.293172 -278.243771)
			(xy 69.284502 -278.224228) (xy 69.276976 -278.216614) (xy 69.220842 -278.166068) (xy 69.212621 -278.159282)
			(xy 69.192365 -278.152705) (xy 69.181726 -278.153368) (xy 69.181472 -278.153368) (xy 69.149722 -278.155146)
			(xy 69.125729 -278.154677) (xy 69.078332 -278.147174) (xy 69.032693 -278.132349) (xy 68.989934 -278.110567)
			(xy 68.951109 -278.082365) (xy 68.917174 -278.048436) (xy 68.888964 -278.009617) (xy 68.867174 -277.966863)
			(xy 68.85234 -277.921226) (xy 68.844828 -277.873831) (xy 68.844414 -277.849838) (xy 68.844614 -277.835719)
			(xy 68.847288 -277.807608) (xy 68.849748 -277.793704) (xy 68.849748 -277.793196) (xy 68.851258 -277.78096)
			(xy 68.843968 -277.757451) (xy 68.835778 -277.748238) (xy 68.767198 -277.679912) (xy 68.743576 -277.672546)
			(xy 68.734432 -277.674324) (xy 68.707254 -277.678388) (xy 68.706746 -277.678388) (xy 68.684631 -277.680393)
			(xy 68.640258 -277.678731) (xy 68.618354 -277.675086) (xy 68.605908 -277.6728) (xy 68.581778 -277.680166)
			(xy 68.504816 -277.757382) (xy 68.49745 -277.781004) (xy 68.499736 -277.79345) (xy 68.50222 -277.807415)
			(xy 68.504889 -277.835655) (xy 68.50507 -277.849838) (xy 68.504597 -277.873826) (xy 68.497085 -277.921211)
			(xy 68.482254 -277.966838) (xy 68.460468 -278.009582) (xy 68.432263 -278.048392) (xy 68.398335 -278.082313)
			(xy 68.359517 -278.110508) (xy 68.316767 -278.132283) (xy 68.271137 -278.147103) (xy 68.22375 -278.154602)
			(xy 68.199762 -278.155146) (xy 68.168266 -278.153368) (xy 68.167758 -278.153368) (xy 68.157134 -278.152843)
			(xy 68.13692 -278.159391) (xy 68.128642 -278.166068) (xy 68.072508 -278.216614) (xy 68.064854 -278.224134)
			(xy 68.056182 -278.243738) (xy 68.055744 -278.25446) (xy 68.055744 -278.30907) (xy 68.05549 -278.322532)
			(xy 68.055236 -278.324056) (xy 68.055236 -278.327866) (xy 68.055054 -278.338378) (xy 68.053527 -278.359348)
			(xy 68.052188 -278.369776) (xy 68.052188 -278.370284) (xy 68.050918 -278.379174) (xy 68.048886 -278.391112)
			(xy 68.055998 -278.413972) (xy 68.128896 -278.490172) (xy 68.151248 -278.4983) (xy 68.163186 -278.496776)
			(xy 68.172294 -278.495721) (xy 68.190594 -278.494577) (xy 68.199762 -278.49449) (xy 68.224584 -278.494973)
			(xy 68.273574 -278.502998) (xy 68.320621 -278.518844) (xy 68.364484 -278.542093) (xy 68.404008 -278.572131)
			(xy 68.438151 -278.608169) (xy 68.466014 -278.649255) (xy 68.486863 -278.694309) (xy 68.500149 -278.742141)
			(xy 68.50552 -278.791493) (xy 68.502836 -278.841064) (xy 68.492168 -278.889548) (xy 68.473797 -278.935667)
			(xy 68.448205 -278.978206) (xy 68.416069 -279.016044) (xy 68.378235 -279.048184) (xy 68.335699 -279.073781)
			(xy 68.289582 -279.092158) (xy 68.2411 -279.102832) (xy 68.191529 -279.105521) (xy 68.142177 -279.100155)
			(xy 68.094342 -279.086876) (xy 68.049287 -279.066032) (xy 68.008197 -279.038174) (xy 67.972155 -279.004035)
			(xy 67.942112 -278.964514) (xy 67.918858 -278.920654) (xy 67.903007 -278.873609) (xy 67.894976 -278.82462)
			(xy 67.894454 -278.799798) (xy 67.894559 -278.790757) (xy 67.895704 -278.772712) (xy 67.89674 -278.76373)
			(xy 67.89674 -278.763222) (xy 67.89801 -278.751538) (xy 67.889882 -278.729186) (xy 67.813682 -278.656288)
			(xy 67.791076 -278.64943) (xy 67.784472 -278.650446) (xy 67.769617 -278.652981) (xy 67.739597 -278.655657)
			(xy 67.724528 -278.65578) (xy 67.709517 -278.655582) (xy 67.679625 -278.652782) (xy 67.664838 -278.650192)
			(xy 67.663822 -278.650192) (xy 67.658234 -278.649176) (xy 67.635628 -278.656288) (xy 67.559428 -278.729186)
			(xy 67.5513 -278.751538) (xy 67.552824 -278.763476) (xy 67.553812 -278.772523) (xy 67.554827 -278.790697)
			(xy 67.554856 -278.799798) (xy 67.554371 -278.824624) (xy 67.546338 -278.873621) (xy 67.530484 -278.920673)
			(xy 67.507226 -278.96454) (xy 67.477178 -279.004067) (xy 67.441131 -279.038211) (xy 67.400034 -279.066074)
			(xy 67.354971 -279.08692) (xy 67.307129 -279.100202) (xy 67.257769 -279.105568) (xy 67.20819 -279.102877)
			(xy 67.1597 -279.092201) (xy 67.113577 -279.07382) (xy 67.071034 -279.048219) (xy 67.033194 -279.016073)
			(xy 67.001054 -278.978228) (xy 66.975459 -278.935682) (xy 66.957086 -278.889556) (xy 66.946417 -278.841064)
			(xy 66.943734 -278.791485) (xy 66.949107 -278.742126) (xy 66.962396 -278.694286) (xy 66.983249 -278.649226)
			(xy 67.011118 -278.608133) (xy 67.045267 -278.572091) (xy 67.084799 -278.542049) (xy 67.128669 -278.518798)
			(xy 67.175724 -278.502951) (xy 67.224722 -278.494926) (xy 67.249548 -278.49449) (xy 67.258589 -278.494593)
			(xy 67.276635 -278.495735) (xy 67.285616 -278.496776) (xy 67.286378 -278.496776) (xy 67.298054 -278.497491)
			(xy 67.320032 -278.48956) (xy 67.328542 -278.481536) (xy 67.393312 -278.413972) (xy 67.400424 -278.391366)
			(xy 67.399662 -278.38654) (xy 67.396948 -278.371382) (xy 67.394019 -278.340724) (xy 67.39382 -278.325326)
			(xy 67.39382 -278.25446) (xy 67.393254 -278.243769) (xy 67.384594 -278.224217) (xy 67.377056 -278.216614)
			(xy 67.320922 -278.166068) (xy 67.312701 -278.159286) (xy 67.292445 -278.152716) (xy 67.281806 -278.153368)
			(xy 67.281552 -278.153368) (xy 67.249548 -278.155146) (xy 67.225551 -278.154703) (xy 67.178148 -278.147203)
			(xy 67.132501 -278.132379) (xy 67.089736 -278.110597) (xy 67.050904 -278.082393) (xy 67.016963 -278.048461)
			(xy 66.988748 -278.009638) (xy 66.966954 -277.966878) (xy 66.952117 -277.921236) (xy 66.944603 -277.873835)
			(xy 66.94424 -277.849838) (xy 66.944425 -277.835655) (xy 66.947094 -277.807415) (xy 66.949574 -277.79345)
			(xy 66.95186 -277.781004) (xy 66.944494 -277.757382) (xy 66.867024 -277.679912) (xy 66.843402 -277.672546)
			(xy 66.836798 -277.673816) (xy 66.824352 -277.676252) (xy 66.799173 -277.679301) (xy 66.786506 -277.679912)
			(xy 66.769409 -277.680394) (xy 66.735292 -277.677973) (xy 66.718434 -277.675086) (xy 66.705988 -277.6728)
			(xy 66.681858 -277.680166) (xy 66.604896 -277.757382) (xy 66.59753 -277.781004) (xy 66.599816 -277.79345)
			(xy 66.602299 -277.807415) (xy 66.604967 -277.835655) (xy 66.60515 -277.849838) (xy 66.604677 -277.873828)
			(xy 66.597166 -277.921218) (xy 66.582336 -277.96685) (xy 66.560551 -278.0096) (xy 66.532348 -278.048417)
			(xy 66.49842 -278.082345) (xy 66.459604 -278.110549) (xy 66.416853 -278.132334) (xy 66.371222 -278.147165)
			(xy 66.323832 -278.154676) (xy 66.299842 -278.155146) (xy 66.268092 -278.153368) (xy 66.267584 -278.153368)
			(xy 66.256965 -278.152858) (xy 66.236771 -278.159428) (xy 66.228468 -278.166068) (xy 66.172334 -278.216614)
			(xy 66.164677 -278.224132) (xy 66.156 -278.243737) (xy 66.15557 -278.25446) (xy 66.15557 -278.299418)
			(xy 66.155316 -278.306022) (xy 66.155316 -278.324818) (xy 66.155098 -278.339702) (xy 66.1523 -278.369339)
			(xy 66.149728 -278.384) (xy 66.149728 -278.385524) (xy 66.148712 -278.391366) (xy 66.155824 -278.413972)
			(xy 66.22034 -278.481536) (xy 66.228981 -278.489599) (xy 66.251216 -278.49753) (xy 66.263012 -278.496776)
			(xy 66.263266 -278.496776) (xy 66.272373 -278.495721) (xy 66.290674 -278.494575) (xy 66.299842 -278.49449)
			(xy 66.324662 -278.494979) (xy 66.373648 -278.503017) (xy 66.420688 -278.518873) (xy 66.464543 -278.542131)
			(xy 66.504058 -278.572177) (xy 66.538192 -278.608219) (xy 66.566045 -278.64931) (xy 66.586884 -278.694364)
			(xy 66.600159 -278.742197) (xy 66.605522 -278.791547) (xy 66.60283 -278.841115) (xy 66.592154 -278.889594)
			(xy 66.573776 -278.935707) (xy 66.54818 -278.97824) (xy 66.516041 -279.016072) (xy 66.478205 -279.048206)
			(xy 66.435668 -279.073796) (xy 66.389552 -279.092167) (xy 66.341071 -279.102836) (xy 66.291503 -279.10552)
			(xy 66.242154 -279.100151) (xy 66.194323 -279.086869) (xy 66.149271 -279.066023) (xy 66.108185 -279.038164)
			(xy 66.072147 -279.004025) (xy 66.042107 -278.964506) (xy 66.018856 -278.920648) (xy 66.003006 -278.873605)
			(xy 65.994976 -278.824618) (xy 65.994534 -278.799798) (xy 65.994639 -278.790757) (xy 65.995784 -278.772712)
			(xy 65.99682 -278.76373) (xy 65.99682 -278.763222) (xy 65.99809 -278.751538) (xy 65.989962 -278.729186)
			(xy 65.913762 -278.656288) (xy 65.891156 -278.649176) (xy 65.882266 -278.6507) (xy 65.867969 -278.653067)
			(xy 65.839099 -278.65561) (xy 65.824608 -278.65578) (xy 65.824354 -278.65578) (xy 65.809025 -278.655633)
			(xy 65.778494 -278.652837) (xy 65.763394 -278.650192) (xy 65.76187 -278.649938) (xy 65.75806 -278.649176)
			(xy 65.735454 -278.656288) (xy 65.659508 -278.729186) (xy 65.65138 -278.751538) (xy 65.652904 -278.763476)
			(xy 65.653892 -278.772523) (xy 65.654907 -278.790697) (xy 65.654936 -278.799798) (xy 65.65445 -278.824622)
			(xy 65.646418 -278.873615) (xy 65.630566 -278.920663) (xy 65.60731 -278.964527) (xy 65.577265 -279.004051)
			(xy 65.541221 -279.038193) (xy 65.500128 -279.066054) (xy 65.455069 -279.086899) (xy 65.407231 -279.10018)
			(xy 65.357875 -279.105547) (xy 65.3083 -279.102858) (xy 65.259814 -279.092184) (xy 65.213693 -279.073806)
			(xy 65.171154 -279.048208) (xy 65.133316 -279.016066) (xy 65.101177 -278.978225) (xy 65.075583 -278.935683)
			(xy 65.057209 -278.889561) (xy 65.046539 -278.841074) (xy 65.043854 -278.791499) (xy 65.049224 -278.742143)
			(xy 65.06251 -278.694307) (xy 65.083359 -278.649249) (xy 65.111223 -278.608159) (xy 65.145369 -278.572118)
			(xy 65.184895 -278.542076) (xy 65.228761 -278.518824) (xy 65.27581 -278.502975) (xy 65.324804 -278.494948)
			(xy 65.349628 -278.49449) (xy 65.358665 -278.494535) (xy 65.376711 -278.495549) (xy 65.385696 -278.496522)
			(xy 65.397634 -278.498046) (xy 65.419986 -278.489918) (xy 65.492884 -278.413718) (xy 65.499996 -278.391112)
			(xy 65.49898 -278.38527) (xy 65.496374 -278.370293) (xy 65.493577 -278.340019) (xy 65.493392 -278.324818)
			(xy 65.493392 -278.25446) (xy 65.492825 -278.24377) (xy 65.484161 -278.224221) (xy 65.476628 -278.216614)
			(xy 65.41262 -278.158956) (xy 65.391792 -278.152352) (xy 65.381378 -278.153622) (xy 65.349628 -278.155146)
			(xy 65.325634 -278.154678) (xy 65.278237 -278.147175) (xy 65.232597 -278.132351) (xy 65.189837 -278.110569)
			(xy 65.151012 -278.082367) (xy 65.117076 -278.048438) (xy 65.088865 -278.009619) (xy 65.067075 -277.966864)
			(xy 65.05224 -277.921227) (xy 65.044728 -277.873832) (xy 65.04432 -277.849838) (xy 65.044505 -277.835655)
			(xy 65.047175 -277.807415) (xy 65.049654 -277.79345) (xy 65.05194 -277.781004) (xy 65.044574 -277.757382)
			(xy 64.967104 -277.679912) (xy 64.943482 -277.672546) (xy 64.936878 -277.673816) (xy 64.924432 -277.676251)
			(xy 64.899253 -277.679299) (xy 64.886586 -277.679912) (xy 64.86949 -277.680393) (xy 64.835372 -277.67797)
			(xy 64.818514 -277.675086) (xy 64.806068 -277.6728) (xy 64.781938 -277.680166) (xy 64.704976 -277.757382)
			(xy 64.69761 -277.781004) (xy 64.699896 -277.79345) (xy 64.702379 -277.807415) (xy 64.705048 -277.835655)
			(xy 64.70523 -277.849838) (xy 64.704757 -277.873828) (xy 64.697246 -277.921216) (xy 64.682415 -277.966847)
			(xy 64.66063 -278.009596) (xy 64.632427 -278.048411) (xy 64.598499 -278.082337) (xy 64.559682 -278.110539)
			(xy 64.516932 -278.132322) (xy 64.471301 -278.14715) (xy 64.423912 -278.154658) (xy 64.399922 -278.155146)
			(xy 64.368172 -278.153368) (xy 64.367664 -278.153368) (xy 64.35704 -278.152842) (xy 64.336824 -278.159388)
			(xy 64.328548 -278.166068) (xy 64.272414 -278.216614) (xy 64.26476 -278.224133) (xy 64.256086 -278.243738)
			(xy 64.25565 -278.25446) (xy 64.25565 -278.299418) (xy 64.255396 -278.306022) (xy 64.255396 -278.324818)
			(xy 64.255178 -278.339702) (xy 64.25238 -278.369339) (xy 64.249808 -278.384) (xy 64.249808 -278.385524)
			(xy 64.248792 -278.391366) (xy 64.255904 -278.413972) (xy 64.32042 -278.481536) (xy 64.32906 -278.489603)
			(xy 64.351296 -278.497542) (xy 64.363092 -278.496776) (xy 64.363346 -278.496776) (xy 64.372453 -278.49572)
			(xy 64.390754 -278.494573) (xy 64.399922 -278.49449) (xy 64.424743 -278.494978) (xy 64.473729 -278.503012)
			(xy 64.520771 -278.518866) (xy 64.564628 -278.542121) (xy 64.604146 -278.572165) (xy 64.638282 -278.608207)
			(xy 64.666137 -278.649296) (xy 64.686979 -278.69435) (xy 64.700257 -278.742183) (xy 64.705621 -278.791534)
			(xy 64.702931 -278.841102) (xy 64.692258 -278.889582) (xy 64.673881 -278.935697) (xy 64.648287 -278.978232)
			(xy 64.616148 -279.016065) (xy 64.578312 -279.048201) (xy 64.535776 -279.073792) (xy 64.489659 -279.092165)
			(xy 64.441178 -279.102835) (xy 64.39161 -279.105521) (xy 64.342259 -279.100152) (xy 64.294428 -279.08687)
			(xy 64.249375 -279.066026) (xy 64.208288 -279.038167) (xy 64.172249 -279.004028) (xy 64.142208 -278.964508)
			(xy 64.118956 -278.920649) (xy 64.103106 -278.873606) (xy 64.095076 -278.824619) (xy 64.094614 -278.799798)
			(xy 64.094719 -278.790757) (xy 64.095864 -278.772712) (xy 64.0969 -278.76373) (xy 64.0969 -278.763222)
			(xy 64.09817 -278.751538) (xy 64.090042 -278.729186) (xy 64.013842 -278.656288) (xy 63.991236 -278.649176)
			(xy 63.982346 -278.6507) (xy 63.968049 -278.653066) (xy 63.939179 -278.655607) (xy 63.924688 -278.65578)
			(xy 63.924434 -278.65578) (xy 63.909105 -278.655632) (xy 63.878575 -278.652835) (xy 63.863474 -278.650192)
			(xy 63.86195 -278.649938) (xy 63.85814 -278.649176) (xy 63.835534 -278.656288) (xy 63.759588 -278.729186)
			(xy 63.75146 -278.751538) (xy 63.752984 -278.763476) (xy 63.753972 -278.772523) (xy 63.754988 -278.790697)
			(xy 63.755016 -278.799798) (xy 63.75453 -278.82462) (xy 63.746499 -278.873609) (xy 63.730648 -278.920654)
			(xy 63.707395 -278.964514) (xy 63.677352 -279.004035) (xy 63.641311 -279.038175) (xy 63.600222 -279.066034)
			(xy 63.555167 -279.086879) (xy 63.507333 -279.10016) (xy 63.457981 -279.105527) (xy 63.40841 -279.102839)
			(xy 63.359927 -279.092167) (xy 63.31381 -279.073792) (xy 63.271273 -279.048197) (xy 63.233437 -279.016059)
			(xy 63.201299 -278.978222) (xy 63.175706 -278.935685) (xy 63.157331 -278.889567) (xy 63.14666 -278.841084)
			(xy 63.143973 -278.791513) (xy 63.149341 -278.742161) (xy 63.162623 -278.694327) (xy 63.183469 -278.649273)
			(xy 63.211329 -278.608184) (xy 63.245469 -278.572144) (xy 63.284991 -278.542102) (xy 63.328852 -278.51885)
			(xy 63.375897 -278.502999) (xy 63.424886 -278.494969) (xy 63.449708 -278.49449) (xy 63.458745 -278.494537)
			(xy 63.47679 -278.495556) (xy 63.485776 -278.496522) (xy 63.497714 -278.498046) (xy 63.520066 -278.489918)
			(xy 63.592964 -278.413718) (xy 63.600076 -278.391112) (xy 63.59906 -278.38527) (xy 63.596454 -278.370293)
			(xy 63.593657 -278.340019) (xy 63.593472 -278.324818) (xy 63.593472 -278.25446) (xy 63.592905 -278.24377)
			(xy 63.584238 -278.224223) (xy 63.576708 -278.216614) (xy 63.5127 -278.158956) (xy 63.491872 -278.152352)
			(xy 63.481458 -278.153622) (xy 63.449708 -278.155146) (xy 63.425715 -278.154676) (xy 63.37832 -278.147171)
			(xy 63.332683 -278.132345) (xy 63.289926 -278.110562) (xy 63.251103 -278.08236) (xy 63.21717 -278.048432)
			(xy 63.188962 -278.009613) (xy 63.167173 -277.96686) (xy 63.15234 -277.921224) (xy 63.144828 -277.873831)
			(xy 63.1444 -277.849838) (xy 63.144585 -277.835655) (xy 63.147255 -277.807415) (xy 63.149734 -277.79345)
			(xy 63.15202 -277.781004) (xy 63.144654 -277.757382) (xy 63.067184 -277.679912) (xy 63.043562 -277.672546)
			(xy 63.036958 -277.673816) (xy 63.021574 -277.6768) (xy 62.990397 -277.679978) (xy 62.974728 -277.680166)
			(xy 62.959186 -277.67996) (xy 62.928264 -277.67678) (xy 62.913006 -277.673816) (xy 62.91199 -277.673816)
			(xy 62.905894 -277.672546) (xy 62.882272 -277.679912) (xy 62.804802 -277.757382) (xy 62.797436 -277.781004)
			(xy 62.799722 -277.79345) (xy 62.802206 -277.807415) (xy 62.804875 -277.835655) (xy 62.805056 -277.849838)
			(xy 62.804583 -277.873829) (xy 62.797072 -277.921219) (xy 62.782242 -277.966851) (xy 62.760457 -278.009601)
			(xy 62.732254 -278.048419) (xy 62.698326 -278.082347) (xy 62.65951 -278.110552) (xy 62.61676 -278.132338)
			(xy 62.571128 -278.14717) (xy 62.523739 -278.154682) (xy 62.499748 -278.155146) (xy 62.468252 -278.153368)
			(xy 62.467744 -278.153368) (xy 62.457121 -278.152846) (xy 62.436911 -278.159398) (xy 62.428628 -278.166068)
			(xy 62.372494 -278.216614) (xy 62.364842 -278.224134) (xy 62.356172 -278.243739) (xy 62.35573 -278.25446)
			(xy 62.35573 -278.299418) (xy 62.355476 -278.306022) (xy 62.355476 -278.324818) (xy 62.355258 -278.339702)
			(xy 62.35246 -278.369339) (xy 62.349888 -278.384) (xy 62.349888 -278.385524) (xy 62.348872 -278.391366)
			(xy 62.355984 -278.413972) (xy 62.4205 -278.481536) (xy 62.429139 -278.489606) (xy 62.451376 -278.497555)
			(xy 62.463172 -278.496776) (xy 62.463426 -278.496776) (xy 62.47247 -278.495729) (xy 62.490644 -278.494588)
			(xy 62.499748 -278.49449) (xy 62.524568 -278.49498) (xy 62.573553 -278.503018) (xy 62.620593 -278.518875)
			(xy 62.664448 -278.542133) (xy 62.703962 -278.57218) (xy 62.738095 -278.608223) (xy 62.765947 -278.649314)
			(xy 62.786785 -278.694369) (xy 62.80006 -278.742201) (xy 62.805422 -278.791551) (xy 62.802729 -278.841119)
			(xy 62.792053 -278.889597) (xy 62.773675 -278.93571) (xy 62.748079 -278.978243) (xy 62.715939 -279.016074)
			(xy 62.678102 -279.048208) (xy 62.635566 -279.073797) (xy 62.58945 -279.092168) (xy 62.540969 -279.102836)
			(xy 62.491401 -279.10552) (xy 62.442052 -279.100151) (xy 62.394222 -279.086868) (xy 62.34917 -279.066023)
			(xy 62.308084 -279.038164) (xy 62.272047 -279.004025) (xy 62.242007 -278.964505) (xy 62.218755 -278.920647)
			(xy 62.202906 -278.873605) (xy 62.194876 -278.824618) (xy 62.19444 -278.799798) (xy 62.194545 -278.790757)
			(xy 62.19569 -278.772712) (xy 62.196726 -278.76373) (xy 62.196726 -278.763222) (xy 62.197996 -278.751538)
			(xy 62.189868 -278.729186) (xy 62.113668 -278.656288) (xy 62.091062 -278.64943) (xy 62.08268 -278.6507)
			(xy 62.068446 -278.653057) (xy 62.039703 -278.655599) (xy 62.025276 -278.65578) (xy 62.024514 -278.65578)
			(xy 62.009439 -278.655592) (xy 61.97942 -278.652794) (xy 61.96457 -278.650192) (xy 61.963554 -278.650192)
			(xy 61.95822 -278.649176) (xy 61.935614 -278.656288) (xy 61.859414 -278.729186) (xy 61.851286 -278.751538)
			(xy 61.85281 -278.763476) (xy 61.853798 -278.772523) (xy 61.854813 -278.790697) (xy 61.854842 -278.799798)
			(xy 61.854356 -278.824622) (xy 61.846324 -278.873617) (xy 61.830471 -278.920666) (xy 61.807215 -278.964531)
			(xy 61.777169 -279.004056) (xy 61.741124 -279.038198) (xy 61.70003 -279.06606) (xy 61.65497 -279.086906)
			(xy 61.60713 -279.100187) (xy 61.557773 -279.105553) (xy 61.508197 -279.102863) (xy 61.45971 -279.092189)
			(xy 61.413588 -279.07381) (xy 61.371048 -279.048212) (xy 61.333209 -279.016068) (xy 61.30107 -278.978226)
			(xy 61.275476 -278.935683) (xy 61.257102 -278.889559) (xy 61.246432 -278.841071) (xy 61.243748 -278.791495)
			(xy 61.249119 -278.742138) (xy 61.262406 -278.6943) (xy 61.283256 -278.649242) (xy 61.311122 -278.608151)
			(xy 61.345268 -278.57211) (xy 61.384796 -278.542068) (xy 61.428663 -278.518816) (xy 61.475714 -278.502968)
			(xy 61.52471 -278.494941) (xy 61.549534 -278.49449) (xy 61.558635 -278.49453) (xy 61.576807 -278.495549)
			(xy 61.585856 -278.496522) (xy 61.597794 -278.498046) (xy 61.620146 -278.489918) (xy 61.693044 -278.413718)
			(xy 61.700156 -278.391112) (xy 61.69914 -278.38527) (xy 61.696535 -278.370293) (xy 61.693737 -278.340019)
			(xy 61.693552 -278.324818) (xy 61.693552 -278.25446) (xy 61.692984 -278.243771) (xy 61.684315 -278.224226)
			(xy 61.676788 -278.216614) (xy 61.620654 -278.166068) (xy 61.612434 -278.15928) (xy 61.592177 -278.152698)
			(xy 61.581538 -278.153368) (xy 61.581284 -278.153368) (xy 61.549534 -278.155146) (xy 61.52554 -278.154678)
			(xy 61.478142 -278.147176) (xy 61.432501 -278.132352) (xy 61.389741 -278.110571) (xy 61.350914 -278.082369)
			(xy 61.316978 -278.04844) (xy 61.288766 -278.009621) (xy 61.266975 -277.966866) (xy 61.252141 -277.921228)
			(xy 61.244628 -277.873832) (xy 61.244226 -277.849838) (xy 61.244411 -277.835655) (xy 61.247081 -277.807416)
			(xy 61.24956 -277.79345) (xy 61.251846 -277.781004) (xy 61.24448 -277.757382) (xy 61.16701 -277.679912)
			(xy 61.143388 -277.672546) (xy 61.136784 -277.673816) (xy 61.124338 -277.676251) (xy 61.099159 -277.679299)
			(xy 61.086492 -277.679912) (xy 61.069396 -277.680393) (xy 61.035278 -277.677971) (xy 61.01842 -277.675086)
			(xy 61.005974 -277.6728) (xy 60.981844 -277.680166) (xy 60.904882 -277.757382) (xy 60.897516 -277.781004)
			(xy 60.899802 -277.79345) (xy 60.902285 -277.807415) (xy 60.904954 -277.835655) (xy 60.905136 -277.849838)
			(xy 60.904663 -277.873828) (xy 60.897152 -277.921217) (xy 60.882322 -277.966848) (xy 60.860536 -278.009597)
			(xy 60.832333 -278.048413) (xy 60.798405 -278.082339) (xy 60.759588 -278.110542) (xy 60.716838 -278.132325)
			(xy 60.671207 -278.147154) (xy 60.623818 -278.154663) (xy 60.599828 -278.155146) (xy 60.568078 -278.153368)
			(xy 60.56757 -278.153368) (xy 60.556952 -278.152861) (xy 60.536762 -278.159435) (xy 60.528454 -278.166068)
			(xy 60.47232 -278.216614) (xy 60.464665 -278.224133) (xy 60.45599 -278.243738) (xy 60.455556 -278.25446)
			(xy 60.455556 -278.30907) (xy 60.455302 -278.322532) (xy 60.455048 -278.324056) (xy 60.455048 -278.327866)
			(xy 60.454866 -278.338378) (xy 60.453339 -278.359348) (xy 60.452 -278.369776) (xy 60.452 -278.370284)
			(xy 60.45073 -278.379174) (xy 60.448698 -278.391112) (xy 60.45581 -278.413972) (xy 60.528708 -278.490172)
			(xy 60.55106 -278.4983) (xy 60.562998 -278.496776) (xy 60.572169 -278.495714) (xy 60.590596 -278.49457)
			(xy 60.599828 -278.49449) (xy 60.624649 -278.494978) (xy 60.673635 -278.503014) (xy 60.720676 -278.518868)
			(xy 60.764533 -278.542124) (xy 60.804049 -278.572169) (xy 60.838185 -278.608211) (xy 60.86604 -278.6493)
			(xy 60.88688 -278.694355) (xy 60.900157 -278.742187) (xy 60.905521 -278.791538) (xy 60.902831 -278.841106)
			(xy 60.892157 -278.889586) (xy 60.87378 -278.9357) (xy 60.848185 -278.978234) (xy 60.816046 -279.016067)
			(xy 60.77821 -279.048202) (xy 60.735673 -279.073793) (xy 60.689557 -279.092165) (xy 60.641076 -279.102835)
			(xy 60.591508 -279.105521) (xy 60.542158 -279.100152) (xy 60.494326 -279.08687) (xy 60.449274 -279.066025)
			(xy 60.408187 -279.038166) (xy 60.372149 -279.004027) (xy 60.342108 -278.964508) (xy 60.318856 -278.920649)
			(xy 60.303006 -278.873606) (xy 60.294976 -278.824619) (xy 60.29452 -278.799798) (xy 60.294625 -278.790757)
			(xy 60.29577 -278.772712) (xy 60.296806 -278.76373) (xy 60.296806 -278.763222) (xy 60.298076 -278.751538)
			(xy 60.289948 -278.729186) (xy 60.213748 -278.656288) (xy 60.191142 -278.649176) (xy 60.181998 -278.6507)
			(xy 60.167701 -278.653069) (xy 60.138831 -278.655612) (xy 60.12434 -278.65578) (xy 60.109074 -278.655622)
			(xy 60.078672 -278.652823) (xy 60.063634 -278.650192) (xy 60.06211 -278.649938) (xy 60.058046 -278.649176)
			(xy 60.03544 -278.656288) (xy 59.959494 -278.729186) (xy 59.951366 -278.751538) (xy 59.95289 -278.763476)
			(xy 59.953878 -278.772523) (xy 59.954894 -278.790697) (xy 59.954922 -278.799798) (xy 59.954436 -278.82462)
			(xy 59.946405 -278.873611) (xy 59.930553 -278.920657) (xy 59.9073 -278.964518) (xy 59.877256 -279.00404)
			(xy 59.841214 -279.03818) (xy 59.800124 -279.06604) (xy 59.755068 -279.086885) (xy 59.707232 -279.100166)
			(xy 59.657879 -279.105533) (xy 59.608307 -279.102845) (xy 59.559823 -279.092172) (xy 59.513705 -279.073796)
			(xy 59.471167 -279.048201) (xy 59.433331 -279.016061) (xy 59.401192 -278.978223) (xy 59.375599 -278.935684)
			(xy 59.357225 -278.889565) (xy 59.346554 -278.841081) (xy 59.343867 -278.791509) (xy 59.349236 -278.742156)
			(xy 59.362519 -278.694321) (xy 59.383366 -278.649266) (xy 59.411227 -278.608176) (xy 59.445369 -278.572136)
			(xy 59.484892 -278.542094) (xy 59.528754 -278.518842) (xy 59.575801 -278.502992) (xy 59.624792 -278.494963)
			(xy 59.649614 -278.49449) (xy 59.658715 -278.49453) (xy 59.676888 -278.495547) (xy 59.685936 -278.496522)
			(xy 59.697874 -278.498046) (xy 59.720226 -278.489918) (xy 59.793124 -278.413972) (xy 59.800236 -278.391366)
			(xy 59.799474 -278.38654) (xy 59.79676 -278.371382) (xy 59.793831 -278.340724) (xy 59.793632 -278.325326)
			(xy 59.793632 -278.25446) (xy 59.793064 -278.243771) (xy 59.784392 -278.224229) (xy 59.776868 -278.216614)
			(xy 59.720734 -278.166068) (xy 59.712513 -278.159283) (xy 59.692257 -278.152709) (xy 59.681618 -278.153368)
			(xy 59.681364 -278.153368) (xy 59.649614 -278.155146) (xy 59.624352 -278.154654) (xy 59.574518 -278.146341)
			(xy 59.526732 -278.129937) (xy 59.482297 -278.105892) (xy 59.442426 -278.074861) (xy 59.408207 -278.037691)
			(xy 59.380573 -277.995395) (xy 59.360277 -277.949128) (xy 59.347874 -277.900151) (xy 59.343702 -277.8498)
			(xy 59.347874 -277.799449) (xy 59.360277 -277.750472) (xy 59.380573 -277.704205) (xy 59.408207 -277.661909)
			(xy 59.442426 -277.624739) (xy 59.482297 -277.593708) (xy 59.526732 -277.569663) (xy 59.574518 -277.553259)
			(xy 59.624352 -277.544946) (xy 59.649614 -277.54453) (xy 59.68111 -277.546308) (xy 59.681618 -277.546308)
			(xy 59.692236 -277.546817) (xy 59.712428 -277.540244) (xy 59.720734 -277.533608) (xy 59.776868 -277.483062)
			(xy 59.784521 -277.475542) (xy 59.793188 -277.455937) (xy 59.793632 -277.445216) (xy 59.793632 -277.34895)
			(xy 59.79541 -277.314914) (xy 59.79668 -277.303484) (xy 59.78906 -277.281894) (xy 59.716416 -277.209504)
			(xy 59.694826 -277.202138) (xy 59.683396 -277.203408) (xy 59.649868 -277.205186) (xy 59.627144 -277.204773)
			(xy 59.582198 -277.198043) (xy 59.538747 -277.184723) (xy 59.497751 -277.165106) (xy 59.460118 -277.139626)
			(xy 59.42668 -277.108848) (xy 59.412124 -277.091394) (xy 59.404507 -277.082994) (xy 59.384074 -277.073228)
			(xy 59.372754 -277.072598) (xy 58.977022 -277.072598) (xy 58.965687 -277.073193) (xy 58.945221 -277.082939)
			(xy 58.937652 -277.091394) (xy 58.923073 -277.108828) (xy 58.889635 -277.139604) (xy 58.852006 -277.165086)
			(xy 58.811017 -277.184711) (xy 58.767572 -277.198046) (xy 58.72263 -277.204795) (xy 58.699908 -277.205186)
			(xy 58.685789 -277.204989) (xy 58.657677 -277.202322) (xy 58.643774 -277.199852) (xy 58.643266 -277.199852)
			(xy 58.631033 -277.198349) (xy 58.607533 -277.205649) (xy 58.598308 -277.213822) (xy 58.529982 -277.281894)
			(xy 58.522616 -277.306024) (xy 58.524902 -277.31847) (xy 58.527011 -277.330368) (xy 58.529556 -277.3544)
			(xy 58.529982 -277.366476) (xy 58.529982 -277.378414) (xy 58.529643 -277.393128) (xy 58.526467 -277.422391)
			(xy 58.523632 -277.436834) (xy 58.523632 -277.43785) (xy 58.522362 -277.443692) (xy 58.529982 -277.467822)
			(xy 58.598308 -277.535894) (xy 58.607547 -277.544042) (xy 58.631036 -277.551339) (xy 58.643266 -277.549864)
			(xy 58.64352 -277.549864) (xy 58.657485 -277.547379) (xy 58.685725 -277.544707) (xy 58.699908 -277.54453)
			(xy 58.724725 -277.545016) (xy 58.773705 -277.553047) (xy 58.82074 -277.568896) (xy 58.864592 -277.592146)
			(xy 58.904105 -277.622183) (xy 58.938239 -277.658217) (xy 58.966093 -277.699298) (xy 58.986934 -277.744345)
			(xy 59.000213 -277.792169) (xy 59.005581 -277.841512) (xy 59.002895 -277.891073) (xy 58.992226 -277.939547)
			(xy 58.973857 -277.985657) (xy 58.94827 -278.028187) (xy 58.916139 -278.066018) (xy 58.878311 -278.098152)
			(xy 58.835784 -278.123743) (xy 58.789676 -278.142118) (xy 58.741203 -278.152791) (xy 58.691642 -278.155481)
			(xy 58.642299 -278.150119) (xy 58.594473 -278.136844) (xy 58.549425 -278.116008) (xy 58.50834 -278.088158)
			(xy 58.472303 -278.054028) (xy 58.442262 -278.014518) (xy 58.419008 -277.970668) (xy 58.403155 -277.923634)
			(xy 58.395119 -277.874655) (xy 58.3946 -277.849838) (xy 58.3948 -277.835719) (xy 58.397473 -277.807608)
			(xy 58.399934 -277.793704) (xy 58.399934 -277.793196) (xy 58.401444 -277.78096) (xy 58.394153 -277.757452)
			(xy 58.385964 -277.748238) (xy 58.317384 -277.679912) (xy 58.293762 -277.672546) (xy 58.284618 -277.674324)
			(xy 58.257186 -277.678388) (xy 58.256678 -277.678388) (xy 58.234626 -277.680373) (xy 58.190381 -277.678718)
			(xy 58.16854 -277.675086) (xy 58.156094 -277.6728) (xy 58.131964 -277.680166) (xy 58.055002 -277.757382)
			(xy 58.047636 -277.781004) (xy 58.049922 -277.79345) (xy 58.052406 -277.807415) (xy 58.055075 -277.835655)
			(xy 58.055256 -277.849838) (xy 58.054783 -277.873829) (xy 58.047272 -277.921219) (xy 58.032442 -277.966851)
			(xy 58.010657 -278.009601) (xy 57.982454 -278.048419) (xy 57.948526 -278.082347) (xy 57.90971 -278.110552)
			(xy 57.86696 -278.132338) (xy 57.821328 -278.14717) (xy 57.773939 -278.154682) (xy 57.749948 -278.155146)
			(xy 57.717944 -278.153368) (xy 57.717436 -278.153368) (xy 57.706814 -278.152848) (xy 57.686606 -278.159402)
			(xy 57.67832 -278.166068) (xy 57.622186 -278.216614) (xy 57.614523 -278.224129) (xy 57.605836 -278.243735)
			(xy 57.605422 -278.25446) (xy 57.605422 -278.299418) (xy 57.605168 -278.306022) (xy 57.605168 -278.324818)
			(xy 57.60495 -278.339702) (xy 57.602152 -278.369339) (xy 57.59958 -278.384) (xy 57.59958 -278.385524)
			(xy 57.598564 -278.391366) (xy 57.605676 -278.413972) (xy 57.678828 -278.490172) (xy 57.70118 -278.4983)
			(xy 57.713118 -278.496776) (xy 57.722289 -278.495715) (xy 57.740716 -278.494571) (xy 57.749948 -278.49449)
			(xy 57.774768 -278.49498) (xy 57.823753 -278.503018) (xy 57.870793 -278.518875) (xy 57.914648 -278.542133)
			(xy 57.954162 -278.57218) (xy 57.988295 -278.608223) (xy 58.016147 -278.649314) (xy 58.036985 -278.694369)
			(xy 58.05026 -278.742201) (xy 58.055622 -278.791551) (xy 58.055174 -278.799798) (xy 58.394104 -278.799798)
			(xy 58.398064 -278.750744) (xy 58.409841 -278.70296) (xy 58.429132 -278.657684) (xy 58.455435 -278.616088)
			(xy 58.48807 -278.579251) (xy 58.526191 -278.548126) (xy 58.568812 -278.523519) (xy 58.614828 -278.506067)
			(xy 58.663047 -278.496223) (xy 58.712222 -278.494242) (xy 58.761077 -278.500174) (xy 58.808348 -278.513866)
			(xy 58.85281 -278.534964) (xy 58.893313 -278.56292) (xy 58.928806 -278.597012) (xy 58.958371 -278.636356)
			(xy 58.981242 -278.679933) (xy 58.996826 -278.726614) (xy 59.004721 -278.775191) (xy 59.005216 -278.799798)
			(xy 59.004721 -278.824405) (xy 58.996826 -278.872982) (xy 58.981242 -278.919663) (xy 58.958371 -278.96324)
			(xy 58.928806 -279.002584) (xy 58.893313 -279.036676) (xy 58.85281 -279.064632) (xy 58.808348 -279.08573)
			(xy 58.761077 -279.099422) (xy 58.712222 -279.105354) (xy 58.663047 -279.103373) (xy 58.614828 -279.093529)
			(xy 58.568812 -279.076077) (xy 58.526191 -279.05147) (xy 58.48807 -279.020345) (xy 58.455435 -278.983508)
			(xy 58.429132 -278.941912) (xy 58.409841 -278.896636) (xy 58.398064 -278.848852) (xy 58.394104 -278.799798)
			(xy 58.055174 -278.799798) (xy 58.052929 -278.841119) (xy 58.042253 -278.889597) (xy 58.023875 -278.93571)
			(xy 57.998279 -278.978243) (xy 57.966139 -279.016074) (xy 57.928302 -279.048208) (xy 57.885766 -279.073797)
			(xy 57.83965 -279.092168) (xy 57.791169 -279.102836) (xy 57.741601 -279.10552) (xy 57.692252 -279.100151)
			(xy 57.644422 -279.086868) (xy 57.59937 -279.066023) (xy 57.558284 -279.038164) (xy 57.522247 -279.004025)
			(xy 57.492207 -278.964505) (xy 57.468955 -278.920647) (xy 57.453106 -278.873605) (xy 57.445076 -278.824618)
			(xy 57.44464 -278.799798) (xy 57.444745 -278.790757) (xy 57.44589 -278.772712) (xy 57.446926 -278.76373)
			(xy 57.446926 -278.763222) (xy 57.448196 -278.751538) (xy 57.440068 -278.729186) (xy 57.363868 -278.656288)
			(xy 57.341008 -278.649176) (xy 57.32907 -278.651208) (xy 57.315456 -278.653354) (xy 57.287988 -278.655645)
			(xy 57.274206 -278.65578) (xy 57.260747 -278.655654) (xy 57.233917 -278.653493) (xy 57.220612 -278.651462)
			(xy 57.220358 -278.651462) (xy 57.208619 -278.650168) (xy 57.1861 -278.657186) (xy 57.177178 -278.664924)
			(xy 57.109868 -278.72944) (xy 57.10174 -278.751792) (xy 57.103264 -278.76373) (xy 57.104248 -278.772714)
			(xy 57.105267 -278.79076) (xy 57.105296 -278.799798) (xy 57.10481 -278.824618) (xy 57.09678 -278.873603)
			(xy 57.08093 -278.920644) (xy 57.057679 -278.964502) (xy 57.027639 -279.00402) (xy 56.991602 -279.038157)
			(xy 56.950516 -279.066015) (xy 56.905465 -279.086858) (xy 56.857635 -279.100139) (xy 56.808287 -279.105507)
			(xy 56.75872 -279.10282) (xy 56.710241 -279.09215) (xy 56.664127 -279.073778) (xy 56.621592 -279.048187)
			(xy 56.583758 -279.016052) (xy 56.551622 -278.978219) (xy 56.526029 -278.935686) (xy 56.507654 -278.889572)
			(xy 56.496982 -278.841094) (xy 56.494293 -278.791527) (xy 56.499658 -278.742179) (xy 56.512937 -278.694348)
			(xy 56.533779 -278.649296) (xy 56.561634 -278.608209) (xy 56.59577 -278.57217) (xy 56.635287 -278.542128)
			(xy 56.679143 -278.518875) (xy 56.726183 -278.503023) (xy 56.775168 -278.494991) (xy 56.799988 -278.49449)
			(xy 56.808898 -278.494538) (xy 56.82669 -278.495555) (xy 56.835548 -278.496522) (xy 56.847437 -278.497311)
			(xy 56.869814 -278.489216) (xy 56.878474 -278.481028) (xy 56.942736 -278.413718) (xy 56.949848 -278.391112)
			(xy 56.949086 -278.38654) (xy 56.946352 -278.371256) (xy 56.943429 -278.340343) (xy 56.943244 -278.324818)
			(xy 56.943244 -278.254714) (xy 56.942686 -278.24402) (xy 56.93403 -278.224461) (xy 56.92648 -278.216868)
			(xy 56.8706 -278.166576) (xy 56.862339 -278.159843) (xy 56.842131 -278.153149) (xy 56.831484 -278.153622)
			(xy 56.83123 -278.153622) (xy 56.799988 -278.155146) (xy 56.775996 -278.154675) (xy 56.728604 -278.147167)
			(xy 56.682969 -278.132339) (xy 56.640215 -278.110556) (xy 56.601395 -278.082353) (xy 56.567464 -278.048425)
			(xy 56.539258 -278.009607) (xy 56.517471 -277.966855) (xy 56.502639 -277.921221) (xy 56.495128 -277.87383)
			(xy 56.49468 -277.849838) (xy 56.49488 -277.835719) (xy 56.497553 -277.807608) (xy 56.500014 -277.793704)
			(xy 56.500014 -277.793196) (xy 56.501524 -277.780959) (xy 56.494241 -277.757445) (xy 56.486044 -277.748238)
			(xy 56.417718 -277.679912) (xy 56.393588 -277.672546) (xy 56.38673 -277.673816) (xy 56.357012 -277.678388)
			(xy 56.356504 -277.678388) (xy 56.334452 -277.680375) (xy 56.290207 -277.678723) (xy 56.268366 -277.675086)
			(xy 56.25592 -277.6728) (xy 56.23179 -277.680166) (xy 56.154828 -277.757382) (xy 56.147462 -277.781004)
			(xy 56.149748 -277.79345) (xy 56.152232 -277.807415) (xy 56.154901 -277.835655) (xy 56.155082 -277.849838)
			(xy 56.154609 -277.873827) (xy 56.147098 -277.921212) (xy 56.132266 -277.966839) (xy 56.11048 -278.009585)
			(xy 56.082276 -278.048396) (xy 56.048347 -278.082318) (xy 56.00953 -278.110514) (xy 55.96678 -278.132291)
			(xy 55.92115 -278.147112) (xy 55.873763 -278.154614) (xy 55.849774 -278.155146) (xy 55.81777 -278.153368)
			(xy 55.817262 -278.153368) (xy 55.806848 -278.152352) (xy 55.786528 -278.158956) (xy 55.722012 -278.216614)
			(xy 55.714358 -278.224134) (xy 55.705685 -278.243738) (xy 55.705248 -278.25446) (xy 55.705248 -278.30907)
			(xy 55.704994 -278.322532) (xy 55.70474 -278.324056) (xy 55.70474 -278.327866) (xy 55.704565 -278.338441)
			(xy 55.703043 -278.35954) (xy 55.701692 -278.37003) (xy 55.698898 -278.386794) (xy 55.698898 -278.38781)
			(xy 55.698136 -278.391366) (xy 55.705248 -278.413972) (xy 55.7784 -278.490172) (xy 55.800752 -278.4983)
			(xy 55.81269 -278.496776) (xy 55.821924 -278.495708) (xy 55.840479 -278.494564) (xy 55.849774 -278.49449)
			(xy 55.874596 -278.494974) (xy 55.923585 -278.503001) (xy 55.970631 -278.518849) (xy 56.014493 -278.542098)
			(xy 56.054015 -278.572138) (xy 56.088157 -278.608176) (xy 56.116019 -278.649264) (xy 56.136866 -278.694317)
			(xy 56.15015 -278.74215) (xy 56.15552 -278.791501) (xy 56.152835 -278.841072) (xy 56.142166 -278.889555)
			(xy 56.123794 -278.935673) (xy 56.098202 -278.978211) (xy 56.066065 -279.016048) (xy 56.02823 -279.048188)
			(xy 55.985694 -279.073783) (xy 55.939578 -279.092159) (xy 55.891096 -279.102832) (xy 55.841525 -279.105521)
			(xy 55.792173 -279.100155) (xy 55.74434 -279.086875) (xy 55.699284 -279.066031) (xy 55.658195 -279.038172)
			(xy 55.622154 -279.004033) (xy 55.592111 -278.964513) (xy 55.568858 -278.920653) (xy 55.553007 -278.873609)
			(xy 55.544976 -278.82462) (xy 55.544466 -278.799798) (xy 55.544571 -278.790757) (xy 55.545716 -278.772712)
			(xy 55.546752 -278.76373) (xy 55.546752 -278.763222) (xy 55.548022 -278.751538) (xy 55.539894 -278.729186)
			(xy 55.463694 -278.656288) (xy 55.440834 -278.649176) (xy 55.428896 -278.651208) (xy 55.415282 -278.653356)
			(xy 55.387814 -278.655647) (xy 55.374032 -278.65578) (xy 55.360574 -278.655652) (xy 55.333744 -278.653486)
			(xy 55.320438 -278.651462) (xy 55.320184 -278.651462) (xy 55.308443 -278.650162) (xy 55.285915 -278.657172)
			(xy 55.277004 -278.664924) (xy 55.209694 -278.72944) (xy 55.201566 -278.751792) (xy 55.20309 -278.76373)
			(xy 55.204074 -278.772714) (xy 55.205093 -278.79076) (xy 55.205122 -278.799798) (xy 55.204636 -278.82462)
			(xy 55.196605 -278.873611) (xy 55.180753 -278.920657) (xy 55.1575 -278.964518) (xy 55.127456 -279.00404)
			(xy 55.091414 -279.03818) (xy 55.050324 -279.06604) (xy 55.005268 -279.086885) (xy 54.957432 -279.100166)
			(xy 54.908079 -279.105533) (xy 54.858507 -279.102845) (xy 54.810023 -279.092172) (xy 54.763905 -279.073796)
			(xy 54.721367 -279.048201) (xy 54.683531 -279.016061) (xy 54.651392 -278.978223) (xy 54.625799 -278.935684)
			(xy 54.607425 -278.889565) (xy 54.596754 -278.841081) (xy 54.594067 -278.791509) (xy 54.599436 -278.742156)
			(xy 54.612719 -278.694321) (xy 54.633566 -278.649266) (xy 54.661427 -278.608176) (xy 54.695569 -278.572136)
			(xy 54.735092 -278.542094) (xy 54.778954 -278.518842) (xy 54.826001 -278.502992) (xy 54.874992 -278.494963)
			(xy 54.899814 -278.49449) (xy 54.908788 -278.49453) (xy 54.926707 -278.495544) (xy 54.935628 -278.496522)
			(xy 54.947566 -278.498046) (xy 54.969918 -278.489918) (xy 55.042562 -278.413718) (xy 55.049674 -278.390858)
			(xy 55.047642 -278.379174) (xy 55.045592 -278.365807) (xy 55.043427 -278.338849) (xy 55.043324 -278.325326)
			(xy 55.043324 -278.25446) (xy 55.042758 -278.243769) (xy 55.034098 -278.224216) (xy 55.02656 -278.216614)
			(xy 54.962552 -278.158956) (xy 54.941724 -278.152352) (xy 54.93131 -278.153622) (xy 54.899814 -278.155146)
			(xy 54.875821 -278.154676) (xy 54.828425 -278.147172) (xy 54.782787 -278.132347) (xy 54.74003 -278.110564)
			(xy 54.701206 -278.082362) (xy 54.667272 -278.048434) (xy 54.639063 -278.009615) (xy 54.617273 -277.966861)
			(xy 54.60244 -277.921225) (xy 54.594928 -277.873831) (xy 54.594506 -277.849838) (xy 54.594706 -277.835719)
			(xy 54.59738 -277.807608) (xy 54.59984 -277.793704) (xy 54.59984 -277.793196) (xy 54.60135 -277.78096)
			(xy 54.594059 -277.757451) (xy 54.58587 -277.748238) (xy 54.51729 -277.679912) (xy 54.493668 -277.672546)
			(xy 54.484524 -277.674324) (xy 54.457092 -277.678388) (xy 54.456584 -277.678388) (xy 54.434532 -277.680374)
			(xy 54.390287 -277.678719) (xy 54.368446 -277.675086) (xy 54.356 -277.6728) (xy 54.33187 -277.680166)
			(xy 54.254908 -277.757382) (xy 54.247542 -277.781004) (xy 54.249828 -277.79345) (xy 54.252312 -277.807415)
			(xy 54.254981 -277.835655) (xy 54.255162 -277.849838) (xy 54.254713 -277.873828) (xy 54.247201 -277.921216)
			(xy 54.232369 -277.966846) (xy 54.210581 -278.009593) (xy 54.182374 -278.048406) (xy 54.148442 -278.082328)
			(xy 54.109621 -278.110525) (xy 54.066868 -278.132301) (xy 54.021234 -278.147121) (xy 53.973844 -278.15462)
			(xy 53.949854 -278.155146) (xy 53.917596 -278.153368) (xy 53.917088 -278.153368) (xy 53.906674 -278.152352)
			(xy 53.886354 -278.158956) (xy 53.821838 -278.216614) (xy 53.81418 -278.224132) (xy 53.805503 -278.243737)
			(xy 53.805074 -278.25446) (xy 53.805074 -278.299418) (xy 53.80482 -278.306022) (xy 53.80482 -278.324818)
			(xy 53.804602 -278.339702) (xy 53.801804 -278.369339) (xy 53.799232 -278.384) (xy 53.799232 -278.385524)
			(xy 53.798216 -278.391366) (xy 53.805328 -278.413972) (xy 53.87848 -278.490172) (xy 53.900832 -278.4983)
			(xy 53.91277 -278.496776) (xy 53.922004 -278.495707) (xy 53.940559 -278.494562) (xy 53.949854 -278.49449)
			(xy 53.974676 -278.494972) (xy 54.023667 -278.502997) (xy 54.070714 -278.518841) (xy 54.114578 -278.542089)
			(xy 54.154103 -278.572127) (xy 54.188247 -278.608164) (xy 54.216111 -278.64925) (xy 54.236961 -278.694303)
			(xy 54.250248 -278.742136) (xy 54.25562 -278.791488) (xy 54.252937 -278.841059) (xy 54.24227 -278.889543)
			(xy 54.223899 -278.935662) (xy 54.198308 -278.978202) (xy 54.166172 -279.016041) (xy 54.128338 -279.048182)
			(xy 54.085802 -279.073779) (xy 54.039685 -279.092157) (xy 53.991203 -279.102831) (xy 53.941632 -279.105521)
			(xy 53.892279 -279.100156) (xy 53.844444 -279.086877) (xy 53.799388 -279.066033) (xy 53.758298 -279.038175)
			(xy 53.722256 -279.004036) (xy 53.692213 -278.964515) (xy 53.668959 -278.920654) (xy 53.653107 -278.87361)
			(xy 53.645076 -278.82462) (xy 53.644546 -278.799798) (xy 53.644651 -278.790757) (xy 53.645796 -278.772712)
			(xy 53.646832 -278.76373) (xy 53.646832 -278.762968) (xy 53.647535 -278.751298) (xy 53.639582 -278.729341)
			(xy 53.631592 -278.720804) (xy 53.563774 -278.656288) (xy 53.540914 -278.649176) (xy 53.528976 -278.651208)
			(xy 53.515299 -278.653367) (xy 53.487704 -278.65566) (xy 53.473858 -278.65578) (xy 53.4604 -278.655652)
			(xy 53.43357 -278.653487) (xy 53.420264 -278.651462) (xy 53.408326 -278.64943) (xy 53.38572 -278.656542)
			(xy 53.309774 -278.72944) (xy 53.301646 -278.751792) (xy 53.30317 -278.76373) (xy 53.304154 -278.772714)
			(xy 53.305173 -278.79076) (xy 53.305202 -278.799798) (xy 53.304716 -278.824618) (xy 53.296686 -278.873605)
			(xy 53.280836 -278.920647) (xy 53.257584 -278.964505) (xy 53.227543 -279.004024) (xy 53.191505 -279.038162)
			(xy 53.150418 -279.06602) (xy 53.105365 -279.086864) (xy 53.057534 -279.100145) (xy 53.008185 -279.105513)
			(xy 52.958617 -279.102826) (xy 52.910137 -279.092155) (xy 52.864022 -279.073782) (xy 52.821486 -279.04819)
			(xy 52.783652 -279.016054) (xy 52.751515 -278.97822) (xy 52.725922 -278.935685) (xy 52.707547 -278.889571)
			(xy 52.696875 -278.841091) (xy 52.694187 -278.791523) (xy 52.699553 -278.742173) (xy 52.712833 -278.694342)
			(xy 52.733676 -278.649289) (xy 52.761533 -278.608202) (xy 52.79567 -278.572162) (xy 52.835188 -278.54212)
			(xy 52.879045 -278.518867) (xy 52.926087 -278.503016) (xy 52.975074 -278.494984) (xy 52.999894 -278.49449)
			(xy 53.008804 -278.494538) (xy 53.026596 -278.495556) (xy 53.035454 -278.496522) (xy 53.047138 -278.498046)
			(xy 53.069998 -278.489918) (xy 53.142388 -278.413718) (xy 53.1495 -278.391112) (xy 53.148738 -278.38654)
			(xy 53.146005 -278.371256) (xy 53.143082 -278.340343) (xy 53.142896 -278.324818) (xy 53.142896 -278.254714)
			(xy 53.14234 -278.244019) (xy 53.13369 -278.224454) (xy 53.126132 -278.216868) (xy 53.070252 -278.166576)
			(xy 53.061993 -278.159834) (xy 53.041783 -278.153119) (xy 53.031136 -278.153622) (xy 53.030882 -278.153622)
			(xy 52.999894 -278.155146) (xy 52.975902 -278.154675) (xy 52.928509 -278.147168) (xy 52.882873 -278.132341)
			(xy 52.840119 -278.110558) (xy 52.801298 -278.082355) (xy 52.767366 -278.048427) (xy 52.739159 -278.009609)
			(xy 52.717371 -277.966856) (xy 52.702539 -277.921222) (xy 52.695028 -277.87383) (xy 52.694586 -277.849838)
			(xy 52.694786 -277.835719) (xy 52.697459 -277.807608) (xy 52.69992 -277.793704) (xy 52.69992 -277.793196)
			(xy 52.701565 -277.780953) (xy 52.694253 -277.757383) (xy 52.68595 -277.748238) (xy 52.61737 -277.679912)
			(xy 52.593748 -277.672546) (xy 52.584604 -277.674324) (xy 52.557172 -277.678388) (xy 52.556664 -277.678388)
			(xy 52.534612 -277.680372) (xy 52.490368 -277.678715) (xy 52.468526 -277.675086) (xy 52.45608 -277.6728)
			(xy 52.43195 -277.680166) (xy 52.354988 -277.757382) (xy 52.347622 -277.781004) (xy 52.349908 -277.79345)
			(xy 52.352391 -277.807415) (xy 52.35506 -277.835655) (xy 52.355242 -277.849838) (xy 52.354769 -277.873828)
			(xy 52.347258 -277.921217) (xy 52.332428 -277.966848) (xy 52.310643 -278.009598) (xy 52.282439 -278.048415)
			(xy 52.248512 -278.082342) (xy 52.209695 -278.110545) (xy 52.166945 -278.132329) (xy 52.121313 -278.147159)
			(xy 52.073924 -278.154669) (xy 52.049934 -278.155146) (xy 52.017676 -278.153368) (xy 52.017168 -278.153368)
			(xy 52.006754 -278.152352) (xy 51.986434 -278.158956) (xy 51.921918 -278.216614) (xy 51.914263 -278.224133)
			(xy 51.905589 -278.243738) (xy 51.905154 -278.25446) (xy 51.905154 -278.299418) (xy 51.9049 -278.306022)
			(xy 51.9049 -278.324818) (xy 51.904682 -278.339702) (xy 51.901884 -278.369339) (xy 51.899312 -278.384)
			(xy 51.899312 -278.385524) (xy 51.898296 -278.391366) (xy 51.905408 -278.413972) (xy 51.97856 -278.490172)
			(xy 52.000912 -278.4983) (xy 52.01285 -278.496776) (xy 52.022084 -278.495707) (xy 52.040639 -278.494561)
			(xy 52.049934 -278.49449) (xy 52.074754 -278.494979) (xy 52.123741 -278.503015) (xy 52.170781 -278.51887)
			(xy 52.214637 -278.542127) (xy 52.254153 -278.572172) (xy 52.288288 -278.608214) (xy 52.316142 -278.649304)
			(xy 52.336982 -278.694359) (xy 52.350258 -278.742191) (xy 52.355621 -278.791542) (xy 52.35293 -278.84111)
			(xy 52.342255 -278.889589) (xy 52.323878 -278.935703) (xy 52.298283 -278.978237) (xy 52.266144 -279.016069)
			(xy 52.228308 -279.048204) (xy 52.185771 -279.073794) (xy 52.139655 -279.092166) (xy 52.091174 -279.102835)
			(xy 52.041606 -279.105521) (xy 51.992256 -279.100151) (xy 51.944425 -279.086869) (xy 51.899373 -279.066024)
			(xy 51.858286 -279.038165) (xy 51.822248 -279.004026) (xy 51.792207 -278.964507) (xy 51.768956 -278.920648)
			(xy 51.753106 -278.873606) (xy 51.745076 -278.824618) (xy 51.744626 -278.799798) (xy 51.744731 -278.790757)
			(xy 51.745876 -278.772712) (xy 51.746912 -278.76373) (xy 51.746912 -278.762968) (xy 51.747615 -278.751299)
			(xy 51.73966 -278.729343) (xy 51.731672 -278.720804) (xy 51.663854 -278.656288) (xy 51.640994 -278.649176)
			(xy 51.629056 -278.651208) (xy 51.615379 -278.653367) (xy 51.587783 -278.655658) (xy 51.573938 -278.65578)
			(xy 51.560479 -278.655656) (xy 51.533649 -278.653497) (xy 51.520344 -278.651462) (xy 51.508406 -278.64943)
			(xy 51.4858 -278.656542) (xy 51.409854 -278.72944) (xy 51.401726 -278.751792) (xy 51.40325 -278.76373)
			(xy 51.404234 -278.772714) (xy 51.405253 -278.79076) (xy 51.405282 -278.799798) (xy 51.404796 -278.824616)
			(xy 51.396767 -278.873599) (xy 51.380918 -278.920638) (xy 51.357668 -278.964493) (xy 51.32763 -279.004009)
			(xy 51.291595 -279.038144) (xy 51.250512 -279.066001) (xy 51.205463 -279.086844) (xy 51.157636 -279.100124)
			(xy 51.108291 -279.105493) (xy 51.058727 -279.102807) (xy 51.01025 -279.092138) (xy 50.964138 -279.073768)
			(xy 50.921606 -279.048179) (xy 50.883773 -279.016047) (xy 50.851637 -278.978217) (xy 50.826045 -278.935687)
			(xy 50.80767 -278.889576) (xy 50.796997 -278.841101) (xy 50.794307 -278.791537) (xy 50.79967 -278.742191)
			(xy 50.812946 -278.694363) (xy 50.833785 -278.649312) (xy 50.861638 -278.608227) (xy 50.895771 -278.572188)
			(xy 50.935284 -278.542147) (xy 50.979137 -278.518893) (xy 51.026174 -278.50304) (xy 51.075156 -278.495006)
			(xy 51.099974 -278.49449) (xy 51.108884 -278.494537) (xy 51.126676 -278.495554) (xy 51.135534 -278.496522)
			(xy 51.147218 -278.498046) (xy 51.170078 -278.489918) (xy 51.242468 -278.413718) (xy 51.24958 -278.391112)
			(xy 51.248818 -278.38654) (xy 51.246085 -278.371256) (xy 51.243162 -278.340343) (xy 51.242976 -278.324818)
			(xy 51.242976 -278.254714) (xy 51.242419 -278.244019) (xy 51.233767 -278.224456) (xy 51.226212 -278.216868)
			(xy 51.170332 -278.166576) (xy 51.162072 -278.159837) (xy 51.141863 -278.153131) (xy 51.131216 -278.153622)
			(xy 51.130962 -278.153622) (xy 51.099974 -278.155146) (xy 51.075983 -278.154673) (xy 51.028592 -278.147164)
			(xy 50.982959 -278.132335) (xy 50.940207 -278.110551) (xy 50.901389 -278.082348) (xy 50.86746 -278.04842)
			(xy 50.839255 -278.009603) (xy 50.817469 -277.966852) (xy 50.802638 -277.921219) (xy 50.795127 -277.873829)
			(xy 50.794666 -277.849838) (xy 50.794866 -277.835719) (xy 50.797539 -277.807608) (xy 50.8 -277.793704)
			(xy 50.8 -277.793196) (xy 50.80151 -277.780959) (xy 50.794226 -277.757446) (xy 50.78603 -277.748238)
			(xy 50.71745 -277.679912) (xy 50.693828 -277.672546) (xy 50.684684 -277.674324) (xy 50.654479 -277.679581)
			(xy 50.593179 -277.679324) (xy 50.563018 -277.673816) (xy 50.562002 -277.673816) (xy 50.555906 -277.672546)
			(xy 50.532284 -277.679912) (xy 50.454814 -277.757382) (xy 50.447448 -277.781004) (xy 50.449734 -277.79345)
			(xy 50.452218 -277.807415) (xy 50.454887 -277.835655) (xy 50.455068 -277.849838) (xy 50.454619 -277.873828)
			(xy 50.447107 -277.921217) (xy 50.432275 -277.966847) (xy 50.410487 -278.009595) (xy 50.38228 -278.048408)
			(xy 50.348348 -278.082331) (xy 50.309528 -278.110528) (xy 50.266774 -278.132305) (xy 50.221141 -278.147125)
			(xy 50.17375 -278.154625) (xy 50.14976 -278.155146) (xy 50.117756 -278.153368) (xy 50.117248 -278.153368)
			(xy 50.106625 -278.152845) (xy 50.086414 -278.159396) (xy 50.078132 -278.166068) (xy 50.021998 -278.216614)
			(xy 50.014345 -278.224134) (xy 50.005675 -278.243739) (xy 50.005234 -278.25446) (xy 50.005234 -278.299418)
			(xy 50.00498 -278.306022) (xy 50.00498 -278.324818) (xy 50.004762 -278.339702) (xy 50.001964 -278.369339)
			(xy 49.999392 -278.384) (xy 49.999392 -278.385524) (xy 49.998376 -278.391366) (xy 50.005488 -278.413972)
			(xy 50.07864 -278.490172) (xy 50.100992 -278.4983) (xy 50.11293 -278.496776) (xy 50.122101 -278.495715)
			(xy 50.140528 -278.494572) (xy 50.14976 -278.49449) (xy 50.174582 -278.494973) (xy 50.223572 -278.502998)
			(xy 50.270619 -278.518843) (xy 50.314482 -278.542092) (xy 50.354007 -278.57213) (xy 50.38815 -278.608168)
			(xy 50.416014 -278.649254) (xy 50.436863 -278.694307) (xy 50.450148 -278.74214) (xy 50.45552 -278.791492)
			(xy 50.452837 -278.841063) (xy 50.442169 -278.889547) (xy 50.423797 -278.935666) (xy 50.398206 -278.978205)
			(xy 50.36607 -279.016043) (xy 50.328236 -279.048184) (xy 50.2857 -279.07378) (xy 50.239583 -279.092157)
			(xy 50.191101 -279.102831) (xy 50.14153 -279.105521) (xy 50.092177 -279.100156) (xy 50.044343 -279.086876)
			(xy 49.999287 -279.066032) (xy 49.958197 -279.038174) (xy 49.922156 -279.004035) (xy 49.892112 -278.964514)
			(xy 49.868858 -278.920654) (xy 49.853007 -278.873609) (xy 49.844976 -278.82462) (xy 49.844452 -278.799798)
			(xy 49.844557 -278.790757) (xy 49.845702 -278.772712) (xy 49.846738 -278.76373) (xy 49.846738 -278.763222)
			(xy 49.848008 -278.751538) (xy 49.83988 -278.729186) (xy 49.76368 -278.656288) (xy 49.74082 -278.649176)
			(xy 49.728882 -278.651208) (xy 49.715268 -278.653355) (xy 49.6878 -278.655646) (xy 49.674018 -278.65578)
			(xy 49.660559 -278.655655) (xy 49.633729 -278.653495) (xy 49.620424 -278.651462) (xy 49.62017 -278.651462)
			(xy 49.60843 -278.650166) (xy 49.585907 -278.65718) (xy 49.57699 -278.664924) (xy 49.50968 -278.72944)
			(xy 49.501552 -278.751792) (xy 49.503076 -278.76373) (xy 49.50406 -278.772714) (xy 49.505079 -278.79076)
			(xy 49.505108 -278.799798) (xy 49.504622 -278.824619) (xy 49.496591 -278.873607) (xy 49.480741 -278.92065)
			(xy 49.457489 -278.964509) (xy 49.427447 -279.004029) (xy 49.391407 -279.038168) (xy 49.35032 -279.066026)
			(xy 49.305266 -279.086871) (xy 49.257434 -279.100151) (xy 49.208083 -279.105519) (xy 49.158514 -279.102831)
			(xy 49.110033 -279.09216) (xy 49.063917 -279.073786) (xy 49.021381 -279.048193) (xy 48.983546 -279.016056)
			(xy 48.951408 -278.978221) (xy 48.925815 -278.935685) (xy 48.90744 -278.889569) (xy 48.896769 -278.841088)
			(xy 48.894081 -278.791519) (xy 48.899448 -278.742168) (xy 48.912729 -278.694336) (xy 48.933573 -278.649282)
			(xy 48.961431 -278.608194) (xy 48.99557 -278.572154) (xy 49.035089 -278.542112) (xy 49.078948 -278.51886)
			(xy 49.125991 -278.503009) (xy 49.174979 -278.494978) (xy 49.1998 -278.49449) (xy 49.20871 -278.494538)
			(xy 49.226502 -278.495556) (xy 49.23536 -278.496522) (xy 49.247257 -278.497331) (xy 49.269663 -278.489262)
			(xy 49.278286 -278.481028) (xy 49.342548 -278.413718) (xy 49.34966 -278.391112) (xy 49.348898 -278.38654)
			(xy 49.346165 -278.371256) (xy 49.343242 -278.340343) (xy 49.343056 -278.324818) (xy 49.343056 -278.254714)
			(xy 49.342498 -278.24402) (xy 49.333844 -278.224459) (xy 49.326292 -278.216868) (xy 49.270412 -278.166576)
			(xy 49.262151 -278.159841) (xy 49.241943 -278.153142) (xy 49.231296 -278.153622) (xy 49.231042 -278.153622)
			(xy 49.1998 -278.155146) (xy 49.175808 -278.154675) (xy 49.128414 -278.14717) (xy 49.082777 -278.132343)
			(xy 49.040022 -278.11056) (xy 49.0012 -278.082357) (xy 48.967268 -278.048429) (xy 48.93906 -278.009611)
			(xy 48.917272 -277.966858) (xy 48.902439 -277.921223) (xy 48.894928 -277.87383) (xy 48.894492 -277.849838)
			(xy 48.894692 -277.835719) (xy 48.897365 -277.807608) (xy 48.899826 -277.793704) (xy 48.899826 -277.793196)
			(xy 48.901336 -277.78096) (xy 48.894044 -277.757453) (xy 48.885856 -277.748238) (xy 48.817276 -277.679912)
			(xy 48.793654 -277.672546) (xy 48.78451 -277.674324) (xy 48.757078 -277.678388) (xy 48.75657 -277.678388)
			(xy 48.734518 -277.680373) (xy 48.690274 -277.678716) (xy 48.668432 -277.675086) (xy 48.655986 -277.6728)
			(xy 48.631856 -277.680166) (xy 48.554894 -277.757382) (xy 48.547528 -277.781004) (xy 48.549814 -277.79345)
			(xy 48.552297 -277.807415) (xy 48.554965 -277.835655) (xy 48.555148 -277.849838) (xy 48.554675 -277.873828)
			(xy 48.547164 -277.921218) (xy 48.532334 -277.966849) (xy 48.510549 -278.0096) (xy 48.482345 -278.048416)
			(xy 48.448418 -278.082344) (xy 48.409601 -278.110548) (xy 48.366851 -278.132333) (xy 48.32122 -278.147164)
			(xy 48.27383 -278.154674) (xy 48.24984 -278.155146) (xy 48.217582 -278.153368) (xy 48.217074 -278.153368)
			(xy 48.20666 -278.152352) (xy 48.18634 -278.158956) (xy 48.121824 -278.216614) (xy 48.114168 -278.224133)
			(xy 48.105493 -278.243737) (xy 48.10506 -278.25446) (xy 48.10506 -278.30907) (xy 48.104806 -278.322532)
			(xy 48.104552 -278.324056) (xy 48.104552 -278.327866) (xy 48.104377 -278.338441) (xy 48.102855 -278.35954)
			(xy 48.101504 -278.37003) (xy 48.09871 -278.386794) (xy 48.09871 -278.38781) (xy 48.097948 -278.391366)
			(xy 48.10506 -278.413972) (xy 48.16983 -278.481536) (xy 48.178471 -278.489601) (xy 48.200706 -278.497536)
			(xy 48.212502 -278.496776) (xy 48.212756 -278.496776) (xy 48.22199 -278.495707) (xy 48.240545 -278.494561)
			(xy 48.24984 -278.49449) (xy 48.27466 -278.494979) (xy 48.323646 -278.503016) (xy 48.370686 -278.518872)
			(xy 48.414542 -278.54213) (xy 48.454057 -278.572175) (xy 48.488191 -278.608218) (xy 48.516044 -278.649308)
			(xy 48.536883 -278.694363) (xy 48.550159 -278.742196) (xy 48.555522 -278.791546) (xy 48.55283 -278.841114)
			(xy 48.542154 -278.889593) (xy 48.523777 -278.935706) (xy 48.498181 -278.978239) (xy 48.466042 -279.016071)
			(xy 48.428205 -279.048206) (xy 48.385669 -279.073795) (xy 48.339553 -279.092167) (xy 48.291072 -279.102835)
			(xy 48.241504 -279.10552) (xy 48.192154 -279.100151) (xy 48.144323 -279.086869) (xy 48.099272 -279.066024)
			(xy 48.058185 -279.038165) (xy 48.022147 -279.004026) (xy 47.992107 -278.964506) (xy 47.968856 -278.920648)
			(xy 47.953006 -278.873605) (xy 47.944976 -278.824618) (xy 47.944532 -278.799798) (xy 47.944637 -278.790757)
			(xy 47.945782 -278.772712) (xy 47.946818 -278.76373) (xy 47.946818 -278.762968) (xy 47.947521 -278.751298)
			(xy 47.939566 -278.729342) (xy 47.931578 -278.720804) (xy 47.86376 -278.656288) (xy 47.8409 -278.649176)
			(xy 47.828962 -278.651208) (xy 47.815285 -278.653365) (xy 47.787689 -278.655652) (xy 47.773844 -278.65578)
			(xy 47.760386 -278.655652) (xy 47.733556 -278.653488) (xy 47.72025 -278.651462) (xy 47.708312 -278.64943)
			(xy 47.685706 -278.656542) (xy 47.60976 -278.72944) (xy 47.601632 -278.751792) (xy 47.603156 -278.76373)
			(xy 47.60414 -278.772714) (xy 47.605159 -278.79076) (xy 47.605188 -278.799798) (xy 47.604702 -278.824617)
			(xy 47.596672 -278.873601) (xy 47.580823 -278.920641) (xy 47.557573 -278.964496) (xy 47.527534 -279.004013)
			(xy 47.491498 -279.03815) (xy 47.450414 -279.066007) (xy 47.405364 -279.08685) (xy 47.357536 -279.100131)
			(xy 47.308189 -279.105499) (xy 47.258624 -279.102813) (xy 47.210146 -279.092143) (xy 47.164033 -279.073772)
			(xy 47.1215 -279.048182) (xy 47.083667 -279.016049) (xy 47.05153 -278.978218) (xy 47.025938 -278.935686)
			(xy 47.007563 -278.889575) (xy 46.99689 -278.841098) (xy 46.994201 -278.791533) (xy 46.999565 -278.742186)
			(xy 47.012842 -278.694357) (xy 47.033682 -278.649305) (xy 47.061536 -278.608219) (xy 47.09567 -278.572181)
			(xy 47.135185 -278.542139) (xy 47.179039 -278.518885) (xy 47.226078 -278.503033) (xy 47.275061 -278.494999)
			(xy 47.29988 -278.49449) (xy 47.30879 -278.494537) (xy 47.326582 -278.495554) (xy 47.33544 -278.496522)
			(xy 47.347378 -278.498046) (xy 47.36973 -278.489918) (xy 47.442374 -278.413718) (xy 47.449486 -278.390858)
			(xy 47.447454 -278.379174) (xy 47.445404 -278.365807) (xy 47.44324 -278.338849) (xy 47.443136 -278.325326)
			(xy 47.443136 -278.254714) (xy 47.442578 -278.24402) (xy 47.433921 -278.224462) (xy 47.426372 -278.216868)
			(xy 47.370492 -278.166576) (xy 47.362231 -278.159844) (xy 47.342023 -278.153153) (xy 47.331376 -278.153622)
			(xy 47.331122 -278.153622) (xy 47.29988 -278.155146) (xy 47.275889 -278.154674) (xy 47.228497 -278.147166)
			(xy 47.182863 -278.132337) (xy 47.140111 -278.110553) (xy 47.101292 -278.08235) (xy 47.067362 -278.048422)
			(xy 47.039157 -278.009605) (xy 47.01737 -277.966853) (xy 47.002539 -277.92122) (xy 46.995027 -277.873829)
			(xy 46.994572 -277.849838) (xy 46.994772 -277.835719) (xy 46.997445 -277.807608) (xy 46.999906 -277.793704)
			(xy 46.999906 -277.793196) (xy 47.001416 -277.780959) (xy 46.994133 -277.757445) (xy 46.985936 -277.748238)
			(xy 46.917356 -277.679912) (xy 46.893734 -277.672546) (xy 46.88459 -277.674324) (xy 46.857158 -277.678388)
			(xy 46.85665 -277.678388) (xy 46.834598 -277.680371) (xy 46.790354 -277.678712) (xy 46.768512 -277.675086)
			(xy 46.756066 -277.6728) (xy 46.731936 -277.680166) (xy 46.654974 -277.757382) (xy 46.647608 -277.781004)
			(xy 46.649894 -277.79345) (xy 46.652377 -277.807415) (xy 46.655046 -277.835655) (xy 46.655228 -277.849838)
			(xy 46.654755 -277.873828) (xy 46.647244 -277.921216) (xy 46.632413 -277.966846) (xy 46.610628 -278.009595)
			(xy 46.582424 -278.04841) (xy 46.548497 -278.082336) (xy 46.50968 -278.110538) (xy 46.46693 -278.13232)
			(xy 46.421299 -278.147148) (xy 46.37391 -278.154656) (xy 46.34992 -278.155146) (xy 46.317662 -278.153368)
			(xy 46.317154 -278.153368) (xy 46.30674 -278.152352) (xy 46.28642 -278.158956) (xy 46.221904 -278.216614)
			(xy 46.21425 -278.224134) (xy 46.205579 -278.243738) (xy 46.20514 -278.25446) (xy 46.20514 -278.30907)
			(xy 46.204886 -278.322532) (xy 46.204632 -278.324056) (xy 46.204632 -278.327866) (xy 46.204457 -278.338441)
			(xy 46.202935 -278.35954) (xy 46.201584 -278.37003) (xy 46.19879 -278.386794) (xy 46.19879 -278.38781)
			(xy 46.198028 -278.391366) (xy 46.20514 -278.413972) (xy 46.26991 -278.481536) (xy 46.27855 -278.489605)
			(xy 46.300786 -278.497548) (xy 46.312582 -278.496776) (xy 46.312836 -278.496776) (xy 46.32207 -278.495709)
			(xy 46.340625 -278.494568) (xy 46.34992 -278.49449) (xy 46.374741 -278.494977) (xy 46.423728 -278.503012)
			(xy 46.470769 -278.518865) (xy 46.514627 -278.54212) (xy 46.554144 -278.572164) (xy 46.588281 -278.608206)
			(xy 46.616137 -278.649295) (xy 46.636978 -278.694349) (xy 46.650256 -278.742182) (xy 46.655621 -278.791532)
			(xy 46.652931 -278.841101) (xy 46.642258 -278.889581) (xy 46.623882 -278.935696) (xy 46.598287 -278.978231)
			(xy 46.566149 -279.016064) (xy 46.528313 -279.0482) (xy 46.485776 -279.073792) (xy 46.43966 -279.092164)
			(xy 46.391179 -279.102834) (xy 46.34161 -279.105521) (xy 46.29226 -279.100152) (xy 46.244428 -279.086871)
			(xy 46.199375 -279.066026) (xy 46.158288 -279.038167) (xy 46.122249 -279.004028) (xy 46.092208 -278.964508)
			(xy 46.068956 -278.920649) (xy 46.053106 -278.873606) (xy 46.045076 -278.824619) (xy 46.044612 -278.799798)
			(xy 46.044717 -278.790757) (xy 46.045862 -278.772712) (xy 46.046898 -278.76373) (xy 46.046898 -278.762968)
			(xy 46.047602 -278.751297) (xy 46.039656 -278.729334) (xy 46.031658 -278.720804) (xy 45.96384 -278.656288)
			(xy 45.94098 -278.649176) (xy 45.929042 -278.651208) (xy 45.915365 -278.653364) (xy 45.887769 -278.655649)
			(xy 45.873924 -278.65578) (xy 45.860465 -278.655655) (xy 45.833634 -278.653497) (xy 45.82033 -278.651462)
			(xy 45.808392 -278.64943) (xy 45.785786 -278.656542) (xy 45.70984 -278.72944) (xy 45.701712 -278.751792)
			(xy 45.703236 -278.76373) (xy 45.70422 -278.772714) (xy 45.70524 -278.79076) (xy 45.705268 -278.799798)
			(xy 45.704782 -278.824615) (xy 45.696753 -278.873595) (xy 45.680906 -278.920631) (xy 45.657658 -278.964484)
			(xy 45.627621 -279.003998) (xy 45.591588 -279.038132) (xy 45.550508 -279.065987) (xy 45.505462 -279.086829)
			(xy 45.457638 -279.10011) (xy 45.408295 -279.105478) (xy 45.358734 -279.102794) (xy 45.31026 -279.092127)
			(xy 45.26415 -279.073758) (xy 45.221619 -279.048172) (xy 45.183788 -279.016042) (xy 45.151653 -278.978215)
			(xy 45.126061 -278.935688) (xy 45.107686 -278.88958) (xy 45.097012 -278.841108) (xy 45.09432 -278.791547)
			(xy 45.099682 -278.742204) (xy 45.112956 -278.694377) (xy 45.133792 -278.649329) (xy 45.161642 -278.608244)
			(xy 45.195771 -278.572207) (xy 45.235281 -278.542165) (xy 45.27913 -278.518911) (xy 45.326164 -278.503057)
			(xy 45.375143 -278.495021) (xy 45.39996 -278.49449) (xy 45.40887 -278.494537) (xy 45.426662 -278.495553)
			(xy 45.43552 -278.496522) (xy 45.447458 -278.498046) (xy 45.46981 -278.489918) (xy 45.542454 -278.413718)
			(xy 45.549566 -278.390858) (xy 45.547534 -278.379174) (xy 45.545484 -278.365807) (xy 45.543319 -278.338849)
			(xy 45.543216 -278.325326) (xy 45.543216 -278.254714) (xy 45.54266 -278.244018) (xy 45.534013 -278.224451)
			(xy 45.526452 -278.216868) (xy 45.470572 -278.166576) (xy 45.46231 -278.159848) (xy 45.442102 -278.153164)
			(xy 45.431456 -278.153622) (xy 45.431202 -278.153622) (xy 45.39996 -278.155146) (xy 45.37597 -278.154672)
			(xy 45.328581 -278.147162) (xy 45.28295 -278.132331) (xy 45.2402 -278.110546) (xy 45.201383 -278.082343)
			(xy 45.167456 -278.048415) (xy 45.139253 -278.009599) (xy 45.117468 -277.966849) (xy 45.102638 -277.921217)
			(xy 45.095127 -277.873828) (xy 45.094652 -277.849838) (xy 45.094852 -277.835719) (xy 45.097526 -277.807608)
			(xy 45.099986 -277.793704) (xy 45.099986 -277.793196) (xy 45.101496 -277.780959) (xy 45.09421 -277.757447)
			(xy 45.086016 -277.748238) (xy 45.017436 -277.679912) (xy 44.993814 -277.672546) (xy 44.98467 -277.674324)
			(xy 44.954465 -277.67958) (xy 44.893165 -277.67932) (xy 44.863004 -277.673816) (xy 44.861988 -277.673816)
			(xy 44.855892 -277.672546) (xy 44.83227 -277.679912) (xy 44.7548 -277.757382) (xy 44.747434 -277.781004)
			(xy 44.74972 -277.79345) (xy 44.752203 -277.807415) (xy 44.754871 -277.835655) (xy 44.755054 -277.849838)
			(xy 44.754581 -277.873829) (xy 44.74707 -277.921218) (xy 44.73224 -277.96685) (xy 44.710455 -278.009601)
			(xy 44.682252 -278.048418) (xy 44.648324 -278.082347) (xy 44.609508 -278.110551) (xy 44.566758 -278.132337)
			(xy 44.521126 -278.147168) (xy 44.473737 -278.15468) (xy 44.449746 -278.155146) (xy 44.417742 -278.153368)
			(xy 44.417234 -278.153368) (xy 44.40682 -278.152352) (xy 44.3865 -278.158956) (xy 44.321984 -278.216614)
			(xy 44.314321 -278.224129) (xy 44.305635 -278.243735) (xy 44.30522 -278.25446) (xy 44.30522 -278.30907)
			(xy 44.304966 -278.322532) (xy 44.304712 -278.324056) (xy 44.304712 -278.327866) (xy 44.304537 -278.338441)
			(xy 44.303015 -278.35954) (xy 44.301664 -278.37003) (xy 44.29887 -278.386794) (xy 44.29887 -278.38781)
			(xy 44.298108 -278.391366) (xy 44.30522 -278.413972) (xy 44.378372 -278.490172) (xy 44.400724 -278.4983)
			(xy 44.412662 -278.496776) (xy 44.421896 -278.495707) (xy 44.440451 -278.494562) (xy 44.449746 -278.49449)
			(xy 44.474566 -278.49498) (xy 44.523552 -278.503018) (xy 44.570591 -278.518875) (xy 44.614446 -278.542133)
			(xy 44.653961 -278.572179) (xy 44.688094 -278.608222) (xy 44.715947 -278.649312) (xy 44.736785 -278.694367)
			(xy 44.75006 -278.7422) (xy 44.755422 -278.79155) (xy 44.752729 -278.841117) (xy 44.742053 -278.889596)
			(xy 44.723675 -278.935709) (xy 44.698079 -278.978242) (xy 44.66594 -279.016074) (xy 44.628103 -279.048207)
			(xy 44.585566 -279.073797) (xy 44.53945 -279.092167) (xy 44.49097 -279.102836) (xy 44.441402 -279.10552)
			(xy 44.392053 -279.100151) (xy 44.344222 -279.086868) (xy 44.29917 -279.066023) (xy 44.258084 -279.038164)
			(xy 44.222047 -279.004025) (xy 44.192007 -278.964506) (xy 44.168756 -278.920647) (xy 44.152906 -278.873605)
			(xy 44.144876 -278.824618) (xy 44.144438 -278.799798) (xy 44.144543 -278.790757) (xy 44.145688 -278.772712)
			(xy 44.146724 -278.76373) (xy 44.146724 -278.763222) (xy 44.147994 -278.751538) (xy 44.139866 -278.729186)
			(xy 44.063666 -278.656288) (xy 44.040806 -278.649176) (xy 44.028868 -278.651208) (xy 44.015254 -278.653355)
			(xy 43.987786 -278.655643) (xy 43.974004 -278.65578) (xy 43.960545 -278.655654) (xy 43.933715 -278.653495)
			(xy 43.92041 -278.651462) (xy 43.920156 -278.651462) (xy 43.908417 -278.650169) (xy 43.885898 -278.657187)
			(xy 43.876976 -278.664924) (xy 43.809666 -278.72944) (xy 43.801538 -278.751792) (xy 43.803062 -278.76373)
			(xy 43.804046 -278.772714) (xy 43.805065 -278.79076) (xy 43.805094 -278.799798) (xy 43.804608 -278.824618)
			(xy 43.796578 -278.873603) (xy 43.780729 -278.920643) (xy 43.757478 -278.9645) (xy 43.727438 -279.004018)
			(xy 43.691401 -279.038155) (xy 43.650315 -279.066013) (xy 43.605265 -279.086856) (xy 43.557435 -279.100137)
			(xy 43.508087 -279.105505) (xy 43.458521 -279.102818) (xy 43.410042 -279.092148) (xy 43.363928 -279.073776)
			(xy 43.321394 -279.048186) (xy 43.28356 -279.016051) (xy 43.251424 -278.978219) (xy 43.225831 -278.935686)
			(xy 43.207456 -278.889573) (xy 43.196784 -278.841095) (xy 43.194095 -278.791529) (xy 43.19946 -278.742181)
			(xy 43.212738 -278.69435) (xy 43.23358 -278.649298) (xy 43.261435 -278.608212) (xy 43.29557 -278.572173)
			(xy 43.335086 -278.542131) (xy 43.378942 -278.518878) (xy 43.425982 -278.503026) (xy 43.474967 -278.494993)
			(xy 43.499786 -278.49449) (xy 43.50876 -278.494532) (xy 43.526679 -278.495551) (xy 43.5356 -278.496522)
			(xy 43.547538 -278.498046) (xy 43.56989 -278.489918) (xy 43.642534 -278.413718) (xy 43.649646 -278.390858)
			(xy 43.647614 -278.379174) (xy 43.645564 -278.365807) (xy 43.643399 -278.338849) (xy 43.643296 -278.325326)
			(xy 43.643296 -278.25446) (xy 43.642729 -278.24377) (xy 43.634066 -278.22422) (xy 43.626532 -278.216614)
			(xy 43.562524 -278.158956) (xy 43.541696 -278.152352) (xy 43.531282 -278.153622) (xy 43.499786 -278.155146)
			(xy 43.475794 -278.154674) (xy 43.428402 -278.147167) (xy 43.382768 -278.132339) (xy 43.340014 -278.110555)
			(xy 43.301194 -278.082352) (xy 43.267264 -278.048424) (xy 43.239058 -278.009606) (xy 43.217271 -277.966855)
			(xy 43.202439 -277.921221) (xy 43.194928 -277.87383) (xy 43.194478 -277.849838) (xy 43.194678 -277.835719)
			(xy 43.197351 -277.807608) (xy 43.199812 -277.793704) (xy 43.199812 -277.793196) (xy 43.201322 -277.780959)
			(xy 43.194039 -277.757445) (xy 43.185842 -277.748238) (xy 43.117262 -277.679912) (xy 43.09364 -277.672546)
			(xy 43.084496 -277.674324) (xy 43.060478 -277.67865) (xy 43.011712 -277.680507) (xy 42.963273 -277.674581)
			(xy 42.916393 -277.661026) (xy 42.872267 -277.640184) (xy 42.832018 -277.612589) (xy 42.796672 -277.578942)
			(xy 42.767129 -277.5401) (xy 42.744141 -277.497052) (xy 42.728295 -277.450897) (xy 42.719993 -277.402807)
			(xy 42.719244 -277.378414) (xy 42.719244 -277.374096) (xy 42.71976 -277.348787) (xy 42.728151 -277.29887)
			(xy 42.744669 -277.251023) (xy 42.756328 -277.228554) (xy 42.757344 -277.226522) (xy 42.757852 -277.22576)
			(xy 42.761408 -277.218902) (xy 42.763316 -277.214041) (xy 42.765362 -277.203803) (xy 42.765472 -277.198582)
			(xy 42.765218 -277.18512) (xy 42.753026 -277.164292) (xy 42.711878 -277.093934) (xy 42.706188 -277.086636)
			(xy 42.69082 -277.076354) (xy 42.681906 -277.073868) (xy 42.417238 -277.073868) (xy 42.408314 -277.076333)
			(xy 42.392938 -277.086618) (xy 42.387266 -277.093934) (xy 42.346118 -277.164292) (xy 42.34053 -277.17369)
			(xy 42.33731 -277.179548) (xy 42.3337 -277.192412) (xy 42.333418 -277.19909) (xy 42.333418 -277.200106)
			(xy 42.333499 -277.204315) (xy 42.334905 -277.212614) (xy 42.336212 -277.216616) (xy 42.34053 -277.223982)
			(xy 42.352386 -277.245897) (xy 42.369594 -277.292655) (xy 42.378985 -277.341586) (xy 42.380154 -277.366476)
			(xy 42.380154 -277.374858) (xy 42.379687 -277.398853) (xy 42.372186 -277.446252) (xy 42.357363 -277.491895)
			(xy 42.335582 -277.534657) (xy 42.30738 -277.573485) (xy 42.273452 -277.607423) (xy 42.234632 -277.635636)
			(xy 42.191876 -277.657429) (xy 42.146238 -277.672265) (xy 42.098841 -277.67978) (xy 42.074846 -277.680166)
			(xy 42.074592 -277.680166) (xy 42.050777 -277.679709) (xy 42.003725 -277.672312) (xy 41.958392 -277.6577)
			(xy 41.915877 -277.636227) (xy 41.877212 -277.608413) (xy 41.843335 -277.574933) (xy 41.815066 -277.536599)
			(xy 41.793092 -277.494341) (xy 41.777945 -277.449184) (xy 41.769994 -277.402222) (xy 41.769284 -277.378414)
			(xy 41.769284 -277.374096) (xy 41.769799 -277.348787) (xy 41.778189 -277.298869) (xy 41.794704 -277.251021)
			(xy 41.806368 -277.228554) (xy 41.807384 -277.226522) (xy 41.807892 -277.22576) (xy 41.811448 -277.218902)
			(xy 41.813358 -277.214041) (xy 41.815406 -277.203803) (xy 41.815512 -277.198582) (xy 41.815258 -277.18512)
			(xy 41.803066 -277.164292) (xy 41.761918 -277.093934) (xy 41.756231 -277.086632) (xy 41.740866 -277.076338)
			(xy 41.731946 -277.073868) (xy 41.467278 -277.073868) (xy 41.45836 -277.076342) (xy 41.442999 -277.086637)
			(xy 41.437306 -277.093934) (xy 41.396158 -277.164292) (xy 41.39057 -277.17369) (xy 41.38733 -277.179539)
			(xy 41.383716 -277.192409) (xy 41.383458 -277.19909) (xy 41.383458 -277.200106) (xy 41.383539 -277.204315)
			(xy 41.384946 -277.212614) (xy 41.386252 -277.216616) (xy 41.39057 -277.223982) (xy 41.402424 -277.245898)
			(xy 41.41963 -277.292656) (xy 41.42902 -277.341587) (xy 41.430194 -277.366476) (xy 41.430194 -277.374858)
			(xy 41.429751 -277.398853) (xy 41.422249 -277.446253) (xy 41.407424 -277.491895) (xy 41.385641 -277.534656)
			(xy 41.357436 -277.573482) (xy 41.323504 -277.607418) (xy 41.28468 -277.635626) (xy 41.241921 -277.657414)
			(xy 41.19628 -277.672243) (xy 41.148881 -277.679749) (xy 41.124886 -277.680166) (xy 41.124632 -277.680166)
			(xy 41.100815 -277.679712) (xy 41.053758 -277.67232) (xy 41.00842 -277.657712) (xy 40.9659 -277.63624)
			(xy 40.927229 -277.608427) (xy 40.893347 -277.574947) (xy 40.865073 -277.536611) (xy 40.843096 -277.494351)
			(xy 40.827947 -277.44919) (xy 40.819994 -277.402225) (xy 40.819324 -277.378414) (xy 40.819324 -277.374096)
			(xy 40.819839 -277.348787) (xy 40.82823 -277.29887) (xy 40.844747 -277.251022) (xy 40.856408 -277.228554)
			(xy 40.857424 -277.226522) (xy 40.857932 -277.22576) (xy 40.861488 -277.218902) (xy 40.863396 -277.214041)
			(xy 40.865443 -277.203803) (xy 40.865552 -277.198582) (xy 40.865298 -277.18512) (xy 40.853106 -277.164292)
			(xy 40.811958 -277.093934) (xy 40.806267 -277.086639) (xy 40.790897 -277.076362) (xy 40.781986 -277.073868)
			(xy 40.517318 -277.073868) (xy 40.508396 -277.076336) (xy 40.493025 -277.086624) (xy 40.487346 -277.093934)
			(xy 40.446198 -277.164292) (xy 40.44061 -277.17369) (xy 40.437368 -277.179538) (xy 40.433751 -277.192408)
			(xy 40.433498 -277.19909) (xy 40.433498 -277.200106) (xy 40.433579 -277.204315) (xy 40.434984 -277.212615)
			(xy 40.436292 -277.216616) (xy 40.44061 -277.223982) (xy 40.452463 -277.245898) (xy 40.469666 -277.292657)
			(xy 40.479055 -277.341587) (xy 40.480234 -277.366476) (xy 40.480234 -277.374858) (xy 40.479791 -277.398854)
			(xy 40.47229 -277.446256) (xy 40.457465 -277.491901) (xy 40.435682 -277.534665) (xy 40.407478 -277.573495)
			(xy 40.373546 -277.607434) (xy 40.334723 -277.635647) (xy 40.291964 -277.657439) (xy 40.246322 -277.672274)
			(xy 40.198922 -277.679786) (xy 40.174926 -277.680166) (xy 40.174672 -277.680166) (xy 40.150858 -277.679707)
			(xy 40.103808 -277.672308) (xy 40.058478 -277.657695) (xy 40.015966 -277.63622) (xy 39.977304 -277.608406)
			(xy 39.943429 -277.574926) (xy 39.915162 -277.536593) (xy 39.89319 -277.494336) (xy 39.878045 -277.449181)
			(xy 39.870094 -277.402221) (xy 39.869364 -277.378414) (xy 39.869364 -277.374096) (xy 39.86988 -277.348787)
			(xy 39.878271 -277.29887) (xy 39.89479 -277.251024) (xy 39.906448 -277.228554) (xy 39.907464 -277.226522)
			(xy 39.907972 -277.22576) (xy 39.911528 -277.218648) (xy 39.913424 -277.213849) (xy 39.915482 -277.20374)
			(xy 39.915592 -277.198582) (xy 39.915338 -277.18512) (xy 39.915338 -277.032466) (xy 39.914907 -277.0224)
			(xy 39.907177 -277.00381) (xy 39.900352 -276.996398) (xy 39.68369 -276.77999) (xy 39.676835 -276.772595)
			(xy 39.66909 -276.753996) (xy 39.668704 -276.743922) (xy 39.668704 -272.305526) (xy 39.669141 -272.295462)
			(xy 39.676875 -272.276877) (xy 39.68369 -272.269458) (xy 39.85514 -272.098262) (xy 39.861987 -272.090864)
			(xy 39.869717 -272.072265) (xy 39.870126 -272.062194) (xy 39.870126 -271.412208) (xy 39.869705 -271.402137)
			(xy 39.861996 -271.383528) (xy 39.85514 -271.37614) (xy 39.751762 -271.272762) (xy 39.744364 -271.265915)
			(xy 39.725766 -271.258184) (xy 39.715694 -271.257776) (xy 38.210236 -271.257776) (xy 38.20017 -271.25821)
			(xy 38.181581 -271.265938) (xy 38.174168 -271.272762) (xy 37.64407 -271.80286) (xy 37.637225 -271.810258)
			(xy 37.629502 -271.828857) (xy 37.629084 -271.838928) (xy 37.629084 -272.624804) (xy 37.969202 -272.624804)
			(xy 37.973162 -272.57575) (xy 37.984939 -272.527966) (xy 38.00423 -272.48269) (xy 38.030533 -272.441094)
			(xy 38.063168 -272.404257) (xy 38.101289 -272.373132) (xy 38.14391 -272.348525) (xy 38.189926 -272.331073)
			(xy 38.238145 -272.321229) (xy 38.28732 -272.319248) (xy 38.336175 -272.32518) (xy 38.383446 -272.338872)
			(xy 38.427908 -272.35997) (xy 38.468411 -272.387926) (xy 38.503904 -272.422018) (xy 38.533469 -272.461362)
			(xy 38.55634 -272.504939) (xy 38.571924 -272.55162) (xy 38.579819 -272.600197) (xy 38.580314 -272.624804)
			(xy 38.919162 -272.624804) (xy 38.923122 -272.57575) (xy 38.934899 -272.527966) (xy 38.95419 -272.48269)
			(xy 38.980493 -272.441094) (xy 39.013128 -272.404257) (xy 39.051249 -272.373132) (xy 39.09387 -272.348525)
			(xy 39.139886 -272.331073) (xy 39.188105 -272.321229) (xy 39.23728 -272.319248) (xy 39.286135 -272.32518)
			(xy 39.333406 -272.338872) (xy 39.377868 -272.35997) (xy 39.418371 -272.387926) (xy 39.453864 -272.422018)
			(xy 39.483429 -272.461362) (xy 39.5063 -272.504939) (xy 39.521884 -272.55162) (xy 39.529779 -272.600197)
			(xy 39.530274 -272.624804) (xy 39.529779 -272.649411) (xy 39.521884 -272.697988) (xy 39.5063 -272.744669)
			(xy 39.483429 -272.788246) (xy 39.453864 -272.82759) (xy 39.418371 -272.861682) (xy 39.377868 -272.889638)
			(xy 39.333406 -272.910736) (xy 39.286135 -272.924428) (xy 39.23728 -272.93036) (xy 39.188105 -272.928379)
			(xy 39.139886 -272.918535) (xy 39.09387 -272.901083) (xy 39.051249 -272.876476) (xy 39.013128 -272.845351)
			(xy 38.980493 -272.808514) (xy 38.95419 -272.766918) (xy 38.934899 -272.721642) (xy 38.923122 -272.673858)
			(xy 38.919162 -272.624804) (xy 38.580314 -272.624804) (xy 38.579819 -272.649411) (xy 38.571924 -272.697988)
			(xy 38.55634 -272.744669) (xy 38.533469 -272.788246) (xy 38.503904 -272.82759) (xy 38.468411 -272.861682)
			(xy 38.427908 -272.889638) (xy 38.383446 -272.910736) (xy 38.336175 -272.924428) (xy 38.28732 -272.93036)
			(xy 38.238145 -272.928379) (xy 38.189926 -272.918535) (xy 38.14391 -272.901083) (xy 38.101289 -272.876476)
			(xy 38.063168 -272.845351) (xy 38.030533 -272.808514) (xy 38.00423 -272.766918) (xy 37.984939 -272.721642)
			(xy 37.973162 -272.673858) (xy 37.969202 -272.624804) (xy 37.629084 -272.624804) (xy 37.629084 -273.549872)
			(xy 37.629338 -273.55165) (xy 37.6301 -273.57451) (xy 37.6301 -273.574764) (xy 37.968948 -273.574764)
			(xy 37.972908 -273.52571) (xy 37.984685 -273.477926) (xy 38.003976 -273.43265) (xy 38.030279 -273.391054)
			(xy 38.062914 -273.354217) (xy 38.101035 -273.323092) (xy 38.143656 -273.298485) (xy 38.189672 -273.281033)
			(xy 38.237891 -273.271189) (xy 38.287066 -273.269208) (xy 38.335921 -273.27514) (xy 38.383192 -273.288832)
			(xy 38.427654 -273.30993) (xy 38.468157 -273.337886) (xy 38.50365 -273.371978) (xy 38.533215 -273.411322)
			(xy 38.556086 -273.454899) (xy 38.57167 -273.50158) (xy 38.579565 -273.550157) (xy 38.58006 -273.574764)
			(xy 38.919162 -273.574764) (xy 38.923122 -273.52571) (xy 38.934899 -273.477926) (xy 38.95419 -273.43265)
			(xy 38.980493 -273.391054) (xy 39.013128 -273.354217) (xy 39.051249 -273.323092) (xy 39.09387 -273.298485)
			(xy 39.139886 -273.281033) (xy 39.188105 -273.271189) (xy 39.23728 -273.269208) (xy 39.286135 -273.27514)
			(xy 39.333406 -273.288832) (xy 39.377868 -273.30993) (xy 39.418371 -273.337886) (xy 39.453864 -273.371978)
			(xy 39.483429 -273.411322) (xy 39.5063 -273.454899) (xy 39.521884 -273.50158) (xy 39.529779 -273.550157)
			(xy 39.530274 -273.574764) (xy 39.529779 -273.599371) (xy 39.521884 -273.647948) (xy 39.5063 -273.694629)
			(xy 39.483429 -273.738206) (xy 39.453864 -273.77755) (xy 39.418371 -273.811642) (xy 39.377868 -273.839598)
			(xy 39.333406 -273.860696) (xy 39.286135 -273.874388) (xy 39.23728 -273.88032) (xy 39.188105 -273.878339)
			(xy 39.139886 -273.868495) (xy 39.09387 -273.851043) (xy 39.051249 -273.826436) (xy 39.013128 -273.795311)
			(xy 38.980493 -273.758474) (xy 38.95419 -273.716878) (xy 38.934899 -273.671602) (xy 38.923122 -273.623818)
			(xy 38.919162 -273.574764) (xy 38.58006 -273.574764) (xy 38.579565 -273.599371) (xy 38.57167 -273.647948)
			(xy 38.556086 -273.694629) (xy 38.533215 -273.738206) (xy 38.50365 -273.77755) (xy 38.468157 -273.811642)
			(xy 38.427654 -273.839598) (xy 38.383192 -273.860696) (xy 38.335921 -273.874388) (xy 38.287066 -273.88032)
			(xy 38.237891 -273.878339) (xy 38.189672 -273.868495) (xy 38.143656 -273.851043) (xy 38.101035 -273.826436)
			(xy 38.062914 -273.795311) (xy 38.030279 -273.758474) (xy 38.003976 -273.716878) (xy 37.984685 -273.671602)
			(xy 37.972908 -273.623818) (xy 37.968948 -273.574764) (xy 37.6301 -273.574764) (xy 37.6301 -273.575018)
			(xy 37.629338 -273.597878) (xy 37.629084 -273.599656) (xy 37.629084 -274.499832) (xy 37.629338 -274.50161)
			(xy 37.6301 -274.52447) (xy 37.6301 -274.524978) (xy 37.969202 -274.524978) (xy 37.973162 -274.475924)
			(xy 37.984939 -274.42814) (xy 38.00423 -274.382864) (xy 38.030533 -274.341268) (xy 38.063168 -274.304431)
			(xy 38.101289 -274.273306) (xy 38.14391 -274.248699) (xy 38.189926 -274.231247) (xy 38.238145 -274.221403)
			(xy 38.28732 -274.219422) (xy 38.336175 -274.225354) (xy 38.383446 -274.239046) (xy 38.427908 -274.260144)
			(xy 38.468411 -274.2881) (xy 38.503904 -274.322192) (xy 38.533469 -274.361536) (xy 38.55634 -274.405113)
			(xy 38.571924 -274.451794) (xy 38.579819 -274.500371) (xy 38.580314 -274.524978) (xy 38.919162 -274.524978)
			(xy 38.923122 -274.475924) (xy 38.934899 -274.42814) (xy 38.95419 -274.382864) (xy 38.980493 -274.341268)
			(xy 39.013128 -274.304431) (xy 39.051249 -274.273306) (xy 39.09387 -274.248699) (xy 39.139886 -274.231247)
			(xy 39.188105 -274.221403) (xy 39.23728 -274.219422) (xy 39.286135 -274.225354) (xy 39.333406 -274.239046)
			(xy 39.377868 -274.260144) (xy 39.418371 -274.2881) (xy 39.453864 -274.322192) (xy 39.483429 -274.361536)
			(xy 39.5063 -274.405113) (xy 39.521884 -274.451794) (xy 39.529779 -274.500371) (xy 39.530274 -274.524978)
			(xy 39.529779 -274.549585) (xy 39.521884 -274.598162) (xy 39.5063 -274.644843) (xy 39.483429 -274.68842)
			(xy 39.453864 -274.727764) (xy 39.418371 -274.761856) (xy 39.377868 -274.789812) (xy 39.333406 -274.81091)
			(xy 39.286135 -274.824602) (xy 39.23728 -274.830534) (xy 39.188105 -274.828553) (xy 39.139886 -274.818709)
			(xy 39.09387 -274.801257) (xy 39.051249 -274.77665) (xy 39.013128 -274.745525) (xy 38.980493 -274.708688)
			(xy 38.95419 -274.667092) (xy 38.934899 -274.621816) (xy 38.923122 -274.574032) (xy 38.919162 -274.524978)
			(xy 38.580314 -274.524978) (xy 38.579819 -274.549585) (xy 38.571924 -274.598162) (xy 38.55634 -274.644843)
			(xy 38.533469 -274.68842) (xy 38.503904 -274.727764) (xy 38.468411 -274.761856) (xy 38.427908 -274.789812)
			(xy 38.383446 -274.81091) (xy 38.336175 -274.824602) (xy 38.28732 -274.830534) (xy 38.238145 -274.828553)
			(xy 38.189926 -274.818709) (xy 38.14391 -274.801257) (xy 38.101289 -274.77665) (xy 38.063168 -274.745525)
			(xy 38.030533 -274.708688) (xy 38.00423 -274.667092) (xy 37.984939 -274.621816) (xy 37.973162 -274.574032)
			(xy 37.969202 -274.524978) (xy 37.6301 -274.524978) (xy 37.629338 -274.547838) (xy 37.629084 -274.549616)
			(xy 37.629084 -275.450046) (xy 37.629338 -275.451824) (xy 37.6301 -275.474684) (xy 37.6301 -275.474938)
			(xy 37.969202 -275.474938) (xy 37.973162 -275.425884) (xy 37.984939 -275.3781) (xy 38.00423 -275.332824)
			(xy 38.030533 -275.291228) (xy 38.063168 -275.254391) (xy 38.101289 -275.223266) (xy 38.14391 -275.198659)
			(xy 38.189926 -275.181207) (xy 38.238145 -275.171363) (xy 38.28732 -275.169382) (xy 38.336175 -275.175314)
			(xy 38.383446 -275.189006) (xy 38.427908 -275.210104) (xy 38.468411 -275.23806) (xy 38.503904 -275.272152)
			(xy 38.533469 -275.311496) (xy 38.55634 -275.355073) (xy 38.571924 -275.401754) (xy 38.579819 -275.450331)
			(xy 38.580314 -275.474938) (xy 38.919162 -275.474938) (xy 38.923122 -275.425884) (xy 38.934899 -275.3781)
			(xy 38.95419 -275.332824) (xy 38.980493 -275.291228) (xy 39.013128 -275.254391) (xy 39.051249 -275.223266)
			(xy 39.09387 -275.198659) (xy 39.139886 -275.181207) (xy 39.188105 -275.171363) (xy 39.23728 -275.169382)
			(xy 39.286135 -275.175314) (xy 39.333406 -275.189006) (xy 39.377868 -275.210104) (xy 39.418371 -275.23806)
			(xy 39.453864 -275.272152) (xy 39.483429 -275.311496) (xy 39.5063 -275.355073) (xy 39.521884 -275.401754)
			(xy 39.529779 -275.450331) (xy 39.530274 -275.474938) (xy 39.529779 -275.499545) (xy 39.521884 -275.548122)
			(xy 39.5063 -275.594803) (xy 39.483429 -275.63838) (xy 39.453864 -275.677724) (xy 39.418371 -275.711816)
			(xy 39.377868 -275.739772) (xy 39.333406 -275.76087) (xy 39.286135 -275.774562) (xy 39.23728 -275.780494)
			(xy 39.188105 -275.778513) (xy 39.139886 -275.768669) (xy 39.09387 -275.751217) (xy 39.051249 -275.72661)
			(xy 39.013128 -275.695485) (xy 38.980493 -275.658648) (xy 38.95419 -275.617052) (xy 38.934899 -275.571776)
			(xy 38.923122 -275.523992) (xy 38.919162 -275.474938) (xy 38.580314 -275.474938) (xy 38.579819 -275.499545)
			(xy 38.571924 -275.548122) (xy 38.55634 -275.594803) (xy 38.533469 -275.63838) (xy 38.503904 -275.677724)
			(xy 38.468411 -275.711816) (xy 38.427908 -275.739772) (xy 38.383446 -275.76087) (xy 38.336175 -275.774562)
			(xy 38.28732 -275.780494) (xy 38.238145 -275.778513) (xy 38.189926 -275.768669) (xy 38.14391 -275.751217)
			(xy 38.101289 -275.72661) (xy 38.063168 -275.695485) (xy 38.030533 -275.658648) (xy 38.00423 -275.617052)
			(xy 37.984939 -275.571776) (xy 37.973162 -275.523992) (xy 37.969202 -275.474938) (xy 37.6301 -275.474938)
			(xy 37.6301 -275.475192) (xy 37.629338 -275.498052) (xy 37.629084 -275.49983) (xy 37.629084 -276.190202)
			(xy 37.62866 -276.200272) (xy 37.620943 -276.218874) (xy 37.614098 -276.22627) (xy 37.60851 -276.231858)
			(xy 37.601458 -276.239691) (xy 37.593828 -276.259315) (xy 37.594676 -276.280352) (xy 37.598858 -276.290024)
			(xy 37.598858 -276.290278) (xy 37.608707 -276.311338) (xy 37.622623 -276.355697) (xy 37.629655 -276.401653)
			(xy 37.6301 -276.424898) (xy 37.969202 -276.424898) (xy 37.973162 -276.375844) (xy 37.984939 -276.32806)
			(xy 38.00423 -276.282784) (xy 38.030533 -276.241188) (xy 38.063168 -276.204351) (xy 38.101289 -276.173226)
			(xy 38.14391 -276.148619) (xy 38.189926 -276.131167) (xy 38.238145 -276.121323) (xy 38.28732 -276.119342)
			(xy 38.336175 -276.125274) (xy 38.383446 -276.138966) (xy 38.427908 -276.160064) (xy 38.468411 -276.18802)
			(xy 38.503904 -276.222112) (xy 38.533469 -276.261456) (xy 38.55634 -276.305033) (xy 38.571924 -276.351714)
			(xy 38.579819 -276.400291) (xy 38.580314 -276.424898) (xy 38.919162 -276.424898) (xy 38.923122 -276.375844)
			(xy 38.934899 -276.32806) (xy 38.95419 -276.282784) (xy 38.980493 -276.241188) (xy 39.013128 -276.204351)
			(xy 39.051249 -276.173226) (xy 39.09387 -276.148619) (xy 39.139886 -276.131167) (xy 39.188105 -276.121323)
			(xy 39.23728 -276.119342) (xy 39.286135 -276.125274) (xy 39.333406 -276.138966) (xy 39.377868 -276.160064)
			(xy 39.418371 -276.18802) (xy 39.453864 -276.222112) (xy 39.483429 -276.261456) (xy 39.5063 -276.305033)
			(xy 39.521884 -276.351714) (xy 39.529779 -276.400291) (xy 39.530274 -276.424898) (xy 39.529779 -276.449505)
			(xy 39.521884 -276.498082) (xy 39.5063 -276.544763) (xy 39.483429 -276.58834) (xy 39.453864 -276.627684)
			(xy 39.418371 -276.661776) (xy 39.377868 -276.689732) (xy 39.333406 -276.71083) (xy 39.286135 -276.724522)
			(xy 39.23728 -276.730454) (xy 39.188105 -276.728473) (xy 39.139886 -276.718629) (xy 39.09387 -276.701177)
			(xy 39.051249 -276.67657) (xy 39.013128 -276.645445) (xy 38.980493 -276.608608) (xy 38.95419 -276.567012)
			(xy 38.934899 -276.521736) (xy 38.923122 -276.473952) (xy 38.919162 -276.424898) (xy 38.580314 -276.424898)
			(xy 38.579819 -276.449505) (xy 38.571924 -276.498082) (xy 38.55634 -276.544763) (xy 38.533469 -276.58834)
			(xy 38.503904 -276.627684) (xy 38.468411 -276.661776) (xy 38.427908 -276.689732) (xy 38.383446 -276.71083)
			(xy 38.336175 -276.724522) (xy 38.28732 -276.730454) (xy 38.238145 -276.728473) (xy 38.189926 -276.718629)
			(xy 38.14391 -276.701177) (xy 38.101289 -276.67657) (xy 38.063168 -276.645445) (xy 38.030533 -276.608608)
			(xy 38.00423 -276.567012) (xy 37.984939 -276.521736) (xy 37.973162 -276.473952) (xy 37.969202 -276.424898)
			(xy 37.6301 -276.424898) (xy 37.629654 -276.448891) (xy 37.622147 -276.496286) (xy 37.607319 -276.541924)
			(xy 37.585534 -276.58468) (xy 37.557328 -276.623501) (xy 37.523396 -276.657432) (xy 37.484574 -276.685637)
			(xy 37.441818 -276.707421) (xy 37.39618 -276.722249) (xy 37.348785 -276.729754) (xy 37.324792 -276.730206)
			(xy 37.301546 -276.729772) (xy 37.255591 -276.722731) (xy 37.211232 -276.708813) (xy 37.190172 -276.698964)
			(xy 37.189918 -276.698964) (xy 37.180234 -276.694803) (xy 37.159198 -276.693915) (xy 37.139579 -276.701556)
			(xy 37.131752 -276.708616) (xy 36.767262 -277.073106) (xy 36.761166 -277.073106) (xy 36.755864 -277.073948)
			(xy 36.745747 -277.077531) (xy 36.7411 -277.080218) (xy 36.730432 -277.08987) (xy 36.729924 -277.090378)
			(xy 36.727384 -277.092664) (xy 36.724844 -277.094442) (xy 36.669726 -277.14956) (xy 36.66397 -277.155675)
			(xy 36.656552 -277.17073) (xy 36.655248 -277.179024) (xy 36.655248 -277.179278) (xy 36.654858 -277.182891)
			(xy 36.65499 -277.190158) (xy 36.655502 -277.193756) (xy 36.65601 -277.19655) (xy 36.659566 -277.206964)
			(xy 36.661598 -277.21052) (xy 36.675312 -277.235718) (xy 36.694793 -277.289672) (xy 36.704686 -277.346176)
			(xy 36.705286 -277.374858) (xy 37.018988 -277.374858) (xy 37.022948 -277.325804) (xy 37.034725 -277.27802)
			(xy 37.054016 -277.232744) (xy 37.080319 -277.191148) (xy 37.112954 -277.154311) (xy 37.151075 -277.123186)
			(xy 37.193696 -277.098579) (xy 37.239712 -277.081127) (xy 37.287931 -277.071283) (xy 37.337106 -277.069302)
			(xy 37.385961 -277.075234) (xy 37.433232 -277.088926) (xy 37.477694 -277.110024) (xy 37.518197 -277.13798)
			(xy 37.55369 -277.172072) (xy 37.583255 -277.211416) (xy 37.606126 -277.254993) (xy 37.62171 -277.301674)
			(xy 37.629605 -277.350251) (xy 37.6301 -277.374858) (xy 37.969202 -277.374858) (xy 37.973162 -277.325804)
			(xy 37.984939 -277.27802) (xy 38.00423 -277.232744) (xy 38.030533 -277.191148) (xy 38.063168 -277.154311)
			(xy 38.101289 -277.123186) (xy 38.14391 -277.098579) (xy 38.189926 -277.081127) (xy 38.238145 -277.071283)
			(xy 38.28732 -277.069302) (xy 38.336175 -277.075234) (xy 38.383446 -277.088926) (xy 38.427908 -277.110024)
			(xy 38.468411 -277.13798) (xy 38.503904 -277.172072) (xy 38.533469 -277.211416) (xy 38.55634 -277.254993)
			(xy 38.571924 -277.301674) (xy 38.579819 -277.350251) (xy 38.580314 -277.374858) (xy 38.919162 -277.374858)
			(xy 38.923122 -277.325804) (xy 38.934899 -277.27802) (xy 38.95419 -277.232744) (xy 38.980493 -277.191148)
			(xy 39.013128 -277.154311) (xy 39.051249 -277.123186) (xy 39.09387 -277.098579) (xy 39.139886 -277.081127)
			(xy 39.188105 -277.071283) (xy 39.23728 -277.069302) (xy 39.286135 -277.075234) (xy 39.333406 -277.088926)
			(xy 39.377868 -277.110024) (xy 39.418371 -277.13798) (xy 39.453864 -277.172072) (xy 39.483429 -277.211416)
			(xy 39.5063 -277.254993) (xy 39.521884 -277.301674) (xy 39.529779 -277.350251) (xy 39.530274 -277.374858)
			(xy 39.529779 -277.399465) (xy 39.521884 -277.448042) (xy 39.5063 -277.494723) (xy 39.483429 -277.5383)
			(xy 39.453864 -277.577644) (xy 39.418371 -277.611736) (xy 39.377868 -277.639692) (xy 39.333406 -277.66079)
			(xy 39.286135 -277.674482) (xy 39.23728 -277.680414) (xy 39.188105 -277.678433) (xy 39.139886 -277.668589)
			(xy 39.09387 -277.651137) (xy 39.051249 -277.62653) (xy 39.013128 -277.595405) (xy 38.980493 -277.558568)
			(xy 38.95419 -277.516972) (xy 38.934899 -277.471696) (xy 38.923122 -277.423912) (xy 38.919162 -277.374858)
			(xy 38.580314 -277.374858) (xy 38.579819 -277.399465) (xy 38.571924 -277.448042) (xy 38.55634 -277.494723)
			(xy 38.533469 -277.5383) (xy 38.503904 -277.577644) (xy 38.468411 -277.611736) (xy 38.427908 -277.639692)
			(xy 38.383446 -277.66079) (xy 38.336175 -277.674482) (xy 38.28732 -277.680414) (xy 38.238145 -277.678433)
			(xy 38.189926 -277.668589) (xy 38.14391 -277.651137) (xy 38.101289 -277.62653) (xy 38.063168 -277.595405)
			(xy 38.030533 -277.558568) (xy 38.00423 -277.516972) (xy 37.984939 -277.471696) (xy 37.973162 -277.423912)
			(xy 37.969202 -277.374858) (xy 37.6301 -277.374858) (xy 37.629605 -277.399465) (xy 37.62171 -277.448042)
			(xy 37.606126 -277.494723) (xy 37.583255 -277.5383) (xy 37.55369 -277.577644) (xy 37.518197 -277.611736)
			(xy 37.477694 -277.639692) (xy 37.433232 -277.66079) (xy 37.385961 -277.674482) (xy 37.337106 -277.680414)
			(xy 37.287931 -277.678433) (xy 37.239712 -277.668589) (xy 37.193696 -277.651137) (xy 37.151075 -277.62653)
			(xy 37.112954 -277.595405) (xy 37.080319 -277.558568) (xy 37.054016 -277.516972) (xy 37.034725 -277.471696)
			(xy 37.022948 -277.423912) (xy 37.018988 -277.374858) (xy 36.705286 -277.374858) (xy 36.704806 -277.400849)
			(xy 36.69668 -277.452191) (xy 36.680621 -277.50163) (xy 36.657025 -277.547947) (xy 36.626473 -277.590003)
			(xy 36.589718 -277.62676) (xy 36.547664 -277.657315) (xy 36.501348 -277.680913) (xy 36.451911 -277.696975)
			(xy 36.400569 -277.705104) (xy 36.374578 -277.705566) (xy 36.347971 -277.705016) (xy 36.295447 -277.696463)
			(xy 36.244969 -277.679614) (xy 36.221162 -277.66772) (xy 36.220908 -277.66772) (xy 36.215436 -277.665047)
			(xy 36.203626 -277.662095) (xy 36.19754 -277.661878) (xy 36.159948 -277.661878) (xy 36.155122 -277.664164)
			(xy 35.494468 -278.324818) (xy 36.069028 -278.324818) (xy 36.072988 -278.275764) (xy 36.084765 -278.22798)
			(xy 36.104056 -278.182704) (xy 36.130359 -278.141108) (xy 36.162994 -278.104271) (xy 36.201115 -278.073146)
			(xy 36.243736 -278.048539) (xy 36.289752 -278.031087) (xy 36.337971 -278.021243) (xy 36.387146 -278.019262)
			(xy 36.436001 -278.025194) (xy 36.483272 -278.038886) (xy 36.527734 -278.059984) (xy 36.568237 -278.08794)
			(xy 36.60373 -278.122032) (xy 36.633295 -278.161376) (xy 36.656166 -278.204953) (xy 36.67175 -278.251634)
			(xy 36.679645 -278.300211) (xy 36.68014 -278.324818) (xy 37.018988 -278.324818) (xy 37.022948 -278.275764)
			(xy 37.034725 -278.22798) (xy 37.054016 -278.182704) (xy 37.080319 -278.141108) (xy 37.112954 -278.104271)
			(xy 37.151075 -278.073146) (xy 37.193696 -278.048539) (xy 37.239712 -278.031087) (xy 37.287931 -278.021243)
			(xy 37.337106 -278.019262) (xy 37.385961 -278.025194) (xy 37.433232 -278.038886) (xy 37.477694 -278.059984)
			(xy 37.518197 -278.08794) (xy 37.55369 -278.122032) (xy 37.583255 -278.161376) (xy 37.606126 -278.204953)
			(xy 37.62171 -278.251634) (xy 37.629605 -278.300211) (xy 37.6301 -278.324818) (xy 37.969202 -278.324818)
			(xy 37.973162 -278.275764) (xy 37.984939 -278.22798) (xy 38.00423 -278.182704) (xy 38.030533 -278.141108)
			(xy 38.063168 -278.104271) (xy 38.101289 -278.073146) (xy 38.14391 -278.048539) (xy 38.189926 -278.031087)
			(xy 38.238145 -278.021243) (xy 38.28732 -278.019262) (xy 38.336175 -278.025194) (xy 38.383446 -278.038886)
			(xy 38.427908 -278.059984) (xy 38.468411 -278.08794) (xy 38.503904 -278.122032) (xy 38.533469 -278.161376)
			(xy 38.55634 -278.204953) (xy 38.571924 -278.251634) (xy 38.579819 -278.300211) (xy 38.580314 -278.324818)
			(xy 38.919162 -278.324818) (xy 38.923122 -278.275764) (xy 38.934899 -278.22798) (xy 38.95419 -278.182704)
			(xy 38.980493 -278.141108) (xy 39.013128 -278.104271) (xy 39.051249 -278.073146) (xy 39.09387 -278.048539)
			(xy 39.139886 -278.031087) (xy 39.188105 -278.021243) (xy 39.23728 -278.019262) (xy 39.286135 -278.025194)
			(xy 39.333406 -278.038886) (xy 39.377868 -278.059984) (xy 39.418371 -278.08794) (xy 39.453864 -278.122032)
			(xy 39.483429 -278.161376) (xy 39.5063 -278.204953) (xy 39.521884 -278.251634) (xy 39.529779 -278.300211)
			(xy 39.530274 -278.324818) (xy 39.869122 -278.324818) (xy 39.873082 -278.275764) (xy 39.884859 -278.22798)
			(xy 39.90415 -278.182704) (xy 39.930453 -278.141108) (xy 39.963088 -278.104271) (xy 40.001209 -278.073146)
			(xy 40.04383 -278.048539) (xy 40.089846 -278.031087) (xy 40.138065 -278.021243) (xy 40.18724 -278.019262)
			(xy 40.236095 -278.025194) (xy 40.283366 -278.038886) (xy 40.327828 -278.059984) (xy 40.368331 -278.08794)
			(xy 40.403824 -278.122032) (xy 40.433389 -278.161376) (xy 40.45626 -278.204953) (xy 40.471844 -278.251634)
			(xy 40.479739 -278.300211) (xy 40.480234 -278.324818) (xy 40.819082 -278.324818) (xy 40.823042 -278.275764)
			(xy 40.834819 -278.22798) (xy 40.85411 -278.182704) (xy 40.880413 -278.141108) (xy 40.913048 -278.104271)
			(xy 40.951169 -278.073146) (xy 40.99379 -278.048539) (xy 41.039806 -278.031087) (xy 41.088025 -278.021243)
			(xy 41.1372 -278.019262) (xy 41.186055 -278.025194) (xy 41.233326 -278.038886) (xy 41.277788 -278.059984)
			(xy 41.318291 -278.08794) (xy 41.353784 -278.122032) (xy 41.383349 -278.161376) (xy 41.40622 -278.204953)
			(xy 41.421804 -278.251634) (xy 41.429699 -278.300211) (xy 41.430194 -278.324818) (xy 41.769042 -278.324818)
			(xy 41.773002 -278.275764) (xy 41.784779 -278.22798) (xy 41.80407 -278.182704) (xy 41.830373 -278.141108)
			(xy 41.863008 -278.104271) (xy 41.901129 -278.073146) (xy 41.94375 -278.048539) (xy 41.989766 -278.031087)
			(xy 42.037985 -278.021243) (xy 42.08716 -278.019262) (xy 42.136015 -278.025194) (xy 42.183286 -278.038886)
			(xy 42.227748 -278.059984) (xy 42.268251 -278.08794) (xy 42.303744 -278.122032) (xy 42.333309 -278.161376)
			(xy 42.35618 -278.204953) (xy 42.371764 -278.251634) (xy 42.379659 -278.300211) (xy 42.380154 -278.324818)
			(xy 42.379659 -278.349425) (xy 42.371764 -278.398002) (xy 42.35618 -278.444683) (xy 42.333309 -278.48826)
			(xy 42.303744 -278.527604) (xy 42.268251 -278.561696) (xy 42.227748 -278.589652) (xy 42.183286 -278.61075)
			(xy 42.136015 -278.624442) (xy 42.08716 -278.630374) (xy 42.037985 -278.628393) (xy 41.989766 -278.618549)
			(xy 41.94375 -278.601097) (xy 41.901129 -278.57649) (xy 41.863008 -278.545365) (xy 41.830373 -278.508528)
			(xy 41.80407 -278.466932) (xy 41.784779 -278.421656) (xy 41.773002 -278.373872) (xy 41.769042 -278.324818)
			(xy 41.430194 -278.324818) (xy 41.429699 -278.349425) (xy 41.421804 -278.398002) (xy 41.40622 -278.444683)
			(xy 41.383349 -278.48826) (xy 41.353784 -278.527604) (xy 41.318291 -278.561696) (xy 41.277788 -278.589652)
			(xy 41.233326 -278.61075) (xy 41.186055 -278.624442) (xy 41.1372 -278.630374) (xy 41.088025 -278.628393)
			(xy 41.039806 -278.618549) (xy 40.99379 -278.601097) (xy 40.951169 -278.57649) (xy 40.913048 -278.545365)
			(xy 40.880413 -278.508528) (xy 40.85411 -278.466932) (xy 40.834819 -278.421656) (xy 40.823042 -278.373872)
			(xy 40.819082 -278.324818) (xy 40.480234 -278.324818) (xy 40.479739 -278.349425) (xy 40.471844 -278.398002)
			(xy 40.45626 -278.444683) (xy 40.433389 -278.48826) (xy 40.403824 -278.527604) (xy 40.368331 -278.561696)
			(xy 40.327828 -278.589652) (xy 40.283366 -278.61075) (xy 40.236095 -278.624442) (xy 40.18724 -278.630374)
			(xy 40.138065 -278.628393) (xy 40.089846 -278.618549) (xy 40.04383 -278.601097) (xy 40.001209 -278.57649)
			(xy 39.963088 -278.545365) (xy 39.930453 -278.508528) (xy 39.90415 -278.466932) (xy 39.884859 -278.421656)
			(xy 39.873082 -278.373872) (xy 39.869122 -278.324818) (xy 39.530274 -278.324818) (xy 39.529779 -278.349425)
			(xy 39.521884 -278.398002) (xy 39.5063 -278.444683) (xy 39.483429 -278.48826) (xy 39.453864 -278.527604)
			(xy 39.418371 -278.561696) (xy 39.377868 -278.589652) (xy 39.333406 -278.61075) (xy 39.286135 -278.624442)
			(xy 39.23728 -278.630374) (xy 39.188105 -278.628393) (xy 39.139886 -278.618549) (xy 39.09387 -278.601097)
			(xy 39.051249 -278.57649) (xy 39.013128 -278.545365) (xy 38.980493 -278.508528) (xy 38.95419 -278.466932)
			(xy 38.934899 -278.421656) (xy 38.923122 -278.373872) (xy 38.919162 -278.324818) (xy 38.580314 -278.324818)
			(xy 38.579819 -278.349425) (xy 38.571924 -278.398002) (xy 38.55634 -278.444683) (xy 38.533469 -278.48826)
			(xy 38.503904 -278.527604) (xy 38.468411 -278.561696) (xy 38.427908 -278.589652) (xy 38.383446 -278.61075)
			(xy 38.336175 -278.624442) (xy 38.28732 -278.630374) (xy 38.238145 -278.628393) (xy 38.189926 -278.618549)
			(xy 38.14391 -278.601097) (xy 38.101289 -278.57649) (xy 38.063168 -278.545365) (xy 38.030533 -278.508528)
			(xy 38.00423 -278.466932) (xy 37.984939 -278.421656) (xy 37.973162 -278.373872) (xy 37.969202 -278.324818)
			(xy 37.6301 -278.324818) (xy 37.629605 -278.349425) (xy 37.62171 -278.398002) (xy 37.606126 -278.444683)
			(xy 37.583255 -278.48826) (xy 37.55369 -278.527604) (xy 37.518197 -278.561696) (xy 37.477694 -278.589652)
			(xy 37.433232 -278.61075) (xy 37.385961 -278.624442) (xy 37.337106 -278.630374) (xy 37.287931 -278.628393)
			(xy 37.239712 -278.618549) (xy 37.193696 -278.601097) (xy 37.151075 -278.57649) (xy 37.112954 -278.545365)
			(xy 37.080319 -278.508528) (xy 37.054016 -278.466932) (xy 37.034725 -278.421656) (xy 37.022948 -278.373872)
			(xy 37.018988 -278.324818) (xy 36.68014 -278.324818) (xy 36.679645 -278.349425) (xy 36.67175 -278.398002)
			(xy 36.656166 -278.444683) (xy 36.633295 -278.48826) (xy 36.60373 -278.527604) (xy 36.568237 -278.561696)
			(xy 36.527734 -278.589652) (xy 36.483272 -278.61075) (xy 36.436001 -278.624442) (xy 36.387146 -278.630374)
			(xy 36.337971 -278.628393) (xy 36.289752 -278.618549) (xy 36.243736 -278.601097) (xy 36.201115 -278.57649)
			(xy 36.162994 -278.545365) (xy 36.130359 -278.508528) (xy 36.104056 -278.466932) (xy 36.084765 -278.421656)
			(xy 36.072988 -278.373872) (xy 36.069028 -278.324818) (xy 35.494468 -278.324818) (xy 34.544508 -279.274778)
			(xy 36.069028 -279.274778) (xy 36.072988 -279.225724) (xy 36.084765 -279.17794) (xy 36.104056 -279.132664)
			(xy 36.130359 -279.091068) (xy 36.162994 -279.054231) (xy 36.201115 -279.023106) (xy 36.243736 -278.998499)
			(xy 36.289752 -278.981047) (xy 36.337971 -278.971203) (xy 36.387146 -278.969222) (xy 36.436001 -278.975154)
			(xy 36.483272 -278.988846) (xy 36.527734 -279.009944) (xy 36.568237 -279.0379) (xy 36.60373 -279.071992)
			(xy 36.633295 -279.111336) (xy 36.656166 -279.154913) (xy 36.67175 -279.201594) (xy 36.679645 -279.250171)
			(xy 36.68014 -279.274778) (xy 37.018988 -279.274778) (xy 37.022948 -279.225724) (xy 37.034725 -279.17794)
			(xy 37.054016 -279.132664) (xy 37.080319 -279.091068) (xy 37.112954 -279.054231) (xy 37.151075 -279.023106)
			(xy 37.193696 -278.998499) (xy 37.239712 -278.981047) (xy 37.287931 -278.971203) (xy 37.337106 -278.969222)
			(xy 37.385961 -278.975154) (xy 37.433232 -278.988846) (xy 37.477694 -279.009944) (xy 37.518197 -279.0379)
			(xy 37.55369 -279.071992) (xy 37.583255 -279.111336) (xy 37.606126 -279.154913) (xy 37.62171 -279.201594)
			(xy 37.629605 -279.250171) (xy 37.6301 -279.274778) (xy 37.969202 -279.274778) (xy 37.973162 -279.225724)
			(xy 37.984939 -279.17794) (xy 38.00423 -279.132664) (xy 38.030533 -279.091068) (xy 38.063168 -279.054231)
			(xy 38.101289 -279.023106) (xy 38.14391 -278.998499) (xy 38.189926 -278.981047) (xy 38.238145 -278.971203)
			(xy 38.28732 -278.969222) (xy 38.336175 -278.975154) (xy 38.383446 -278.988846) (xy 38.427908 -279.009944)
			(xy 38.468411 -279.0379) (xy 38.503904 -279.071992) (xy 38.533469 -279.111336) (xy 38.55634 -279.154913)
			(xy 38.571924 -279.201594) (xy 38.579819 -279.250171) (xy 38.580314 -279.274778) (xy 38.919162 -279.274778)
			(xy 38.923122 -279.225724) (xy 38.934899 -279.17794) (xy 38.95419 -279.132664) (xy 38.980493 -279.091068)
			(xy 39.013128 -279.054231) (xy 39.051249 -279.023106) (xy 39.09387 -278.998499) (xy 39.139886 -278.981047)
			(xy 39.188105 -278.971203) (xy 39.23728 -278.969222) (xy 39.286135 -278.975154) (xy 39.333406 -278.988846)
			(xy 39.377868 -279.009944) (xy 39.418371 -279.0379) (xy 39.453864 -279.071992) (xy 39.483429 -279.111336)
			(xy 39.5063 -279.154913) (xy 39.521884 -279.201594) (xy 39.529779 -279.250171) (xy 39.530274 -279.274778)
			(xy 39.869122 -279.274778) (xy 39.873082 -279.225724) (xy 39.884859 -279.17794) (xy 39.90415 -279.132664)
			(xy 39.930453 -279.091068) (xy 39.963088 -279.054231) (xy 40.001209 -279.023106) (xy 40.04383 -278.998499)
			(xy 40.089846 -278.981047) (xy 40.138065 -278.971203) (xy 40.18724 -278.969222) (xy 40.236095 -278.975154)
			(xy 40.283366 -278.988846) (xy 40.327828 -279.009944) (xy 40.368331 -279.0379) (xy 40.403824 -279.071992)
			(xy 40.433389 -279.111336) (xy 40.45626 -279.154913) (xy 40.471844 -279.201594) (xy 40.479739 -279.250171)
			(xy 40.480234 -279.274778) (xy 40.819082 -279.274778) (xy 40.823042 -279.225724) (xy 40.834819 -279.17794)
			(xy 40.85411 -279.132664) (xy 40.880413 -279.091068) (xy 40.913048 -279.054231) (xy 40.951169 -279.023106)
			(xy 40.99379 -278.998499) (xy 41.039806 -278.981047) (xy 41.088025 -278.971203) (xy 41.1372 -278.969222)
			(xy 41.186055 -278.975154) (xy 41.233326 -278.988846) (xy 41.277788 -279.009944) (xy 41.318291 -279.0379)
			(xy 41.353784 -279.071992) (xy 41.383349 -279.111336) (xy 41.40622 -279.154913) (xy 41.421804 -279.201594)
			(xy 41.429699 -279.250171) (xy 41.430194 -279.274778) (xy 41.769042 -279.274778) (xy 41.773002 -279.225724)
			(xy 41.784779 -279.17794) (xy 41.80407 -279.132664) (xy 41.830373 -279.091068) (xy 41.863008 -279.054231)
			(xy 41.901129 -279.023106) (xy 41.94375 -278.998499) (xy 41.989766 -278.981047) (xy 42.037985 -278.971203)
			(xy 42.08716 -278.969222) (xy 42.136015 -278.975154) (xy 42.183286 -278.988846) (xy 42.227748 -279.009944)
			(xy 42.268251 -279.0379) (xy 42.303744 -279.071992) (xy 42.333309 -279.111336) (xy 42.35618 -279.154913)
			(xy 42.371764 -279.201594) (xy 42.379659 -279.250171) (xy 42.380154 -279.274778) (xy 42.379659 -279.299385)
			(xy 42.371764 -279.347962) (xy 42.35618 -279.394643) (xy 42.333309 -279.43822) (xy 42.303744 -279.477564)
			(xy 42.268251 -279.511656) (xy 42.227748 -279.539612) (xy 42.183286 -279.56071) (xy 42.136015 -279.574402)
			(xy 42.08716 -279.580334) (xy 42.037985 -279.578353) (xy 41.989766 -279.568509) (xy 41.94375 -279.551057)
			(xy 41.901129 -279.52645) (xy 41.863008 -279.495325) (xy 41.830373 -279.458488) (xy 41.80407 -279.416892)
			(xy 41.784779 -279.371616) (xy 41.773002 -279.323832) (xy 41.769042 -279.274778) (xy 41.430194 -279.274778)
			(xy 41.429699 -279.299385) (xy 41.421804 -279.347962) (xy 41.40622 -279.394643) (xy 41.383349 -279.43822)
			(xy 41.353784 -279.477564) (xy 41.318291 -279.511656) (xy 41.277788 -279.539612) (xy 41.233326 -279.56071)
			(xy 41.186055 -279.574402) (xy 41.1372 -279.580334) (xy 41.088025 -279.578353) (xy 41.039806 -279.568509)
			(xy 40.99379 -279.551057) (xy 40.951169 -279.52645) (xy 40.913048 -279.495325) (xy 40.880413 -279.458488)
			(xy 40.85411 -279.416892) (xy 40.834819 -279.371616) (xy 40.823042 -279.323832) (xy 40.819082 -279.274778)
			(xy 40.480234 -279.274778) (xy 40.479739 -279.299385) (xy 40.471844 -279.347962) (xy 40.45626 -279.394643)
			(xy 40.433389 -279.43822) (xy 40.403824 -279.477564) (xy 40.368331 -279.511656) (xy 40.327828 -279.539612)
			(xy 40.283366 -279.56071) (xy 40.236095 -279.574402) (xy 40.18724 -279.580334) (xy 40.138065 -279.578353)
			(xy 40.089846 -279.568509) (xy 40.04383 -279.551057) (xy 40.001209 -279.52645) (xy 39.963088 -279.495325)
			(xy 39.930453 -279.458488) (xy 39.90415 -279.416892) (xy 39.884859 -279.371616) (xy 39.873082 -279.323832)
			(xy 39.869122 -279.274778) (xy 39.530274 -279.274778) (xy 39.529779 -279.299385) (xy 39.521884 -279.347962)
			(xy 39.5063 -279.394643) (xy 39.483429 -279.43822) (xy 39.453864 -279.477564) (xy 39.418371 -279.511656)
			(xy 39.377868 -279.539612) (xy 39.333406 -279.56071) (xy 39.286135 -279.574402) (xy 39.23728 -279.580334)
			(xy 39.188105 -279.578353) (xy 39.139886 -279.568509) (xy 39.09387 -279.551057) (xy 39.051249 -279.52645)
			(xy 39.013128 -279.495325) (xy 38.980493 -279.458488) (xy 38.95419 -279.416892) (xy 38.934899 -279.371616)
			(xy 38.923122 -279.323832) (xy 38.919162 -279.274778) (xy 38.580314 -279.274778) (xy 38.579819 -279.299385)
			(xy 38.571924 -279.347962) (xy 38.55634 -279.394643) (xy 38.533469 -279.43822) (xy 38.503904 -279.477564)
			(xy 38.468411 -279.511656) (xy 38.427908 -279.539612) (xy 38.383446 -279.56071) (xy 38.336175 -279.574402)
			(xy 38.28732 -279.580334) (xy 38.238145 -279.578353) (xy 38.189926 -279.568509) (xy 38.14391 -279.551057)
			(xy 38.101289 -279.52645) (xy 38.063168 -279.495325) (xy 38.030533 -279.458488) (xy 38.00423 -279.416892)
			(xy 37.984939 -279.371616) (xy 37.973162 -279.323832) (xy 37.969202 -279.274778) (xy 37.6301 -279.274778)
			(xy 37.629605 -279.299385) (xy 37.62171 -279.347962) (xy 37.606126 -279.394643) (xy 37.583255 -279.43822)
			(xy 37.55369 -279.477564) (xy 37.518197 -279.511656) (xy 37.477694 -279.539612) (xy 37.433232 -279.56071)
			(xy 37.385961 -279.574402) (xy 37.337106 -279.580334) (xy 37.287931 -279.578353) (xy 37.239712 -279.568509)
			(xy 37.193696 -279.551057) (xy 37.151075 -279.52645) (xy 37.112954 -279.495325) (xy 37.080319 -279.458488)
			(xy 37.054016 -279.416892) (xy 37.034725 -279.371616) (xy 37.022948 -279.323832) (xy 37.018988 -279.274778)
			(xy 36.68014 -279.274778) (xy 36.679645 -279.299385) (xy 36.67175 -279.347962) (xy 36.656166 -279.394643)
			(xy 36.633295 -279.43822) (xy 36.60373 -279.477564) (xy 36.568237 -279.511656) (xy 36.527734 -279.539612)
			(xy 36.483272 -279.56071) (xy 36.436001 -279.574402) (xy 36.387146 -279.580334) (xy 36.337971 -279.578353)
			(xy 36.289752 -279.568509) (xy 36.243736 -279.551057) (xy 36.201115 -279.52645) (xy 36.162994 -279.495325)
			(xy 36.130359 -279.458488) (xy 36.104056 -279.416892) (xy 36.084765 -279.371616) (xy 36.072988 -279.323832)
			(xy 36.069028 -279.274778) (xy 34.544508 -279.274778) (xy 34.405062 -279.414224) (xy 34.402356 -279.417075)
			(xy 34.397764 -279.423454) (xy 34.395918 -279.426924) (xy 34.393332 -279.43235) (xy 34.390503 -279.44403)
			(xy 34.39033 -279.450038) (xy 34.39033 -279.749758) (xy 44.143942 -279.749758) (xy 44.147902 -279.700704)
			(xy 44.159679 -279.65292) (xy 44.17897 -279.607644) (xy 44.205273 -279.566048) (xy 44.237908 -279.529211)
			(xy 44.276029 -279.498086) (xy 44.31865 -279.473479) (xy 44.364666 -279.456027) (xy 44.412885 -279.446183)
			(xy 44.46206 -279.444202) (xy 44.510915 -279.450134) (xy 44.558186 -279.463826) (xy 44.602648 -279.484924)
			(xy 44.643151 -279.51288) (xy 44.678644 -279.546972) (xy 44.708209 -279.586316) (xy 44.73108 -279.629893)
			(xy 44.746664 -279.676574) (xy 44.754559 -279.725151) (xy 44.755049 -279.749504) (xy 45.094156 -279.749504)
			(xy 45.098116 -279.70045) (xy 45.109893 -279.652666) (xy 45.129184 -279.60739) (xy 45.155487 -279.565794)
			(xy 45.188122 -279.528957) (xy 45.226243 -279.497832) (xy 45.268864 -279.473225) (xy 45.31488 -279.455773)
			(xy 45.363099 -279.445929) (xy 45.412274 -279.443948) (xy 45.461129 -279.44988) (xy 45.5084 -279.463572)
			(xy 45.552862 -279.48467) (xy 45.593365 -279.512626) (xy 45.628858 -279.546718) (xy 45.658423 -279.586062)
			(xy 45.681294 -279.629639) (xy 45.696878 -279.67632) (xy 45.704773 -279.724897) (xy 45.705268 -279.749504)
			(xy 45.705263 -279.749758) (xy 46.044116 -279.749758) (xy 46.048076 -279.700704) (xy 46.059853 -279.65292)
			(xy 46.079144 -279.607644) (xy 46.105447 -279.566048) (xy 46.138082 -279.529211) (xy 46.176203 -279.498086)
			(xy 46.218824 -279.473479) (xy 46.26484 -279.456027) (xy 46.313059 -279.446183) (xy 46.362234 -279.444202)
			(xy 46.411089 -279.450134) (xy 46.45836 -279.463826) (xy 46.502822 -279.484924) (xy 46.543325 -279.51288)
			(xy 46.578818 -279.546972) (xy 46.608383 -279.586316) (xy 46.631254 -279.629893) (xy 46.646838 -279.676574)
			(xy 46.654733 -279.725151) (xy 46.655223 -279.749504) (xy 46.994076 -279.749504) (xy 46.998036 -279.70045)
			(xy 47.009813 -279.652666) (xy 47.029104 -279.60739) (xy 47.055407 -279.565794) (xy 47.088042 -279.528957)
			(xy 47.126163 -279.497832) (xy 47.168784 -279.473225) (xy 47.2148 -279.455773) (xy 47.263019 -279.445929)
			(xy 47.312194 -279.443948) (xy 47.361049 -279.44988) (xy 47.40832 -279.463572) (xy 47.452782 -279.48467)
			(xy 47.493285 -279.512626) (xy 47.528778 -279.546718) (xy 47.558343 -279.586062) (xy 47.581214 -279.629639)
			(xy 47.596798 -279.67632) (xy 47.604693 -279.724897) (xy 47.605188 -279.749504) (xy 47.605183 -279.749758)
			(xy 47.944036 -279.749758) (xy 47.947996 -279.700704) (xy 47.959773 -279.65292) (xy 47.979064 -279.607644)
			(xy 48.005367 -279.566048) (xy 48.038002 -279.529211) (xy 48.076123 -279.498086) (xy 48.118744 -279.473479)
			(xy 48.16476 -279.456027) (xy 48.212979 -279.446183) (xy 48.262154 -279.444202) (xy 48.311009 -279.450134)
			(xy 48.35828 -279.463826) (xy 48.402742 -279.484924) (xy 48.443245 -279.51288) (xy 48.478738 -279.546972)
			(xy 48.508303 -279.586316) (xy 48.531174 -279.629893) (xy 48.546758 -279.676574) (xy 48.554653 -279.725151)
			(xy 48.555143 -279.749504) (xy 48.893996 -279.749504) (xy 48.897956 -279.70045) (xy 48.909733 -279.652666)
			(xy 48.929024 -279.60739) (xy 48.955327 -279.565794) (xy 48.987962 -279.528957) (xy 49.026083 -279.497832)
			(xy 49.068704 -279.473225) (xy 49.11472 -279.455773) (xy 49.162939 -279.445929) (xy 49.212114 -279.443948)
			(xy 49.260969 -279.44988) (xy 49.30824 -279.463572) (xy 49.352702 -279.48467) (xy 49.393205 -279.512626)
			(xy 49.428698 -279.546718) (xy 49.458263 -279.586062) (xy 49.481134 -279.629639) (xy 49.496718 -279.67632)
			(xy 49.504613 -279.724897) (xy 49.505108 -279.749504) (xy 49.505103 -279.749758) (xy 49.843956 -279.749758)
			(xy 49.847916 -279.700704) (xy 49.859693 -279.65292) (xy 49.878984 -279.607644) (xy 49.905287 -279.566048)
			(xy 49.937922 -279.529211) (xy 49.976043 -279.498086) (xy 50.018664 -279.473479) (xy 50.06468 -279.456027)
			(xy 50.112899 -279.446183) (xy 50.162074 -279.444202) (xy 50.210929 -279.450134) (xy 50.2582 -279.463826)
			(xy 50.302662 -279.484924) (xy 50.343165 -279.51288) (xy 50.378658 -279.546972) (xy 50.408223 -279.586316)
			(xy 50.431094 -279.629893) (xy 50.446678 -279.676574) (xy 50.454573 -279.725151) (xy 50.455063 -279.749504)
			(xy 50.79417 -279.749504) (xy 50.79813 -279.70045) (xy 50.809907 -279.652666) (xy 50.829198 -279.60739)
			(xy 50.855501 -279.565794) (xy 50.888136 -279.528957) (xy 50.926257 -279.497832) (xy 50.968878 -279.473225)
			(xy 51.014894 -279.455773) (xy 51.063113 -279.445929) (xy 51.112288 -279.443948) (xy 51.161143 -279.44988)
			(xy 51.208414 -279.463572) (xy 51.252876 -279.48467) (xy 51.293379 -279.512626) (xy 51.328872 -279.546718)
			(xy 51.358437 -279.586062) (xy 51.381308 -279.629639) (xy 51.396892 -279.67632) (xy 51.404787 -279.724897)
			(xy 51.405282 -279.749504) (xy 51.405277 -279.749758) (xy 51.74413 -279.749758) (xy 51.74809 -279.700704)
			(xy 51.759867 -279.65292) (xy 51.779158 -279.607644) (xy 51.805461 -279.566048) (xy 51.838096 -279.529211)
			(xy 51.876217 -279.498086) (xy 51.918838 -279.473479) (xy 51.964854 -279.456027) (xy 52.013073 -279.446183)
			(xy 52.062248 -279.444202) (xy 52.111103 -279.450134) (xy 52.158374 -279.463826) (xy 52.202836 -279.484924)
			(xy 52.243339 -279.51288) (xy 52.278832 -279.546972) (xy 52.308397 -279.586316) (xy 52.331268 -279.629893)
			(xy 52.346852 -279.676574) (xy 52.354747 -279.725151) (xy 52.355237 -279.749504) (xy 52.69409 -279.749504)
			(xy 52.69805 -279.70045) (xy 52.709827 -279.652666) (xy 52.729118 -279.60739) (xy 52.755421 -279.565794)
			(xy 52.788056 -279.528957) (xy 52.826177 -279.497832) (xy 52.868798 -279.473225) (xy 52.914814 -279.455773)
			(xy 52.963033 -279.445929) (xy 53.012208 -279.443948) (xy 53.061063 -279.44988) (xy 53.108334 -279.463572)
			(xy 53.152796 -279.48467) (xy 53.193299 -279.512626) (xy 53.228792 -279.546718) (xy 53.258357 -279.586062)
			(xy 53.281228 -279.629639) (xy 53.296812 -279.67632) (xy 53.304707 -279.724897) (xy 53.305202 -279.749504)
			(xy 53.305197 -279.749758) (xy 53.64405 -279.749758) (xy 53.64801 -279.700704) (xy 53.659787 -279.65292)
			(xy 53.679078 -279.607644) (xy 53.705381 -279.566048) (xy 53.738016 -279.529211) (xy 53.776137 -279.498086)
			(xy 53.818758 -279.473479) (xy 53.864774 -279.456027) (xy 53.912993 -279.446183) (xy 53.962168 -279.444202)
			(xy 54.011023 -279.450134) (xy 54.058294 -279.463826) (xy 54.102756 -279.484924) (xy 54.143259 -279.51288)
			(xy 54.178752 -279.546972) (xy 54.208317 -279.586316) (xy 54.231188 -279.629893) (xy 54.246772 -279.676574)
			(xy 54.254667 -279.725151) (xy 54.255157 -279.749504) (xy 54.59401 -279.749504) (xy 54.59797 -279.70045)
			(xy 54.609747 -279.652666) (xy 54.629038 -279.60739) (xy 54.655341 -279.565794) (xy 54.687976 -279.528957)
			(xy 54.726097 -279.497832) (xy 54.768718 -279.473225) (xy 54.814734 -279.455773) (xy 54.862953 -279.445929)
			(xy 54.912128 -279.443948) (xy 54.960983 -279.44988) (xy 55.008254 -279.463572) (xy 55.052716 -279.48467)
			(xy 55.093219 -279.512626) (xy 55.128712 -279.546718) (xy 55.158277 -279.586062) (xy 55.181148 -279.629639)
			(xy 55.196732 -279.67632) (xy 55.204627 -279.724897) (xy 55.205122 -279.749504) (xy 55.205117 -279.749758)
			(xy 55.54397 -279.749758) (xy 55.54793 -279.700704) (xy 55.559707 -279.65292) (xy 55.578998 -279.607644)
			(xy 55.605301 -279.566048) (xy 55.637936 -279.529211) (xy 55.676057 -279.498086) (xy 55.718678 -279.473479)
			(xy 55.764694 -279.456027) (xy 55.812913 -279.446183) (xy 55.862088 -279.444202) (xy 55.910943 -279.450134)
			(xy 55.958214 -279.463826) (xy 56.002676 -279.484924) (xy 56.043179 -279.51288) (xy 56.078672 -279.546972)
			(xy 56.108237 -279.586316) (xy 56.131108 -279.629893) (xy 56.146692 -279.676574) (xy 56.154587 -279.725151)
			(xy 56.155077 -279.749504) (xy 56.49393 -279.749504) (xy 56.49789 -279.70045) (xy 56.509667 -279.652666)
			(xy 56.528958 -279.60739) (xy 56.555261 -279.565794) (xy 56.587896 -279.528957) (xy 56.626017 -279.497832)
			(xy 56.668638 -279.473225) (xy 56.714654 -279.455773) (xy 56.762873 -279.445929) (xy 56.812048 -279.443948)
			(xy 56.860903 -279.44988) (xy 56.908174 -279.463572) (xy 56.952636 -279.48467) (xy 56.993139 -279.512626)
			(xy 57.028632 -279.546718) (xy 57.058197 -279.586062) (xy 57.081068 -279.629639) (xy 57.096652 -279.67632)
			(xy 57.104547 -279.724897) (xy 57.105042 -279.749504) (xy 57.105037 -279.749758) (xy 57.444144 -279.749758)
			(xy 57.448104 -279.700704) (xy 57.459881 -279.65292) (xy 57.479172 -279.607644) (xy 57.505475 -279.566048)
			(xy 57.53811 -279.529211) (xy 57.576231 -279.498086) (xy 57.618852 -279.473479) (xy 57.664868 -279.456027)
			(xy 57.713087 -279.446183) (xy 57.762262 -279.444202) (xy 57.811117 -279.450134) (xy 57.858388 -279.463826)
			(xy 57.90285 -279.484924) (xy 57.943353 -279.51288) (xy 57.978846 -279.546972) (xy 58.008411 -279.586316)
			(xy 58.031282 -279.629893) (xy 58.046866 -279.676574) (xy 58.054761 -279.725151) (xy 58.055251 -279.749504)
			(xy 58.394104 -279.749504) (xy 58.398064 -279.70045) (xy 58.409841 -279.652666) (xy 58.429132 -279.60739)
			(xy 58.455435 -279.565794) (xy 58.48807 -279.528957) (xy 58.526191 -279.497832) (xy 58.568812 -279.473225)
			(xy 58.614828 -279.455773) (xy 58.663047 -279.445929) (xy 58.712222 -279.443948) (xy 58.761077 -279.44988)
			(xy 58.808348 -279.463572) (xy 58.85281 -279.48467) (xy 58.893313 -279.512626) (xy 58.928806 -279.546718)
			(xy 58.958371 -279.586062) (xy 58.981242 -279.629639) (xy 58.996826 -279.67632) (xy 59.004721 -279.724897)
			(xy 59.005216 -279.749504) (xy 59.005211 -279.749758) (xy 59.344064 -279.749758) (xy 59.348024 -279.700704)
			(xy 59.359801 -279.65292) (xy 59.379092 -279.607644) (xy 59.405395 -279.566048) (xy 59.43803 -279.529211)
			(xy 59.476151 -279.498086) (xy 59.518772 -279.473479) (xy 59.564788 -279.456027) (xy 59.613007 -279.446183)
			(xy 59.662182 -279.444202) (xy 59.711037 -279.450134) (xy 59.758308 -279.463826) (xy 59.80277 -279.484924)
			(xy 59.843273 -279.51288) (xy 59.878766 -279.546972) (xy 59.908331 -279.586316) (xy 59.931202 -279.629893)
			(xy 59.946786 -279.676574) (xy 59.954681 -279.725151) (xy 59.955171 -279.749504) (xy 60.294024 -279.749504)
			(xy 60.297984 -279.70045) (xy 60.309761 -279.652666) (xy 60.329052 -279.60739) (xy 60.355355 -279.565794)
			(xy 60.38799 -279.528957) (xy 60.426111 -279.497832) (xy 60.468732 -279.473225) (xy 60.514748 -279.455773)
			(xy 60.562967 -279.445929) (xy 60.612142 -279.443948) (xy 60.660997 -279.44988) (xy 60.708268 -279.463572)
			(xy 60.75273 -279.48467) (xy 60.793233 -279.512626) (xy 60.828726 -279.546718) (xy 60.858291 -279.586062)
			(xy 60.881162 -279.629639) (xy 60.896746 -279.67632) (xy 60.904641 -279.724897) (xy 60.905136 -279.749504)
			(xy 60.905131 -279.749758) (xy 61.243984 -279.749758) (xy 61.247944 -279.700704) (xy 61.259721 -279.65292)
			(xy 61.279012 -279.607644) (xy 61.305315 -279.566048) (xy 61.33795 -279.529211) (xy 61.376071 -279.498086)
			(xy 61.418692 -279.473479) (xy 61.464708 -279.456027) (xy 61.512927 -279.446183) (xy 61.562102 -279.444202)
			(xy 61.610957 -279.450134) (xy 61.658228 -279.463826) (xy 61.70269 -279.484924) (xy 61.743193 -279.51288)
			(xy 61.778686 -279.546972) (xy 61.808251 -279.586316) (xy 61.831122 -279.629893) (xy 61.846706 -279.676574)
			(xy 61.854601 -279.725151) (xy 61.855091 -279.749504) (xy 62.193944 -279.749504) (xy 62.197904 -279.70045)
			(xy 62.209681 -279.652666) (xy 62.228972 -279.60739) (xy 62.255275 -279.565794) (xy 62.28791 -279.528957)
			(xy 62.326031 -279.497832) (xy 62.368652 -279.473225) (xy 62.414668 -279.455773) (xy 62.462887 -279.445929)
			(xy 62.512062 -279.443948) (xy 62.560917 -279.44988) (xy 62.608188 -279.463572) (xy 62.65265 -279.48467)
			(xy 62.693153 -279.512626) (xy 62.728646 -279.546718) (xy 62.758211 -279.586062) (xy 62.781082 -279.629639)
			(xy 62.796666 -279.67632) (xy 62.804561 -279.724897) (xy 62.805056 -279.749504) (xy 62.805051 -279.749758)
			(xy 63.144158 -279.749758) (xy 63.148118 -279.700704) (xy 63.159895 -279.65292) (xy 63.179186 -279.607644)
			(xy 63.205489 -279.566048) (xy 63.238124 -279.529211) (xy 63.276245 -279.498086) (xy 63.318866 -279.473479)
			(xy 63.364882 -279.456027) (xy 63.413101 -279.446183) (xy 63.462276 -279.444202) (xy 63.511131 -279.450134)
			(xy 63.558402 -279.463826) (xy 63.602864 -279.484924) (xy 63.643367 -279.51288) (xy 63.67886 -279.546972)
			(xy 63.708425 -279.586316) (xy 63.731296 -279.629893) (xy 63.74688 -279.676574) (xy 63.754775 -279.725151)
			(xy 63.755265 -279.749504) (xy 64.094118 -279.749504) (xy 64.098078 -279.70045) (xy 64.109855 -279.652666)
			(xy 64.129146 -279.60739) (xy 64.155449 -279.565794) (xy 64.188084 -279.528957) (xy 64.226205 -279.497832)
			(xy 64.268826 -279.473225) (xy 64.314842 -279.455773) (xy 64.363061 -279.445929) (xy 64.412236 -279.443948)
			(xy 64.461091 -279.44988) (xy 64.508362 -279.463572) (xy 64.552824 -279.48467) (xy 64.593327 -279.512626)
			(xy 64.62882 -279.546718) (xy 64.658385 -279.586062) (xy 64.681256 -279.629639) (xy 64.69684 -279.67632)
			(xy 64.704735 -279.724897) (xy 64.70523 -279.749504) (xy 64.705225 -279.749758) (xy 65.044078 -279.749758)
			(xy 65.048038 -279.700704) (xy 65.059815 -279.65292) (xy 65.079106 -279.607644) (xy 65.105409 -279.566048)
			(xy 65.138044 -279.529211) (xy 65.176165 -279.498086) (xy 65.218786 -279.473479) (xy 65.264802 -279.456027)
			(xy 65.313021 -279.446183) (xy 65.362196 -279.444202) (xy 65.411051 -279.450134) (xy 65.458322 -279.463826)
			(xy 65.502784 -279.484924) (xy 65.543287 -279.51288) (xy 65.57878 -279.546972) (xy 65.608345 -279.586316)
			(xy 65.631216 -279.629893) (xy 65.6468 -279.676574) (xy 65.654695 -279.725151) (xy 65.655185 -279.749504)
			(xy 65.994038 -279.749504) (xy 65.997998 -279.70045) (xy 66.009775 -279.652666) (xy 66.029066 -279.60739)
			(xy 66.055369 -279.565794) (xy 66.088004 -279.528957) (xy 66.126125 -279.497832) (xy 66.168746 -279.473225)
			(xy 66.214762 -279.455773) (xy 66.262981 -279.445929) (xy 66.312156 -279.443948) (xy 66.361011 -279.44988)
			(xy 66.408282 -279.463572) (xy 66.452744 -279.48467) (xy 66.493247 -279.512626) (xy 66.52874 -279.546718)
			(xy 66.558305 -279.586062) (xy 66.581176 -279.629639) (xy 66.59676 -279.67632) (xy 66.604655 -279.724897)
			(xy 66.60515 -279.749504) (xy 66.605145 -279.749758) (xy 66.943998 -279.749758) (xy 66.947958 -279.700704)
			(xy 66.959735 -279.65292) (xy 66.979026 -279.607644) (xy 67.005329 -279.566048) (xy 67.037964 -279.529211)
			(xy 67.076085 -279.498086) (xy 67.118706 -279.473479) (xy 67.164722 -279.456027) (xy 67.212941 -279.446183)
			(xy 67.262116 -279.444202) (xy 67.310971 -279.450134) (xy 67.358242 -279.463826) (xy 67.402704 -279.484924)
			(xy 67.443207 -279.51288) (xy 67.4787 -279.546972) (xy 67.508265 -279.586316) (xy 67.531136 -279.629893)
			(xy 67.54672 -279.676574) (xy 67.554615 -279.725151) (xy 67.555105 -279.749504) (xy 67.893958 -279.749504)
			(xy 67.897918 -279.70045) (xy 67.909695 -279.652666) (xy 67.928986 -279.60739) (xy 67.955289 -279.565794)
			(xy 67.987924 -279.528957) (xy 68.026045 -279.497832) (xy 68.068666 -279.473225) (xy 68.114682 -279.455773)
			(xy 68.162901 -279.445929) (xy 68.212076 -279.443948) (xy 68.260931 -279.44988) (xy 68.308202 -279.463572)
			(xy 68.352664 -279.48467) (xy 68.393167 -279.512626) (xy 68.42866 -279.546718) (xy 68.458225 -279.586062)
			(xy 68.481096 -279.629639) (xy 68.49668 -279.67632) (xy 68.504575 -279.724897) (xy 68.50507 -279.749504)
			(xy 68.505065 -279.749758) (xy 68.844172 -279.749758) (xy 68.848132 -279.700704) (xy 68.859909 -279.65292)
			(xy 68.8792 -279.607644) (xy 68.905503 -279.566048) (xy 68.938138 -279.529211) (xy 68.976259 -279.498086)
			(xy 69.01888 -279.473479) (xy 69.064896 -279.456027) (xy 69.113115 -279.446183) (xy 69.16229 -279.444202)
			(xy 69.211145 -279.450134) (xy 69.258416 -279.463826) (xy 69.302878 -279.484924) (xy 69.343381 -279.51288)
			(xy 69.378874 -279.546972) (xy 69.408439 -279.586316) (xy 69.43131 -279.629893) (xy 69.446894 -279.676574)
			(xy 69.454789 -279.725151) (xy 69.455279 -279.749504) (xy 69.794132 -279.749504) (xy 69.798092 -279.70045)
			(xy 69.809869 -279.652666) (xy 69.82916 -279.60739) (xy 69.855463 -279.565794) (xy 69.888098 -279.528957)
			(xy 69.926219 -279.497832) (xy 69.96884 -279.473225) (xy 70.014856 -279.455773) (xy 70.063075 -279.445929)
			(xy 70.11225 -279.443948) (xy 70.161105 -279.44988) (xy 70.208376 -279.463572) (xy 70.252838 -279.48467)
			(xy 70.293341 -279.512626) (xy 70.328834 -279.546718) (xy 70.358399 -279.586062) (xy 70.38127 -279.629639)
			(xy 70.396854 -279.67632) (xy 70.404749 -279.724897) (xy 70.405244 -279.749504) (xy 70.405239 -279.749758)
			(xy 70.744092 -279.749758) (xy 70.748052 -279.700704) (xy 70.759829 -279.65292) (xy 70.77912 -279.607644)
			(xy 70.805423 -279.566048) (xy 70.838058 -279.529211) (xy 70.876179 -279.498086) (xy 70.9188 -279.473479)
			(xy 70.964816 -279.456027) (xy 71.013035 -279.446183) (xy 71.06221 -279.444202) (xy 71.111065 -279.450134)
			(xy 71.158336 -279.463826) (xy 71.202798 -279.484924) (xy 71.243301 -279.51288) (xy 71.278794 -279.546972)
			(xy 71.308359 -279.586316) (xy 71.33123 -279.629893) (xy 71.346814 -279.676574) (xy 71.354709 -279.725151)
			(xy 71.355199 -279.749504) (xy 71.694052 -279.749504) (xy 71.698012 -279.70045) (xy 71.709789 -279.652666)
			(xy 71.72908 -279.60739) (xy 71.755383 -279.565794) (xy 71.788018 -279.528957) (xy 71.826139 -279.497832)
			(xy 71.86876 -279.473225) (xy 71.914776 -279.455773) (xy 71.962995 -279.445929) (xy 72.01217 -279.443948)
			(xy 72.061025 -279.44988) (xy 72.108296 -279.463572) (xy 72.152758 -279.48467) (xy 72.193261 -279.512626)
			(xy 72.228754 -279.546718) (xy 72.258319 -279.586062) (xy 72.28119 -279.629639) (xy 72.296774 -279.67632)
			(xy 72.304669 -279.724897) (xy 72.305164 -279.749504) (xy 72.305159 -279.749758) (xy 72.644012 -279.749758)
			(xy 72.647972 -279.700704) (xy 72.659749 -279.65292) (xy 72.67904 -279.607644) (xy 72.705343 -279.566048)
			(xy 72.737978 -279.529211) (xy 72.776099 -279.498086) (xy 72.81872 -279.473479) (xy 72.864736 -279.456027)
			(xy 72.912955 -279.446183) (xy 72.96213 -279.444202) (xy 73.010985 -279.450134) (xy 73.058256 -279.463826)
			(xy 73.102718 -279.484924) (xy 73.143221 -279.51288) (xy 73.178714 -279.546972) (xy 73.208279 -279.586316)
			(xy 73.23115 -279.629893) (xy 73.246734 -279.676574) (xy 73.254629 -279.725151) (xy 73.255119 -279.749504)
			(xy 73.593972 -279.749504) (xy 73.597932 -279.70045) (xy 73.609709 -279.652666) (xy 73.629 -279.60739)
			(xy 73.655303 -279.565794) (xy 73.687938 -279.528957) (xy 73.726059 -279.497832) (xy 73.76868 -279.473225)
			(xy 73.814696 -279.455773) (xy 73.862915 -279.445929) (xy 73.91209 -279.443948) (xy 73.960945 -279.44988)
			(xy 74.008216 -279.463572) (xy 74.052678 -279.48467) (xy 74.093181 -279.512626) (xy 74.128674 -279.546718)
			(xy 74.158239 -279.586062) (xy 74.18111 -279.629639) (xy 74.196694 -279.67632) (xy 74.204589 -279.724897)
			(xy 74.205084 -279.749504) (xy 74.205079 -279.749758) (xy 74.543932 -279.749758) (xy 74.547892 -279.700704)
			(xy 74.559669 -279.65292) (xy 74.57896 -279.607644) (xy 74.605263 -279.566048) (xy 74.637898 -279.529211)
			(xy 74.676019 -279.498086) (xy 74.71864 -279.473479) (xy 74.764656 -279.456027) (xy 74.812875 -279.446183)
			(xy 74.86205 -279.444202) (xy 74.910905 -279.450134) (xy 74.958176 -279.463826) (xy 75.002638 -279.484924)
			(xy 75.043141 -279.51288) (xy 75.078634 -279.546972) (xy 75.108199 -279.586316) (xy 75.13107 -279.629893)
			(xy 75.146654 -279.676574) (xy 75.154549 -279.725151) (xy 75.155039 -279.749504) (xy 75.494146 -279.749504)
			(xy 75.498106 -279.70045) (xy 75.509883 -279.652666) (xy 75.529174 -279.60739) (xy 75.555477 -279.565794)
			(xy 75.588112 -279.528957) (xy 75.626233 -279.497832) (xy 75.668854 -279.473225) (xy 75.71487 -279.455773)
			(xy 75.763089 -279.445929) (xy 75.812264 -279.443948) (xy 75.861119 -279.44988) (xy 75.90839 -279.463572)
			(xy 75.952852 -279.48467) (xy 75.993355 -279.512626) (xy 76.028848 -279.546718) (xy 76.058413 -279.586062)
			(xy 76.081284 -279.629639) (xy 76.096868 -279.67632) (xy 76.104763 -279.724897) (xy 76.105258 -279.749504)
			(xy 76.105253 -279.749758) (xy 76.444106 -279.749758) (xy 76.448066 -279.700704) (xy 76.459843 -279.65292)
			(xy 76.479134 -279.607644) (xy 76.505437 -279.566048) (xy 76.538072 -279.529211) (xy 76.576193 -279.498086)
			(xy 76.618814 -279.473479) (xy 76.66483 -279.456027) (xy 76.713049 -279.446183) (xy 76.762224 -279.444202)
			(xy 76.811079 -279.450134) (xy 76.85835 -279.463826) (xy 76.902812 -279.484924) (xy 76.943315 -279.51288)
			(xy 76.978808 -279.546972) (xy 77.008373 -279.586316) (xy 77.031244 -279.629893) (xy 77.046828 -279.676574)
			(xy 77.054723 -279.725151) (xy 77.055218 -279.749758) (xy 77.054723 -279.774365) (xy 77.046828 -279.822942)
			(xy 77.031244 -279.869623) (xy 77.008373 -279.9132) (xy 76.978808 -279.952544) (xy 76.943315 -279.986636)
			(xy 76.902812 -280.014592) (xy 76.85835 -280.03569) (xy 76.811079 -280.049382) (xy 76.762224 -280.055314)
			(xy 76.713049 -280.053333) (xy 76.66483 -280.043489) (xy 76.618814 -280.026037) (xy 76.576193 -280.00143)
			(xy 76.538072 -279.970305) (xy 76.505437 -279.933468) (xy 76.479134 -279.891872) (xy 76.459843 -279.846596)
			(xy 76.448066 -279.798812) (xy 76.444106 -279.749758) (xy 76.105253 -279.749758) (xy 76.104763 -279.774111)
			(xy 76.096868 -279.822688) (xy 76.081284 -279.869369) (xy 76.058413 -279.912946) (xy 76.028848 -279.95229)
			(xy 75.993355 -279.986382) (xy 75.952852 -280.014338) (xy 75.90839 -280.035436) (xy 75.861119 -280.049128)
			(xy 75.812264 -280.05506) (xy 75.763089 -280.053079) (xy 75.71487 -280.043235) (xy 75.668854 -280.025783)
			(xy 75.626233 -280.001176) (xy 75.588112 -279.970051) (xy 75.555477 -279.933214) (xy 75.529174 -279.891618)
			(xy 75.509883 -279.846342) (xy 75.498106 -279.798558) (xy 75.494146 -279.749504) (xy 75.155039 -279.749504)
			(xy 75.155044 -279.749758) (xy 75.154549 -279.774365) (xy 75.146654 -279.822942) (xy 75.13107 -279.869623)
			(xy 75.108199 -279.9132) (xy 75.078634 -279.952544) (xy 75.043141 -279.986636) (xy 75.002638 -280.014592)
			(xy 74.958176 -280.03569) (xy 74.910905 -280.049382) (xy 74.86205 -280.055314) (xy 74.812875 -280.053333)
			(xy 74.764656 -280.043489) (xy 74.71864 -280.026037) (xy 74.676019 -280.00143) (xy 74.637898 -279.970305)
			(xy 74.605263 -279.933468) (xy 74.57896 -279.891872) (xy 74.559669 -279.846596) (xy 74.547892 -279.798812)
			(xy 74.543932 -279.749758) (xy 74.205079 -279.749758) (xy 74.204589 -279.774111) (xy 74.196694 -279.822688)
			(xy 74.18111 -279.869369) (xy 74.158239 -279.912946) (xy 74.128674 -279.95229) (xy 74.093181 -279.986382)
			(xy 74.052678 -280.014338) (xy 74.008216 -280.035436) (xy 73.960945 -280.049128) (xy 73.91209 -280.05506)
			(xy 73.862915 -280.053079) (xy 73.814696 -280.043235) (xy 73.76868 -280.025783) (xy 73.726059 -280.001176)
			(xy 73.687938 -279.970051) (xy 73.655303 -279.933214) (xy 73.629 -279.891618) (xy 73.609709 -279.846342)
			(xy 73.597932 -279.798558) (xy 73.593972 -279.749504) (xy 73.255119 -279.749504) (xy 73.255124 -279.749758)
			(xy 73.254629 -279.774365) (xy 73.246734 -279.822942) (xy 73.23115 -279.869623) (xy 73.208279 -279.9132)
			(xy 73.178714 -279.952544) (xy 73.143221 -279.986636) (xy 73.102718 -280.014592) (xy 73.058256 -280.03569)
			(xy 73.010985 -280.049382) (xy 72.96213 -280.055314) (xy 72.912955 -280.053333) (xy 72.864736 -280.043489)
			(xy 72.81872 -280.026037) (xy 72.776099 -280.00143) (xy 72.737978 -279.970305) (xy 72.705343 -279.933468)
			(xy 72.67904 -279.891872) (xy 72.659749 -279.846596) (xy 72.647972 -279.798812) (xy 72.644012 -279.749758)
			(xy 72.305159 -279.749758) (xy 72.304669 -279.774111) (xy 72.296774 -279.822688) (xy 72.28119 -279.869369)
			(xy 72.258319 -279.912946) (xy 72.228754 -279.95229) (xy 72.193261 -279.986382) (xy 72.152758 -280.014338)
			(xy 72.108296 -280.035436) (xy 72.061025 -280.049128) (xy 72.01217 -280.05506) (xy 71.962995 -280.053079)
			(xy 71.914776 -280.043235) (xy 71.86876 -280.025783) (xy 71.826139 -280.001176) (xy 71.788018 -279.970051)
			(xy 71.755383 -279.933214) (xy 71.72908 -279.891618) (xy 71.709789 -279.846342) (xy 71.698012 -279.798558)
			(xy 71.694052 -279.749504) (xy 71.355199 -279.749504) (xy 71.355204 -279.749758) (xy 71.354709 -279.774365)
			(xy 71.346814 -279.822942) (xy 71.33123 -279.869623) (xy 71.308359 -279.9132) (xy 71.278794 -279.952544)
			(xy 71.243301 -279.986636) (xy 71.202798 -280.014592) (xy 71.158336 -280.03569) (xy 71.111065 -280.049382)
			(xy 71.06221 -280.055314) (xy 71.013035 -280.053333) (xy 70.964816 -280.043489) (xy 70.9188 -280.026037)
			(xy 70.876179 -280.00143) (xy 70.838058 -279.970305) (xy 70.805423 -279.933468) (xy 70.77912 -279.891872)
			(xy 70.759829 -279.846596) (xy 70.748052 -279.798812) (xy 70.744092 -279.749758) (xy 70.405239 -279.749758)
			(xy 70.404749 -279.774111) (xy 70.396854 -279.822688) (xy 70.38127 -279.869369) (xy 70.358399 -279.912946)
			(xy 70.328834 -279.95229) (xy 70.293341 -279.986382) (xy 70.252838 -280.014338) (xy 70.208376 -280.035436)
			(xy 70.161105 -280.049128) (xy 70.11225 -280.05506) (xy 70.063075 -280.053079) (xy 70.014856 -280.043235)
			(xy 69.96884 -280.025783) (xy 69.926219 -280.001176) (xy 69.888098 -279.970051) (xy 69.855463 -279.933214)
			(xy 69.82916 -279.891618) (xy 69.809869 -279.846342) (xy 69.798092 -279.798558) (xy 69.794132 -279.749504)
			(xy 69.455279 -279.749504) (xy 69.455284 -279.749758) (xy 69.454789 -279.774365) (xy 69.446894 -279.822942)
			(xy 69.43131 -279.869623) (xy 69.408439 -279.9132) (xy 69.378874 -279.952544) (xy 69.343381 -279.986636)
			(xy 69.302878 -280.014592) (xy 69.258416 -280.03569) (xy 69.211145 -280.049382) (xy 69.16229 -280.055314)
			(xy 69.113115 -280.053333) (xy 69.064896 -280.043489) (xy 69.01888 -280.026037) (xy 68.976259 -280.00143)
			(xy 68.938138 -279.970305) (xy 68.905503 -279.933468) (xy 68.8792 -279.891872) (xy 68.859909 -279.846596)
			(xy 68.848132 -279.798812) (xy 68.844172 -279.749758) (xy 68.505065 -279.749758) (xy 68.504575 -279.774111)
			(xy 68.49668 -279.822688) (xy 68.481096 -279.869369) (xy 68.458225 -279.912946) (xy 68.42866 -279.95229)
			(xy 68.393167 -279.986382) (xy 68.352664 -280.014338) (xy 68.308202 -280.035436) (xy 68.260931 -280.049128)
			(xy 68.212076 -280.05506) (xy 68.162901 -280.053079) (xy 68.114682 -280.043235) (xy 68.068666 -280.025783)
			(xy 68.026045 -280.001176) (xy 67.987924 -279.970051) (xy 67.955289 -279.933214) (xy 67.928986 -279.891618)
			(xy 67.909695 -279.846342) (xy 67.897918 -279.798558) (xy 67.893958 -279.749504) (xy 67.555105 -279.749504)
			(xy 67.55511 -279.749758) (xy 67.554615 -279.774365) (xy 67.54672 -279.822942) (xy 67.531136 -279.869623)
			(xy 67.508265 -279.9132) (xy 67.4787 -279.952544) (xy 67.443207 -279.986636) (xy 67.402704 -280.014592)
			(xy 67.358242 -280.03569) (xy 67.310971 -280.049382) (xy 67.262116 -280.055314) (xy 67.212941 -280.053333)
			(xy 67.164722 -280.043489) (xy 67.118706 -280.026037) (xy 67.076085 -280.00143) (xy 67.037964 -279.970305)
			(xy 67.005329 -279.933468) (xy 66.979026 -279.891872) (xy 66.959735 -279.846596) (xy 66.947958 -279.798812)
			(xy 66.943998 -279.749758) (xy 66.605145 -279.749758) (xy 66.604655 -279.774111) (xy 66.59676 -279.822688)
			(xy 66.581176 -279.869369) (xy 66.558305 -279.912946) (xy 66.52874 -279.95229) (xy 66.493247 -279.986382)
			(xy 66.452744 -280.014338) (xy 66.408282 -280.035436) (xy 66.361011 -280.049128) (xy 66.312156 -280.05506)
			(xy 66.262981 -280.053079) (xy 66.214762 -280.043235) (xy 66.168746 -280.025783) (xy 66.126125 -280.001176)
			(xy 66.088004 -279.970051) (xy 66.055369 -279.933214) (xy 66.029066 -279.891618) (xy 66.009775 -279.846342)
			(xy 65.997998 -279.798558) (xy 65.994038 -279.749504) (xy 65.655185 -279.749504) (xy 65.65519 -279.749758)
			(xy 65.654695 -279.774365) (xy 65.6468 -279.822942) (xy 65.631216 -279.869623) (xy 65.608345 -279.9132)
			(xy 65.57878 -279.952544) (xy 65.543287 -279.986636) (xy 65.502784 -280.014592) (xy 65.458322 -280.03569)
			(xy 65.411051 -280.049382) (xy 65.362196 -280.055314) (xy 65.313021 -280.053333) (xy 65.264802 -280.043489)
			(xy 65.218786 -280.026037) (xy 65.176165 -280.00143) (xy 65.138044 -279.970305) (xy 65.105409 -279.933468)
			(xy 65.079106 -279.891872) (xy 65.059815 -279.846596) (xy 65.048038 -279.798812) (xy 65.044078 -279.749758)
			(xy 64.705225 -279.749758) (xy 64.704735 -279.774111) (xy 64.69684 -279.822688) (xy 64.681256 -279.869369)
			(xy 64.658385 -279.912946) (xy 64.62882 -279.95229) (xy 64.593327 -279.986382) (xy 64.552824 -280.014338)
			(xy 64.508362 -280.035436) (xy 64.461091 -280.049128) (xy 64.412236 -280.05506) (xy 64.363061 -280.053079)
			(xy 64.314842 -280.043235) (xy 64.268826 -280.025783) (xy 64.226205 -280.001176) (xy 64.188084 -279.970051)
			(xy 64.155449 -279.933214) (xy 64.129146 -279.891618) (xy 64.109855 -279.846342) (xy 64.098078 -279.798558)
			(xy 64.094118 -279.749504) (xy 63.755265 -279.749504) (xy 63.75527 -279.749758) (xy 63.754775 -279.774365)
			(xy 63.74688 -279.822942) (xy 63.731296 -279.869623) (xy 63.708425 -279.9132) (xy 63.67886 -279.952544)
			(xy 63.643367 -279.986636) (xy 63.602864 -280.014592) (xy 63.558402 -280.03569) (xy 63.511131 -280.049382)
			(xy 63.462276 -280.055314) (xy 63.413101 -280.053333) (xy 63.364882 -280.043489) (xy 63.318866 -280.026037)
			(xy 63.276245 -280.00143) (xy 63.238124 -279.970305) (xy 63.205489 -279.933468) (xy 63.179186 -279.891872)
			(xy 63.159895 -279.846596) (xy 63.148118 -279.798812) (xy 63.144158 -279.749758) (xy 62.805051 -279.749758)
			(xy 62.804561 -279.774111) (xy 62.796666 -279.822688) (xy 62.781082 -279.869369) (xy 62.758211 -279.912946)
			(xy 62.728646 -279.95229) (xy 62.693153 -279.986382) (xy 62.65265 -280.014338) (xy 62.608188 -280.035436)
			(xy 62.560917 -280.049128) (xy 62.512062 -280.05506) (xy 62.462887 -280.053079) (xy 62.414668 -280.043235)
			(xy 62.368652 -280.025783) (xy 62.326031 -280.001176) (xy 62.28791 -279.970051) (xy 62.255275 -279.933214)
			(xy 62.228972 -279.891618) (xy 62.209681 -279.846342) (xy 62.197904 -279.798558) (xy 62.193944 -279.749504)
			(xy 61.855091 -279.749504) (xy 61.855096 -279.749758) (xy 61.854601 -279.774365) (xy 61.846706 -279.822942)
			(xy 61.831122 -279.869623) (xy 61.808251 -279.9132) (xy 61.778686 -279.952544) (xy 61.743193 -279.986636)
			(xy 61.70269 -280.014592) (xy 61.658228 -280.03569) (xy 61.610957 -280.049382) (xy 61.562102 -280.055314)
			(xy 61.512927 -280.053333) (xy 61.464708 -280.043489) (xy 61.418692 -280.026037) (xy 61.376071 -280.00143)
			(xy 61.33795 -279.970305) (xy 61.305315 -279.933468) (xy 61.279012 -279.891872) (xy 61.259721 -279.846596)
			(xy 61.247944 -279.798812) (xy 61.243984 -279.749758) (xy 60.905131 -279.749758) (xy 60.904641 -279.774111)
			(xy 60.896746 -279.822688) (xy 60.881162 -279.869369) (xy 60.858291 -279.912946) (xy 60.828726 -279.95229)
			(xy 60.793233 -279.986382) (xy 60.75273 -280.014338) (xy 60.708268 -280.035436) (xy 60.660997 -280.049128)
			(xy 60.612142 -280.05506) (xy 60.562967 -280.053079) (xy 60.514748 -280.043235) (xy 60.468732 -280.025783)
			(xy 60.426111 -280.001176) (xy 60.38799 -279.970051) (xy 60.355355 -279.933214) (xy 60.329052 -279.891618)
			(xy 60.309761 -279.846342) (xy 60.297984 -279.798558) (xy 60.294024 -279.749504) (xy 59.955171 -279.749504)
			(xy 59.955176 -279.749758) (xy 59.954681 -279.774365) (xy 59.946786 -279.822942) (xy 59.931202 -279.869623)
			(xy 59.908331 -279.9132) (xy 59.878766 -279.952544) (xy 59.843273 -279.986636) (xy 59.80277 -280.014592)
			(xy 59.758308 -280.03569) (xy 59.711037 -280.049382) (xy 59.662182 -280.055314) (xy 59.613007 -280.053333)
			(xy 59.564788 -280.043489) (xy 59.518772 -280.026037) (xy 59.476151 -280.00143) (xy 59.43803 -279.970305)
			(xy 59.405395 -279.933468) (xy 59.379092 -279.891872) (xy 59.359801 -279.846596) (xy 59.348024 -279.798812)
			(xy 59.344064 -279.749758) (xy 59.005211 -279.749758) (xy 59.004721 -279.774111) (xy 58.996826 -279.822688)
			(xy 58.981242 -279.869369) (xy 58.958371 -279.912946) (xy 58.928806 -279.95229) (xy 58.893313 -279.986382)
			(xy 58.85281 -280.014338) (xy 58.808348 -280.035436) (xy 58.761077 -280.049128) (xy 58.712222 -280.05506)
			(xy 58.663047 -280.053079) (xy 58.614828 -280.043235) (xy 58.568812 -280.025783) (xy 58.526191 -280.001176)
			(xy 58.48807 -279.970051) (xy 58.455435 -279.933214) (xy 58.429132 -279.891618) (xy 58.409841 -279.846342)
			(xy 58.398064 -279.798558) (xy 58.394104 -279.749504) (xy 58.055251 -279.749504) (xy 58.055256 -279.749758)
			(xy 58.054761 -279.774365) (xy 58.046866 -279.822942) (xy 58.031282 -279.869623) (xy 58.008411 -279.9132)
			(xy 57.978846 -279.952544) (xy 57.943353 -279.986636) (xy 57.90285 -280.014592) (xy 57.858388 -280.03569)
			(xy 57.811117 -280.049382) (xy 57.762262 -280.055314) (xy 57.713087 -280.053333) (xy 57.664868 -280.043489)
			(xy 57.618852 -280.026037) (xy 57.576231 -280.00143) (xy 57.53811 -279.970305) (xy 57.505475 -279.933468)
			(xy 57.479172 -279.891872) (xy 57.459881 -279.846596) (xy 57.448104 -279.798812) (xy 57.444144 -279.749758)
			(xy 57.105037 -279.749758) (xy 57.104547 -279.774111) (xy 57.096652 -279.822688) (xy 57.081068 -279.869369)
			(xy 57.058197 -279.912946) (xy 57.028632 -279.95229) (xy 56.993139 -279.986382) (xy 56.952636 -280.014338)
			(xy 56.908174 -280.035436) (xy 56.860903 -280.049128) (xy 56.812048 -280.05506) (xy 56.762873 -280.053079)
			(xy 56.714654 -280.043235) (xy 56.668638 -280.025783) (xy 56.626017 -280.001176) (xy 56.587896 -279.970051)
			(xy 56.555261 -279.933214) (xy 56.528958 -279.891618) (xy 56.509667 -279.846342) (xy 56.49789 -279.798558)
			(xy 56.49393 -279.749504) (xy 56.155077 -279.749504) (xy 56.155082 -279.749758) (xy 56.154587 -279.774365)
			(xy 56.146692 -279.822942) (xy 56.131108 -279.869623) (xy 56.108237 -279.9132) (xy 56.078672 -279.952544)
			(xy 56.043179 -279.986636) (xy 56.002676 -280.014592) (xy 55.958214 -280.03569) (xy 55.910943 -280.049382)
			(xy 55.862088 -280.055314) (xy 55.812913 -280.053333) (xy 55.764694 -280.043489) (xy 55.718678 -280.026037)
			(xy 55.676057 -280.00143) (xy 55.637936 -279.970305) (xy 55.605301 -279.933468) (xy 55.578998 -279.891872)
			(xy 55.559707 -279.846596) (xy 55.54793 -279.798812) (xy 55.54397 -279.749758) (xy 55.205117 -279.749758)
			(xy 55.204627 -279.774111) (xy 55.196732 -279.822688) (xy 55.181148 -279.869369) (xy 55.158277 -279.912946)
			(xy 55.128712 -279.95229) (xy 55.093219 -279.986382) (xy 55.052716 -280.014338) (xy 55.008254 -280.035436)
			(xy 54.960983 -280.049128) (xy 54.912128 -280.05506) (xy 54.862953 -280.053079) (xy 54.814734 -280.043235)
			(xy 54.768718 -280.025783) (xy 54.726097 -280.001176) (xy 54.687976 -279.970051) (xy 54.655341 -279.933214)
			(xy 54.629038 -279.891618) (xy 54.609747 -279.846342) (xy 54.59797 -279.798558) (xy 54.59401 -279.749504)
			(xy 54.255157 -279.749504) (xy 54.255162 -279.749758) (xy 54.254667 -279.774365) (xy 54.246772 -279.822942)
			(xy 54.231188 -279.869623) (xy 54.208317 -279.9132) (xy 54.178752 -279.952544) (xy 54.143259 -279.986636)
			(xy 54.102756 -280.014592) (xy 54.058294 -280.03569) (xy 54.011023 -280.049382) (xy 53.962168 -280.055314)
			(xy 53.912993 -280.053333) (xy 53.864774 -280.043489) (xy 53.818758 -280.026037) (xy 53.776137 -280.00143)
			(xy 53.738016 -279.970305) (xy 53.705381 -279.933468) (xy 53.679078 -279.891872) (xy 53.659787 -279.846596)
			(xy 53.64801 -279.798812) (xy 53.64405 -279.749758) (xy 53.305197 -279.749758) (xy 53.304707 -279.774111)
			(xy 53.296812 -279.822688) (xy 53.281228 -279.869369) (xy 53.258357 -279.912946) (xy 53.228792 -279.95229)
			(xy 53.193299 -279.986382) (xy 53.152796 -280.014338) (xy 53.108334 -280.035436) (xy 53.061063 -280.049128)
			(xy 53.012208 -280.05506) (xy 52.963033 -280.053079) (xy 52.914814 -280.043235) (xy 52.868798 -280.025783)
			(xy 52.826177 -280.001176) (xy 52.788056 -279.970051) (xy 52.755421 -279.933214) (xy 52.729118 -279.891618)
			(xy 52.709827 -279.846342) (xy 52.69805 -279.798558) (xy 52.69409 -279.749504) (xy 52.355237 -279.749504)
			(xy 52.355242 -279.749758) (xy 52.354747 -279.774365) (xy 52.346852 -279.822942) (xy 52.331268 -279.869623)
			(xy 52.308397 -279.9132) (xy 52.278832 -279.952544) (xy 52.243339 -279.986636) (xy 52.202836 -280.014592)
			(xy 52.158374 -280.03569) (xy 52.111103 -280.049382) (xy 52.062248 -280.055314) (xy 52.013073 -280.053333)
			(xy 51.964854 -280.043489) (xy 51.918838 -280.026037) (xy 51.876217 -280.00143) (xy 51.838096 -279.970305)
			(xy 51.805461 -279.933468) (xy 51.779158 -279.891872) (xy 51.759867 -279.846596) (xy 51.74809 -279.798812)
			(xy 51.74413 -279.749758) (xy 51.405277 -279.749758) (xy 51.404787 -279.774111) (xy 51.396892 -279.822688)
			(xy 51.381308 -279.869369) (xy 51.358437 -279.912946) (xy 51.328872 -279.95229) (xy 51.293379 -279.986382)
			(xy 51.252876 -280.014338) (xy 51.208414 -280.035436) (xy 51.161143 -280.049128) (xy 51.112288 -280.05506)
			(xy 51.063113 -280.053079) (xy 51.014894 -280.043235) (xy 50.968878 -280.025783) (xy 50.926257 -280.001176)
			(xy 50.888136 -279.970051) (xy 50.855501 -279.933214) (xy 50.829198 -279.891618) (xy 50.809907 -279.846342)
			(xy 50.79813 -279.798558) (xy 50.79417 -279.749504) (xy 50.455063 -279.749504) (xy 50.455068 -279.749758)
			(xy 50.454573 -279.774365) (xy 50.446678 -279.822942) (xy 50.431094 -279.869623) (xy 50.408223 -279.9132)
			(xy 50.378658 -279.952544) (xy 50.343165 -279.986636) (xy 50.302662 -280.014592) (xy 50.2582 -280.03569)
			(xy 50.210929 -280.049382) (xy 50.162074 -280.055314) (xy 50.112899 -280.053333) (xy 50.06468 -280.043489)
			(xy 50.018664 -280.026037) (xy 49.976043 -280.00143) (xy 49.937922 -279.970305) (xy 49.905287 -279.933468)
			(xy 49.878984 -279.891872) (xy 49.859693 -279.846596) (xy 49.847916 -279.798812) (xy 49.843956 -279.749758)
			(xy 49.505103 -279.749758) (xy 49.504613 -279.774111) (xy 49.496718 -279.822688) (xy 49.481134 -279.869369)
			(xy 49.458263 -279.912946) (xy 49.428698 -279.95229) (xy 49.393205 -279.986382) (xy 49.352702 -280.014338)
			(xy 49.30824 -280.035436) (xy 49.260969 -280.049128) (xy 49.212114 -280.05506) (xy 49.162939 -280.053079)
			(xy 49.11472 -280.043235) (xy 49.068704 -280.025783) (xy 49.026083 -280.001176) (xy 48.987962 -279.970051)
			(xy 48.955327 -279.933214) (xy 48.929024 -279.891618) (xy 48.909733 -279.846342) (xy 48.897956 -279.798558)
			(xy 48.893996 -279.749504) (xy 48.555143 -279.749504) (xy 48.555148 -279.749758) (xy 48.554653 -279.774365)
			(xy 48.546758 -279.822942) (xy 48.531174 -279.869623) (xy 48.508303 -279.9132) (xy 48.478738 -279.952544)
			(xy 48.443245 -279.986636) (xy 48.402742 -280.014592) (xy 48.35828 -280.03569) (xy 48.311009 -280.049382)
			(xy 48.262154 -280.055314) (xy 48.212979 -280.053333) (xy 48.16476 -280.043489) (xy 48.118744 -280.026037)
			(xy 48.076123 -280.00143) (xy 48.038002 -279.970305) (xy 48.005367 -279.933468) (xy 47.979064 -279.891872)
			(xy 47.959773 -279.846596) (xy 47.947996 -279.798812) (xy 47.944036 -279.749758) (xy 47.605183 -279.749758)
			(xy 47.604693 -279.774111) (xy 47.596798 -279.822688) (xy 47.581214 -279.869369) (xy 47.558343 -279.912946)
			(xy 47.528778 -279.95229) (xy 47.493285 -279.986382) (xy 47.452782 -280.014338) (xy 47.40832 -280.035436)
			(xy 47.361049 -280.049128) (xy 47.312194 -280.05506) (xy 47.263019 -280.053079) (xy 47.2148 -280.043235)
			(xy 47.168784 -280.025783) (xy 47.126163 -280.001176) (xy 47.088042 -279.970051) (xy 47.055407 -279.933214)
			(xy 47.029104 -279.891618) (xy 47.009813 -279.846342) (xy 46.998036 -279.798558) (xy 46.994076 -279.749504)
			(xy 46.655223 -279.749504) (xy 46.655228 -279.749758) (xy 46.654733 -279.774365) (xy 46.646838 -279.822942)
			(xy 46.631254 -279.869623) (xy 46.608383 -279.9132) (xy 46.578818 -279.952544) (xy 46.543325 -279.986636)
			(xy 46.502822 -280.014592) (xy 46.45836 -280.03569) (xy 46.411089 -280.049382) (xy 46.362234 -280.055314)
			(xy 46.313059 -280.053333) (xy 46.26484 -280.043489) (xy 46.218824 -280.026037) (xy 46.176203 -280.00143)
			(xy 46.138082 -279.970305) (xy 46.105447 -279.933468) (xy 46.079144 -279.891872) (xy 46.059853 -279.846596)
			(xy 46.048076 -279.798812) (xy 46.044116 -279.749758) (xy 45.705263 -279.749758) (xy 45.704773 -279.774111)
			(xy 45.696878 -279.822688) (xy 45.681294 -279.869369) (xy 45.658423 -279.912946) (xy 45.628858 -279.95229)
			(xy 45.593365 -279.986382) (xy 45.552862 -280.014338) (xy 45.5084 -280.035436) (xy 45.461129 -280.049128)
			(xy 45.412274 -280.05506) (xy 45.363099 -280.053079) (xy 45.31488 -280.043235) (xy 45.268864 -280.025783)
			(xy 45.226243 -280.001176) (xy 45.188122 -279.970051) (xy 45.155487 -279.933214) (xy 45.129184 -279.891618)
			(xy 45.109893 -279.846342) (xy 45.098116 -279.798558) (xy 45.094156 -279.749504) (xy 44.755049 -279.749504)
			(xy 44.755054 -279.749758) (xy 44.754559 -279.774365) (xy 44.746664 -279.822942) (xy 44.73108 -279.869623)
			(xy 44.708209 -279.9132) (xy 44.678644 -279.952544) (xy 44.643151 -279.986636) (xy 44.602648 -280.014592)
			(xy 44.558186 -280.03569) (xy 44.510915 -280.049382) (xy 44.46206 -280.055314) (xy 44.412885 -280.053333)
			(xy 44.364666 -280.043489) (xy 44.31865 -280.026037) (xy 44.276029 -280.00143) (xy 44.237908 -279.970305)
			(xy 44.205273 -279.933468) (xy 44.17897 -279.891872) (xy 44.159679 -279.846596) (xy 44.147902 -279.798812)
			(xy 44.143942 -279.749758) (xy 34.39033 -279.749758) (xy 34.39033 -280.224738) (xy 36.069028 -280.224738)
			(xy 36.072988 -280.175684) (xy 36.084765 -280.1279) (xy 36.104056 -280.082624) (xy 36.130359 -280.041028)
			(xy 36.162994 -280.004191) (xy 36.201115 -279.973066) (xy 36.243736 -279.948459) (xy 36.289752 -279.931007)
			(xy 36.337971 -279.921163) (xy 36.387146 -279.919182) (xy 36.436001 -279.925114) (xy 36.483272 -279.938806)
			(xy 36.527734 -279.959904) (xy 36.568237 -279.98786) (xy 36.60373 -280.021952) (xy 36.633295 -280.061296)
			(xy 36.656166 -280.104873) (xy 36.67175 -280.151554) (xy 36.679645 -280.200131) (xy 36.68014 -280.224738)
			(xy 37.018988 -280.224738) (xy 37.022948 -280.175684) (xy 37.034725 -280.1279) (xy 37.054016 -280.082624)
			(xy 37.080319 -280.041028) (xy 37.112954 -280.004191) (xy 37.151075 -279.973066) (xy 37.193696 -279.948459)
			(xy 37.239712 -279.931007) (xy 37.287931 -279.921163) (xy 37.337106 -279.919182) (xy 37.385961 -279.925114)
			(xy 37.433232 -279.938806) (xy 37.477694 -279.959904) (xy 37.518197 -279.98786) (xy 37.55369 -280.021952)
			(xy 37.583255 -280.061296) (xy 37.606126 -280.104873) (xy 37.62171 -280.151554) (xy 37.629605 -280.200131)
			(xy 37.6301 -280.224738) (xy 37.969202 -280.224738) (xy 37.973162 -280.175684) (xy 37.984939 -280.1279)
			(xy 38.00423 -280.082624) (xy 38.030533 -280.041028) (xy 38.063168 -280.004191) (xy 38.101289 -279.973066)
			(xy 38.14391 -279.948459) (xy 38.189926 -279.931007) (xy 38.238145 -279.921163) (xy 38.28732 -279.919182)
			(xy 38.336175 -279.925114) (xy 38.383446 -279.938806) (xy 38.427908 -279.959904) (xy 38.468411 -279.98786)
			(xy 38.503904 -280.021952) (xy 38.533469 -280.061296) (xy 38.55634 -280.104873) (xy 38.571924 -280.151554)
			(xy 38.579819 -280.200131) (xy 38.580314 -280.224738) (xy 38.919162 -280.224738) (xy 38.923122 -280.175684)
			(xy 38.934899 -280.1279) (xy 38.95419 -280.082624) (xy 38.980493 -280.041028) (xy 39.013128 -280.004191)
			(xy 39.051249 -279.973066) (xy 39.09387 -279.948459) (xy 39.139886 -279.931007) (xy 39.188105 -279.921163)
			(xy 39.23728 -279.919182) (xy 39.286135 -279.925114) (xy 39.333406 -279.938806) (xy 39.377868 -279.959904)
			(xy 39.418371 -279.98786) (xy 39.453864 -280.021952) (xy 39.483429 -280.061296) (xy 39.5063 -280.104873)
			(xy 39.521884 -280.151554) (xy 39.529779 -280.200131) (xy 39.530274 -280.224738) (xy 39.869122 -280.224738)
			(xy 39.873082 -280.175684) (xy 39.884859 -280.1279) (xy 39.90415 -280.082624) (xy 39.930453 -280.041028)
			(xy 39.963088 -280.004191) (xy 40.001209 -279.973066) (xy 40.04383 -279.948459) (xy 40.089846 -279.931007)
			(xy 40.138065 -279.921163) (xy 40.18724 -279.919182) (xy 40.236095 -279.925114) (xy 40.283366 -279.938806)
			(xy 40.327828 -279.959904) (xy 40.368331 -279.98786) (xy 40.403824 -280.021952) (xy 40.433389 -280.061296)
			(xy 40.45626 -280.104873) (xy 40.471844 -280.151554) (xy 40.479739 -280.200131) (xy 40.480234 -280.224738)
			(xy 40.819082 -280.224738) (xy 40.823042 -280.175684) (xy 40.834819 -280.1279) (xy 40.85411 -280.082624)
			(xy 40.880413 -280.041028) (xy 40.913048 -280.004191) (xy 40.951169 -279.973066) (xy 40.99379 -279.948459)
			(xy 41.039806 -279.931007) (xy 41.088025 -279.921163) (xy 41.1372 -279.919182) (xy 41.186055 -279.925114)
			(xy 41.233326 -279.938806) (xy 41.277788 -279.959904) (xy 41.318291 -279.98786) (xy 41.353784 -280.021952)
			(xy 41.383349 -280.061296) (xy 41.40622 -280.104873) (xy 41.421804 -280.151554) (xy 41.429699 -280.200131)
			(xy 41.430194 -280.224738) (xy 41.769042 -280.224738) (xy 41.773002 -280.175684) (xy 41.784779 -280.1279)
			(xy 41.80407 -280.082624) (xy 41.830373 -280.041028) (xy 41.863008 -280.004191) (xy 41.901129 -279.973066)
			(xy 41.94375 -279.948459) (xy 41.989766 -279.931007) (xy 42.037985 -279.921163) (xy 42.08716 -279.919182)
			(xy 42.136015 -279.925114) (xy 42.183286 -279.938806) (xy 42.227748 -279.959904) (xy 42.268251 -279.98786)
			(xy 42.303744 -280.021952) (xy 42.333309 -280.061296) (xy 42.35618 -280.104873) (xy 42.371764 -280.151554)
			(xy 42.379659 -280.200131) (xy 42.380154 -280.224738) (xy 42.719002 -280.224738) (xy 42.722962 -280.175684)
			(xy 42.734739 -280.1279) (xy 42.75403 -280.082624) (xy 42.780333 -280.041028) (xy 42.812968 -280.004191)
			(xy 42.851089 -279.973066) (xy 42.89371 -279.948459) (xy 42.939726 -279.931007) (xy 42.987945 -279.921163)
			(xy 43.03712 -279.919182) (xy 43.085975 -279.925114) (xy 43.133246 -279.938806) (xy 43.177708 -279.959904)
			(xy 43.218211 -279.98786) (xy 43.253704 -280.021952) (xy 43.283269 -280.061296) (xy 43.30614 -280.104873)
			(xy 43.321724 -280.151554) (xy 43.329619 -280.200131) (xy 43.330114 -280.224738) (xy 43.329619 -280.249345)
			(xy 43.321724 -280.297922) (xy 43.30614 -280.344603) (xy 43.283269 -280.38818) (xy 43.253704 -280.427524)
			(xy 43.218211 -280.461616) (xy 43.177708 -280.489572) (xy 43.133246 -280.51067) (xy 43.085975 -280.524362)
			(xy 43.03712 -280.530294) (xy 42.987945 -280.528313) (xy 42.939726 -280.518469) (xy 42.89371 -280.501017)
			(xy 42.851089 -280.47641) (xy 42.812968 -280.445285) (xy 42.780333 -280.408448) (xy 42.75403 -280.366852)
			(xy 42.734739 -280.321576) (xy 42.722962 -280.273792) (xy 42.719002 -280.224738) (xy 42.380154 -280.224738)
			(xy 42.379659 -280.249345) (xy 42.371764 -280.297922) (xy 42.35618 -280.344603) (xy 42.333309 -280.38818)
			(xy 42.303744 -280.427524) (xy 42.268251 -280.461616) (xy 42.227748 -280.489572) (xy 42.183286 -280.51067)
			(xy 42.136015 -280.524362) (xy 42.08716 -280.530294) (xy 42.037985 -280.528313) (xy 41.989766 -280.518469)
			(xy 41.94375 -280.501017) (xy 41.901129 -280.47641) (xy 41.863008 -280.445285) (xy 41.830373 -280.408448)
			(xy 41.80407 -280.366852) (xy 41.784779 -280.321576) (xy 41.773002 -280.273792) (xy 41.769042 -280.224738)
			(xy 41.430194 -280.224738) (xy 41.429699 -280.249345) (xy 41.421804 -280.297922) (xy 41.40622 -280.344603)
			(xy 41.383349 -280.38818) (xy 41.353784 -280.427524) (xy 41.318291 -280.461616) (xy 41.277788 -280.489572)
			(xy 41.233326 -280.51067) (xy 41.186055 -280.524362) (xy 41.1372 -280.530294) (xy 41.088025 -280.528313)
			(xy 41.039806 -280.518469) (xy 40.99379 -280.501017) (xy 40.951169 -280.47641) (xy 40.913048 -280.445285)
			(xy 40.880413 -280.408448) (xy 40.85411 -280.366852) (xy 40.834819 -280.321576) (xy 40.823042 -280.273792)
			(xy 40.819082 -280.224738) (xy 40.480234 -280.224738) (xy 40.479739 -280.249345) (xy 40.471844 -280.297922)
			(xy 40.45626 -280.344603) (xy 40.433389 -280.38818) (xy 40.403824 -280.427524) (xy 40.368331 -280.461616)
			(xy 40.327828 -280.489572) (xy 40.283366 -280.51067) (xy 40.236095 -280.524362) (xy 40.18724 -280.530294)
			(xy 40.138065 -280.528313) (xy 40.089846 -280.518469) (xy 40.04383 -280.501017) (xy 40.001209 -280.47641)
			(xy 39.963088 -280.445285) (xy 39.930453 -280.408448) (xy 39.90415 -280.366852) (xy 39.884859 -280.321576)
			(xy 39.873082 -280.273792) (xy 39.869122 -280.224738) (xy 39.530274 -280.224738) (xy 39.529779 -280.249345)
			(xy 39.521884 -280.297922) (xy 39.5063 -280.344603) (xy 39.483429 -280.38818) (xy 39.453864 -280.427524)
			(xy 39.418371 -280.461616) (xy 39.377868 -280.489572) (xy 39.333406 -280.51067) (xy 39.286135 -280.524362)
			(xy 39.23728 -280.530294) (xy 39.188105 -280.528313) (xy 39.139886 -280.518469) (xy 39.09387 -280.501017)
			(xy 39.051249 -280.47641) (xy 39.013128 -280.445285) (xy 38.980493 -280.408448) (xy 38.95419 -280.366852)
			(xy 38.934899 -280.321576) (xy 38.923122 -280.273792) (xy 38.919162 -280.224738) (xy 38.580314 -280.224738)
			(xy 38.579819 -280.249345) (xy 38.571924 -280.297922) (xy 38.55634 -280.344603) (xy 38.533469 -280.38818)
			(xy 38.503904 -280.427524) (xy 38.468411 -280.461616) (xy 38.427908 -280.489572) (xy 38.383446 -280.51067)
			(xy 38.336175 -280.524362) (xy 38.28732 -280.530294) (xy 38.238145 -280.528313) (xy 38.189926 -280.518469)
			(xy 38.14391 -280.501017) (xy 38.101289 -280.47641) (xy 38.063168 -280.445285) (xy 38.030533 -280.408448)
			(xy 38.00423 -280.366852) (xy 37.984939 -280.321576) (xy 37.973162 -280.273792) (xy 37.969202 -280.224738)
			(xy 37.6301 -280.224738) (xy 37.629605 -280.249345) (xy 37.62171 -280.297922) (xy 37.606126 -280.344603)
			(xy 37.583255 -280.38818) (xy 37.55369 -280.427524) (xy 37.518197 -280.461616) (xy 37.477694 -280.489572)
			(xy 37.433232 -280.51067) (xy 37.385961 -280.524362) (xy 37.337106 -280.530294) (xy 37.287931 -280.528313)
			(xy 37.239712 -280.518469) (xy 37.193696 -280.501017) (xy 37.151075 -280.47641) (xy 37.112954 -280.445285)
			(xy 37.080319 -280.408448) (xy 37.054016 -280.366852) (xy 37.034725 -280.321576) (xy 37.022948 -280.273792)
			(xy 37.018988 -280.224738) (xy 36.68014 -280.224738) (xy 36.679645 -280.249345) (xy 36.67175 -280.297922)
			(xy 36.656166 -280.344603) (xy 36.633295 -280.38818) (xy 36.60373 -280.427524) (xy 36.568237 -280.461616)
			(xy 36.527734 -280.489572) (xy 36.483272 -280.51067) (xy 36.436001 -280.524362) (xy 36.387146 -280.530294)
			(xy 36.337971 -280.528313) (xy 36.289752 -280.518469) (xy 36.243736 -280.501017) (xy 36.201115 -280.47641)
			(xy 36.162994 -280.445285) (xy 36.130359 -280.408448) (xy 36.104056 -280.366852) (xy 36.084765 -280.321576)
			(xy 36.072988 -280.273792) (xy 36.069028 -280.224738) (xy 34.39033 -280.224738) (xy 34.39033 -280.699718)
			(xy 44.143942 -280.699718) (xy 44.147902 -280.650664) (xy 44.159679 -280.60288) (xy 44.17897 -280.557604)
			(xy 44.205273 -280.516008) (xy 44.237908 -280.479171) (xy 44.276029 -280.448046) (xy 44.31865 -280.423439)
			(xy 44.364666 -280.405987) (xy 44.412885 -280.396143) (xy 44.46206 -280.394162) (xy 44.510915 -280.400094)
			(xy 44.558186 -280.413786) (xy 44.602648 -280.434884) (xy 44.643151 -280.46284) (xy 44.678644 -280.496932)
			(xy 44.708209 -280.536276) (xy 44.73108 -280.579853) (xy 44.746664 -280.626534) (xy 44.754559 -280.675111)
			(xy 44.755054 -280.699718) (xy 45.094156 -280.699718) (xy 45.098116 -280.650664) (xy 45.109893 -280.60288)
			(xy 45.129184 -280.557604) (xy 45.155487 -280.516008) (xy 45.188122 -280.479171) (xy 45.226243 -280.448046)
			(xy 45.268864 -280.423439) (xy 45.31488 -280.405987) (xy 45.363099 -280.396143) (xy 45.412274 -280.394162)
			(xy 45.461129 -280.400094) (xy 45.5084 -280.413786) (xy 45.552862 -280.434884) (xy 45.593365 -280.46284)
			(xy 45.628858 -280.496932) (xy 45.658423 -280.536276) (xy 45.681294 -280.579853) (xy 45.696878 -280.626534)
			(xy 45.704773 -280.675111) (xy 45.705268 -280.699718) (xy 46.044116 -280.699718) (xy 46.048076 -280.650664)
			(xy 46.059853 -280.60288) (xy 46.079144 -280.557604) (xy 46.105447 -280.516008) (xy 46.138082 -280.479171)
			(xy 46.176203 -280.448046) (xy 46.218824 -280.423439) (xy 46.26484 -280.405987) (xy 46.313059 -280.396143)
			(xy 46.362234 -280.394162) (xy 46.411089 -280.400094) (xy 46.45836 -280.413786) (xy 46.502822 -280.434884)
			(xy 46.543325 -280.46284) (xy 46.578818 -280.496932) (xy 46.608383 -280.536276) (xy 46.631254 -280.579853)
			(xy 46.646838 -280.626534) (xy 46.654733 -280.675111) (xy 46.655228 -280.699718) (xy 46.994076 -280.699718)
			(xy 46.998036 -280.650664) (xy 47.009813 -280.60288) (xy 47.029104 -280.557604) (xy 47.055407 -280.516008)
			(xy 47.088042 -280.479171) (xy 47.126163 -280.448046) (xy 47.168784 -280.423439) (xy 47.2148 -280.405987)
			(xy 47.263019 -280.396143) (xy 47.312194 -280.394162) (xy 47.361049 -280.400094) (xy 47.40832 -280.413786)
			(xy 47.452782 -280.434884) (xy 47.493285 -280.46284) (xy 47.528778 -280.496932) (xy 47.558343 -280.536276)
			(xy 47.581214 -280.579853) (xy 47.596798 -280.626534) (xy 47.604693 -280.675111) (xy 47.605188 -280.699718)
			(xy 47.944036 -280.699718) (xy 47.947996 -280.650664) (xy 47.959773 -280.60288) (xy 47.979064 -280.557604)
			(xy 48.005367 -280.516008) (xy 48.038002 -280.479171) (xy 48.076123 -280.448046) (xy 48.118744 -280.423439)
			(xy 48.16476 -280.405987) (xy 48.212979 -280.396143) (xy 48.262154 -280.394162) (xy 48.311009 -280.400094)
			(xy 48.35828 -280.413786) (xy 48.402742 -280.434884) (xy 48.443245 -280.46284) (xy 48.478738 -280.496932)
			(xy 48.508303 -280.536276) (xy 48.531174 -280.579853) (xy 48.546758 -280.626534) (xy 48.554653 -280.675111)
			(xy 48.555148 -280.699718) (xy 48.893996 -280.699718) (xy 48.897956 -280.650664) (xy 48.909733 -280.60288)
			(xy 48.929024 -280.557604) (xy 48.955327 -280.516008) (xy 48.987962 -280.479171) (xy 49.026083 -280.448046)
			(xy 49.068704 -280.423439) (xy 49.11472 -280.405987) (xy 49.162939 -280.396143) (xy 49.212114 -280.394162)
			(xy 49.260969 -280.400094) (xy 49.30824 -280.413786) (xy 49.352702 -280.434884) (xy 49.393205 -280.46284)
			(xy 49.428698 -280.496932) (xy 49.458263 -280.536276) (xy 49.481134 -280.579853) (xy 49.496718 -280.626534)
			(xy 49.504613 -280.675111) (xy 49.505108 -280.699718) (xy 49.843956 -280.699718) (xy 49.847916 -280.650664)
			(xy 49.859693 -280.60288) (xy 49.878984 -280.557604) (xy 49.905287 -280.516008) (xy 49.937922 -280.479171)
			(xy 49.976043 -280.448046) (xy 50.018664 -280.423439) (xy 50.06468 -280.405987) (xy 50.112899 -280.396143)
			(xy 50.162074 -280.394162) (xy 50.210929 -280.400094) (xy 50.2582 -280.413786) (xy 50.302662 -280.434884)
			(xy 50.343165 -280.46284) (xy 50.378658 -280.496932) (xy 50.408223 -280.536276) (xy 50.431094 -280.579853)
			(xy 50.446678 -280.626534) (xy 50.454573 -280.675111) (xy 50.455068 -280.699718) (xy 50.79417 -280.699718)
			(xy 50.79813 -280.650664) (xy 50.809907 -280.60288) (xy 50.829198 -280.557604) (xy 50.855501 -280.516008)
			(xy 50.888136 -280.479171) (xy 50.926257 -280.448046) (xy 50.968878 -280.423439) (xy 51.014894 -280.405987)
			(xy 51.063113 -280.396143) (xy 51.112288 -280.394162) (xy 51.161143 -280.400094) (xy 51.208414 -280.413786)
			(xy 51.252876 -280.434884) (xy 51.293379 -280.46284) (xy 51.328872 -280.496932) (xy 51.358437 -280.536276)
			(xy 51.381308 -280.579853) (xy 51.396892 -280.626534) (xy 51.404787 -280.675111) (xy 51.405282 -280.699718)
			(xy 51.74413 -280.699718) (xy 51.74809 -280.650664) (xy 51.759867 -280.60288) (xy 51.779158 -280.557604)
			(xy 51.805461 -280.516008) (xy 51.838096 -280.479171) (xy 51.876217 -280.448046) (xy 51.918838 -280.423439)
			(xy 51.964854 -280.405987) (xy 52.013073 -280.396143) (xy 52.062248 -280.394162) (xy 52.111103 -280.400094)
			(xy 52.158374 -280.413786) (xy 52.202836 -280.434884) (xy 52.243339 -280.46284) (xy 52.278832 -280.496932)
			(xy 52.308397 -280.536276) (xy 52.331268 -280.579853) (xy 52.346852 -280.626534) (xy 52.354747 -280.675111)
			(xy 52.355242 -280.699718) (xy 52.69409 -280.699718) (xy 52.69805 -280.650664) (xy 52.709827 -280.60288)
			(xy 52.729118 -280.557604) (xy 52.755421 -280.516008) (xy 52.788056 -280.479171) (xy 52.826177 -280.448046)
			(xy 52.868798 -280.423439) (xy 52.914814 -280.405987) (xy 52.963033 -280.396143) (xy 53.012208 -280.394162)
			(xy 53.061063 -280.400094) (xy 53.108334 -280.413786) (xy 53.152796 -280.434884) (xy 53.193299 -280.46284)
			(xy 53.228792 -280.496932) (xy 53.258357 -280.536276) (xy 53.281228 -280.579853) (xy 53.296812 -280.626534)
			(xy 53.304707 -280.675111) (xy 53.305202 -280.699718) (xy 53.64405 -280.699718) (xy 53.64801 -280.650664)
			(xy 53.659787 -280.60288) (xy 53.679078 -280.557604) (xy 53.705381 -280.516008) (xy 53.738016 -280.479171)
			(xy 53.776137 -280.448046) (xy 53.818758 -280.423439) (xy 53.864774 -280.405987) (xy 53.912993 -280.396143)
			(xy 53.962168 -280.394162) (xy 54.011023 -280.400094) (xy 54.058294 -280.413786) (xy 54.102756 -280.434884)
			(xy 54.143259 -280.46284) (xy 54.178752 -280.496932) (xy 54.208317 -280.536276) (xy 54.231188 -280.579853)
			(xy 54.246772 -280.626534) (xy 54.254667 -280.675111) (xy 54.255162 -280.699718) (xy 54.59401 -280.699718)
			(xy 54.59797 -280.650664) (xy 54.609747 -280.60288) (xy 54.629038 -280.557604) (xy 54.655341 -280.516008)
			(xy 54.687976 -280.479171) (xy 54.726097 -280.448046) (xy 54.768718 -280.423439) (xy 54.814734 -280.405987)
			(xy 54.862953 -280.396143) (xy 54.912128 -280.394162) (xy 54.960983 -280.400094) (xy 55.008254 -280.413786)
			(xy 55.052716 -280.434884) (xy 55.093219 -280.46284) (xy 55.128712 -280.496932) (xy 55.158277 -280.536276)
			(xy 55.181148 -280.579853) (xy 55.196732 -280.626534) (xy 55.204627 -280.675111) (xy 55.205122 -280.699718)
			(xy 55.54397 -280.699718) (xy 55.54793 -280.650664) (xy 55.559707 -280.60288) (xy 55.578998 -280.557604)
			(xy 55.605301 -280.516008) (xy 55.637936 -280.479171) (xy 55.676057 -280.448046) (xy 55.718678 -280.423439)
			(xy 55.764694 -280.405987) (xy 55.812913 -280.396143) (xy 55.862088 -280.394162) (xy 55.910943 -280.400094)
			(xy 55.958214 -280.413786) (xy 56.002676 -280.434884) (xy 56.043179 -280.46284) (xy 56.078672 -280.496932)
			(xy 56.108237 -280.536276) (xy 56.131108 -280.579853) (xy 56.146692 -280.626534) (xy 56.154587 -280.675111)
			(xy 56.155082 -280.699718) (xy 56.49393 -280.699718) (xy 56.49789 -280.650664) (xy 56.509667 -280.60288)
			(xy 56.528958 -280.557604) (xy 56.555261 -280.516008) (xy 56.587896 -280.479171) (xy 56.626017 -280.448046)
			(xy 56.668638 -280.423439) (xy 56.714654 -280.405987) (xy 56.762873 -280.396143) (xy 56.812048 -280.394162)
			(xy 56.860903 -280.400094) (xy 56.908174 -280.413786) (xy 56.952636 -280.434884) (xy 56.993139 -280.46284)
			(xy 57.028632 -280.496932) (xy 57.058197 -280.536276) (xy 57.081068 -280.579853) (xy 57.096652 -280.626534)
			(xy 57.104547 -280.675111) (xy 57.105042 -280.699718) (xy 57.444144 -280.699718) (xy 57.448104 -280.650664)
			(xy 57.459881 -280.60288) (xy 57.479172 -280.557604) (xy 57.505475 -280.516008) (xy 57.53811 -280.479171)
			(xy 57.576231 -280.448046) (xy 57.618852 -280.423439) (xy 57.664868 -280.405987) (xy 57.713087 -280.396143)
			(xy 57.762262 -280.394162) (xy 57.811117 -280.400094) (xy 57.858388 -280.413786) (xy 57.90285 -280.434884)
			(xy 57.943353 -280.46284) (xy 57.978846 -280.496932) (xy 58.008411 -280.536276) (xy 58.031282 -280.579853)
			(xy 58.046866 -280.626534) (xy 58.054761 -280.675111) (xy 58.055256 -280.699718) (xy 58.394104 -280.699718)
			(xy 58.398064 -280.650664) (xy 58.409841 -280.60288) (xy 58.429132 -280.557604) (xy 58.455435 -280.516008)
			(xy 58.48807 -280.479171) (xy 58.526191 -280.448046) (xy 58.568812 -280.423439) (xy 58.614828 -280.405987)
			(xy 58.663047 -280.396143) (xy 58.712222 -280.394162) (xy 58.761077 -280.400094) (xy 58.808348 -280.413786)
			(xy 58.85281 -280.434884) (xy 58.893313 -280.46284) (xy 58.928806 -280.496932) (xy 58.958371 -280.536276)
			(xy 58.981242 -280.579853) (xy 58.996826 -280.626534) (xy 59.004721 -280.675111) (xy 59.005216 -280.699718)
			(xy 59.344064 -280.699718) (xy 59.348024 -280.650664) (xy 59.359801 -280.60288) (xy 59.379092 -280.557604)
			(xy 59.405395 -280.516008) (xy 59.43803 -280.479171) (xy 59.476151 -280.448046) (xy 59.518772 -280.423439)
			(xy 59.564788 -280.405987) (xy 59.613007 -280.396143) (xy 59.662182 -280.394162) (xy 59.711037 -280.400094)
			(xy 59.758308 -280.413786) (xy 59.80277 -280.434884) (xy 59.843273 -280.46284) (xy 59.878766 -280.496932)
			(xy 59.908331 -280.536276) (xy 59.931202 -280.579853) (xy 59.946786 -280.626534) (xy 59.954681 -280.675111)
			(xy 59.955176 -280.699718) (xy 60.294024 -280.699718) (xy 60.297984 -280.650664) (xy 60.309761 -280.60288)
			(xy 60.329052 -280.557604) (xy 60.355355 -280.516008) (xy 60.38799 -280.479171) (xy 60.426111 -280.448046)
			(xy 60.468732 -280.423439) (xy 60.514748 -280.405987) (xy 60.562967 -280.396143) (xy 60.612142 -280.394162)
			(xy 60.660997 -280.400094) (xy 60.708268 -280.413786) (xy 60.75273 -280.434884) (xy 60.793233 -280.46284)
			(xy 60.828726 -280.496932) (xy 60.858291 -280.536276) (xy 60.881162 -280.579853) (xy 60.896746 -280.626534)
			(xy 60.904641 -280.675111) (xy 60.905136 -280.699718) (xy 61.243984 -280.699718) (xy 61.247944 -280.650664)
			(xy 61.259721 -280.60288) (xy 61.279012 -280.557604) (xy 61.305315 -280.516008) (xy 61.33795 -280.479171)
			(xy 61.376071 -280.448046) (xy 61.418692 -280.423439) (xy 61.464708 -280.405987) (xy 61.512927 -280.396143)
			(xy 61.562102 -280.394162) (xy 61.610957 -280.400094) (xy 61.658228 -280.413786) (xy 61.70269 -280.434884)
			(xy 61.743193 -280.46284) (xy 61.778686 -280.496932) (xy 61.808251 -280.536276) (xy 61.831122 -280.579853)
			(xy 61.846706 -280.626534) (xy 61.854601 -280.675111) (xy 61.855096 -280.699718) (xy 62.193944 -280.699718)
			(xy 62.197904 -280.650664) (xy 62.209681 -280.60288) (xy 62.228972 -280.557604) (xy 62.255275 -280.516008)
			(xy 62.28791 -280.479171) (xy 62.326031 -280.448046) (xy 62.368652 -280.423439) (xy 62.414668 -280.405987)
			(xy 62.462887 -280.396143) (xy 62.512062 -280.394162) (xy 62.560917 -280.400094) (xy 62.608188 -280.413786)
			(xy 62.65265 -280.434884) (xy 62.693153 -280.46284) (xy 62.728646 -280.496932) (xy 62.758211 -280.536276)
			(xy 62.781082 -280.579853) (xy 62.796666 -280.626534) (xy 62.804561 -280.675111) (xy 62.805056 -280.699718)
			(xy 63.144158 -280.699718) (xy 63.148118 -280.650664) (xy 63.159895 -280.60288) (xy 63.179186 -280.557604)
			(xy 63.205489 -280.516008) (xy 63.238124 -280.479171) (xy 63.276245 -280.448046) (xy 63.318866 -280.423439)
			(xy 63.364882 -280.405987) (xy 63.413101 -280.396143) (xy 63.462276 -280.394162) (xy 63.511131 -280.400094)
			(xy 63.558402 -280.413786) (xy 63.602864 -280.434884) (xy 63.643367 -280.46284) (xy 63.67886 -280.496932)
			(xy 63.708425 -280.536276) (xy 63.731296 -280.579853) (xy 63.74688 -280.626534) (xy 63.754775 -280.675111)
			(xy 63.75527 -280.699718) (xy 64.094118 -280.699718) (xy 64.098078 -280.650664) (xy 64.109855 -280.60288)
			(xy 64.129146 -280.557604) (xy 64.155449 -280.516008) (xy 64.188084 -280.479171) (xy 64.226205 -280.448046)
			(xy 64.268826 -280.423439) (xy 64.314842 -280.405987) (xy 64.363061 -280.396143) (xy 64.412236 -280.394162)
			(xy 64.461091 -280.400094) (xy 64.508362 -280.413786) (xy 64.552824 -280.434884) (xy 64.593327 -280.46284)
			(xy 64.62882 -280.496932) (xy 64.658385 -280.536276) (xy 64.681256 -280.579853) (xy 64.69684 -280.626534)
			(xy 64.704735 -280.675111) (xy 64.70523 -280.699718) (xy 65.044078 -280.699718) (xy 65.048038 -280.650664)
			(xy 65.059815 -280.60288) (xy 65.079106 -280.557604) (xy 65.105409 -280.516008) (xy 65.138044 -280.479171)
			(xy 65.176165 -280.448046) (xy 65.218786 -280.423439) (xy 65.264802 -280.405987) (xy 65.313021 -280.396143)
			(xy 65.362196 -280.394162) (xy 65.411051 -280.400094) (xy 65.458322 -280.413786) (xy 65.502784 -280.434884)
			(xy 65.543287 -280.46284) (xy 65.57878 -280.496932) (xy 65.608345 -280.536276) (xy 65.631216 -280.579853)
			(xy 65.6468 -280.626534) (xy 65.654695 -280.675111) (xy 65.65519 -280.699718) (xy 65.994038 -280.699718)
			(xy 65.997998 -280.650664) (xy 66.009775 -280.60288) (xy 66.029066 -280.557604) (xy 66.055369 -280.516008)
			(xy 66.088004 -280.479171) (xy 66.126125 -280.448046) (xy 66.168746 -280.423439) (xy 66.214762 -280.405987)
			(xy 66.262981 -280.396143) (xy 66.312156 -280.394162) (xy 66.361011 -280.400094) (xy 66.408282 -280.413786)
			(xy 66.452744 -280.434884) (xy 66.493247 -280.46284) (xy 66.52874 -280.496932) (xy 66.558305 -280.536276)
			(xy 66.581176 -280.579853) (xy 66.59676 -280.626534) (xy 66.604655 -280.675111) (xy 66.60515 -280.699718)
			(xy 66.943998 -280.699718) (xy 66.947958 -280.650664) (xy 66.959735 -280.60288) (xy 66.979026 -280.557604)
			(xy 67.005329 -280.516008) (xy 67.037964 -280.479171) (xy 67.076085 -280.448046) (xy 67.118706 -280.423439)
			(xy 67.164722 -280.405987) (xy 67.212941 -280.396143) (xy 67.262116 -280.394162) (xy 67.310971 -280.400094)
			(xy 67.358242 -280.413786) (xy 67.402704 -280.434884) (xy 67.443207 -280.46284) (xy 67.4787 -280.496932)
			(xy 67.508265 -280.536276) (xy 67.531136 -280.579853) (xy 67.54672 -280.626534) (xy 67.554615 -280.675111)
			(xy 67.55511 -280.699718) (xy 67.893958 -280.699718) (xy 67.897918 -280.650664) (xy 67.909695 -280.60288)
			(xy 67.928986 -280.557604) (xy 67.955289 -280.516008) (xy 67.987924 -280.479171) (xy 68.026045 -280.448046)
			(xy 68.068666 -280.423439) (xy 68.114682 -280.405987) (xy 68.162901 -280.396143) (xy 68.212076 -280.394162)
			(xy 68.260931 -280.400094) (xy 68.308202 -280.413786) (xy 68.352664 -280.434884) (xy 68.393167 -280.46284)
			(xy 68.42866 -280.496932) (xy 68.458225 -280.536276) (xy 68.481096 -280.579853) (xy 68.49668 -280.626534)
			(xy 68.504575 -280.675111) (xy 68.50507 -280.699718) (xy 68.844172 -280.699718) (xy 68.848132 -280.650664)
			(xy 68.859909 -280.60288) (xy 68.8792 -280.557604) (xy 68.905503 -280.516008) (xy 68.938138 -280.479171)
			(xy 68.976259 -280.448046) (xy 69.01888 -280.423439) (xy 69.064896 -280.405987) (xy 69.113115 -280.396143)
			(xy 69.16229 -280.394162) (xy 69.211145 -280.400094) (xy 69.258416 -280.413786) (xy 69.302878 -280.434884)
			(xy 69.343381 -280.46284) (xy 69.378874 -280.496932) (xy 69.408439 -280.536276) (xy 69.43131 -280.579853)
			(xy 69.446894 -280.626534) (xy 69.454789 -280.675111) (xy 69.455284 -280.699718) (xy 69.794132 -280.699718)
			(xy 69.798092 -280.650664) (xy 69.809869 -280.60288) (xy 69.82916 -280.557604) (xy 69.855463 -280.516008)
			(xy 69.888098 -280.479171) (xy 69.926219 -280.448046) (xy 69.96884 -280.423439) (xy 70.014856 -280.405987)
			(xy 70.063075 -280.396143) (xy 70.11225 -280.394162) (xy 70.161105 -280.400094) (xy 70.208376 -280.413786)
			(xy 70.252838 -280.434884) (xy 70.293341 -280.46284) (xy 70.328834 -280.496932) (xy 70.358399 -280.536276)
			(xy 70.38127 -280.579853) (xy 70.396854 -280.626534) (xy 70.404749 -280.675111) (xy 70.405244 -280.699718)
			(xy 70.744092 -280.699718) (xy 70.748052 -280.650664) (xy 70.759829 -280.60288) (xy 70.77912 -280.557604)
			(xy 70.805423 -280.516008) (xy 70.838058 -280.479171) (xy 70.876179 -280.448046) (xy 70.9188 -280.423439)
			(xy 70.964816 -280.405987) (xy 71.013035 -280.396143) (xy 71.06221 -280.394162) (xy 71.111065 -280.400094)
			(xy 71.158336 -280.413786) (xy 71.202798 -280.434884) (xy 71.243301 -280.46284) (xy 71.278794 -280.496932)
			(xy 71.308359 -280.536276) (xy 71.33123 -280.579853) (xy 71.346814 -280.626534) (xy 71.354709 -280.675111)
			(xy 71.355204 -280.699718) (xy 71.694052 -280.699718) (xy 71.698012 -280.650664) (xy 71.709789 -280.60288)
			(xy 71.72908 -280.557604) (xy 71.755383 -280.516008) (xy 71.788018 -280.479171) (xy 71.826139 -280.448046)
			(xy 71.86876 -280.423439) (xy 71.914776 -280.405987) (xy 71.962995 -280.396143) (xy 72.01217 -280.394162)
			(xy 72.061025 -280.400094) (xy 72.108296 -280.413786) (xy 72.152758 -280.434884) (xy 72.193261 -280.46284)
			(xy 72.228754 -280.496932) (xy 72.258319 -280.536276) (xy 72.28119 -280.579853) (xy 72.296774 -280.626534)
			(xy 72.304669 -280.675111) (xy 72.305164 -280.699718) (xy 72.644012 -280.699718) (xy 72.647972 -280.650664)
			(xy 72.659749 -280.60288) (xy 72.67904 -280.557604) (xy 72.705343 -280.516008) (xy 72.737978 -280.479171)
			(xy 72.776099 -280.448046) (xy 72.81872 -280.423439) (xy 72.864736 -280.405987) (xy 72.912955 -280.396143)
			(xy 72.96213 -280.394162) (xy 73.010985 -280.400094) (xy 73.058256 -280.413786) (xy 73.102718 -280.434884)
			(xy 73.143221 -280.46284) (xy 73.178714 -280.496932) (xy 73.208279 -280.536276) (xy 73.23115 -280.579853)
			(xy 73.246734 -280.626534) (xy 73.254629 -280.675111) (xy 73.255124 -280.699718) (xy 73.593972 -280.699718)
			(xy 73.597932 -280.650664) (xy 73.609709 -280.60288) (xy 73.629 -280.557604) (xy 73.655303 -280.516008)
			(xy 73.687938 -280.479171) (xy 73.726059 -280.448046) (xy 73.76868 -280.423439) (xy 73.814696 -280.405987)
			(xy 73.862915 -280.396143) (xy 73.91209 -280.394162) (xy 73.960945 -280.400094) (xy 74.008216 -280.413786)
			(xy 74.052678 -280.434884) (xy 74.093181 -280.46284) (xy 74.128674 -280.496932) (xy 74.158239 -280.536276)
			(xy 74.18111 -280.579853) (xy 74.196694 -280.626534) (xy 74.204589 -280.675111) (xy 74.205084 -280.699718)
			(xy 74.544186 -280.699718) (xy 74.548146 -280.650664) (xy 74.559923 -280.60288) (xy 74.579214 -280.557604)
			(xy 74.605517 -280.516008) (xy 74.638152 -280.479171) (xy 74.676273 -280.448046) (xy 74.718894 -280.423439)
			(xy 74.76491 -280.405987) (xy 74.813129 -280.396143) (xy 74.862304 -280.394162) (xy 74.911159 -280.400094)
			(xy 74.95843 -280.413786) (xy 75.002892 -280.434884) (xy 75.043395 -280.46284) (xy 75.078888 -280.496932)
			(xy 75.108453 -280.536276) (xy 75.131324 -280.579853) (xy 75.146908 -280.626534) (xy 75.154803 -280.675111)
			(xy 75.155298 -280.699718) (xy 75.494146 -280.699718) (xy 75.498106 -280.650664) (xy 75.509883 -280.60288)
			(xy 75.529174 -280.557604) (xy 75.555477 -280.516008) (xy 75.588112 -280.479171) (xy 75.626233 -280.448046)
			(xy 75.668854 -280.423439) (xy 75.71487 -280.405987) (xy 75.763089 -280.396143) (xy 75.812264 -280.394162)
			(xy 75.861119 -280.400094) (xy 75.90839 -280.413786) (xy 75.952852 -280.434884) (xy 75.993355 -280.46284)
			(xy 76.028848 -280.496932) (xy 76.058413 -280.536276) (xy 76.081284 -280.579853) (xy 76.096868 -280.626534)
			(xy 76.104763 -280.675111) (xy 76.105258 -280.699718) (xy 76.444106 -280.699718) (xy 76.448066 -280.650664)
			(xy 76.459843 -280.60288) (xy 76.479134 -280.557604) (xy 76.505437 -280.516008) (xy 76.538072 -280.479171)
			(xy 76.576193 -280.448046) (xy 76.618814 -280.423439) (xy 76.66483 -280.405987) (xy 76.713049 -280.396143)
			(xy 76.762224 -280.394162) (xy 76.811079 -280.400094) (xy 76.85835 -280.413786) (xy 76.902812 -280.434884)
			(xy 76.943315 -280.46284) (xy 76.978808 -280.496932) (xy 77.008373 -280.536276) (xy 77.031244 -280.579853)
			(xy 77.046828 -280.626534) (xy 77.054723 -280.675111) (xy 77.055218 -280.699718) (xy 77.054723 -280.724325)
			(xy 77.046828 -280.772902) (xy 77.031244 -280.819583) (xy 77.008373 -280.86316) (xy 76.978808 -280.902504)
			(xy 76.943315 -280.936596) (xy 76.902812 -280.964552) (xy 76.85835 -280.98565) (xy 76.811079 -280.999342)
			(xy 76.762224 -281.005274) (xy 76.713049 -281.003293) (xy 76.66483 -280.993449) (xy 76.618814 -280.975997)
			(xy 76.576193 -280.95139) (xy 76.538072 -280.920265) (xy 76.505437 -280.883428) (xy 76.479134 -280.841832)
			(xy 76.459843 -280.796556) (xy 76.448066 -280.748772) (xy 76.444106 -280.699718) (xy 76.105258 -280.699718)
			(xy 76.104763 -280.724325) (xy 76.096868 -280.772902) (xy 76.081284 -280.819583) (xy 76.058413 -280.86316)
			(xy 76.028848 -280.902504) (xy 75.993355 -280.936596) (xy 75.952852 -280.964552) (xy 75.90839 -280.98565)
			(xy 75.861119 -280.999342) (xy 75.812264 -281.005274) (xy 75.763089 -281.003293) (xy 75.71487 -280.993449)
			(xy 75.668854 -280.975997) (xy 75.626233 -280.95139) (xy 75.588112 -280.920265) (xy 75.555477 -280.883428)
			(xy 75.529174 -280.841832) (xy 75.509883 -280.796556) (xy 75.498106 -280.748772) (xy 75.494146 -280.699718)
			(xy 75.155298 -280.699718) (xy 75.154803 -280.724325) (xy 75.146908 -280.772902) (xy 75.131324 -280.819583)
			(xy 75.108453 -280.86316) (xy 75.078888 -280.902504) (xy 75.043395 -280.936596) (xy 75.002892 -280.964552)
			(xy 74.95843 -280.98565) (xy 74.911159 -280.999342) (xy 74.862304 -281.005274) (xy 74.813129 -281.003293)
			(xy 74.76491 -280.993449) (xy 74.718894 -280.975997) (xy 74.676273 -280.95139) (xy 74.638152 -280.920265)
			(xy 74.605517 -280.883428) (xy 74.579214 -280.841832) (xy 74.559923 -280.796556) (xy 74.548146 -280.748772)
			(xy 74.544186 -280.699718) (xy 74.205084 -280.699718) (xy 74.204589 -280.724325) (xy 74.196694 -280.772902)
			(xy 74.18111 -280.819583) (xy 74.158239 -280.86316) (xy 74.128674 -280.902504) (xy 74.093181 -280.936596)
			(xy 74.052678 -280.964552) (xy 74.008216 -280.98565) (xy 73.960945 -280.999342) (xy 73.91209 -281.005274)
			(xy 73.862915 -281.003293) (xy 73.814696 -280.993449) (xy 73.76868 -280.975997) (xy 73.726059 -280.95139)
			(xy 73.687938 -280.920265) (xy 73.655303 -280.883428) (xy 73.629 -280.841832) (xy 73.609709 -280.796556)
			(xy 73.597932 -280.748772) (xy 73.593972 -280.699718) (xy 73.255124 -280.699718) (xy 73.254629 -280.724325)
			(xy 73.246734 -280.772902) (xy 73.23115 -280.819583) (xy 73.208279 -280.86316) (xy 73.178714 -280.902504)
			(xy 73.143221 -280.936596) (xy 73.102718 -280.964552) (xy 73.058256 -280.98565) (xy 73.010985 -280.999342)
			(xy 72.96213 -281.005274) (xy 72.912955 -281.003293) (xy 72.864736 -280.993449) (xy 72.81872 -280.975997)
			(xy 72.776099 -280.95139) (xy 72.737978 -280.920265) (xy 72.705343 -280.883428) (xy 72.67904 -280.841832)
			(xy 72.659749 -280.796556) (xy 72.647972 -280.748772) (xy 72.644012 -280.699718) (xy 72.305164 -280.699718)
			(xy 72.304669 -280.724325) (xy 72.296774 -280.772902) (xy 72.28119 -280.819583) (xy 72.258319 -280.86316)
			(xy 72.228754 -280.902504) (xy 72.193261 -280.936596) (xy 72.152758 -280.964552) (xy 72.108296 -280.98565)
			(xy 72.061025 -280.999342) (xy 72.01217 -281.005274) (xy 71.962995 -281.003293) (xy 71.914776 -280.993449)
			(xy 71.86876 -280.975997) (xy 71.826139 -280.95139) (xy 71.788018 -280.920265) (xy 71.755383 -280.883428)
			(xy 71.72908 -280.841832) (xy 71.709789 -280.796556) (xy 71.698012 -280.748772) (xy 71.694052 -280.699718)
			(xy 71.355204 -280.699718) (xy 71.354709 -280.724325) (xy 71.346814 -280.772902) (xy 71.33123 -280.819583)
			(xy 71.308359 -280.86316) (xy 71.278794 -280.902504) (xy 71.243301 -280.936596) (xy 71.202798 -280.964552)
			(xy 71.158336 -280.98565) (xy 71.111065 -280.999342) (xy 71.06221 -281.005274) (xy 71.013035 -281.003293)
			(xy 70.964816 -280.993449) (xy 70.9188 -280.975997) (xy 70.876179 -280.95139) (xy 70.838058 -280.920265)
			(xy 70.805423 -280.883428) (xy 70.77912 -280.841832) (xy 70.759829 -280.796556) (xy 70.748052 -280.748772)
			(xy 70.744092 -280.699718) (xy 70.405244 -280.699718) (xy 70.404749 -280.724325) (xy 70.396854 -280.772902)
			(xy 70.38127 -280.819583) (xy 70.358399 -280.86316) (xy 70.328834 -280.902504) (xy 70.293341 -280.936596)
			(xy 70.252838 -280.964552) (xy 70.208376 -280.98565) (xy 70.161105 -280.999342) (xy 70.11225 -281.005274)
			(xy 70.063075 -281.003293) (xy 70.014856 -280.993449) (xy 69.96884 -280.975997) (xy 69.926219 -280.95139)
			(xy 69.888098 -280.920265) (xy 69.855463 -280.883428) (xy 69.82916 -280.841832) (xy 69.809869 -280.796556)
			(xy 69.798092 -280.748772) (xy 69.794132 -280.699718) (xy 69.455284 -280.699718) (xy 69.454789 -280.724325)
			(xy 69.446894 -280.772902) (xy 69.43131 -280.819583) (xy 69.408439 -280.86316) (xy 69.378874 -280.902504)
			(xy 69.343381 -280.936596) (xy 69.302878 -280.964552) (xy 69.258416 -280.98565) (xy 69.211145 -280.999342)
			(xy 69.16229 -281.005274) (xy 69.113115 -281.003293) (xy 69.064896 -280.993449) (xy 69.01888 -280.975997)
			(xy 68.976259 -280.95139) (xy 68.938138 -280.920265) (xy 68.905503 -280.883428) (xy 68.8792 -280.841832)
			(xy 68.859909 -280.796556) (xy 68.848132 -280.748772) (xy 68.844172 -280.699718) (xy 68.50507 -280.699718)
			(xy 68.504575 -280.724325) (xy 68.49668 -280.772902) (xy 68.481096 -280.819583) (xy 68.458225 -280.86316)
			(xy 68.42866 -280.902504) (xy 68.393167 -280.936596) (xy 68.352664 -280.964552) (xy 68.308202 -280.98565)
			(xy 68.260931 -280.999342) (xy 68.212076 -281.005274) (xy 68.162901 -281.003293) (xy 68.114682 -280.993449)
			(xy 68.068666 -280.975997) (xy 68.026045 -280.95139) (xy 67.987924 -280.920265) (xy 67.955289 -280.883428)
			(xy 67.928986 -280.841832) (xy 67.909695 -280.796556) (xy 67.897918 -280.748772) (xy 67.893958 -280.699718)
			(xy 67.55511 -280.699718) (xy 67.554615 -280.724325) (xy 67.54672 -280.772902) (xy 67.531136 -280.819583)
			(xy 67.508265 -280.86316) (xy 67.4787 -280.902504) (xy 67.443207 -280.936596) (xy 67.402704 -280.964552)
			(xy 67.358242 -280.98565) (xy 67.310971 -280.999342) (xy 67.262116 -281.005274) (xy 67.212941 -281.003293)
			(xy 67.164722 -280.993449) (xy 67.118706 -280.975997) (xy 67.076085 -280.95139) (xy 67.037964 -280.920265)
			(xy 67.005329 -280.883428) (xy 66.979026 -280.841832) (xy 66.959735 -280.796556) (xy 66.947958 -280.748772)
			(xy 66.943998 -280.699718) (xy 66.60515 -280.699718) (xy 66.604655 -280.724325) (xy 66.59676 -280.772902)
			(xy 66.581176 -280.819583) (xy 66.558305 -280.86316) (xy 66.52874 -280.902504) (xy 66.493247 -280.936596)
			(xy 66.452744 -280.964552) (xy 66.408282 -280.98565) (xy 66.361011 -280.999342) (xy 66.312156 -281.005274)
			(xy 66.262981 -281.003293) (xy 66.214762 -280.993449) (xy 66.168746 -280.975997) (xy 66.126125 -280.95139)
			(xy 66.088004 -280.920265) (xy 66.055369 -280.883428) (xy 66.029066 -280.841832) (xy 66.009775 -280.796556)
			(xy 65.997998 -280.748772) (xy 65.994038 -280.699718) (xy 65.65519 -280.699718) (xy 65.654695 -280.724325)
			(xy 65.6468 -280.772902) (xy 65.631216 -280.819583) (xy 65.608345 -280.86316) (xy 65.57878 -280.902504)
			(xy 65.543287 -280.936596) (xy 65.502784 -280.964552) (xy 65.458322 -280.98565) (xy 65.411051 -280.999342)
			(xy 65.362196 -281.005274) (xy 65.313021 -281.003293) (xy 65.264802 -280.993449) (xy 65.218786 -280.975997)
			(xy 65.176165 -280.95139) (xy 65.138044 -280.920265) (xy 65.105409 -280.883428) (xy 65.079106 -280.841832)
			(xy 65.059815 -280.796556) (xy 65.048038 -280.748772) (xy 65.044078 -280.699718) (xy 64.70523 -280.699718)
			(xy 64.704735 -280.724325) (xy 64.69684 -280.772902) (xy 64.681256 -280.819583) (xy 64.658385 -280.86316)
			(xy 64.62882 -280.902504) (xy 64.593327 -280.936596) (xy 64.552824 -280.964552) (xy 64.508362 -280.98565)
			(xy 64.461091 -280.999342) (xy 64.412236 -281.005274) (xy 64.363061 -281.003293) (xy 64.314842 -280.993449)
			(xy 64.268826 -280.975997) (xy 64.226205 -280.95139) (xy 64.188084 -280.920265) (xy 64.155449 -280.883428)
			(xy 64.129146 -280.841832) (xy 64.109855 -280.796556) (xy 64.098078 -280.748772) (xy 64.094118 -280.699718)
			(xy 63.75527 -280.699718) (xy 63.754775 -280.724325) (xy 63.74688 -280.772902) (xy 63.731296 -280.819583)
			(xy 63.708425 -280.86316) (xy 63.67886 -280.902504) (xy 63.643367 -280.936596) (xy 63.602864 -280.964552)
			(xy 63.558402 -280.98565) (xy 63.511131 -280.999342) (xy 63.462276 -281.005274) (xy 63.413101 -281.003293)
			(xy 63.364882 -280.993449) (xy 63.318866 -280.975997) (xy 63.276245 -280.95139) (xy 63.238124 -280.920265)
			(xy 63.205489 -280.883428) (xy 63.179186 -280.841832) (xy 63.159895 -280.796556) (xy 63.148118 -280.748772)
			(xy 63.144158 -280.699718) (xy 62.805056 -280.699718) (xy 62.804561 -280.724325) (xy 62.796666 -280.772902)
			(xy 62.781082 -280.819583) (xy 62.758211 -280.86316) (xy 62.728646 -280.902504) (xy 62.693153 -280.936596)
			(xy 62.65265 -280.964552) (xy 62.608188 -280.98565) (xy 62.560917 -280.999342) (xy 62.512062 -281.005274)
			(xy 62.462887 -281.003293) (xy 62.414668 -280.993449) (xy 62.368652 -280.975997) (xy 62.326031 -280.95139)
			(xy 62.28791 -280.920265) (xy 62.255275 -280.883428) (xy 62.228972 -280.841832) (xy 62.209681 -280.796556)
			(xy 62.197904 -280.748772) (xy 62.193944 -280.699718) (xy 61.855096 -280.699718) (xy 61.854601 -280.724325)
			(xy 61.846706 -280.772902) (xy 61.831122 -280.819583) (xy 61.808251 -280.86316) (xy 61.778686 -280.902504)
			(xy 61.743193 -280.936596) (xy 61.70269 -280.964552) (xy 61.658228 -280.98565) (xy 61.610957 -280.999342)
			(xy 61.562102 -281.005274) (xy 61.512927 -281.003293) (xy 61.464708 -280.993449) (xy 61.418692 -280.975997)
			(xy 61.376071 -280.95139) (xy 61.33795 -280.920265) (xy 61.305315 -280.883428) (xy 61.279012 -280.841832)
			(xy 61.259721 -280.796556) (xy 61.247944 -280.748772) (xy 61.243984 -280.699718) (xy 60.905136 -280.699718)
			(xy 60.904641 -280.724325) (xy 60.896746 -280.772902) (xy 60.881162 -280.819583) (xy 60.858291 -280.86316)
			(xy 60.828726 -280.902504) (xy 60.793233 -280.936596) (xy 60.75273 -280.964552) (xy 60.708268 -280.98565)
			(xy 60.660997 -280.999342) (xy 60.612142 -281.005274) (xy 60.562967 -281.003293) (xy 60.514748 -280.993449)
			(xy 60.468732 -280.975997) (xy 60.426111 -280.95139) (xy 60.38799 -280.920265) (xy 60.355355 -280.883428)
			(xy 60.329052 -280.841832) (xy 60.309761 -280.796556) (xy 60.297984 -280.748772) (xy 60.294024 -280.699718)
			(xy 59.955176 -280.699718) (xy 59.954681 -280.724325) (xy 59.946786 -280.772902) (xy 59.931202 -280.819583)
			(xy 59.908331 -280.86316) (xy 59.878766 -280.902504) (xy 59.843273 -280.936596) (xy 59.80277 -280.964552)
			(xy 59.758308 -280.98565) (xy 59.711037 -280.999342) (xy 59.662182 -281.005274) (xy 59.613007 -281.003293)
			(xy 59.564788 -280.993449) (xy 59.518772 -280.975997) (xy 59.476151 -280.95139) (xy 59.43803 -280.920265)
			(xy 59.405395 -280.883428) (xy 59.379092 -280.841832) (xy 59.359801 -280.796556) (xy 59.348024 -280.748772)
			(xy 59.344064 -280.699718) (xy 59.005216 -280.699718) (xy 59.004721 -280.724325) (xy 58.996826 -280.772902)
			(xy 58.981242 -280.819583) (xy 58.958371 -280.86316) (xy 58.928806 -280.902504) (xy 58.893313 -280.936596)
			(xy 58.85281 -280.964552) (xy 58.808348 -280.98565) (xy 58.761077 -280.999342) (xy 58.712222 -281.005274)
			(xy 58.663047 -281.003293) (xy 58.614828 -280.993449) (xy 58.568812 -280.975997) (xy 58.526191 -280.95139)
			(xy 58.48807 -280.920265) (xy 58.455435 -280.883428) (xy 58.429132 -280.841832) (xy 58.409841 -280.796556)
			(xy 58.398064 -280.748772) (xy 58.394104 -280.699718) (xy 58.055256 -280.699718) (xy 58.054761 -280.724325)
			(xy 58.046866 -280.772902) (xy 58.031282 -280.819583) (xy 58.008411 -280.86316) (xy 57.978846 -280.902504)
			(xy 57.943353 -280.936596) (xy 57.90285 -280.964552) (xy 57.858388 -280.98565) (xy 57.811117 -280.999342)
			(xy 57.762262 -281.005274) (xy 57.713087 -281.003293) (xy 57.664868 -280.993449) (xy 57.618852 -280.975997)
			(xy 57.576231 -280.95139) (xy 57.53811 -280.920265) (xy 57.505475 -280.883428) (xy 57.479172 -280.841832)
			(xy 57.459881 -280.796556) (xy 57.448104 -280.748772) (xy 57.444144 -280.699718) (xy 57.105042 -280.699718)
			(xy 57.104547 -280.724325) (xy 57.096652 -280.772902) (xy 57.081068 -280.819583) (xy 57.058197 -280.86316)
			(xy 57.028632 -280.902504) (xy 56.993139 -280.936596) (xy 56.952636 -280.964552) (xy 56.908174 -280.98565)
			(xy 56.860903 -280.999342) (xy 56.812048 -281.005274) (xy 56.762873 -281.003293) (xy 56.714654 -280.993449)
			(xy 56.668638 -280.975997) (xy 56.626017 -280.95139) (xy 56.587896 -280.920265) (xy 56.555261 -280.883428)
			(xy 56.528958 -280.841832) (xy 56.509667 -280.796556) (xy 56.49789 -280.748772) (xy 56.49393 -280.699718)
			(xy 56.155082 -280.699718) (xy 56.154587 -280.724325) (xy 56.146692 -280.772902) (xy 56.131108 -280.819583)
			(xy 56.108237 -280.86316) (xy 56.078672 -280.902504) (xy 56.043179 -280.936596) (xy 56.002676 -280.964552)
			(xy 55.958214 -280.98565) (xy 55.910943 -280.999342) (xy 55.862088 -281.005274) (xy 55.812913 -281.003293)
			(xy 55.764694 -280.993449) (xy 55.718678 -280.975997) (xy 55.676057 -280.95139) (xy 55.637936 -280.920265)
			(xy 55.605301 -280.883428) (xy 55.578998 -280.841832) (xy 55.559707 -280.796556) (xy 55.54793 -280.748772)
			(xy 55.54397 -280.699718) (xy 55.205122 -280.699718) (xy 55.204627 -280.724325) (xy 55.196732 -280.772902)
			(xy 55.181148 -280.819583) (xy 55.158277 -280.86316) (xy 55.128712 -280.902504) (xy 55.093219 -280.936596)
			(xy 55.052716 -280.964552) (xy 55.008254 -280.98565) (xy 54.960983 -280.999342) (xy 54.912128 -281.005274)
			(xy 54.862953 -281.003293) (xy 54.814734 -280.993449) (xy 54.768718 -280.975997) (xy 54.726097 -280.95139)
			(xy 54.687976 -280.920265) (xy 54.655341 -280.883428) (xy 54.629038 -280.841832) (xy 54.609747 -280.796556)
			(xy 54.59797 -280.748772) (xy 54.59401 -280.699718) (xy 54.255162 -280.699718) (xy 54.254667 -280.724325)
			(xy 54.246772 -280.772902) (xy 54.231188 -280.819583) (xy 54.208317 -280.86316) (xy 54.178752 -280.902504)
			(xy 54.143259 -280.936596) (xy 54.102756 -280.964552) (xy 54.058294 -280.98565) (xy 54.011023 -280.999342)
			(xy 53.962168 -281.005274) (xy 53.912993 -281.003293) (xy 53.864774 -280.993449) (xy 53.818758 -280.975997)
			(xy 53.776137 -280.95139) (xy 53.738016 -280.920265) (xy 53.705381 -280.883428) (xy 53.679078 -280.841832)
			(xy 53.659787 -280.796556) (xy 53.64801 -280.748772) (xy 53.64405 -280.699718) (xy 53.305202 -280.699718)
			(xy 53.304707 -280.724325) (xy 53.296812 -280.772902) (xy 53.281228 -280.819583) (xy 53.258357 -280.86316)
			(xy 53.228792 -280.902504) (xy 53.193299 -280.936596) (xy 53.152796 -280.964552) (xy 53.108334 -280.98565)
			(xy 53.061063 -280.999342) (xy 53.012208 -281.005274) (xy 52.963033 -281.003293) (xy 52.914814 -280.993449)
			(xy 52.868798 -280.975997) (xy 52.826177 -280.95139) (xy 52.788056 -280.920265) (xy 52.755421 -280.883428)
			(xy 52.729118 -280.841832) (xy 52.709827 -280.796556) (xy 52.69805 -280.748772) (xy 52.69409 -280.699718)
			(xy 52.355242 -280.699718) (xy 52.354747 -280.724325) (xy 52.346852 -280.772902) (xy 52.331268 -280.819583)
			(xy 52.308397 -280.86316) (xy 52.278832 -280.902504) (xy 52.243339 -280.936596) (xy 52.202836 -280.964552)
			(xy 52.158374 -280.98565) (xy 52.111103 -280.999342) (xy 52.062248 -281.005274) (xy 52.013073 -281.003293)
			(xy 51.964854 -280.993449) (xy 51.918838 -280.975997) (xy 51.876217 -280.95139) (xy 51.838096 -280.920265)
			(xy 51.805461 -280.883428) (xy 51.779158 -280.841832) (xy 51.759867 -280.796556) (xy 51.74809 -280.748772)
			(xy 51.74413 -280.699718) (xy 51.405282 -280.699718) (xy 51.404787 -280.724325) (xy 51.396892 -280.772902)
			(xy 51.381308 -280.819583) (xy 51.358437 -280.86316) (xy 51.328872 -280.902504) (xy 51.293379 -280.936596)
			(xy 51.252876 -280.964552) (xy 51.208414 -280.98565) (xy 51.161143 -280.999342) (xy 51.112288 -281.005274)
			(xy 51.063113 -281.003293) (xy 51.014894 -280.993449) (xy 50.968878 -280.975997) (xy 50.926257 -280.95139)
			(xy 50.888136 -280.920265) (xy 50.855501 -280.883428) (xy 50.829198 -280.841832) (xy 50.809907 -280.796556)
			(xy 50.79813 -280.748772) (xy 50.79417 -280.699718) (xy 50.455068 -280.699718) (xy 50.454573 -280.724325)
			(xy 50.446678 -280.772902) (xy 50.431094 -280.819583) (xy 50.408223 -280.86316) (xy 50.378658 -280.902504)
			(xy 50.343165 -280.936596) (xy 50.302662 -280.964552) (xy 50.2582 -280.98565) (xy 50.210929 -280.999342)
			(xy 50.162074 -281.005274) (xy 50.112899 -281.003293) (xy 50.06468 -280.993449) (xy 50.018664 -280.975997)
			(xy 49.976043 -280.95139) (xy 49.937922 -280.920265) (xy 49.905287 -280.883428) (xy 49.878984 -280.841832)
			(xy 49.859693 -280.796556) (xy 49.847916 -280.748772) (xy 49.843956 -280.699718) (xy 49.505108 -280.699718)
			(xy 49.504613 -280.724325) (xy 49.496718 -280.772902) (xy 49.481134 -280.819583) (xy 49.458263 -280.86316)
			(xy 49.428698 -280.902504) (xy 49.393205 -280.936596) (xy 49.352702 -280.964552) (xy 49.30824 -280.98565)
			(xy 49.260969 -280.999342) (xy 49.212114 -281.005274) (xy 49.162939 -281.003293) (xy 49.11472 -280.993449)
			(xy 49.068704 -280.975997) (xy 49.026083 -280.95139) (xy 48.987962 -280.920265) (xy 48.955327 -280.883428)
			(xy 48.929024 -280.841832) (xy 48.909733 -280.796556) (xy 48.897956 -280.748772) (xy 48.893996 -280.699718)
			(xy 48.555148 -280.699718) (xy 48.554653 -280.724325) (xy 48.546758 -280.772902) (xy 48.531174 -280.819583)
			(xy 48.508303 -280.86316) (xy 48.478738 -280.902504) (xy 48.443245 -280.936596) (xy 48.402742 -280.964552)
			(xy 48.35828 -280.98565) (xy 48.311009 -280.999342) (xy 48.262154 -281.005274) (xy 48.212979 -281.003293)
			(xy 48.16476 -280.993449) (xy 48.118744 -280.975997) (xy 48.076123 -280.95139) (xy 48.038002 -280.920265)
			(xy 48.005367 -280.883428) (xy 47.979064 -280.841832) (xy 47.959773 -280.796556) (xy 47.947996 -280.748772)
			(xy 47.944036 -280.699718) (xy 47.605188 -280.699718) (xy 47.604693 -280.724325) (xy 47.596798 -280.772902)
			(xy 47.581214 -280.819583) (xy 47.558343 -280.86316) (xy 47.528778 -280.902504) (xy 47.493285 -280.936596)
			(xy 47.452782 -280.964552) (xy 47.40832 -280.98565) (xy 47.361049 -280.999342) (xy 47.312194 -281.005274)
			(xy 47.263019 -281.003293) (xy 47.2148 -280.993449) (xy 47.168784 -280.975997) (xy 47.126163 -280.95139)
			(xy 47.088042 -280.920265) (xy 47.055407 -280.883428) (xy 47.029104 -280.841832) (xy 47.009813 -280.796556)
			(xy 46.998036 -280.748772) (xy 46.994076 -280.699718) (xy 46.655228 -280.699718) (xy 46.654733 -280.724325)
			(xy 46.646838 -280.772902) (xy 46.631254 -280.819583) (xy 46.608383 -280.86316) (xy 46.578818 -280.902504)
			(xy 46.543325 -280.936596) (xy 46.502822 -280.964552) (xy 46.45836 -280.98565) (xy 46.411089 -280.999342)
			(xy 46.362234 -281.005274) (xy 46.313059 -281.003293) (xy 46.26484 -280.993449) (xy 46.218824 -280.975997)
			(xy 46.176203 -280.95139) (xy 46.138082 -280.920265) (xy 46.105447 -280.883428) (xy 46.079144 -280.841832)
			(xy 46.059853 -280.796556) (xy 46.048076 -280.748772) (xy 46.044116 -280.699718) (xy 45.705268 -280.699718)
			(xy 45.704773 -280.724325) (xy 45.696878 -280.772902) (xy 45.681294 -280.819583) (xy 45.658423 -280.86316)
			(xy 45.628858 -280.902504) (xy 45.593365 -280.936596) (xy 45.552862 -280.964552) (xy 45.5084 -280.98565)
			(xy 45.461129 -280.999342) (xy 45.412274 -281.005274) (xy 45.363099 -281.003293) (xy 45.31488 -280.993449)
			(xy 45.268864 -280.975997) (xy 45.226243 -280.95139) (xy 45.188122 -280.920265) (xy 45.155487 -280.883428)
			(xy 45.129184 -280.841832) (xy 45.109893 -280.796556) (xy 45.098116 -280.748772) (xy 45.094156 -280.699718)
			(xy 44.755054 -280.699718) (xy 44.754559 -280.724325) (xy 44.746664 -280.772902) (xy 44.73108 -280.819583)
			(xy 44.708209 -280.86316) (xy 44.678644 -280.902504) (xy 44.643151 -280.936596) (xy 44.602648 -280.964552)
			(xy 44.558186 -280.98565) (xy 44.510915 -280.999342) (xy 44.46206 -281.005274) (xy 44.412885 -281.003293)
			(xy 44.364666 -280.993449) (xy 44.31865 -280.975997) (xy 44.276029 -280.95139) (xy 44.237908 -280.920265)
			(xy 44.205273 -280.883428) (xy 44.17897 -280.841832) (xy 44.159679 -280.796556) (xy 44.147902 -280.748772)
			(xy 44.143942 -280.699718) (xy 34.39033 -280.699718) (xy 34.39033 -281.174952) (xy 36.069028 -281.174952)
			(xy 36.072988 -281.125898) (xy 36.084765 -281.078114) (xy 36.104056 -281.032838) (xy 36.130359 -280.991242)
			(xy 36.162994 -280.954405) (xy 36.201115 -280.92328) (xy 36.243736 -280.898673) (xy 36.289752 -280.881221)
			(xy 36.337971 -280.871377) (xy 36.387146 -280.869396) (xy 36.436001 -280.875328) (xy 36.483272 -280.88902)
			(xy 36.527734 -280.910118) (xy 36.568237 -280.938074) (xy 36.60373 -280.972166) (xy 36.633295 -281.01151)
			(xy 36.656166 -281.055087) (xy 36.67175 -281.101768) (xy 36.679645 -281.150345) (xy 36.68014 -281.174952)
			(xy 37.018988 -281.174952) (xy 37.022948 -281.125898) (xy 37.034725 -281.078114) (xy 37.054016 -281.032838)
			(xy 37.080319 -280.991242) (xy 37.112954 -280.954405) (xy 37.151075 -280.92328) (xy 37.193696 -280.898673)
			(xy 37.239712 -280.881221) (xy 37.287931 -280.871377) (xy 37.337106 -280.869396) (xy 37.385961 -280.875328)
			(xy 37.433232 -280.88902) (xy 37.477694 -280.910118) (xy 37.518197 -280.938074) (xy 37.55369 -280.972166)
			(xy 37.583255 -281.01151) (xy 37.606126 -281.055087) (xy 37.62171 -281.101768) (xy 37.629605 -281.150345)
			(xy 37.6301 -281.174952) (xy 37.969202 -281.174952) (xy 37.973162 -281.125898) (xy 37.984939 -281.078114)
			(xy 38.00423 -281.032838) (xy 38.030533 -280.991242) (xy 38.063168 -280.954405) (xy 38.101289 -280.92328)
			(xy 38.14391 -280.898673) (xy 38.189926 -280.881221) (xy 38.238145 -280.871377) (xy 38.28732 -280.869396)
			(xy 38.336175 -280.875328) (xy 38.383446 -280.88902) (xy 38.427908 -280.910118) (xy 38.468411 -280.938074)
			(xy 38.503904 -280.972166) (xy 38.533469 -281.01151) (xy 38.55634 -281.055087) (xy 38.571924 -281.101768)
			(xy 38.579819 -281.150345) (xy 38.580314 -281.174952) (xy 38.919162 -281.174952) (xy 38.923122 -281.125898)
			(xy 38.934899 -281.078114) (xy 38.95419 -281.032838) (xy 38.980493 -280.991242) (xy 39.013128 -280.954405)
			(xy 39.051249 -280.92328) (xy 39.09387 -280.898673) (xy 39.139886 -280.881221) (xy 39.188105 -280.871377)
			(xy 39.23728 -280.869396) (xy 39.286135 -280.875328) (xy 39.333406 -280.88902) (xy 39.377868 -280.910118)
			(xy 39.418371 -280.938074) (xy 39.453864 -280.972166) (xy 39.483429 -281.01151) (xy 39.5063 -281.055087)
			(xy 39.521884 -281.101768) (xy 39.529779 -281.150345) (xy 39.530274 -281.174952) (xy 39.869122 -281.174952)
			(xy 39.873082 -281.125898) (xy 39.884859 -281.078114) (xy 39.90415 -281.032838) (xy 39.930453 -280.991242)
			(xy 39.963088 -280.954405) (xy 40.001209 -280.92328) (xy 40.04383 -280.898673) (xy 40.089846 -280.881221)
			(xy 40.138065 -280.871377) (xy 40.18724 -280.869396) (xy 40.236095 -280.875328) (xy 40.283366 -280.88902)
			(xy 40.327828 -280.910118) (xy 40.368331 -280.938074) (xy 40.403824 -280.972166) (xy 40.433389 -281.01151)
			(xy 40.45626 -281.055087) (xy 40.471844 -281.101768) (xy 40.479739 -281.150345) (xy 40.480234 -281.174952)
			(xy 40.819082 -281.174952) (xy 40.823042 -281.125898) (xy 40.834819 -281.078114) (xy 40.85411 -281.032838)
			(xy 40.880413 -280.991242) (xy 40.913048 -280.954405) (xy 40.951169 -280.92328) (xy 40.99379 -280.898673)
			(xy 41.039806 -280.881221) (xy 41.088025 -280.871377) (xy 41.1372 -280.869396) (xy 41.186055 -280.875328)
			(xy 41.233326 -280.88902) (xy 41.277788 -280.910118) (xy 41.318291 -280.938074) (xy 41.353784 -280.972166)
			(xy 41.383349 -281.01151) (xy 41.40622 -281.055087) (xy 41.421804 -281.101768) (xy 41.429699 -281.150345)
			(xy 41.430194 -281.174952) (xy 41.769042 -281.174952) (xy 41.773002 -281.125898) (xy 41.784779 -281.078114)
			(xy 41.80407 -281.032838) (xy 41.830373 -280.991242) (xy 41.863008 -280.954405) (xy 41.901129 -280.92328)
			(xy 41.94375 -280.898673) (xy 41.989766 -280.881221) (xy 42.037985 -280.871377) (xy 42.08716 -280.869396)
			(xy 42.136015 -280.875328) (xy 42.183286 -280.88902) (xy 42.227748 -280.910118) (xy 42.268251 -280.938074)
			(xy 42.303744 -280.972166) (xy 42.333309 -281.01151) (xy 42.35618 -281.055087) (xy 42.371764 -281.101768)
			(xy 42.379659 -281.150345) (xy 42.380154 -281.174952) (xy 42.719002 -281.174952) (xy 42.722962 -281.125898)
			(xy 42.734739 -281.078114) (xy 42.75403 -281.032838) (xy 42.780333 -280.991242) (xy 42.812968 -280.954405)
			(xy 42.851089 -280.92328) (xy 42.89371 -280.898673) (xy 42.939726 -280.881221) (xy 42.987945 -280.871377)
			(xy 43.03712 -280.869396) (xy 43.085975 -280.875328) (xy 43.133246 -280.88902) (xy 43.177708 -280.910118)
			(xy 43.218211 -280.938074) (xy 43.253704 -280.972166) (xy 43.283269 -281.01151) (xy 43.30614 -281.055087)
			(xy 43.321724 -281.101768) (xy 43.329619 -281.150345) (xy 43.330114 -281.174952) (xy 43.329619 -281.199559)
			(xy 43.321724 -281.248136) (xy 43.30614 -281.294817) (xy 43.283269 -281.338394) (xy 43.253704 -281.377738)
			(xy 43.218211 -281.41183) (xy 43.177708 -281.439786) (xy 43.133246 -281.460884) (xy 43.085975 -281.474576)
			(xy 43.03712 -281.480508) (xy 42.987945 -281.478527) (xy 42.939726 -281.468683) (xy 42.89371 -281.451231)
			(xy 42.851089 -281.426624) (xy 42.812968 -281.395499) (xy 42.780333 -281.358662) (xy 42.75403 -281.317066)
			(xy 42.734739 -281.27179) (xy 42.722962 -281.224006) (xy 42.719002 -281.174952) (xy 42.380154 -281.174952)
			(xy 42.379659 -281.199559) (xy 42.371764 -281.248136) (xy 42.35618 -281.294817) (xy 42.333309 -281.338394)
			(xy 42.303744 -281.377738) (xy 42.268251 -281.41183) (xy 42.227748 -281.439786) (xy 42.183286 -281.460884)
			(xy 42.136015 -281.474576) (xy 42.08716 -281.480508) (xy 42.037985 -281.478527) (xy 41.989766 -281.468683)
			(xy 41.94375 -281.451231) (xy 41.901129 -281.426624) (xy 41.863008 -281.395499) (xy 41.830373 -281.358662)
			(xy 41.80407 -281.317066) (xy 41.784779 -281.27179) (xy 41.773002 -281.224006) (xy 41.769042 -281.174952)
			(xy 41.430194 -281.174952) (xy 41.429699 -281.199559) (xy 41.421804 -281.248136) (xy 41.40622 -281.294817)
			(xy 41.383349 -281.338394) (xy 41.353784 -281.377738) (xy 41.318291 -281.41183) (xy 41.277788 -281.439786)
			(xy 41.233326 -281.460884) (xy 41.186055 -281.474576) (xy 41.1372 -281.480508) (xy 41.088025 -281.478527)
			(xy 41.039806 -281.468683) (xy 40.99379 -281.451231) (xy 40.951169 -281.426624) (xy 40.913048 -281.395499)
			(xy 40.880413 -281.358662) (xy 40.85411 -281.317066) (xy 40.834819 -281.27179) (xy 40.823042 -281.224006)
			(xy 40.819082 -281.174952) (xy 40.480234 -281.174952) (xy 40.479739 -281.199559) (xy 40.471844 -281.248136)
			(xy 40.45626 -281.294817) (xy 40.433389 -281.338394) (xy 40.403824 -281.377738) (xy 40.368331 -281.41183)
			(xy 40.327828 -281.439786) (xy 40.283366 -281.460884) (xy 40.236095 -281.474576) (xy 40.18724 -281.480508)
			(xy 40.138065 -281.478527) (xy 40.089846 -281.468683) (xy 40.04383 -281.451231) (xy 40.001209 -281.426624)
			(xy 39.963088 -281.395499) (xy 39.930453 -281.358662) (xy 39.90415 -281.317066) (xy 39.884859 -281.27179)
			(xy 39.873082 -281.224006) (xy 39.869122 -281.174952) (xy 39.530274 -281.174952) (xy 39.529779 -281.199559)
			(xy 39.521884 -281.248136) (xy 39.5063 -281.294817) (xy 39.483429 -281.338394) (xy 39.453864 -281.377738)
			(xy 39.418371 -281.41183) (xy 39.377868 -281.439786) (xy 39.333406 -281.460884) (xy 39.286135 -281.474576)
			(xy 39.23728 -281.480508) (xy 39.188105 -281.478527) (xy 39.139886 -281.468683) (xy 39.09387 -281.451231)
			(xy 39.051249 -281.426624) (xy 39.013128 -281.395499) (xy 38.980493 -281.358662) (xy 38.95419 -281.317066)
			(xy 38.934899 -281.27179) (xy 38.923122 -281.224006) (xy 38.919162 -281.174952) (xy 38.580314 -281.174952)
			(xy 38.579819 -281.199559) (xy 38.571924 -281.248136) (xy 38.55634 -281.294817) (xy 38.533469 -281.338394)
			(xy 38.503904 -281.377738) (xy 38.468411 -281.41183) (xy 38.427908 -281.439786) (xy 38.383446 -281.460884)
			(xy 38.336175 -281.474576) (xy 38.28732 -281.480508) (xy 38.238145 -281.478527) (xy 38.189926 -281.468683)
			(xy 38.14391 -281.451231) (xy 38.101289 -281.426624) (xy 38.063168 -281.395499) (xy 38.030533 -281.358662)
			(xy 38.00423 -281.317066) (xy 37.984939 -281.27179) (xy 37.973162 -281.224006) (xy 37.969202 -281.174952)
			(xy 37.6301 -281.174952) (xy 37.629605 -281.199559) (xy 37.62171 -281.248136) (xy 37.606126 -281.294817)
			(xy 37.583255 -281.338394) (xy 37.55369 -281.377738) (xy 37.518197 -281.41183) (xy 37.477694 -281.439786)
			(xy 37.433232 -281.460884) (xy 37.385961 -281.474576) (xy 37.337106 -281.480508) (xy 37.287931 -281.478527)
			(xy 37.239712 -281.468683) (xy 37.193696 -281.451231) (xy 37.151075 -281.426624) (xy 37.112954 -281.395499)
			(xy 37.080319 -281.358662) (xy 37.054016 -281.317066) (xy 37.034725 -281.27179) (xy 37.022948 -281.224006)
			(xy 37.018988 -281.174952) (xy 36.68014 -281.174952) (xy 36.679645 -281.199559) (xy 36.67175 -281.248136)
			(xy 36.656166 -281.294817) (xy 36.633295 -281.338394) (xy 36.60373 -281.377738) (xy 36.568237 -281.41183)
			(xy 36.527734 -281.439786) (xy 36.483272 -281.460884) (xy 36.436001 -281.474576) (xy 36.387146 -281.480508)
			(xy 36.337971 -281.478527) (xy 36.289752 -281.468683) (xy 36.243736 -281.451231) (xy 36.201115 -281.426624)
			(xy 36.162994 -281.395499) (xy 36.130359 -281.358662) (xy 36.104056 -281.317066) (xy 36.084765 -281.27179)
			(xy 36.072988 -281.224006) (xy 36.069028 -281.174952) (xy 34.39033 -281.174952) (xy 34.39033 -282.124912)
			(xy 36.069028 -282.124912) (xy 36.072988 -282.075858) (xy 36.084765 -282.028074) (xy 36.104056 -281.982798)
			(xy 36.130359 -281.941202) (xy 36.162994 -281.904365) (xy 36.201115 -281.87324) (xy 36.243736 -281.848633)
			(xy 36.289752 -281.831181) (xy 36.337971 -281.821337) (xy 36.387146 -281.819356) (xy 36.436001 -281.825288)
			(xy 36.483272 -281.83898) (xy 36.527734 -281.860078) (xy 36.568237 -281.888034) (xy 36.60373 -281.922126)
			(xy 36.633295 -281.96147) (xy 36.656166 -282.005047) (xy 36.67175 -282.051728) (xy 36.679645 -282.100305)
			(xy 36.68014 -282.124912) (xy 37.018988 -282.124912) (xy 37.022948 -282.075858) (xy 37.034725 -282.028074)
			(xy 37.054016 -281.982798) (xy 37.080319 -281.941202) (xy 37.112954 -281.904365) (xy 37.151075 -281.87324)
			(xy 37.193696 -281.848633) (xy 37.239712 -281.831181) (xy 37.287931 -281.821337) (xy 37.337106 -281.819356)
			(xy 37.385961 -281.825288) (xy 37.433232 -281.83898) (xy 37.477694 -281.860078) (xy 37.518197 -281.888034)
			(xy 37.55369 -281.922126) (xy 37.583255 -281.96147) (xy 37.606126 -282.005047) (xy 37.62171 -282.051728)
			(xy 37.629605 -282.100305) (xy 37.6301 -282.124912) (xy 37.969202 -282.124912) (xy 37.973162 -282.075858)
			(xy 37.984939 -282.028074) (xy 38.00423 -281.982798) (xy 38.030533 -281.941202) (xy 38.063168 -281.904365)
			(xy 38.101289 -281.87324) (xy 38.14391 -281.848633) (xy 38.189926 -281.831181) (xy 38.238145 -281.821337)
			(xy 38.28732 -281.819356) (xy 38.336175 -281.825288) (xy 38.383446 -281.83898) (xy 38.427908 -281.860078)
			(xy 38.468411 -281.888034) (xy 38.503904 -281.922126) (xy 38.533469 -281.96147) (xy 38.55634 -282.005047)
			(xy 38.571924 -282.051728) (xy 38.579819 -282.100305) (xy 38.580314 -282.124912) (xy 38.919162 -282.124912)
			(xy 38.923122 -282.075858) (xy 38.934899 -282.028074) (xy 38.95419 -281.982798) (xy 38.980493 -281.941202)
			(xy 39.013128 -281.904365) (xy 39.051249 -281.87324) (xy 39.09387 -281.848633) (xy 39.139886 -281.831181)
			(xy 39.188105 -281.821337) (xy 39.23728 -281.819356) (xy 39.286135 -281.825288) (xy 39.333406 -281.83898)
			(xy 39.377868 -281.860078) (xy 39.418371 -281.888034) (xy 39.453864 -281.922126) (xy 39.483429 -281.96147)
			(xy 39.5063 -282.005047) (xy 39.521884 -282.051728) (xy 39.529779 -282.100305) (xy 39.530274 -282.124912)
			(xy 39.869122 -282.124912) (xy 39.873082 -282.075858) (xy 39.884859 -282.028074) (xy 39.90415 -281.982798)
			(xy 39.930453 -281.941202) (xy 39.963088 -281.904365) (xy 40.001209 -281.87324) (xy 40.04383 -281.848633)
			(xy 40.089846 -281.831181) (xy 40.138065 -281.821337) (xy 40.18724 -281.819356) (xy 40.236095 -281.825288)
			(xy 40.283366 -281.83898) (xy 40.327828 -281.860078) (xy 40.368331 -281.888034) (xy 40.403824 -281.922126)
			(xy 40.433389 -281.96147) (xy 40.45626 -282.005047) (xy 40.471844 -282.051728) (xy 40.479739 -282.100305)
			(xy 40.480234 -282.124912) (xy 40.819082 -282.124912) (xy 40.823042 -282.075858) (xy 40.834819 -282.028074)
			(xy 40.85411 -281.982798) (xy 40.880413 -281.941202) (xy 40.913048 -281.904365) (xy 40.951169 -281.87324)
			(xy 40.99379 -281.848633) (xy 41.039806 -281.831181) (xy 41.088025 -281.821337) (xy 41.1372 -281.819356)
			(xy 41.186055 -281.825288) (xy 41.233326 -281.83898) (xy 41.277788 -281.860078) (xy 41.318291 -281.888034)
			(xy 41.353784 -281.922126) (xy 41.383349 -281.96147) (xy 41.40622 -282.005047) (xy 41.421804 -282.051728)
			(xy 41.429699 -282.100305) (xy 41.430194 -282.124912) (xy 41.769042 -282.124912) (xy 41.773002 -282.075858)
			(xy 41.784779 -282.028074) (xy 41.80407 -281.982798) (xy 41.830373 -281.941202) (xy 41.863008 -281.904365)
			(xy 41.901129 -281.87324) (xy 41.94375 -281.848633) (xy 41.989766 -281.831181) (xy 42.037985 -281.821337)
			(xy 42.08716 -281.819356) (xy 42.136015 -281.825288) (xy 42.183286 -281.83898) (xy 42.227748 -281.860078)
			(xy 42.268251 -281.888034) (xy 42.303744 -281.922126) (xy 42.333309 -281.96147) (xy 42.35618 -282.005047)
			(xy 42.371764 -282.051728) (xy 42.379659 -282.100305) (xy 42.380154 -282.124912) (xy 42.719002 -282.124912)
			(xy 42.722962 -282.075858) (xy 42.734739 -282.028074) (xy 42.75403 -281.982798) (xy 42.780333 -281.941202)
			(xy 42.812968 -281.904365) (xy 42.851089 -281.87324) (xy 42.89371 -281.848633) (xy 42.939726 -281.831181)
			(xy 42.987945 -281.821337) (xy 43.03712 -281.819356) (xy 43.085975 -281.825288) (xy 43.133246 -281.83898)
			(xy 43.177708 -281.860078) (xy 43.218211 -281.888034) (xy 43.253704 -281.922126) (xy 43.283269 -281.96147)
			(xy 43.30614 -282.005047) (xy 43.321724 -282.051728) (xy 43.329619 -282.100305) (xy 43.329948 -282.116638)
			(xy 43.669093 -282.116638) (xy 43.674456 -282.06729) (xy 43.687733 -282.01946) (xy 43.708572 -281.974408)
			(xy 43.736425 -281.933321) (xy 43.770558 -281.897281) (xy 43.810072 -281.867238) (xy 43.853925 -281.843983)
			(xy 43.900964 -281.828128) (xy 43.949947 -281.820093) (xy 43.974766 -281.819604) (xy 43.988949 -281.819785)
			(xy 44.017189 -281.822454) (xy 44.031154 -281.824938) (xy 44.045114 -281.827133) (xy 44.073246 -281.824541)
			(xy 44.099592 -281.814343) (xy 44.122137 -281.797318) (xy 44.139156 -281.774768) (xy 44.149347 -281.74842)
			(xy 44.151931 -281.720287) (xy 44.149772 -281.70632) (xy 44.147288 -281.692355) (xy 44.144621 -281.664115)
			(xy 44.144438 -281.649932) (xy 44.144843 -281.625109) (xy 44.15287 -281.576115) (xy 44.168717 -281.529066)
			(xy 44.191967 -281.4852) (xy 44.222007 -281.445674) (xy 44.258047 -281.411528) (xy 44.299135 -281.383662)
			(xy 44.344191 -281.362811) (xy 44.392026 -281.349524) (xy 44.441381 -281.34415) (xy 44.490955 -281.346832)
			(xy 44.539442 -281.357499) (xy 44.585564 -281.375869) (xy 44.628107 -281.401459) (xy 44.66595 -281.433595)
			(xy 44.698095 -281.471429) (xy 44.723696 -281.513966) (xy 44.742078 -281.560084) (xy 44.752757 -281.608568)
			(xy 44.755006 -281.649932) (xy 45.094156 -281.649932) (xy 45.098116 -281.600878) (xy 45.109893 -281.553094)
			(xy 45.129184 -281.507818) (xy 45.155487 -281.466222) (xy 45.188122 -281.429385) (xy 45.226243 -281.39826)
			(xy 45.268864 -281.373653) (xy 45.31488 -281.356201) (xy 45.363099 -281.346357) (xy 45.412274 -281.344376)
			(xy 45.461129 -281.350308) (xy 45.5084 -281.364) (xy 45.552862 -281.385098) (xy 45.593365 -281.413054)
			(xy 45.628858 -281.447146) (xy 45.658423 -281.48649) (xy 45.681294 -281.530067) (xy 45.696878 -281.576748)
			(xy 45.704773 -281.625325) (xy 45.705268 -281.649932) (xy 46.044116 -281.649932) (xy 46.048076 -281.600878)
			(xy 46.059853 -281.553094) (xy 46.079144 -281.507818) (xy 46.105447 -281.466222) (xy 46.138082 -281.429385)
			(xy 46.176203 -281.39826) (xy 46.218824 -281.373653) (xy 46.26484 -281.356201) (xy 46.313059 -281.346357)
			(xy 46.362234 -281.344376) (xy 46.411089 -281.350308) (xy 46.45836 -281.364) (xy 46.502822 -281.385098)
			(xy 46.543325 -281.413054) (xy 46.578818 -281.447146) (xy 46.608383 -281.48649) (xy 46.631254 -281.530067)
			(xy 46.646838 -281.576748) (xy 46.654733 -281.625325) (xy 46.655228 -281.649932) (xy 46.994076 -281.649932)
			(xy 46.998036 -281.600878) (xy 47.009813 -281.553094) (xy 47.029104 -281.507818) (xy 47.055407 -281.466222)
			(xy 47.088042 -281.429385) (xy 47.126163 -281.39826) (xy 47.168784 -281.373653) (xy 47.2148 -281.356201)
			(xy 47.263019 -281.346357) (xy 47.312194 -281.344376) (xy 47.361049 -281.350308) (xy 47.40832 -281.364)
			(xy 47.452782 -281.385098) (xy 47.493285 -281.413054) (xy 47.528778 -281.447146) (xy 47.558343 -281.48649)
			(xy 47.581214 -281.530067) (xy 47.596798 -281.576748) (xy 47.604693 -281.625325) (xy 47.605188 -281.649932)
			(xy 47.944036 -281.649932) (xy 47.947996 -281.600878) (xy 47.959773 -281.553094) (xy 47.979064 -281.507818)
			(xy 48.005367 -281.466222) (xy 48.038002 -281.429385) (xy 48.076123 -281.39826) (xy 48.118744 -281.373653)
			(xy 48.16476 -281.356201) (xy 48.212979 -281.346357) (xy 48.262154 -281.344376) (xy 48.311009 -281.350308)
			(xy 48.35828 -281.364) (xy 48.402742 -281.385098) (xy 48.443245 -281.413054) (xy 48.478738 -281.447146)
			(xy 48.508303 -281.48649) (xy 48.531174 -281.530067) (xy 48.546758 -281.576748) (xy 48.554653 -281.625325)
			(xy 48.555148 -281.649932) (xy 48.893996 -281.649932) (xy 48.897956 -281.600878) (xy 48.909733 -281.553094)
			(xy 48.929024 -281.507818) (xy 48.955327 -281.466222) (xy 48.987962 -281.429385) (xy 49.026083 -281.39826)
			(xy 49.068704 -281.373653) (xy 49.11472 -281.356201) (xy 49.162939 -281.346357) (xy 49.212114 -281.344376)
			(xy 49.260969 -281.350308) (xy 49.30824 -281.364) (xy 49.352702 -281.385098) (xy 49.393205 -281.413054)
			(xy 49.428698 -281.447146) (xy 49.458263 -281.48649) (xy 49.481134 -281.530067) (xy 49.496718 -281.576748)
			(xy 49.504613 -281.625325) (xy 49.505108 -281.649932) (xy 49.843956 -281.649932) (xy 49.847916 -281.600878)
			(xy 49.859693 -281.553094) (xy 49.878984 -281.507818) (xy 49.905287 -281.466222) (xy 49.937922 -281.429385)
			(xy 49.976043 -281.39826) (xy 50.018664 -281.373653) (xy 50.06468 -281.356201) (xy 50.112899 -281.346357)
			(xy 50.162074 -281.344376) (xy 50.210929 -281.350308) (xy 50.2582 -281.364) (xy 50.302662 -281.385098)
			(xy 50.343165 -281.413054) (xy 50.378658 -281.447146) (xy 50.408223 -281.48649) (xy 50.431094 -281.530067)
			(xy 50.446678 -281.576748) (xy 50.454573 -281.625325) (xy 50.455068 -281.649932) (xy 50.79417 -281.649932)
			(xy 50.79813 -281.600878) (xy 50.809907 -281.553094) (xy 50.829198 -281.507818) (xy 50.855501 -281.466222)
			(xy 50.888136 -281.429385) (xy 50.926257 -281.39826) (xy 50.968878 -281.373653) (xy 51.014894 -281.356201)
			(xy 51.063113 -281.346357) (xy 51.112288 -281.344376) (xy 51.161143 -281.350308) (xy 51.208414 -281.364)
			(xy 51.252876 -281.385098) (xy 51.293379 -281.413054) (xy 51.328872 -281.447146) (xy 51.358437 -281.48649)
			(xy 51.381308 -281.530067) (xy 51.396892 -281.576748) (xy 51.404787 -281.625325) (xy 51.405282 -281.649932)
			(xy 51.74413 -281.649932) (xy 51.74809 -281.600878) (xy 51.759867 -281.553094) (xy 51.779158 -281.507818)
			(xy 51.805461 -281.466222) (xy 51.838096 -281.429385) (xy 51.876217 -281.39826) (xy 51.918838 -281.373653)
			(xy 51.964854 -281.356201) (xy 52.013073 -281.346357) (xy 52.062248 -281.344376) (xy 52.111103 -281.350308)
			(xy 52.158374 -281.364) (xy 52.202836 -281.385098) (xy 52.243339 -281.413054) (xy 52.278832 -281.447146)
			(xy 52.308397 -281.48649) (xy 52.331268 -281.530067) (xy 52.346852 -281.576748) (xy 52.354747 -281.625325)
			(xy 52.355242 -281.649932) (xy 52.69409 -281.649932) (xy 52.69805 -281.600878) (xy 52.709827 -281.553094)
			(xy 52.729118 -281.507818) (xy 52.755421 -281.466222) (xy 52.788056 -281.429385) (xy 52.826177 -281.39826)
			(xy 52.868798 -281.373653) (xy 52.914814 -281.356201) (xy 52.963033 -281.346357) (xy 53.012208 -281.344376)
			(xy 53.061063 -281.350308) (xy 53.108334 -281.364) (xy 53.152796 -281.385098) (xy 53.193299 -281.413054)
			(xy 53.228792 -281.447146) (xy 53.258357 -281.48649) (xy 53.281228 -281.530067) (xy 53.296812 -281.576748)
			(xy 53.304707 -281.625325) (xy 53.305202 -281.649932) (xy 53.305037 -281.658139) (xy 53.644226 -281.658139)
			(xy 53.64692 -281.608578) (xy 53.657596 -281.560106) (xy 53.675973 -281.514) (xy 53.701568 -281.471475)
			(xy 53.733705 -281.43365) (xy 53.771538 -281.401522) (xy 53.81407 -281.375939) (xy 53.860181 -281.357573)
			(xy 53.908656 -281.346909) (xy 53.958217 -281.344228) (xy 54.007559 -281.3496) (xy 54.055382 -281.362884)
			(xy 54.100426 -281.38373) (xy 54.141504 -281.411589) (xy 54.177534 -281.445726) (xy 54.207567 -281.485242)
			(xy 54.230811 -281.529097) (xy 54.246654 -281.576134) (xy 54.254679 -281.625115) (xy 54.255162 -281.649932)
			(xy 54.254991 -281.664115) (xy 54.252315 -281.692355) (xy 54.249828 -281.70632) (xy 54.247542 -281.718766)
			(xy 54.254908 -281.742388) (xy 54.332378 -281.819858) (xy 54.356 -281.827224) (xy 54.368446 -281.824938)
			(xy 54.382412 -281.82246) (xy 54.410651 -281.819789) (xy 54.424834 -281.819604) (xy 54.439017 -281.819776)
			(xy 54.467257 -281.822451) (xy 54.481222 -281.824938) (xy 54.493668 -281.827224) (xy 54.51729 -281.819858)
			(xy 54.59476 -281.742388) (xy 54.602126 -281.718766) (xy 54.59984 -281.70632) (xy 54.597357 -281.692355)
			(xy 54.594689 -281.664115) (xy 54.594506 -281.649932) (xy 54.594943 -281.625108) (xy 54.60297 -281.576114)
			(xy 54.618818 -281.529064) (xy 54.642069 -281.485197) (xy 54.672111 -281.44567) (xy 54.708151 -281.411524)
			(xy 54.749242 -281.383659) (xy 54.794299 -281.362808) (xy 54.842135 -281.349522) (xy 54.891491 -281.34415)
			(xy 54.941066 -281.346834) (xy 54.989554 -281.357502) (xy 55.035677 -281.375875) (xy 55.07822 -281.401468)
			(xy 55.116062 -281.433606) (xy 55.148205 -281.471443) (xy 55.173804 -281.513982) (xy 55.192184 -281.560102)
			(xy 55.20286 -281.608588) (xy 55.205104 -281.649932) (xy 55.54397 -281.649932) (xy 55.54793 -281.600878)
			(xy 55.559707 -281.553094) (xy 55.578998 -281.507818) (xy 55.605301 -281.466222) (xy 55.637936 -281.429385)
			(xy 55.676057 -281.39826) (xy 55.718678 -281.373653) (xy 55.764694 -281.356201) (xy 55.812913 -281.346357)
			(xy 55.862088 -281.344376) (xy 55.910943 -281.350308) (xy 55.958214 -281.364) (xy 56.002676 -281.385098)
			(xy 56.043179 -281.413054) (xy 56.078672 -281.447146) (xy 56.108237 -281.48649) (xy 56.131108 -281.530067)
			(xy 56.146692 -281.576748) (xy 56.154587 -281.625325) (xy 56.155082 -281.649932) (xy 56.494184 -281.649932)
			(xy 56.498144 -281.600878) (xy 56.509921 -281.553094) (xy 56.529212 -281.507818) (xy 56.555515 -281.466222)
			(xy 56.58815 -281.429385) (xy 56.626271 -281.39826) (xy 56.668892 -281.373653) (xy 56.714908 -281.356201)
			(xy 56.763127 -281.346357) (xy 56.812302 -281.344376) (xy 56.861157 -281.350308) (xy 56.908428 -281.364)
			(xy 56.95289 -281.385098) (xy 56.993393 -281.413054) (xy 57.028886 -281.447146) (xy 57.058451 -281.48649)
			(xy 57.081322 -281.530067) (xy 57.096906 -281.576748) (xy 57.104801 -281.625325) (xy 57.105296 -281.649932)
			(xy 57.444144 -281.649932) (xy 57.448104 -281.600878) (xy 57.459881 -281.553094) (xy 57.479172 -281.507818)
			(xy 57.505475 -281.466222) (xy 57.53811 -281.429385) (xy 57.576231 -281.39826) (xy 57.618852 -281.373653)
			(xy 57.664868 -281.356201) (xy 57.713087 -281.346357) (xy 57.762262 -281.344376) (xy 57.811117 -281.350308)
			(xy 57.858388 -281.364) (xy 57.90285 -281.385098) (xy 57.943353 -281.413054) (xy 57.978846 -281.447146)
			(xy 58.008411 -281.48649) (xy 58.031282 -281.530067) (xy 58.046866 -281.576748) (xy 58.054761 -281.625325)
			(xy 58.055256 -281.649932) (xy 58.394104 -281.649932) (xy 58.398064 -281.600878) (xy 58.409841 -281.553094)
			(xy 58.429132 -281.507818) (xy 58.455435 -281.466222) (xy 58.48807 -281.429385) (xy 58.526191 -281.39826)
			(xy 58.568812 -281.373653) (xy 58.614828 -281.356201) (xy 58.663047 -281.346357) (xy 58.712222 -281.344376)
			(xy 58.761077 -281.350308) (xy 58.808348 -281.364) (xy 58.85281 -281.385098) (xy 58.893313 -281.413054)
			(xy 58.928806 -281.447146) (xy 58.958371 -281.48649) (xy 58.981242 -281.530067) (xy 58.996826 -281.576748)
			(xy 59.004721 -281.625325) (xy 59.005216 -281.649932) (xy 59.344064 -281.649932) (xy 59.348024 -281.600878)
			(xy 59.359801 -281.553094) (xy 59.379092 -281.507818) (xy 59.405395 -281.466222) (xy 59.43803 -281.429385)
			(xy 59.476151 -281.39826) (xy 59.518772 -281.373653) (xy 59.564788 -281.356201) (xy 59.613007 -281.346357)
			(xy 59.662182 -281.344376) (xy 59.711037 -281.350308) (xy 59.758308 -281.364) (xy 59.80277 -281.385098)
			(xy 59.843273 -281.413054) (xy 59.878766 -281.447146) (xy 59.908331 -281.48649) (xy 59.931202 -281.530067)
			(xy 59.946786 -281.576748) (xy 59.954681 -281.625325) (xy 59.955176 -281.649932) (xy 60.294024 -281.649932)
			(xy 60.297984 -281.600878) (xy 60.309761 -281.553094) (xy 60.329052 -281.507818) (xy 60.355355 -281.466222)
			(xy 60.38799 -281.429385) (xy 60.426111 -281.39826) (xy 60.468732 -281.373653) (xy 60.514748 -281.356201)
			(xy 60.562967 -281.346357) (xy 60.612142 -281.344376) (xy 60.660997 -281.350308) (xy 60.708268 -281.364)
			(xy 60.75273 -281.385098) (xy 60.793233 -281.413054) (xy 60.828726 -281.447146) (xy 60.858291 -281.48649)
			(xy 60.881162 -281.530067) (xy 60.896746 -281.576748) (xy 60.904641 -281.625325) (xy 60.905136 -281.649932)
			(xy 61.243984 -281.649932) (xy 61.247944 -281.600878) (xy 61.259721 -281.553094) (xy 61.279012 -281.507818)
			(xy 61.305315 -281.466222) (xy 61.33795 -281.429385) (xy 61.376071 -281.39826) (xy 61.418692 -281.373653)
			(xy 61.464708 -281.356201) (xy 61.512927 -281.346357) (xy 61.562102 -281.344376) (xy 61.610957 -281.350308)
			(xy 61.658228 -281.364) (xy 61.70269 -281.385098) (xy 61.743193 -281.413054) (xy 61.778686 -281.447146)
			(xy 61.808251 -281.48649) (xy 61.831122 -281.530067) (xy 61.846706 -281.576748) (xy 61.854601 -281.625325)
			(xy 61.855096 -281.649932) (xy 62.193944 -281.649932) (xy 62.197904 -281.600878) (xy 62.209681 -281.553094)
			(xy 62.228972 -281.507818) (xy 62.255275 -281.466222) (xy 62.28791 -281.429385) (xy 62.326031 -281.39826)
			(xy 62.368652 -281.373653) (xy 62.414668 -281.356201) (xy 62.462887 -281.346357) (xy 62.512062 -281.344376)
			(xy 62.560917 -281.350308) (xy 62.608188 -281.364) (xy 62.65265 -281.385098) (xy 62.693153 -281.413054)
			(xy 62.728646 -281.447146) (xy 62.758211 -281.48649) (xy 62.781082 -281.530067) (xy 62.796666 -281.576748)
			(xy 62.804561 -281.625325) (xy 62.805056 -281.649932) (xy 63.144158 -281.649932) (xy 63.148118 -281.600878)
			(xy 63.159895 -281.553094) (xy 63.179186 -281.507818) (xy 63.205489 -281.466222) (xy 63.238124 -281.429385)
			(xy 63.276245 -281.39826) (xy 63.318866 -281.373653) (xy 63.364882 -281.356201) (xy 63.413101 -281.346357)
			(xy 63.462276 -281.344376) (xy 63.511131 -281.350308) (xy 63.558402 -281.364) (xy 63.602864 -281.385098)
			(xy 63.643367 -281.413054) (xy 63.67886 -281.447146) (xy 63.708425 -281.48649) (xy 63.731296 -281.530067)
			(xy 63.74688 -281.576748) (xy 63.754775 -281.625325) (xy 63.75527 -281.649932) (xy 64.094118 -281.649932)
			(xy 64.098078 -281.600878) (xy 64.109855 -281.553094) (xy 64.129146 -281.507818) (xy 64.155449 -281.466222)
			(xy 64.188084 -281.429385) (xy 64.226205 -281.39826) (xy 64.268826 -281.373653) (xy 64.314842 -281.356201)
			(xy 64.363061 -281.346357) (xy 64.412236 -281.344376) (xy 64.461091 -281.350308) (xy 64.508362 -281.364)
			(xy 64.552824 -281.385098) (xy 64.593327 -281.413054) (xy 64.62882 -281.447146) (xy 64.658385 -281.48649)
			(xy 64.681256 -281.530067) (xy 64.69684 -281.576748) (xy 64.704735 -281.625325) (xy 64.70523 -281.649932)
			(xy 65.044078 -281.649932) (xy 65.048038 -281.600878) (xy 65.059815 -281.553094) (xy 65.079106 -281.507818)
			(xy 65.105409 -281.466222) (xy 65.138044 -281.429385) (xy 65.176165 -281.39826) (xy 65.218786 -281.373653)
			(xy 65.264802 -281.356201) (xy 65.313021 -281.346357) (xy 65.362196 -281.344376) (xy 65.411051 -281.350308)
			(xy 65.458322 -281.364) (xy 65.502784 -281.385098) (xy 65.543287 -281.413054) (xy 65.57878 -281.447146)
			(xy 65.608345 -281.48649) (xy 65.631216 -281.530067) (xy 65.6468 -281.576748) (xy 65.654695 -281.625325)
			(xy 65.65519 -281.649932) (xy 65.994038 -281.649932) (xy 65.997998 -281.600878) (xy 66.009775 -281.553094)
			(xy 66.029066 -281.507818) (xy 66.055369 -281.466222) (xy 66.088004 -281.429385) (xy 66.126125 -281.39826)
			(xy 66.168746 -281.373653) (xy 66.214762 -281.356201) (xy 66.262981 -281.346357) (xy 66.312156 -281.344376)
			(xy 66.361011 -281.350308) (xy 66.408282 -281.364) (xy 66.452744 -281.385098) (xy 66.493247 -281.413054)
			(xy 66.52874 -281.447146) (xy 66.558305 -281.48649) (xy 66.581176 -281.530067) (xy 66.59676 -281.576748)
			(xy 66.604655 -281.625325) (xy 66.60515 -281.649932) (xy 66.943998 -281.649932) (xy 66.947958 -281.600878)
			(xy 66.959735 -281.553094) (xy 66.979026 -281.507818) (xy 67.005329 -281.466222) (xy 67.037964 -281.429385)
			(xy 67.076085 -281.39826) (xy 67.118706 -281.373653) (xy 67.164722 -281.356201) (xy 67.212941 -281.346357)
			(xy 67.262116 -281.344376) (xy 67.310971 -281.350308) (xy 67.358242 -281.364) (xy 67.402704 -281.385098)
			(xy 67.443207 -281.413054) (xy 67.4787 -281.447146) (xy 67.508265 -281.48649) (xy 67.531136 -281.530067)
			(xy 67.54672 -281.576748) (xy 67.554615 -281.625325) (xy 67.55511 -281.649932) (xy 67.893958 -281.649932)
			(xy 67.897918 -281.600878) (xy 67.909695 -281.553094) (xy 67.928986 -281.507818) (xy 67.955289 -281.466222)
			(xy 67.987924 -281.429385) (xy 68.026045 -281.39826) (xy 68.068666 -281.373653) (xy 68.114682 -281.356201)
			(xy 68.162901 -281.346357) (xy 68.212076 -281.344376) (xy 68.260931 -281.350308) (xy 68.308202 -281.364)
			(xy 68.352664 -281.385098) (xy 68.393167 -281.413054) (xy 68.42866 -281.447146) (xy 68.458225 -281.48649)
			(xy 68.481096 -281.530067) (xy 68.49668 -281.576748) (xy 68.504575 -281.625325) (xy 68.50507 -281.649932)
			(xy 68.844172 -281.649932) (xy 68.848132 -281.600878) (xy 68.859909 -281.553094) (xy 68.8792 -281.507818)
			(xy 68.905503 -281.466222) (xy 68.938138 -281.429385) (xy 68.976259 -281.39826) (xy 69.01888 -281.373653)
			(xy 69.064896 -281.356201) (xy 69.113115 -281.346357) (xy 69.16229 -281.344376) (xy 69.211145 -281.350308)
			(xy 69.258416 -281.364) (xy 69.302878 -281.385098) (xy 69.343381 -281.413054) (xy 69.378874 -281.447146)
			(xy 69.408439 -281.48649) (xy 69.43131 -281.530067) (xy 69.446894 -281.576748) (xy 69.454789 -281.625325)
			(xy 69.455284 -281.649932) (xy 69.794132 -281.649932) (xy 69.798092 -281.600878) (xy 69.809869 -281.553094)
			(xy 69.82916 -281.507818) (xy 69.855463 -281.466222) (xy 69.888098 -281.429385) (xy 69.926219 -281.39826)
			(xy 69.96884 -281.373653) (xy 70.014856 -281.356201) (xy 70.063075 -281.346357) (xy 70.11225 -281.344376)
			(xy 70.161105 -281.350308) (xy 70.208376 -281.364) (xy 70.252838 -281.385098) (xy 70.293341 -281.413054)
			(xy 70.328834 -281.447146) (xy 70.358399 -281.48649) (xy 70.38127 -281.530067) (xy 70.396854 -281.576748)
			(xy 70.404749 -281.625325) (xy 70.405244 -281.649932) (xy 70.744092 -281.649932) (xy 70.748052 -281.600878)
			(xy 70.759829 -281.553094) (xy 70.77912 -281.507818) (xy 70.805423 -281.466222) (xy 70.838058 -281.429385)
			(xy 70.876179 -281.39826) (xy 70.9188 -281.373653) (xy 70.964816 -281.356201) (xy 71.013035 -281.346357)
			(xy 71.06221 -281.344376) (xy 71.111065 -281.350308) (xy 71.158336 -281.364) (xy 71.202798 -281.385098)
			(xy 71.243301 -281.413054) (xy 71.278794 -281.447146) (xy 71.308359 -281.48649) (xy 71.33123 -281.530067)
			(xy 71.346814 -281.576748) (xy 71.354709 -281.625325) (xy 71.355204 -281.649932) (xy 71.694052 -281.649932)
			(xy 71.698012 -281.600878) (xy 71.709789 -281.553094) (xy 71.72908 -281.507818) (xy 71.755383 -281.466222)
			(xy 71.788018 -281.429385) (xy 71.826139 -281.39826) (xy 71.86876 -281.373653) (xy 71.914776 -281.356201)
			(xy 71.962995 -281.346357) (xy 72.01217 -281.344376) (xy 72.061025 -281.350308) (xy 72.108296 -281.364)
			(xy 72.152758 -281.385098) (xy 72.193261 -281.413054) (xy 72.228754 -281.447146) (xy 72.258319 -281.48649)
			(xy 72.28119 -281.530067) (xy 72.296774 -281.576748) (xy 72.304669 -281.625325) (xy 72.305164 -281.649932)
			(xy 72.644012 -281.649932) (xy 72.647972 -281.600878) (xy 72.659749 -281.553094) (xy 72.67904 -281.507818)
			(xy 72.705343 -281.466222) (xy 72.737978 -281.429385) (xy 72.776099 -281.39826) (xy 72.81872 -281.373653)
			(xy 72.864736 -281.356201) (xy 72.912955 -281.346357) (xy 72.96213 -281.344376) (xy 73.010985 -281.350308)
			(xy 73.058256 -281.364) (xy 73.102718 -281.385098) (xy 73.143221 -281.413054) (xy 73.178714 -281.447146)
			(xy 73.208279 -281.48649) (xy 73.23115 -281.530067) (xy 73.246734 -281.576748) (xy 73.254629 -281.625325)
			(xy 73.255124 -281.649932) (xy 73.593972 -281.649932) (xy 73.597932 -281.600878) (xy 73.609709 -281.553094)
			(xy 73.629 -281.507818) (xy 73.655303 -281.466222) (xy 73.687938 -281.429385) (xy 73.726059 -281.39826)
			(xy 73.76868 -281.373653) (xy 73.814696 -281.356201) (xy 73.862915 -281.346357) (xy 73.91209 -281.344376)
			(xy 73.960945 -281.350308) (xy 74.008216 -281.364) (xy 74.052678 -281.385098) (xy 74.093181 -281.413054)
			(xy 74.128674 -281.447146) (xy 74.158239 -281.48649) (xy 74.18111 -281.530067) (xy 74.196694 -281.576748)
			(xy 74.204589 -281.625325) (xy 74.205084 -281.649932) (xy 74.544186 -281.649932) (xy 74.548146 -281.600878)
			(xy 74.559923 -281.553094) (xy 74.579214 -281.507818) (xy 74.605517 -281.466222) (xy 74.638152 -281.429385)
			(xy 74.676273 -281.39826) (xy 74.718894 -281.373653) (xy 74.76491 -281.356201) (xy 74.813129 -281.346357)
			(xy 74.862304 -281.344376) (xy 74.911159 -281.350308) (xy 74.95843 -281.364) (xy 75.002892 -281.385098)
			(xy 75.043395 -281.413054) (xy 75.078888 -281.447146) (xy 75.108453 -281.48649) (xy 75.131324 -281.530067)
			(xy 75.146908 -281.576748) (xy 75.154803 -281.625325) (xy 75.155298 -281.649932) (xy 75.494146 -281.649932)
			(xy 75.498106 -281.600878) (xy 75.509883 -281.553094) (xy 75.529174 -281.507818) (xy 75.555477 -281.466222)
			(xy 75.588112 -281.429385) (xy 75.626233 -281.39826) (xy 75.668854 -281.373653) (xy 75.71487 -281.356201)
			(xy 75.763089 -281.346357) (xy 75.812264 -281.344376) (xy 75.861119 -281.350308) (xy 75.90839 -281.364)
			(xy 75.952852 -281.385098) (xy 75.993355 -281.413054) (xy 76.028848 -281.447146) (xy 76.058413 -281.48649)
			(xy 76.081284 -281.530067) (xy 76.096868 -281.576748) (xy 76.104763 -281.625325) (xy 76.105258 -281.649932)
			(xy 76.444106 -281.649932) (xy 76.448066 -281.600878) (xy 76.459843 -281.553094) (xy 76.479134 -281.507818)
			(xy 76.505437 -281.466222) (xy 76.538072 -281.429385) (xy 76.576193 -281.39826) (xy 76.618814 -281.373653)
			(xy 76.66483 -281.356201) (xy 76.713049 -281.346357) (xy 76.762224 -281.344376) (xy 76.811079 -281.350308)
			(xy 76.85835 -281.364) (xy 76.902812 -281.385098) (xy 76.943315 -281.413054) (xy 76.978808 -281.447146)
			(xy 77.008373 -281.48649) (xy 77.031244 -281.530067) (xy 77.046828 -281.576748) (xy 77.054723 -281.625325)
			(xy 77.055218 -281.649932) (xy 77.054723 -281.674539) (xy 77.046828 -281.723116) (xy 77.031244 -281.769797)
			(xy 77.008373 -281.813374) (xy 76.978808 -281.852718) (xy 76.943315 -281.88681) (xy 76.902812 -281.914766)
			(xy 76.85835 -281.935864) (xy 76.811079 -281.949556) (xy 76.762224 -281.955488) (xy 76.713049 -281.953507)
			(xy 76.66483 -281.943663) (xy 76.618814 -281.926211) (xy 76.576193 -281.901604) (xy 76.538072 -281.870479)
			(xy 76.505437 -281.833642) (xy 76.479134 -281.792046) (xy 76.459843 -281.74677) (xy 76.448066 -281.698986)
			(xy 76.444106 -281.649932) (xy 76.105258 -281.649932) (xy 76.104763 -281.674539) (xy 76.096868 -281.723116)
			(xy 76.081284 -281.769797) (xy 76.058413 -281.813374) (xy 76.028848 -281.852718) (xy 75.993355 -281.88681)
			(xy 75.952852 -281.914766) (xy 75.90839 -281.935864) (xy 75.861119 -281.949556) (xy 75.812264 -281.955488)
			(xy 75.763089 -281.953507) (xy 75.71487 -281.943663) (xy 75.668854 -281.926211) (xy 75.626233 -281.901604)
			(xy 75.588112 -281.870479) (xy 75.555477 -281.833642) (xy 75.529174 -281.792046) (xy 75.509883 -281.74677)
			(xy 75.498106 -281.698986) (xy 75.494146 -281.649932) (xy 75.155298 -281.649932) (xy 75.154803 -281.674539)
			(xy 75.146908 -281.723116) (xy 75.131324 -281.769797) (xy 75.108453 -281.813374) (xy 75.078888 -281.852718)
			(xy 75.043395 -281.88681) (xy 75.002892 -281.914766) (xy 74.95843 -281.935864) (xy 74.911159 -281.949556)
			(xy 74.862304 -281.955488) (xy 74.813129 -281.953507) (xy 74.76491 -281.943663) (xy 74.718894 -281.926211)
			(xy 74.676273 -281.901604) (xy 74.638152 -281.870479) (xy 74.605517 -281.833642) (xy 74.579214 -281.792046)
			(xy 74.559923 -281.74677) (xy 74.548146 -281.698986) (xy 74.544186 -281.649932) (xy 74.205084 -281.649932)
			(xy 74.204589 -281.674539) (xy 74.196694 -281.723116) (xy 74.18111 -281.769797) (xy 74.158239 -281.813374)
			(xy 74.128674 -281.852718) (xy 74.093181 -281.88681) (xy 74.052678 -281.914766) (xy 74.008216 -281.935864)
			(xy 73.960945 -281.949556) (xy 73.91209 -281.955488) (xy 73.862915 -281.953507) (xy 73.814696 -281.943663)
			(xy 73.76868 -281.926211) (xy 73.726059 -281.901604) (xy 73.687938 -281.870479) (xy 73.655303 -281.833642)
			(xy 73.629 -281.792046) (xy 73.609709 -281.74677) (xy 73.597932 -281.698986) (xy 73.593972 -281.649932)
			(xy 73.255124 -281.649932) (xy 73.254629 -281.674539) (xy 73.246734 -281.723116) (xy 73.23115 -281.769797)
			(xy 73.208279 -281.813374) (xy 73.178714 -281.852718) (xy 73.143221 -281.88681) (xy 73.102718 -281.914766)
			(xy 73.058256 -281.935864) (xy 73.010985 -281.949556) (xy 72.96213 -281.955488) (xy 72.912955 -281.953507)
			(xy 72.864736 -281.943663) (xy 72.81872 -281.926211) (xy 72.776099 -281.901604) (xy 72.737978 -281.870479)
			(xy 72.705343 -281.833642) (xy 72.67904 -281.792046) (xy 72.659749 -281.74677) (xy 72.647972 -281.698986)
			(xy 72.644012 -281.649932) (xy 72.305164 -281.649932) (xy 72.304669 -281.674539) (xy 72.296774 -281.723116)
			(xy 72.28119 -281.769797) (xy 72.258319 -281.813374) (xy 72.228754 -281.852718) (xy 72.193261 -281.88681)
			(xy 72.152758 -281.914766) (xy 72.108296 -281.935864) (xy 72.061025 -281.949556) (xy 72.01217 -281.955488)
			(xy 71.962995 -281.953507) (xy 71.914776 -281.943663) (xy 71.86876 -281.926211) (xy 71.826139 -281.901604)
			(xy 71.788018 -281.870479) (xy 71.755383 -281.833642) (xy 71.72908 -281.792046) (xy 71.709789 -281.74677)
			(xy 71.698012 -281.698986) (xy 71.694052 -281.649932) (xy 71.355204 -281.649932) (xy 71.354709 -281.674539)
			(xy 71.346814 -281.723116) (xy 71.33123 -281.769797) (xy 71.308359 -281.813374) (xy 71.278794 -281.852718)
			(xy 71.243301 -281.88681) (xy 71.202798 -281.914766) (xy 71.158336 -281.935864) (xy 71.111065 -281.949556)
			(xy 71.06221 -281.955488) (xy 71.013035 -281.953507) (xy 70.964816 -281.943663) (xy 70.9188 -281.926211)
			(xy 70.876179 -281.901604) (xy 70.838058 -281.870479) (xy 70.805423 -281.833642) (xy 70.77912 -281.792046)
			(xy 70.759829 -281.74677) (xy 70.748052 -281.698986) (xy 70.744092 -281.649932) (xy 70.405244 -281.649932)
			(xy 70.404749 -281.674539) (xy 70.396854 -281.723116) (xy 70.38127 -281.769797) (xy 70.358399 -281.813374)
			(xy 70.328834 -281.852718) (xy 70.293341 -281.88681) (xy 70.252838 -281.914766) (xy 70.208376 -281.935864)
			(xy 70.161105 -281.949556) (xy 70.11225 -281.955488) (xy 70.063075 -281.953507) (xy 70.014856 -281.943663)
			(xy 69.96884 -281.926211) (xy 69.926219 -281.901604) (xy 69.888098 -281.870479) (xy 69.855463 -281.833642)
			(xy 69.82916 -281.792046) (xy 69.809869 -281.74677) (xy 69.798092 -281.698986) (xy 69.794132 -281.649932)
			(xy 69.455284 -281.649932) (xy 69.454789 -281.674539) (xy 69.446894 -281.723116) (xy 69.43131 -281.769797)
			(xy 69.408439 -281.813374) (xy 69.378874 -281.852718) (xy 69.343381 -281.88681) (xy 69.302878 -281.914766)
			(xy 69.258416 -281.935864) (xy 69.211145 -281.949556) (xy 69.16229 -281.955488) (xy 69.113115 -281.953507)
			(xy 69.064896 -281.943663) (xy 69.01888 -281.926211) (xy 68.976259 -281.901604) (xy 68.938138 -281.870479)
			(xy 68.905503 -281.833642) (xy 68.8792 -281.792046) (xy 68.859909 -281.74677) (xy 68.848132 -281.698986)
			(xy 68.844172 -281.649932) (xy 68.50507 -281.649932) (xy 68.504575 -281.674539) (xy 68.49668 -281.723116)
			(xy 68.481096 -281.769797) (xy 68.458225 -281.813374) (xy 68.42866 -281.852718) (xy 68.393167 -281.88681)
			(xy 68.352664 -281.914766) (xy 68.308202 -281.935864) (xy 68.260931 -281.949556) (xy 68.212076 -281.955488)
			(xy 68.162901 -281.953507) (xy 68.114682 -281.943663) (xy 68.068666 -281.926211) (xy 68.026045 -281.901604)
			(xy 67.987924 -281.870479) (xy 67.955289 -281.833642) (xy 67.928986 -281.792046) (xy 67.909695 -281.74677)
			(xy 67.897918 -281.698986) (xy 67.893958 -281.649932) (xy 67.55511 -281.649932) (xy 67.554615 -281.674539)
			(xy 67.54672 -281.723116) (xy 67.531136 -281.769797) (xy 67.508265 -281.813374) (xy 67.4787 -281.852718)
			(xy 67.443207 -281.88681) (xy 67.402704 -281.914766) (xy 67.358242 -281.935864) (xy 67.310971 -281.949556)
			(xy 67.262116 -281.955488) (xy 67.212941 -281.953507) (xy 67.164722 -281.943663) (xy 67.118706 -281.926211)
			(xy 67.076085 -281.901604) (xy 67.037964 -281.870479) (xy 67.005329 -281.833642) (xy 66.979026 -281.792046)
			(xy 66.959735 -281.74677) (xy 66.947958 -281.698986) (xy 66.943998 -281.649932) (xy 66.60515 -281.649932)
			(xy 66.604655 -281.674539) (xy 66.59676 -281.723116) (xy 66.581176 -281.769797) (xy 66.558305 -281.813374)
			(xy 66.52874 -281.852718) (xy 66.493247 -281.88681) (xy 66.452744 -281.914766) (xy 66.408282 -281.935864)
			(xy 66.361011 -281.949556) (xy 66.312156 -281.955488) (xy 66.262981 -281.953507) (xy 66.214762 -281.943663)
			(xy 66.168746 -281.926211) (xy 66.126125 -281.901604) (xy 66.088004 -281.870479) (xy 66.055369 -281.833642)
			(xy 66.029066 -281.792046) (xy 66.009775 -281.74677) (xy 65.997998 -281.698986) (xy 65.994038 -281.649932)
			(xy 65.65519 -281.649932) (xy 65.654695 -281.674539) (xy 65.6468 -281.723116) (xy 65.631216 -281.769797)
			(xy 65.608345 -281.813374) (xy 65.57878 -281.852718) (xy 65.543287 -281.88681) (xy 65.502784 -281.914766)
			(xy 65.458322 -281.935864) (xy 65.411051 -281.949556) (xy 65.362196 -281.955488) (xy 65.313021 -281.953507)
			(xy 65.264802 -281.943663) (xy 65.218786 -281.926211) (xy 65.176165 -281.901604) (xy 65.138044 -281.870479)
			(xy 65.105409 -281.833642) (xy 65.079106 -281.792046) (xy 65.059815 -281.74677) (xy 65.048038 -281.698986)
			(xy 65.044078 -281.649932) (xy 64.70523 -281.649932) (xy 64.704735 -281.674539) (xy 64.69684 -281.723116)
			(xy 64.681256 -281.769797) (xy 64.658385 -281.813374) (xy 64.62882 -281.852718) (xy 64.593327 -281.88681)
			(xy 64.552824 -281.914766) (xy 64.508362 -281.935864) (xy 64.461091 -281.949556) (xy 64.412236 -281.955488)
			(xy 64.363061 -281.953507) (xy 64.314842 -281.943663) (xy 64.268826 -281.926211) (xy 64.226205 -281.901604)
			(xy 64.188084 -281.870479) (xy 64.155449 -281.833642) (xy 64.129146 -281.792046) (xy 64.109855 -281.74677)
			(xy 64.098078 -281.698986) (xy 64.094118 -281.649932) (xy 63.75527 -281.649932) (xy 63.754775 -281.674539)
			(xy 63.74688 -281.723116) (xy 63.731296 -281.769797) (xy 63.708425 -281.813374) (xy 63.67886 -281.852718)
			(xy 63.643367 -281.88681) (xy 63.602864 -281.914766) (xy 63.558402 -281.935864) (xy 63.511131 -281.949556)
			(xy 63.462276 -281.955488) (xy 63.413101 -281.953507) (xy 63.364882 -281.943663) (xy 63.318866 -281.926211)
			(xy 63.276245 -281.901604) (xy 63.238124 -281.870479) (xy 63.205489 -281.833642) (xy 63.179186 -281.792046)
			(xy 63.159895 -281.74677) (xy 63.148118 -281.698986) (xy 63.144158 -281.649932) (xy 62.805056 -281.649932)
			(xy 62.804561 -281.674539) (xy 62.796666 -281.723116) (xy 62.781082 -281.769797) (xy 62.758211 -281.813374)
			(xy 62.728646 -281.852718) (xy 62.693153 -281.88681) (xy 62.65265 -281.914766) (xy 62.608188 -281.935864)
			(xy 62.560917 -281.949556) (xy 62.512062 -281.955488) (xy 62.462887 -281.953507) (xy 62.414668 -281.943663)
			(xy 62.368652 -281.926211) (xy 62.326031 -281.901604) (xy 62.28791 -281.870479) (xy 62.255275 -281.833642)
			(xy 62.228972 -281.792046) (xy 62.209681 -281.74677) (xy 62.197904 -281.698986) (xy 62.193944 -281.649932)
			(xy 61.855096 -281.649932) (xy 61.854601 -281.674539) (xy 61.846706 -281.723116) (xy 61.831122 -281.769797)
			(xy 61.808251 -281.813374) (xy 61.778686 -281.852718) (xy 61.743193 -281.88681) (xy 61.70269 -281.914766)
			(xy 61.658228 -281.935864) (xy 61.610957 -281.949556) (xy 61.562102 -281.955488) (xy 61.512927 -281.953507)
			(xy 61.464708 -281.943663) (xy 61.418692 -281.926211) (xy 61.376071 -281.901604) (xy 61.33795 -281.870479)
			(xy 61.305315 -281.833642) (xy 61.279012 -281.792046) (xy 61.259721 -281.74677) (xy 61.247944 -281.698986)
			(xy 61.243984 -281.649932) (xy 60.905136 -281.649932) (xy 60.904641 -281.674539) (xy 60.896746 -281.723116)
			(xy 60.881162 -281.769797) (xy 60.858291 -281.813374) (xy 60.828726 -281.852718) (xy 60.793233 -281.88681)
			(xy 60.75273 -281.914766) (xy 60.708268 -281.935864) (xy 60.660997 -281.949556) (xy 60.612142 -281.955488)
			(xy 60.562967 -281.953507) (xy 60.514748 -281.943663) (xy 60.468732 -281.926211) (xy 60.426111 -281.901604)
			(xy 60.38799 -281.870479) (xy 60.355355 -281.833642) (xy 60.329052 -281.792046) (xy 60.309761 -281.74677)
			(xy 60.297984 -281.698986) (xy 60.294024 -281.649932) (xy 59.955176 -281.649932) (xy 59.954681 -281.674539)
			(xy 59.946786 -281.723116) (xy 59.931202 -281.769797) (xy 59.908331 -281.813374) (xy 59.878766 -281.852718)
			(xy 59.843273 -281.88681) (xy 59.80277 -281.914766) (xy 59.758308 -281.935864) (xy 59.711037 -281.949556)
			(xy 59.662182 -281.955488) (xy 59.613007 -281.953507) (xy 59.564788 -281.943663) (xy 59.518772 -281.926211)
			(xy 59.476151 -281.901604) (xy 59.43803 -281.870479) (xy 59.405395 -281.833642) (xy 59.379092 -281.792046)
			(xy 59.359801 -281.74677) (xy 59.348024 -281.698986) (xy 59.344064 -281.649932) (xy 59.005216 -281.649932)
			(xy 59.004721 -281.674539) (xy 58.996826 -281.723116) (xy 58.981242 -281.769797) (xy 58.958371 -281.813374)
			(xy 58.928806 -281.852718) (xy 58.893313 -281.88681) (xy 58.85281 -281.914766) (xy 58.808348 -281.935864)
			(xy 58.761077 -281.949556) (xy 58.712222 -281.955488) (xy 58.663047 -281.953507) (xy 58.614828 -281.943663)
			(xy 58.568812 -281.926211) (xy 58.526191 -281.901604) (xy 58.48807 -281.870479) (xy 58.455435 -281.833642)
			(xy 58.429132 -281.792046) (xy 58.409841 -281.74677) (xy 58.398064 -281.698986) (xy 58.394104 -281.649932)
			(xy 58.055256 -281.649932) (xy 58.054761 -281.674539) (xy 58.046866 -281.723116) (xy 58.031282 -281.769797)
			(xy 58.008411 -281.813374) (xy 57.978846 -281.852718) (xy 57.943353 -281.88681) (xy 57.90285 -281.914766)
			(xy 57.858388 -281.935864) (xy 57.811117 -281.949556) (xy 57.762262 -281.955488) (xy 57.713087 -281.953507)
			(xy 57.664868 -281.943663) (xy 57.618852 -281.926211) (xy 57.576231 -281.901604) (xy 57.53811 -281.870479)
			(xy 57.505475 -281.833642) (xy 57.479172 -281.792046) (xy 57.459881 -281.74677) (xy 57.448104 -281.698986)
			(xy 57.444144 -281.649932) (xy 57.105296 -281.649932) (xy 57.104801 -281.674539) (xy 57.096906 -281.723116)
			(xy 57.081322 -281.769797) (xy 57.058451 -281.813374) (xy 57.028886 -281.852718) (xy 56.993393 -281.88681)
			(xy 56.95289 -281.914766) (xy 56.908428 -281.935864) (xy 56.861157 -281.949556) (xy 56.812302 -281.955488)
			(xy 56.763127 -281.953507) (xy 56.714908 -281.943663) (xy 56.668892 -281.926211) (xy 56.626271 -281.901604)
			(xy 56.58815 -281.870479) (xy 56.555515 -281.833642) (xy 56.529212 -281.792046) (xy 56.509921 -281.74677)
			(xy 56.498144 -281.698986) (xy 56.494184 -281.649932) (xy 56.155082 -281.649932) (xy 56.154587 -281.674539)
			(xy 56.146692 -281.723116) (xy 56.131108 -281.769797) (xy 56.108237 -281.813374) (xy 56.078672 -281.852718)
			(xy 56.043179 -281.88681) (xy 56.002676 -281.914766) (xy 55.958214 -281.935864) (xy 55.910943 -281.949556)
			(xy 55.862088 -281.955488) (xy 55.812913 -281.953507) (xy 55.764694 -281.943663) (xy 55.718678 -281.926211)
			(xy 55.676057 -281.901604) (xy 55.637936 -281.870479) (xy 55.605301 -281.833642) (xy 55.578998 -281.792046)
			(xy 55.559707 -281.74677) (xy 55.54793 -281.698986) (xy 55.54397 -281.649932) (xy 55.205104 -281.649932)
			(xy 55.205551 -281.658163) (xy 55.200187 -281.707519) (xy 55.186908 -281.755358) (xy 55.166064 -281.800418)
			(xy 55.138205 -281.841513) (xy 55.104064 -281.877558) (xy 55.064542 -281.907606) (xy 55.020679 -281.930864)
			(xy 54.973631 -281.946718) (xy 54.924638 -281.954753) (xy 54.899814 -281.95524) (xy 54.885631 -281.955061)
			(xy 54.857391 -281.95239) (xy 54.843426 -281.949906) (xy 54.83098 -281.94762) (xy 54.807358 -281.954986)
			(xy 54.729888 -282.032456) (xy 54.722522 -282.056078) (xy 54.724808 -282.068524) (xy 54.727284 -282.08249)
			(xy 54.729956 -282.110729) (xy 54.730142 -282.124912) (xy 54.72962 -282.150167) (xy 54.721307 -282.199989)
			(xy 54.704906 -282.247763) (xy 54.680865 -282.292186) (xy 54.649841 -282.332046) (xy 54.612679 -282.366256)
			(xy 54.570393 -282.393882) (xy 54.524137 -282.414172) (xy 54.475172 -282.426572) (xy 54.424834 -282.430743)
			(xy 54.374496 -282.426572) (xy 54.325531 -282.414172) (xy 54.279275 -282.393882) (xy 54.236989 -282.366256)
			(xy 54.199827 -282.332046) (xy 54.168803 -282.292186) (xy 54.144762 -282.247763) (xy 54.128361 -282.199989)
			(xy 54.120048 -282.150167) (xy 54.119526 -282.124912) (xy 54.119704 -282.110729) (xy 54.122375 -282.082489)
			(xy 54.12486 -282.068524) (xy 54.127146 -282.056078) (xy 54.11978 -282.032456) (xy 54.04231 -281.954986)
			(xy 54.018688 -281.94762) (xy 54.006242 -281.949906) (xy 53.992277 -281.952387) (xy 53.964037 -281.955056)
			(xy 53.949854 -281.95524) (xy 53.925037 -281.954673) (xy 53.876058 -281.946635) (xy 53.829025 -281.93078)
			(xy 53.785177 -281.907525) (xy 53.745668 -281.877482) (xy 53.71154 -281.841444) (xy 53.683692 -281.800358)
			(xy 53.662857 -281.755309) (xy 53.649586 -281.707483) (xy 53.644226 -281.658139) (xy 53.305037 -281.658139)
			(xy 53.304707 -281.674539) (xy 53.296812 -281.723116) (xy 53.281228 -281.769797) (xy 53.258357 -281.813374)
			(xy 53.228792 -281.852718) (xy 53.193299 -281.88681) (xy 53.152796 -281.914766) (xy 53.108334 -281.935864)
			(xy 53.061063 -281.949556) (xy 53.012208 -281.955488) (xy 52.963033 -281.953507) (xy 52.914814 -281.943663)
			(xy 52.868798 -281.926211) (xy 52.826177 -281.901604) (xy 52.788056 -281.870479) (xy 52.755421 -281.833642)
			(xy 52.729118 -281.792046) (xy 52.709827 -281.74677) (xy 52.69805 -281.698986) (xy 52.69409 -281.649932)
			(xy 52.355242 -281.649932) (xy 52.354747 -281.674539) (xy 52.346852 -281.723116) (xy 52.331268 -281.769797)
			(xy 52.308397 -281.813374) (xy 52.278832 -281.852718) (xy 52.243339 -281.88681) (xy 52.202836 -281.914766)
			(xy 52.158374 -281.935864) (xy 52.111103 -281.949556) (xy 52.062248 -281.955488) (xy 52.013073 -281.953507)
			(xy 51.964854 -281.943663) (xy 51.918838 -281.926211) (xy 51.876217 -281.901604) (xy 51.838096 -281.870479)
			(xy 51.805461 -281.833642) (xy 51.779158 -281.792046) (xy 51.759867 -281.74677) (xy 51.74809 -281.698986)
			(xy 51.74413 -281.649932) (xy 51.405282 -281.649932) (xy 51.404787 -281.674539) (xy 51.396892 -281.723116)
			(xy 51.381308 -281.769797) (xy 51.358437 -281.813374) (xy 51.328872 -281.852718) (xy 51.293379 -281.88681)
			(xy 51.252876 -281.914766) (xy 51.208414 -281.935864) (xy 51.161143 -281.949556) (xy 51.112288 -281.955488)
			(xy 51.063113 -281.953507) (xy 51.014894 -281.943663) (xy 50.968878 -281.926211) (xy 50.926257 -281.901604)
			(xy 50.888136 -281.870479) (xy 50.855501 -281.833642) (xy 50.829198 -281.792046) (xy 50.809907 -281.74677)
			(xy 50.79813 -281.698986) (xy 50.79417 -281.649932) (xy 50.455068 -281.649932) (xy 50.454573 -281.674539)
			(xy 50.446678 -281.723116) (xy 50.431094 -281.769797) (xy 50.408223 -281.813374) (xy 50.378658 -281.852718)
			(xy 50.343165 -281.88681) (xy 50.302662 -281.914766) (xy 50.2582 -281.935864) (xy 50.210929 -281.949556)
			(xy 50.162074 -281.955488) (xy 50.112899 -281.953507) (xy 50.06468 -281.943663) (xy 50.018664 -281.926211)
			(xy 49.976043 -281.901604) (xy 49.937922 -281.870479) (xy 49.905287 -281.833642) (xy 49.878984 -281.792046)
			(xy 49.859693 -281.74677) (xy 49.847916 -281.698986) (xy 49.843956 -281.649932) (xy 49.505108 -281.649932)
			(xy 49.504613 -281.674539) (xy 49.496718 -281.723116) (xy 49.481134 -281.769797) (xy 49.458263 -281.813374)
			(xy 49.428698 -281.852718) (xy 49.393205 -281.88681) (xy 49.352702 -281.914766) (xy 49.30824 -281.935864)
			(xy 49.260969 -281.949556) (xy 49.212114 -281.955488) (xy 49.162939 -281.953507) (xy 49.11472 -281.943663)
			(xy 49.068704 -281.926211) (xy 49.026083 -281.901604) (xy 48.987962 -281.870479) (xy 48.955327 -281.833642)
			(xy 48.929024 -281.792046) (xy 48.909733 -281.74677) (xy 48.897956 -281.698986) (xy 48.893996 -281.649932)
			(xy 48.555148 -281.649932) (xy 48.554653 -281.674539) (xy 48.546758 -281.723116) (xy 48.531174 -281.769797)
			(xy 48.508303 -281.813374) (xy 48.478738 -281.852718) (xy 48.443245 -281.88681) (xy 48.402742 -281.914766)
			(xy 48.35828 -281.935864) (xy 48.311009 -281.949556) (xy 48.262154 -281.955488) (xy 48.212979 -281.953507)
			(xy 48.16476 -281.943663) (xy 48.118744 -281.926211) (xy 48.076123 -281.901604) (xy 48.038002 -281.870479)
			(xy 48.005367 -281.833642) (xy 47.979064 -281.792046) (xy 47.959773 -281.74677) (xy 47.947996 -281.698986)
			(xy 47.944036 -281.649932) (xy 47.605188 -281.649932) (xy 47.604693 -281.674539) (xy 47.596798 -281.723116)
			(xy 47.581214 -281.769797) (xy 47.558343 -281.813374) (xy 47.528778 -281.852718) (xy 47.493285 -281.88681)
			(xy 47.452782 -281.914766) (xy 47.40832 -281.935864) (xy 47.361049 -281.949556) (xy 47.312194 -281.955488)
			(xy 47.263019 -281.953507) (xy 47.2148 -281.943663) (xy 47.168784 -281.926211) (xy 47.126163 -281.901604)
			(xy 47.088042 -281.870479) (xy 47.055407 -281.833642) (xy 47.029104 -281.792046) (xy 47.009813 -281.74677)
			(xy 46.998036 -281.698986) (xy 46.994076 -281.649932) (xy 46.655228 -281.649932) (xy 46.654733 -281.674539)
			(xy 46.646838 -281.723116) (xy 46.631254 -281.769797) (xy 46.608383 -281.813374) (xy 46.578818 -281.852718)
			(xy 46.543325 -281.88681) (xy 46.502822 -281.914766) (xy 46.45836 -281.935864) (xy 46.411089 -281.949556)
			(xy 46.362234 -281.955488) (xy 46.313059 -281.953507) (xy 46.26484 -281.943663) (xy 46.218824 -281.926211)
			(xy 46.176203 -281.901604) (xy 46.138082 -281.870479) (xy 46.105447 -281.833642) (xy 46.079144 -281.792046)
			(xy 46.059853 -281.74677) (xy 46.048076 -281.698986) (xy 46.044116 -281.649932) (xy 45.705268 -281.649932)
			(xy 45.704773 -281.674539) (xy 45.696878 -281.723116) (xy 45.681294 -281.769797) (xy 45.658423 -281.813374)
			(xy 45.628858 -281.852718) (xy 45.593365 -281.88681) (xy 45.552862 -281.914766) (xy 45.5084 -281.935864)
			(xy 45.461129 -281.949556) (xy 45.412274 -281.955488) (xy 45.363099 -281.953507) (xy 45.31488 -281.943663)
			(xy 45.268864 -281.926211) (xy 45.226243 -281.901604) (xy 45.188122 -281.870479) (xy 45.155487 -281.833642)
			(xy 45.129184 -281.792046) (xy 45.109893 -281.74677) (xy 45.098116 -281.698986) (xy 45.094156 -281.649932)
			(xy 44.755006 -281.649932) (xy 44.755452 -281.658141) (xy 44.750091 -281.707497) (xy 44.736816 -281.755336)
			(xy 44.715976 -281.800397) (xy 44.688121 -281.841492) (xy 44.653984 -281.87754) (xy 44.614465 -281.907591)
			(xy 44.570606 -281.930852) (xy 44.52356 -281.946711) (xy 44.474569 -281.95475) (xy 44.449746 -281.95524)
			(xy 44.435563 -281.955056) (xy 44.407323 -281.952389) (xy 44.393358 -281.949906) (xy 44.379401 -281.947672)
			(xy 44.35126 -281.950261) (xy 44.324907 -281.960462) (xy 44.302357 -281.977494) (xy 44.285336 -282.000053)
			(xy 44.275149 -282.026412) (xy 44.272574 -282.054554) (xy 44.27474 -282.068524) (xy 44.277215 -282.08249)
			(xy 44.279888 -282.11073) (xy 44.280074 -282.124912) (xy 44.279609 -282.149731) (xy 44.271577 -282.198715)
			(xy 44.255726 -282.245754) (xy 44.232474 -282.28961) (xy 44.202434 -282.329126) (xy 44.166396 -282.363261)
			(xy 44.125311 -282.391117) (xy 44.08026 -282.41196) (xy 44.032432 -282.42524) (xy 43.983084 -282.430607)
			(xy 43.933519 -282.42792) (xy 43.885041 -282.41725) (xy 43.838928 -282.398878) (xy 43.796395 -282.373288)
			(xy 43.758561 -282.341154) (xy 43.726425 -282.303323) (xy 43.700832 -282.260792) (xy 43.682456 -282.21468)
			(xy 43.671783 -282.166203) (xy 43.669093 -282.116638) (xy 43.329948 -282.116638) (xy 43.330114 -282.124912)
			(xy 43.329619 -282.149519) (xy 43.321724 -282.198096) (xy 43.30614 -282.244777) (xy 43.283269 -282.288354)
			(xy 43.253704 -282.327698) (xy 43.218211 -282.36179) (xy 43.177708 -282.389746) (xy 43.133246 -282.410844)
			(xy 43.085975 -282.424536) (xy 43.03712 -282.430468) (xy 42.987945 -282.428487) (xy 42.939726 -282.418643)
			(xy 42.89371 -282.401191) (xy 42.851089 -282.376584) (xy 42.812968 -282.345459) (xy 42.780333 -282.308622)
			(xy 42.75403 -282.267026) (xy 42.734739 -282.22175) (xy 42.722962 -282.173966) (xy 42.719002 -282.124912)
			(xy 42.380154 -282.124912) (xy 42.379659 -282.149519) (xy 42.371764 -282.198096) (xy 42.35618 -282.244777)
			(xy 42.333309 -282.288354) (xy 42.303744 -282.327698) (xy 42.268251 -282.36179) (xy 42.227748 -282.389746)
			(xy 42.183286 -282.410844) (xy 42.136015 -282.424536) (xy 42.08716 -282.430468) (xy 42.037985 -282.428487)
			(xy 41.989766 -282.418643) (xy 41.94375 -282.401191) (xy 41.901129 -282.376584) (xy 41.863008 -282.345459)
			(xy 41.830373 -282.308622) (xy 41.80407 -282.267026) (xy 41.784779 -282.22175) (xy 41.773002 -282.173966)
			(xy 41.769042 -282.124912) (xy 41.430194 -282.124912) (xy 41.429699 -282.149519) (xy 41.421804 -282.198096)
			(xy 41.40622 -282.244777) (xy 41.383349 -282.288354) (xy 41.353784 -282.327698) (xy 41.318291 -282.36179)
			(xy 41.277788 -282.389746) (xy 41.233326 -282.410844) (xy 41.186055 -282.424536) (xy 41.1372 -282.430468)
			(xy 41.088025 -282.428487) (xy 41.039806 -282.418643) (xy 40.99379 -282.401191) (xy 40.951169 -282.376584)
			(xy 40.913048 -282.345459) (xy 40.880413 -282.308622) (xy 40.85411 -282.267026) (xy 40.834819 -282.22175)
			(xy 40.823042 -282.173966) (xy 40.819082 -282.124912) (xy 40.480234 -282.124912) (xy 40.479739 -282.149519)
			(xy 40.471844 -282.198096) (xy 40.45626 -282.244777) (xy 40.433389 -282.288354) (xy 40.403824 -282.327698)
			(xy 40.368331 -282.36179) (xy 40.327828 -282.389746) (xy 40.283366 -282.410844) (xy 40.236095 -282.424536)
			(xy 40.18724 -282.430468) (xy 40.138065 -282.428487) (xy 40.089846 -282.418643) (xy 40.04383 -282.401191)
			(xy 40.001209 -282.376584) (xy 39.963088 -282.345459) (xy 39.930453 -282.308622) (xy 39.90415 -282.267026)
			(xy 39.884859 -282.22175) (xy 39.873082 -282.173966) (xy 39.869122 -282.124912) (xy 39.530274 -282.124912)
			(xy 39.529779 -282.149519) (xy 39.521884 -282.198096) (xy 39.5063 -282.244777) (xy 39.483429 -282.288354)
			(xy 39.453864 -282.327698) (xy 39.418371 -282.36179) (xy 39.377868 -282.389746) (xy 39.333406 -282.410844)
			(xy 39.286135 -282.424536) (xy 39.23728 -282.430468) (xy 39.188105 -282.428487) (xy 39.139886 -282.418643)
			(xy 39.09387 -282.401191) (xy 39.051249 -282.376584) (xy 39.013128 -282.345459) (xy 38.980493 -282.308622)
			(xy 38.95419 -282.267026) (xy 38.934899 -282.22175) (xy 38.923122 -282.173966) (xy 38.919162 -282.124912)
			(xy 38.580314 -282.124912) (xy 38.579819 -282.149519) (xy 38.571924 -282.198096) (xy 38.55634 -282.244777)
			(xy 38.533469 -282.288354) (xy 38.503904 -282.327698) (xy 38.468411 -282.36179) (xy 38.427908 -282.389746)
			(xy 38.383446 -282.410844) (xy 38.336175 -282.424536) (xy 38.28732 -282.430468) (xy 38.238145 -282.428487)
			(xy 38.189926 -282.418643) (xy 38.14391 -282.401191) (xy 38.101289 -282.376584) (xy 38.063168 -282.345459)
			(xy 38.030533 -282.308622) (xy 38.00423 -282.267026) (xy 37.984939 -282.22175) (xy 37.973162 -282.173966)
			(xy 37.969202 -282.124912) (xy 37.6301 -282.124912) (xy 37.629605 -282.149519) (xy 37.62171 -282.198096)
			(xy 37.606126 -282.244777) (xy 37.583255 -282.288354) (xy 37.55369 -282.327698) (xy 37.518197 -282.36179)
			(xy 37.477694 -282.389746) (xy 37.433232 -282.410844) (xy 37.385961 -282.424536) (xy 37.337106 -282.430468)
			(xy 37.287931 -282.428487) (xy 37.239712 -282.418643) (xy 37.193696 -282.401191) (xy 37.151075 -282.376584)
			(xy 37.112954 -282.345459) (xy 37.080319 -282.308622) (xy 37.054016 -282.267026) (xy 37.034725 -282.22175)
			(xy 37.022948 -282.173966) (xy 37.018988 -282.124912) (xy 36.68014 -282.124912) (xy 36.679645 -282.149519)
			(xy 36.67175 -282.198096) (xy 36.656166 -282.244777) (xy 36.633295 -282.288354) (xy 36.60373 -282.327698)
			(xy 36.568237 -282.36179) (xy 36.527734 -282.389746) (xy 36.483272 -282.410844) (xy 36.436001 -282.424536)
			(xy 36.387146 -282.430468) (xy 36.337971 -282.428487) (xy 36.289752 -282.418643) (xy 36.243736 -282.401191)
			(xy 36.201115 -282.376584) (xy 36.162994 -282.345459) (xy 36.130359 -282.308622) (xy 36.104056 -282.267026)
			(xy 36.084765 -282.22175) (xy 36.072988 -282.173966) (xy 36.069028 -282.124912) (xy 34.39033 -282.124912)
			(xy 34.39033 -283.074872) (xy 36.069028 -283.074872) (xy 36.072988 -283.025818) (xy 36.084765 -282.978034)
			(xy 36.104056 -282.932758) (xy 36.130359 -282.891162) (xy 36.162994 -282.854325) (xy 36.201115 -282.8232)
			(xy 36.243736 -282.798593) (xy 36.289752 -282.781141) (xy 36.337971 -282.771297) (xy 36.387146 -282.769316)
			(xy 36.436001 -282.775248) (xy 36.483272 -282.78894) (xy 36.527734 -282.810038) (xy 36.568237 -282.837994)
			(xy 36.60373 -282.872086) (xy 36.633295 -282.91143) (xy 36.656166 -282.955007) (xy 36.67175 -283.001688)
			(xy 36.679645 -283.050265) (xy 36.68014 -283.074872) (xy 37.018988 -283.074872) (xy 37.022948 -283.025818)
			(xy 37.034725 -282.978034) (xy 37.054016 -282.932758) (xy 37.080319 -282.891162) (xy 37.112954 -282.854325)
			(xy 37.151075 -282.8232) (xy 37.193696 -282.798593) (xy 37.239712 -282.781141) (xy 37.287931 -282.771297)
			(xy 37.337106 -282.769316) (xy 37.385961 -282.775248) (xy 37.433232 -282.78894) (xy 37.477694 -282.810038)
			(xy 37.518197 -282.837994) (xy 37.55369 -282.872086) (xy 37.583255 -282.91143) (xy 37.606126 -282.955007)
			(xy 37.62171 -283.001688) (xy 37.629605 -283.050265) (xy 37.6301 -283.074872) (xy 37.969202 -283.074872)
			(xy 37.973162 -283.025818) (xy 37.984939 -282.978034) (xy 38.00423 -282.932758) (xy 38.030533 -282.891162)
			(xy 38.063168 -282.854325) (xy 38.101289 -282.8232) (xy 38.14391 -282.798593) (xy 38.189926 -282.781141)
			(xy 38.238145 -282.771297) (xy 38.28732 -282.769316) (xy 38.336175 -282.775248) (xy 38.383446 -282.78894)
			(xy 38.427908 -282.810038) (xy 38.468411 -282.837994) (xy 38.503904 -282.872086) (xy 38.533469 -282.91143)
			(xy 38.55634 -282.955007) (xy 38.571924 -283.001688) (xy 38.579819 -283.050265) (xy 38.580314 -283.074872)
			(xy 38.919162 -283.074872) (xy 38.923122 -283.025818) (xy 38.934899 -282.978034) (xy 38.95419 -282.932758)
			(xy 38.980493 -282.891162) (xy 39.013128 -282.854325) (xy 39.051249 -282.8232) (xy 39.09387 -282.798593)
			(xy 39.139886 -282.781141) (xy 39.188105 -282.771297) (xy 39.23728 -282.769316) (xy 39.286135 -282.775248)
			(xy 39.333406 -282.78894) (xy 39.377868 -282.810038) (xy 39.418371 -282.837994) (xy 39.453864 -282.872086)
			(xy 39.483429 -282.91143) (xy 39.5063 -282.955007) (xy 39.521884 -283.001688) (xy 39.529779 -283.050265)
			(xy 39.530274 -283.074872) (xy 39.869122 -283.074872) (xy 39.873082 -283.025818) (xy 39.884859 -282.978034)
			(xy 39.90415 -282.932758) (xy 39.930453 -282.891162) (xy 39.963088 -282.854325) (xy 40.001209 -282.8232)
			(xy 40.04383 -282.798593) (xy 40.089846 -282.781141) (xy 40.138065 -282.771297) (xy 40.18724 -282.769316)
			(xy 40.236095 -282.775248) (xy 40.283366 -282.78894) (xy 40.327828 -282.810038) (xy 40.368331 -282.837994)
			(xy 40.403824 -282.872086) (xy 40.433389 -282.91143) (xy 40.45626 -282.955007) (xy 40.471844 -283.001688)
			(xy 40.479739 -283.050265) (xy 40.480234 -283.074872) (xy 40.819082 -283.074872) (xy 40.823042 -283.025818)
			(xy 40.834819 -282.978034) (xy 40.85411 -282.932758) (xy 40.880413 -282.891162) (xy 40.913048 -282.854325)
			(xy 40.951169 -282.8232) (xy 40.99379 -282.798593) (xy 41.039806 -282.781141) (xy 41.088025 -282.771297)
			(xy 41.1372 -282.769316) (xy 41.186055 -282.775248) (xy 41.233326 -282.78894) (xy 41.277788 -282.810038)
			(xy 41.318291 -282.837994) (xy 41.353784 -282.872086) (xy 41.383349 -282.91143) (xy 41.40622 -282.955007)
			(xy 41.421804 -283.001688) (xy 41.429699 -283.050265) (xy 41.430194 -283.074872) (xy 41.769042 -283.074872)
			(xy 41.773002 -283.025818) (xy 41.784779 -282.978034) (xy 41.80407 -282.932758) (xy 41.830373 -282.891162)
			(xy 41.863008 -282.854325) (xy 41.901129 -282.8232) (xy 41.94375 -282.798593) (xy 41.989766 -282.781141)
			(xy 42.037985 -282.771297) (xy 42.08716 -282.769316) (xy 42.136015 -282.775248) (xy 42.183286 -282.78894)
			(xy 42.227748 -282.810038) (xy 42.268251 -282.837994) (xy 42.303744 -282.872086) (xy 42.333309 -282.91143)
			(xy 42.35618 -282.955007) (xy 42.371764 -283.001688) (xy 42.379659 -283.050265) (xy 42.379988 -283.06664)
			(xy 44.619253 -283.06664) (xy 44.624617 -283.017284) (xy 44.637895 -282.969446) (xy 44.658738 -282.924387)
			(xy 44.686596 -282.883293) (xy 44.720735 -282.847248) (xy 44.760256 -282.8172) (xy 44.804118 -282.793942)
			(xy 44.851165 -282.778087) (xy 44.900157 -282.770052) (xy 44.92498 -282.769564) (xy 44.939163 -282.769744)
			(xy 44.967403 -282.772414) (xy 44.981368 -282.774898) (xy 44.993814 -282.777184) (xy 45.017436 -282.769818)
			(xy 45.094906 -282.692348) (xy 45.102272 -282.668726) (xy 45.099986 -282.65628) (xy 45.097511 -282.642314)
			(xy 45.094838 -282.614074) (xy 45.094652 -282.599892) (xy 45.095174 -282.574637) (xy 45.103487 -282.524815)
			(xy 45.119888 -282.477041) (xy 45.143929 -282.432618) (xy 45.174953 -282.392758) (xy 45.212115 -282.358548)
			(xy 45.254401 -282.330922) (xy 45.300657 -282.310632) (xy 45.349622 -282.298232) (xy 45.39996 -282.294061)
			(xy 45.450298 -282.298232) (xy 45.499263 -282.310632) (xy 45.545519 -282.330922) (xy 45.587805 -282.358548)
			(xy 45.624967 -282.392758) (xy 45.655991 -282.432618) (xy 45.680032 -282.477041) (xy 45.696433 -282.524815)
			(xy 45.704746 -282.574637) (xy 45.705268 -282.599892) (xy 45.705091 -282.614075) (xy 45.702419 -282.642315)
			(xy 45.699934 -282.65628) (xy 45.697648 -282.668726) (xy 45.705014 -282.692348) (xy 45.782484 -282.769818)
			(xy 45.806106 -282.777184) (xy 45.818552 -282.774898) (xy 45.832517 -282.772418) (xy 45.860757 -282.769749)
			(xy 45.87494 -282.769564) (xy 45.889123 -282.769736) (xy 45.917363 -282.772411) (xy 45.931328 -282.774898)
			(xy 45.943774 -282.777184) (xy 45.967396 -282.769818) (xy 46.044866 -282.692348) (xy 46.052232 -282.668726)
			(xy 46.049946 -282.65628) (xy 46.047471 -282.642314) (xy 46.044798 -282.614074) (xy 46.044612 -282.599892)
			(xy 46.045134 -282.574637) (xy 46.053447 -282.524815) (xy 46.069848 -282.477041) (xy 46.093889 -282.432618)
			(xy 46.124913 -282.392758) (xy 46.162075 -282.358548) (xy 46.204361 -282.330922) (xy 46.250617 -282.310632)
			(xy 46.299582 -282.298232) (xy 46.34992 -282.294061) (xy 46.400258 -282.298232) (xy 46.449223 -282.310632)
			(xy 46.495479 -282.330922) (xy 46.537765 -282.358548) (xy 46.574927 -282.392758) (xy 46.605951 -282.432618)
			(xy 46.629992 -282.477041) (xy 46.646393 -282.524815) (xy 46.654706 -282.574637) (xy 46.655228 -282.599892)
			(xy 73.593972 -282.599892) (xy 73.597932 -282.550838) (xy 73.609709 -282.503054) (xy 73.629 -282.457778)
			(xy 73.655303 -282.416182) (xy 73.687938 -282.379345) (xy 73.726059 -282.34822) (xy 73.76868 -282.323613)
			(xy 73.814696 -282.306161) (xy 73.862915 -282.296317) (xy 73.91209 -282.294336) (xy 73.960945 -282.300268)
			(xy 74.008216 -282.31396) (xy 74.052678 -282.335058) (xy 74.093181 -282.363014) (xy 74.128674 -282.397106)
			(xy 74.158239 -282.43645) (xy 74.18111 -282.480027) (xy 74.196694 -282.526708) (xy 74.204589 -282.575285)
			(xy 74.205084 -282.599892) (xy 74.543932 -282.599892) (xy 74.547892 -282.550838) (xy 74.559669 -282.503054)
			(xy 74.57896 -282.457778) (xy 74.605263 -282.416182) (xy 74.637898 -282.379345) (xy 74.676019 -282.34822)
			(xy 74.71864 -282.323613) (xy 74.764656 -282.306161) (xy 74.812875 -282.296317) (xy 74.86205 -282.294336)
			(xy 74.910905 -282.300268) (xy 74.958176 -282.31396) (xy 75.002638 -282.335058) (xy 75.043141 -282.363014)
			(xy 75.078634 -282.397106) (xy 75.108199 -282.43645) (xy 75.13107 -282.480027) (xy 75.146654 -282.526708)
			(xy 75.154549 -282.575285) (xy 75.155044 -282.599892) (xy 75.494146 -282.599892) (xy 75.498106 -282.550838)
			(xy 75.509883 -282.503054) (xy 75.529174 -282.457778) (xy 75.555477 -282.416182) (xy 75.588112 -282.379345)
			(xy 75.626233 -282.34822) (xy 75.668854 -282.323613) (xy 75.71487 -282.306161) (xy 75.763089 -282.296317)
			(xy 75.812264 -282.294336) (xy 75.861119 -282.300268) (xy 75.90839 -282.31396) (xy 75.952852 -282.335058)
			(xy 75.993355 -282.363014) (xy 76.028848 -282.397106) (xy 76.058413 -282.43645) (xy 76.081284 -282.480027)
			(xy 76.096868 -282.526708) (xy 76.104763 -282.575285) (xy 76.105258 -282.599892) (xy 76.104763 -282.624499)
			(xy 76.096868 -282.673076) (xy 76.081284 -282.719757) (xy 76.058413 -282.763334) (xy 76.028848 -282.802678)
			(xy 75.993355 -282.83677) (xy 75.952852 -282.864726) (xy 75.90839 -282.885824) (xy 75.861119 -282.899516)
			(xy 75.812264 -282.905448) (xy 75.763089 -282.903467) (xy 75.71487 -282.893623) (xy 75.668854 -282.876171)
			(xy 75.626233 -282.851564) (xy 75.588112 -282.820439) (xy 75.555477 -282.783602) (xy 75.529174 -282.742006)
			(xy 75.509883 -282.69673) (xy 75.498106 -282.648946) (xy 75.494146 -282.599892) (xy 75.155044 -282.599892)
			(xy 75.154549 -282.624499) (xy 75.146654 -282.673076) (xy 75.13107 -282.719757) (xy 75.108199 -282.763334)
			(xy 75.078634 -282.802678) (xy 75.043141 -282.83677) (xy 75.002638 -282.864726) (xy 74.958176 -282.885824)
			(xy 74.910905 -282.899516) (xy 74.86205 -282.905448) (xy 74.812875 -282.903467) (xy 74.764656 -282.893623)
			(xy 74.71864 -282.876171) (xy 74.676019 -282.851564) (xy 74.637898 -282.820439) (xy 74.605263 -282.783602)
			(xy 74.57896 -282.742006) (xy 74.559669 -282.69673) (xy 74.547892 -282.648946) (xy 74.543932 -282.599892)
			(xy 74.205084 -282.599892) (xy 74.204589 -282.624499) (xy 74.196694 -282.673076) (xy 74.18111 -282.719757)
			(xy 74.158239 -282.763334) (xy 74.128674 -282.802678) (xy 74.093181 -282.83677) (xy 74.052678 -282.864726)
			(xy 74.008216 -282.885824) (xy 73.960945 -282.899516) (xy 73.91209 -282.905448) (xy 73.862915 -282.903467)
			(xy 73.814696 -282.893623) (xy 73.76868 -282.876171) (xy 73.726059 -282.851564) (xy 73.687938 -282.820439)
			(xy 73.655303 -282.783602) (xy 73.629 -282.742006) (xy 73.609709 -282.69673) (xy 73.597932 -282.648946)
			(xy 73.593972 -282.599892) (xy 46.655228 -282.599892) (xy 46.65505 -282.614075) (xy 46.652379 -282.642315)
			(xy 46.649894 -282.65628) (xy 46.647608 -282.668726) (xy 46.654974 -282.692348) (xy 46.732444 -282.769818)
			(xy 46.756066 -282.777184) (xy 46.768512 -282.774898) (xy 46.782478 -282.772424) (xy 46.810718 -282.769751)
			(xy 46.8249 -282.769564) (xy 46.849721 -282.770078) (xy 46.89871 -282.778109) (xy 46.945754 -282.793961)
			(xy 46.989614 -282.817214) (xy 47.029133 -282.847257) (xy 47.063272 -282.883298) (xy 47.09113 -282.924387)
			(xy 47.111974 -282.969442) (xy 47.125253 -283.017276) (xy 47.130619 -283.066627) (xy 47.130172 -283.074872)
			(xy 47.469056 -283.074872) (xy 47.473016 -283.025818) (xy 47.484793 -282.978034) (xy 47.504084 -282.932758)
			(xy 47.530387 -282.891162) (xy 47.563022 -282.854325) (xy 47.601143 -282.8232) (xy 47.643764 -282.798593)
			(xy 47.68978 -282.781141) (xy 47.737999 -282.771297) (xy 47.787174 -282.769316) (xy 47.836029 -282.775248)
			(xy 47.8833 -282.78894) (xy 47.927762 -282.810038) (xy 47.968265 -282.837994) (xy 48.003758 -282.872086)
			(xy 48.033323 -282.91143) (xy 48.056194 -282.955007) (xy 48.071778 -283.001688) (xy 48.079673 -283.050265)
			(xy 48.080168 -283.074872) (xy 48.419016 -283.074872) (xy 48.422976 -283.025818) (xy 48.434753 -282.978034)
			(xy 48.454044 -282.932758) (xy 48.480347 -282.891162) (xy 48.512982 -282.854325) (xy 48.551103 -282.8232)
			(xy 48.593724 -282.798593) (xy 48.63974 -282.781141) (xy 48.687959 -282.771297) (xy 48.737134 -282.769316)
			(xy 48.785989 -282.775248) (xy 48.83326 -282.78894) (xy 48.877722 -282.810038) (xy 48.918225 -282.837994)
			(xy 48.953718 -282.872086) (xy 48.983283 -282.91143) (xy 49.006154 -282.955007) (xy 49.021738 -283.001688)
			(xy 49.029633 -283.050265) (xy 49.030128 -283.074872) (xy 49.368976 -283.074872) (xy 49.372936 -283.025818)
			(xy 49.384713 -282.978034) (xy 49.404004 -282.932758) (xy 49.430307 -282.891162) (xy 49.462942 -282.854325)
			(xy 49.501063 -282.8232) (xy 49.543684 -282.798593) (xy 49.5897 -282.781141) (xy 49.637919 -282.771297)
			(xy 49.687094 -282.769316) (xy 49.735949 -282.775248) (xy 49.78322 -282.78894) (xy 49.827682 -282.810038)
			(xy 49.868185 -282.837994) (xy 49.903678 -282.872086) (xy 49.933243 -282.91143) (xy 49.956114 -282.955007)
			(xy 49.971698 -283.001688) (xy 49.979593 -283.050265) (xy 49.980088 -283.074872) (xy 50.31919 -283.074872)
			(xy 50.32315 -283.025818) (xy 50.334927 -282.978034) (xy 50.354218 -282.932758) (xy 50.380521 -282.891162)
			(xy 50.413156 -282.854325) (xy 50.451277 -282.8232) (xy 50.493898 -282.798593) (xy 50.539914 -282.781141)
			(xy 50.588133 -282.771297) (xy 50.637308 -282.769316) (xy 50.686163 -282.775248) (xy 50.733434 -282.78894)
			(xy 50.777896 -282.810038) (xy 50.818399 -282.837994) (xy 50.853892 -282.872086) (xy 50.883457 -282.91143)
			(xy 50.906328 -282.955007) (xy 50.921912 -283.001688) (xy 50.929807 -283.050265) (xy 50.930302 -283.074872)
			(xy 51.26915 -283.074872) (xy 51.27311 -283.025818) (xy 51.284887 -282.978034) (xy 51.304178 -282.932758)
			(xy 51.330481 -282.891162) (xy 51.363116 -282.854325) (xy 51.401237 -282.8232) (xy 51.443858 -282.798593)
			(xy 51.489874 -282.781141) (xy 51.538093 -282.771297) (xy 51.587268 -282.769316) (xy 51.636123 -282.775248)
			(xy 51.683394 -282.78894) (xy 51.727856 -282.810038) (xy 51.768359 -282.837994) (xy 51.803852 -282.872086)
			(xy 51.833417 -282.91143) (xy 51.856288 -282.955007) (xy 51.871872 -283.001688) (xy 51.879767 -283.050265)
			(xy 51.880262 -283.074872) (xy 52.21911 -283.074872) (xy 52.22307 -283.025818) (xy 52.234847 -282.978034)
			(xy 52.254138 -282.932758) (xy 52.280441 -282.891162) (xy 52.313076 -282.854325) (xy 52.351197 -282.8232)
			(xy 52.393818 -282.798593) (xy 52.439834 -282.781141) (xy 52.488053 -282.771297) (xy 52.537228 -282.769316)
			(xy 52.586083 -282.775248) (xy 52.633354 -282.78894) (xy 52.677816 -282.810038) (xy 52.718319 -282.837994)
			(xy 52.753812 -282.872086) (xy 52.783377 -282.91143) (xy 52.806248 -282.955007) (xy 52.821832 -283.001688)
			(xy 52.829727 -283.050265) (xy 52.830222 -283.074872) (xy 53.16907 -283.074872) (xy 53.17303 -283.025818)
			(xy 53.184807 -282.978034) (xy 53.204098 -282.932758) (xy 53.230401 -282.891162) (xy 53.263036 -282.854325)
			(xy 53.301157 -282.8232) (xy 53.343778 -282.798593) (xy 53.389794 -282.781141) (xy 53.438013 -282.771297)
			(xy 53.487188 -282.769316) (xy 53.536043 -282.775248) (xy 53.583314 -282.78894) (xy 53.627776 -282.810038)
			(xy 53.668279 -282.837994) (xy 53.703772 -282.872086) (xy 53.733337 -282.91143) (xy 53.756208 -282.955007)
			(xy 53.771792 -283.001688) (xy 53.779687 -283.050265) (xy 53.780182 -283.074872) (xy 54.11903 -283.074872)
			(xy 54.12299 -283.025818) (xy 54.134767 -282.978034) (xy 54.154058 -282.932758) (xy 54.180361 -282.891162)
			(xy 54.212996 -282.854325) (xy 54.251117 -282.8232) (xy 54.293738 -282.798593) (xy 54.339754 -282.781141)
			(xy 54.387973 -282.771297) (xy 54.437148 -282.769316) (xy 54.486003 -282.775248) (xy 54.533274 -282.78894)
			(xy 54.577736 -282.810038) (xy 54.618239 -282.837994) (xy 54.653732 -282.872086) (xy 54.683297 -282.91143)
			(xy 54.706168 -282.955007) (xy 54.721752 -283.001688) (xy 54.729647 -283.050265) (xy 54.730142 -283.074872)
			(xy 55.06899 -283.074872) (xy 55.07295 -283.025818) (xy 55.084727 -282.978034) (xy 55.104018 -282.932758)
			(xy 55.130321 -282.891162) (xy 55.162956 -282.854325) (xy 55.201077 -282.8232) (xy 55.243698 -282.798593)
			(xy 55.289714 -282.781141) (xy 55.337933 -282.771297) (xy 55.387108 -282.769316) (xy 55.435963 -282.775248)
			(xy 55.483234 -282.78894) (xy 55.527696 -282.810038) (xy 55.568199 -282.837994) (xy 55.603692 -282.872086)
			(xy 55.633257 -282.91143) (xy 55.656128 -282.955007) (xy 55.671712 -283.001688) (xy 55.679607 -283.050265)
			(xy 55.680102 -283.074872) (xy 56.019204 -283.074872) (xy 56.023164 -283.025818) (xy 56.034941 -282.978034)
			(xy 56.054232 -282.932758) (xy 56.080535 -282.891162) (xy 56.11317 -282.854325) (xy 56.151291 -282.8232)
			(xy 56.193912 -282.798593) (xy 56.239928 -282.781141) (xy 56.288147 -282.771297) (xy 56.337322 -282.769316)
			(xy 56.386177 -282.775248) (xy 56.433448 -282.78894) (xy 56.47791 -282.810038) (xy 56.518413 -282.837994)
			(xy 56.553906 -282.872086) (xy 56.583471 -282.91143) (xy 56.606342 -282.955007) (xy 56.621926 -283.001688)
			(xy 56.629821 -283.050265) (xy 56.630316 -283.074872) (xy 56.969164 -283.074872) (xy 56.973124 -283.025818)
			(xy 56.984901 -282.978034) (xy 57.004192 -282.932758) (xy 57.030495 -282.891162) (xy 57.06313 -282.854325)
			(xy 57.101251 -282.8232) (xy 57.143872 -282.798593) (xy 57.189888 -282.781141) (xy 57.238107 -282.771297)
			(xy 57.287282 -282.769316) (xy 57.336137 -282.775248) (xy 57.383408 -282.78894) (xy 57.42787 -282.810038)
			(xy 57.468373 -282.837994) (xy 57.503866 -282.872086) (xy 57.533431 -282.91143) (xy 57.556302 -282.955007)
			(xy 57.571886 -283.001688) (xy 57.579781 -283.050265) (xy 57.580276 -283.074872) (xy 57.919124 -283.074872)
			(xy 57.923084 -283.025818) (xy 57.934861 -282.978034) (xy 57.954152 -282.932758) (xy 57.980455 -282.891162)
			(xy 58.01309 -282.854325) (xy 58.051211 -282.8232) (xy 58.093832 -282.798593) (xy 58.139848 -282.781141)
			(xy 58.188067 -282.771297) (xy 58.237242 -282.769316) (xy 58.286097 -282.775248) (xy 58.333368 -282.78894)
			(xy 58.37783 -282.810038) (xy 58.418333 -282.837994) (xy 58.453826 -282.872086) (xy 58.483391 -282.91143)
			(xy 58.506262 -282.955007) (xy 58.521846 -283.001688) (xy 58.529741 -283.050265) (xy 58.530236 -283.074872)
			(xy 59.819044 -283.074872) (xy 59.823004 -283.025818) (xy 59.834781 -282.978034) (xy 59.854072 -282.932758)
			(xy 59.880375 -282.891162) (xy 59.91301 -282.854325) (xy 59.951131 -282.8232) (xy 59.993752 -282.798593)
			(xy 60.039768 -282.781141) (xy 60.087987 -282.771297) (xy 60.137162 -282.769316) (xy 60.186017 -282.775248)
			(xy 60.233288 -282.78894) (xy 60.27775 -282.810038) (xy 60.318253 -282.837994) (xy 60.353746 -282.872086)
			(xy 60.383311 -282.91143) (xy 60.406182 -282.955007) (xy 60.421766 -283.001688) (xy 60.429661 -283.050265)
			(xy 60.430156 -283.074872) (xy 60.769004 -283.074872) (xy 60.772964 -283.025818) (xy 60.784741 -282.978034)
			(xy 60.804032 -282.932758) (xy 60.830335 -282.891162) (xy 60.86297 -282.854325) (xy 60.901091 -282.8232)
			(xy 60.943712 -282.798593) (xy 60.989728 -282.781141) (xy 61.037947 -282.771297) (xy 61.087122 -282.769316)
			(xy 61.135977 -282.775248) (xy 61.183248 -282.78894) (xy 61.22771 -282.810038) (xy 61.268213 -282.837994)
			(xy 61.303706 -282.872086) (xy 61.333271 -282.91143) (xy 61.356142 -282.955007) (xy 61.371726 -283.001688)
			(xy 61.379621 -283.050265) (xy 61.380116 -283.074872) (xy 61.718964 -283.074872) (xy 61.722924 -283.025818)
			(xy 61.734701 -282.978034) (xy 61.753992 -282.932758) (xy 61.780295 -282.891162) (xy 61.81293 -282.854325)
			(xy 61.851051 -282.8232) (xy 61.893672 -282.798593) (xy 61.939688 -282.781141) (xy 61.987907 -282.771297)
			(xy 62.037082 -282.769316) (xy 62.085937 -282.775248) (xy 62.133208 -282.78894) (xy 62.17767 -282.810038)
			(xy 62.218173 -282.837994) (xy 62.253666 -282.872086) (xy 62.283231 -282.91143) (xy 62.306102 -282.955007)
			(xy 62.321686 -283.001688) (xy 62.329581 -283.050265) (xy 62.330076 -283.074872) (xy 62.669178 -283.074872)
			(xy 62.673138 -283.025818) (xy 62.684915 -282.978034) (xy 62.704206 -282.932758) (xy 62.730509 -282.891162)
			(xy 62.763144 -282.854325) (xy 62.801265 -282.8232) (xy 62.843886 -282.798593) (xy 62.889902 -282.781141)
			(xy 62.938121 -282.771297) (xy 62.987296 -282.769316) (xy 63.036151 -282.775248) (xy 63.083422 -282.78894)
			(xy 63.127884 -282.810038) (xy 63.168387 -282.837994) (xy 63.20388 -282.872086) (xy 63.233445 -282.91143)
			(xy 63.256316 -282.955007) (xy 63.2719 -283.001688) (xy 63.279795 -283.050265) (xy 63.28029 -283.074872)
			(xy 63.619138 -283.074872) (xy 63.623098 -283.025818) (xy 63.634875 -282.978034) (xy 63.654166 -282.932758)
			(xy 63.680469 -282.891162) (xy 63.713104 -282.854325) (xy 63.751225 -282.8232) (xy 63.793846 -282.798593)
			(xy 63.839862 -282.781141) (xy 63.888081 -282.771297) (xy 63.937256 -282.769316) (xy 63.986111 -282.775248)
			(xy 64.033382 -282.78894) (xy 64.077844 -282.810038) (xy 64.118347 -282.837994) (xy 64.15384 -282.872086)
			(xy 64.183405 -282.91143) (xy 64.206276 -282.955007) (xy 64.22186 -283.001688) (xy 64.229755 -283.050265)
			(xy 64.23025 -283.074872) (xy 64.569098 -283.074872) (xy 64.573058 -283.025818) (xy 64.584835 -282.978034)
			(xy 64.604126 -282.932758) (xy 64.630429 -282.891162) (xy 64.663064 -282.854325) (xy 64.701185 -282.8232)
			(xy 64.743806 -282.798593) (xy 64.789822 -282.781141) (xy 64.838041 -282.771297) (xy 64.887216 -282.769316)
			(xy 64.936071 -282.775248) (xy 64.983342 -282.78894) (xy 65.027804 -282.810038) (xy 65.068307 -282.837994)
			(xy 65.1038 -282.872086) (xy 65.133365 -282.91143) (xy 65.156236 -282.955007) (xy 65.17182 -283.001688)
			(xy 65.179715 -283.050265) (xy 65.18021 -283.074872) (xy 65.519058 -283.074872) (xy 65.523018 -283.025818)
			(xy 65.534795 -282.978034) (xy 65.554086 -282.932758) (xy 65.580389 -282.891162) (xy 65.613024 -282.854325)
			(xy 65.651145 -282.8232) (xy 65.693766 -282.798593) (xy 65.739782 -282.781141) (xy 65.788001 -282.771297)
			(xy 65.837176 -282.769316) (xy 65.886031 -282.775248) (xy 65.933302 -282.78894) (xy 65.977764 -282.810038)
			(xy 66.018267 -282.837994) (xy 66.05376 -282.872086) (xy 66.083325 -282.91143) (xy 66.106196 -282.955007)
			(xy 66.12178 -283.001688) (xy 66.129675 -283.050265) (xy 66.13017 -283.074872) (xy 66.469018 -283.074872)
			(xy 66.472978 -283.025818) (xy 66.484755 -282.978034) (xy 66.504046 -282.932758) (xy 66.530349 -282.891162)
			(xy 66.562984 -282.854325) (xy 66.601105 -282.8232) (xy 66.643726 -282.798593) (xy 66.689742 -282.781141)
			(xy 66.737961 -282.771297) (xy 66.787136 -282.769316) (xy 66.835991 -282.775248) (xy 66.883262 -282.78894)
			(xy 66.927724 -282.810038) (xy 66.968227 -282.837994) (xy 67.00372 -282.872086) (xy 67.033285 -282.91143)
			(xy 67.056156 -282.955007) (xy 67.07174 -283.001688) (xy 67.079635 -283.050265) (xy 67.08013 -283.074872)
			(xy 68.368938 -283.074872) (xy 68.372898 -283.025818) (xy 68.384675 -282.978034) (xy 68.403966 -282.932758)
			(xy 68.430269 -282.891162) (xy 68.462904 -282.854325) (xy 68.501025 -282.8232) (xy 68.543646 -282.798593)
			(xy 68.589662 -282.781141) (xy 68.637881 -282.771297) (xy 68.687056 -282.769316) (xy 68.735911 -282.775248)
			(xy 68.783182 -282.78894) (xy 68.827644 -282.810038) (xy 68.868147 -282.837994) (xy 68.90364 -282.872086)
			(xy 68.933205 -282.91143) (xy 68.956076 -282.955007) (xy 68.97166 -283.001688) (xy 68.979555 -283.050265)
			(xy 68.98005 -283.074872) (xy 69.319152 -283.074872) (xy 69.323112 -283.025818) (xy 69.334889 -282.978034)
			(xy 69.35418 -282.932758) (xy 69.380483 -282.891162) (xy 69.413118 -282.854325) (xy 69.451239 -282.8232)
			(xy 69.49386 -282.798593) (xy 69.539876 -282.781141) (xy 69.588095 -282.771297) (xy 69.63727 -282.769316)
			(xy 69.686125 -282.775248) (xy 69.733396 -282.78894) (xy 69.777858 -282.810038) (xy 69.818361 -282.837994)
			(xy 69.853854 -282.872086) (xy 69.883419 -282.91143) (xy 69.90629 -282.955007) (xy 69.921874 -283.001688)
			(xy 69.929769 -283.050265) (xy 69.930264 -283.074872) (xy 70.269112 -283.074872) (xy 70.273072 -283.025818)
			(xy 70.284849 -282.978034) (xy 70.30414 -282.932758) (xy 70.330443 -282.891162) (xy 70.363078 -282.854325)
			(xy 70.401199 -282.8232) (xy 70.44382 -282.798593) (xy 70.489836 -282.781141) (xy 70.538055 -282.771297)
			(xy 70.58723 -282.769316) (xy 70.636085 -282.775248) (xy 70.683356 -282.78894) (xy 70.727818 -282.810038)
			(xy 70.768321 -282.837994) (xy 70.803814 -282.872086) (xy 70.833379 -282.91143) (xy 70.85625 -282.955007)
			(xy 70.871834 -283.001688) (xy 70.879729 -283.050265) (xy 70.880224 -283.074872) (xy 71.219072 -283.074872)
			(xy 71.223032 -283.025818) (xy 71.234809 -282.978034) (xy 71.2541 -282.932758) (xy 71.280403 -282.891162)
			(xy 71.313038 -282.854325) (xy 71.351159 -282.8232) (xy 71.39378 -282.798593) (xy 71.439796 -282.781141)
			(xy 71.488015 -282.771297) (xy 71.53719 -282.769316) (xy 71.586045 -282.775248) (xy 71.633316 -282.78894)
			(xy 71.677778 -282.810038) (xy 71.718281 -282.837994) (xy 71.753774 -282.872086) (xy 71.783339 -282.91143)
			(xy 71.80621 -282.955007) (xy 71.821794 -283.001688) (xy 71.829689 -283.050265) (xy 71.830184 -283.074872)
			(xy 72.169032 -283.074872) (xy 72.172992 -283.025818) (xy 72.184769 -282.978034) (xy 72.20406 -282.932758)
			(xy 72.230363 -282.891162) (xy 72.262998 -282.854325) (xy 72.301119 -282.8232) (xy 72.34374 -282.798593)
			(xy 72.389756 -282.781141) (xy 72.437975 -282.771297) (xy 72.48715 -282.769316) (xy 72.536005 -282.775248)
			(xy 72.583276 -282.78894) (xy 72.627738 -282.810038) (xy 72.668241 -282.837994) (xy 72.703734 -282.872086)
			(xy 72.733299 -282.91143) (xy 72.75617 -282.955007) (xy 72.771754 -283.001688) (xy 72.779649 -283.050265)
			(xy 72.780144 -283.074872) (xy 72.779649 -283.099479) (xy 72.771754 -283.148056) (xy 72.75617 -283.194737)
			(xy 72.733299 -283.238314) (xy 72.703734 -283.277658) (xy 72.668241 -283.31175) (xy 72.627738 -283.339706)
			(xy 72.583276 -283.360804) (xy 72.536005 -283.374496) (xy 72.48715 -283.380428) (xy 72.437975 -283.378447)
			(xy 72.389756 -283.368603) (xy 72.34374 -283.351151) (xy 72.301119 -283.326544) (xy 72.262998 -283.295419)
			(xy 72.230363 -283.258582) (xy 72.20406 -283.216986) (xy 72.184769 -283.17171) (xy 72.172992 -283.123926)
			(xy 72.169032 -283.074872) (xy 71.830184 -283.074872) (xy 71.829689 -283.099479) (xy 71.821794 -283.148056)
			(xy 71.80621 -283.194737) (xy 71.783339 -283.238314) (xy 71.753774 -283.277658) (xy 71.718281 -283.31175)
			(xy 71.677778 -283.339706) (xy 71.633316 -283.360804) (xy 71.586045 -283.374496) (xy 71.53719 -283.380428)
			(xy 71.488015 -283.378447) (xy 71.439796 -283.368603) (xy 71.39378 -283.351151) (xy 71.351159 -283.326544)
			(xy 71.313038 -283.295419) (xy 71.280403 -283.258582) (xy 71.2541 -283.216986) (xy 71.234809 -283.17171)
			(xy 71.223032 -283.123926) (xy 71.219072 -283.074872) (xy 70.880224 -283.074872) (xy 70.879729 -283.099479)
			(xy 70.871834 -283.148056) (xy 70.85625 -283.194737) (xy 70.833379 -283.238314) (xy 70.803814 -283.277658)
			(xy 70.768321 -283.31175) (xy 70.727818 -283.339706) (xy 70.683356 -283.360804) (xy 70.636085 -283.374496)
			(xy 70.58723 -283.380428) (xy 70.538055 -283.378447) (xy 70.489836 -283.368603) (xy 70.44382 -283.351151)
			(xy 70.401199 -283.326544) (xy 70.363078 -283.295419) (xy 70.330443 -283.258582) (xy 70.30414 -283.216986)
			(xy 70.284849 -283.17171) (xy 70.273072 -283.123926) (xy 70.269112 -283.074872) (xy 69.930264 -283.074872)
			(xy 69.929769 -283.099479) (xy 69.921874 -283.148056) (xy 69.90629 -283.194737) (xy 69.883419 -283.238314)
			(xy 69.853854 -283.277658) (xy 69.818361 -283.31175) (xy 69.777858 -283.339706) (xy 69.733396 -283.360804)
			(xy 69.686125 -283.374496) (xy 69.63727 -283.380428) (xy 69.588095 -283.378447) (xy 69.539876 -283.368603)
			(xy 69.49386 -283.351151) (xy 69.451239 -283.326544) (xy 69.413118 -283.295419) (xy 69.380483 -283.258582)
			(xy 69.35418 -283.216986) (xy 69.334889 -283.17171) (xy 69.323112 -283.123926) (xy 69.319152 -283.074872)
			(xy 68.98005 -283.074872) (xy 68.979555 -283.099479) (xy 68.97166 -283.148056) (xy 68.956076 -283.194737)
			(xy 68.933205 -283.238314) (xy 68.90364 -283.277658) (xy 68.868147 -283.31175) (xy 68.827644 -283.339706)
			(xy 68.783182 -283.360804) (xy 68.735911 -283.374496) (xy 68.687056 -283.380428) (xy 68.637881 -283.378447)
			(xy 68.589662 -283.368603) (xy 68.543646 -283.351151) (xy 68.501025 -283.326544) (xy 68.462904 -283.295419)
			(xy 68.430269 -283.258582) (xy 68.403966 -283.216986) (xy 68.384675 -283.17171) (xy 68.372898 -283.123926)
			(xy 68.368938 -283.074872) (xy 67.08013 -283.074872) (xy 67.079635 -283.099479) (xy 67.07174 -283.148056)
			(xy 67.056156 -283.194737) (xy 67.033285 -283.238314) (xy 67.00372 -283.277658) (xy 66.968227 -283.31175)
			(xy 66.927724 -283.339706) (xy 66.883262 -283.360804) (xy 66.835991 -283.374496) (xy 66.787136 -283.380428)
			(xy 66.737961 -283.378447) (xy 66.689742 -283.368603) (xy 66.643726 -283.351151) (xy 66.601105 -283.326544)
			(xy 66.562984 -283.295419) (xy 66.530349 -283.258582) (xy 66.504046 -283.216986) (xy 66.484755 -283.17171)
			(xy 66.472978 -283.123926) (xy 66.469018 -283.074872) (xy 66.13017 -283.074872) (xy 66.129675 -283.099479)
			(xy 66.12178 -283.148056) (xy 66.106196 -283.194737) (xy 66.083325 -283.238314) (xy 66.05376 -283.277658)
			(xy 66.018267 -283.31175) (xy 65.977764 -283.339706) (xy 65.933302 -283.360804) (xy 65.886031 -283.374496)
			(xy 65.837176 -283.380428) (xy 65.788001 -283.378447) (xy 65.739782 -283.368603) (xy 65.693766 -283.351151)
			(xy 65.651145 -283.326544) (xy 65.613024 -283.295419) (xy 65.580389 -283.258582) (xy 65.554086 -283.216986)
			(xy 65.534795 -283.17171) (xy 65.523018 -283.123926) (xy 65.519058 -283.074872) (xy 65.18021 -283.074872)
			(xy 65.179715 -283.099479) (xy 65.17182 -283.148056) (xy 65.156236 -283.194737) (xy 65.133365 -283.238314)
			(xy 65.1038 -283.277658) (xy 65.068307 -283.31175) (xy 65.027804 -283.339706) (xy 64.983342 -283.360804)
			(xy 64.936071 -283.374496) (xy 64.887216 -283.380428) (xy 64.838041 -283.378447) (xy 64.789822 -283.368603)
			(xy 64.743806 -283.351151) (xy 64.701185 -283.326544) (xy 64.663064 -283.295419) (xy 64.630429 -283.258582)
			(xy 64.604126 -283.216986) (xy 64.584835 -283.17171) (xy 64.573058 -283.123926) (xy 64.569098 -283.074872)
			(xy 64.23025 -283.074872) (xy 64.229755 -283.099479) (xy 64.22186 -283.148056) (xy 64.206276 -283.194737)
			(xy 64.183405 -283.238314) (xy 64.15384 -283.277658) (xy 64.118347 -283.31175) (xy 64.077844 -283.339706)
			(xy 64.033382 -283.360804) (xy 63.986111 -283.374496) (xy 63.937256 -283.380428) (xy 63.888081 -283.378447)
			(xy 63.839862 -283.368603) (xy 63.793846 -283.351151) (xy 63.751225 -283.326544) (xy 63.713104 -283.295419)
			(xy 63.680469 -283.258582) (xy 63.654166 -283.216986) (xy 63.634875 -283.17171) (xy 63.623098 -283.123926)
			(xy 63.619138 -283.074872) (xy 63.28029 -283.074872) (xy 63.279795 -283.099479) (xy 63.2719 -283.148056)
			(xy 63.256316 -283.194737) (xy 63.233445 -283.238314) (xy 63.20388 -283.277658) (xy 63.168387 -283.31175)
			(xy 63.127884 -283.339706) (xy 63.083422 -283.360804) (xy 63.036151 -283.374496) (xy 62.987296 -283.380428)
			(xy 62.938121 -283.378447) (xy 62.889902 -283.368603) (xy 62.843886 -283.351151) (xy 62.801265 -283.326544)
			(xy 62.763144 -283.295419) (xy 62.730509 -283.258582) (xy 62.704206 -283.216986) (xy 62.684915 -283.17171)
			(xy 62.673138 -283.123926) (xy 62.669178 -283.074872) (xy 62.330076 -283.074872) (xy 62.329581 -283.099479)
			(xy 62.321686 -283.148056) (xy 62.306102 -283.194737) (xy 62.283231 -283.238314) (xy 62.253666 -283.277658)
			(xy 62.218173 -283.31175) (xy 62.17767 -283.339706) (xy 62.133208 -283.360804) (xy 62.085937 -283.374496)
			(xy 62.037082 -283.380428) (xy 61.987907 -283.378447) (xy 61.939688 -283.368603) (xy 61.893672 -283.351151)
			(xy 61.851051 -283.326544) (xy 61.81293 -283.295419) (xy 61.780295 -283.258582) (xy 61.753992 -283.216986)
			(xy 61.734701 -283.17171) (xy 61.722924 -283.123926) (xy 61.718964 -283.074872) (xy 61.380116 -283.074872)
			(xy 61.379621 -283.099479) (xy 61.371726 -283.148056) (xy 61.356142 -283.194737) (xy 61.333271 -283.238314)
			(xy 61.303706 -283.277658) (xy 61.268213 -283.31175) (xy 61.22771 -283.339706) (xy 61.183248 -283.360804)
			(xy 61.135977 -283.374496) (xy 61.087122 -283.380428) (xy 61.037947 -283.378447) (xy 60.989728 -283.368603)
			(xy 60.943712 -283.351151) (xy 60.901091 -283.326544) (xy 60.86297 -283.295419) (xy 60.830335 -283.258582)
			(xy 60.804032 -283.216986) (xy 60.784741 -283.17171) (xy 60.772964 -283.123926) (xy 60.769004 -283.074872)
			(xy 60.430156 -283.074872) (xy 60.429661 -283.099479) (xy 60.421766 -283.148056) (xy 60.406182 -283.194737)
			(xy 60.383311 -283.238314) (xy 60.353746 -283.277658) (xy 60.318253 -283.31175) (xy 60.27775 -283.339706)
			(xy 60.233288 -283.360804) (xy 60.186017 -283.374496) (xy 60.137162 -283.380428) (xy 60.087987 -283.378447)
			(xy 60.039768 -283.368603) (xy 59.993752 -283.351151) (xy 59.951131 -283.326544) (xy 59.91301 -283.295419)
			(xy 59.880375 -283.258582) (xy 59.854072 -283.216986) (xy 59.834781 -283.17171) (xy 59.823004 -283.123926)
			(xy 59.819044 -283.074872) (xy 58.530236 -283.074872) (xy 58.529741 -283.099479) (xy 58.521846 -283.148056)
			(xy 58.506262 -283.194737) (xy 58.483391 -283.238314) (xy 58.453826 -283.277658) (xy 58.418333 -283.31175)
			(xy 58.37783 -283.339706) (xy 58.333368 -283.360804) (xy 58.286097 -283.374496) (xy 58.237242 -283.380428)
			(xy 58.188067 -283.378447) (xy 58.139848 -283.368603) (xy 58.093832 -283.351151) (xy 58.051211 -283.326544)
			(xy 58.01309 -283.295419) (xy 57.980455 -283.258582) (xy 57.954152 -283.216986) (xy 57.934861 -283.17171)
			(xy 57.923084 -283.123926) (xy 57.919124 -283.074872) (xy 57.580276 -283.074872) (xy 57.579781 -283.099479)
			(xy 57.571886 -283.148056) (xy 57.556302 -283.194737) (xy 57.533431 -283.238314) (xy 57.503866 -283.277658)
			(xy 57.468373 -283.31175) (xy 57.42787 -283.339706) (xy 57.383408 -283.360804) (xy 57.336137 -283.374496)
			(xy 57.287282 -283.380428) (xy 57.238107 -283.378447) (xy 57.189888 -283.368603) (xy 57.143872 -283.351151)
			(xy 57.101251 -283.326544) (xy 57.06313 -283.295419) (xy 57.030495 -283.258582) (xy 57.004192 -283.216986)
			(xy 56.984901 -283.17171) (xy 56.973124 -283.123926) (xy 56.969164 -283.074872) (xy 56.630316 -283.074872)
			(xy 56.629821 -283.099479) (xy 56.621926 -283.148056) (xy 56.606342 -283.194737) (xy 56.583471 -283.238314)
			(xy 56.553906 -283.277658) (xy 56.518413 -283.31175) (xy 56.47791 -283.339706) (xy 56.433448 -283.360804)
			(xy 56.386177 -283.374496) (xy 56.337322 -283.380428) (xy 56.288147 -283.378447) (xy 56.239928 -283.368603)
			(xy 56.193912 -283.351151) (xy 56.151291 -283.326544) (xy 56.11317 -283.295419) (xy 56.080535 -283.258582)
			(xy 56.054232 -283.216986) (xy 56.034941 -283.17171) (xy 56.023164 -283.123926) (xy 56.019204 -283.074872)
			(xy 55.680102 -283.074872) (xy 55.679607 -283.099479) (xy 55.671712 -283.148056) (xy 55.656128 -283.194737)
			(xy 55.633257 -283.238314) (xy 55.603692 -283.277658) (xy 55.568199 -283.31175) (xy 55.527696 -283.339706)
			(xy 55.483234 -283.360804) (xy 55.435963 -283.374496) (xy 55.387108 -283.380428) (xy 55.337933 -283.378447)
			(xy 55.289714 -283.368603) (xy 55.243698 -283.351151) (xy 55.201077 -283.326544) (xy 55.162956 -283.295419)
			(xy 55.130321 -283.258582) (xy 55.104018 -283.216986) (xy 55.084727 -283.17171) (xy 55.07295 -283.123926)
			(xy 55.06899 -283.074872) (xy 54.730142 -283.074872) (xy 54.729647 -283.099479) (xy 54.721752 -283.148056)
			(xy 54.706168 -283.194737) (xy 54.683297 -283.238314) (xy 54.653732 -283.277658) (xy 54.618239 -283.31175)
			(xy 54.577736 -283.339706) (xy 54.533274 -283.360804) (xy 54.486003 -283.374496) (xy 54.437148 -283.380428)
			(xy 54.387973 -283.378447) (xy 54.339754 -283.368603) (xy 54.293738 -283.351151) (xy 54.251117 -283.326544)
			(xy 54.212996 -283.295419) (xy 54.180361 -283.258582) (xy 54.154058 -283.216986) (xy 54.134767 -283.17171)
			(xy 54.12299 -283.123926) (xy 54.11903 -283.074872) (xy 53.780182 -283.074872) (xy 53.779687 -283.099479)
			(xy 53.771792 -283.148056) (xy 53.756208 -283.194737) (xy 53.733337 -283.238314) (xy 53.703772 -283.277658)
			(xy 53.668279 -283.31175) (xy 53.627776 -283.339706) (xy 53.583314 -283.360804) (xy 53.536043 -283.374496)
			(xy 53.487188 -283.380428) (xy 53.438013 -283.378447) (xy 53.389794 -283.368603) (xy 53.343778 -283.351151)
			(xy 53.301157 -283.326544) (xy 53.263036 -283.295419) (xy 53.230401 -283.258582) (xy 53.204098 -283.216986)
			(xy 53.184807 -283.17171) (xy 53.17303 -283.123926) (xy 53.16907 -283.074872) (xy 52.830222 -283.074872)
			(xy 52.829727 -283.099479) (xy 52.821832 -283.148056) (xy 52.806248 -283.194737) (xy 52.783377 -283.238314)
			(xy 52.753812 -283.277658) (xy 52.718319 -283.31175) (xy 52.677816 -283.339706) (xy 52.633354 -283.360804)
			(xy 52.586083 -283.374496) (xy 52.537228 -283.380428) (xy 52.488053 -283.378447) (xy 52.439834 -283.368603)
			(xy 52.393818 -283.351151) (xy 52.351197 -283.326544) (xy 52.313076 -283.295419) (xy 52.280441 -283.258582)
			(xy 52.254138 -283.216986) (xy 52.234847 -283.17171) (xy 52.22307 -283.123926) (xy 52.21911 -283.074872)
			(xy 51.880262 -283.074872) (xy 51.879767 -283.099479) (xy 51.871872 -283.148056) (xy 51.856288 -283.194737)
			(xy 51.833417 -283.238314) (xy 51.803852 -283.277658) (xy 51.768359 -283.31175) (xy 51.727856 -283.339706)
			(xy 51.683394 -283.360804) (xy 51.636123 -283.374496) (xy 51.587268 -283.380428) (xy 51.538093 -283.378447)
			(xy 51.489874 -283.368603) (xy 51.443858 -283.351151) (xy 51.401237 -283.326544) (xy 51.363116 -283.295419)
			(xy 51.330481 -283.258582) (xy 51.304178 -283.216986) (xy 51.284887 -283.17171) (xy 51.27311 -283.123926)
			(xy 51.26915 -283.074872) (xy 50.930302 -283.074872) (xy 50.929807 -283.099479) (xy 50.921912 -283.148056)
			(xy 50.906328 -283.194737) (xy 50.883457 -283.238314) (xy 50.853892 -283.277658) (xy 50.818399 -283.31175)
			(xy 50.777896 -283.339706) (xy 50.733434 -283.360804) (xy 50.686163 -283.374496) (xy 50.637308 -283.380428)
			(xy 50.588133 -283.378447) (xy 50.539914 -283.368603) (xy 50.493898 -283.351151) (xy 50.451277 -283.326544)
			(xy 50.413156 -283.295419) (xy 50.380521 -283.258582) (xy 50.354218 -283.216986) (xy 50.334927 -283.17171)
			(xy 50.32315 -283.123926) (xy 50.31919 -283.074872) (xy 49.980088 -283.074872) (xy 49.979593 -283.099479)
			(xy 49.971698 -283.148056) (xy 49.956114 -283.194737) (xy 49.933243 -283.238314) (xy 49.903678 -283.277658)
			(xy 49.868185 -283.31175) (xy 49.827682 -283.339706) (xy 49.78322 -283.360804) (xy 49.735949 -283.374496)
			(xy 49.687094 -283.380428) (xy 49.637919 -283.378447) (xy 49.5897 -283.368603) (xy 49.543684 -283.351151)
			(xy 49.501063 -283.326544) (xy 49.462942 -283.295419) (xy 49.430307 -283.258582) (xy 49.404004 -283.216986)
			(xy 49.384713 -283.17171) (xy 49.372936 -283.123926) (xy 49.368976 -283.074872) (xy 49.030128 -283.074872)
			(xy 49.029633 -283.099479) (xy 49.021738 -283.148056) (xy 49.006154 -283.194737) (xy 48.983283 -283.238314)
			(xy 48.953718 -283.277658) (xy 48.918225 -283.31175) (xy 48.877722 -283.339706) (xy 48.83326 -283.360804)
			(xy 48.785989 -283.374496) (xy 48.737134 -283.380428) (xy 48.687959 -283.378447) (xy 48.63974 -283.368603)
			(xy 48.593724 -283.351151) (xy 48.551103 -283.326544) (xy 48.512982 -283.295419) (xy 48.480347 -283.258582)
			(xy 48.454044 -283.216986) (xy 48.434753 -283.17171) (xy 48.422976 -283.123926) (xy 48.419016 -283.074872)
			(xy 48.080168 -283.074872) (xy 48.079673 -283.099479) (xy 48.071778 -283.148056) (xy 48.056194 -283.194737)
			(xy 48.033323 -283.238314) (xy 48.003758 -283.277658) (xy 47.968265 -283.31175) (xy 47.927762 -283.339706)
			(xy 47.8833 -283.360804) (xy 47.836029 -283.374496) (xy 47.787174 -283.380428) (xy 47.737999 -283.378447)
			(xy 47.68978 -283.368603) (xy 47.643764 -283.351151) (xy 47.601143 -283.326544) (xy 47.563022 -283.295419)
			(xy 47.530387 -283.258582) (xy 47.504084 -283.216986) (xy 47.484793 -283.17171) (xy 47.473016 -283.123926)
			(xy 47.469056 -283.074872) (xy 47.130172 -283.074872) (xy 47.12793 -283.116197) (xy 47.117257 -283.164679)
			(xy 47.09888 -283.210795) (xy 47.073285 -283.253331) (xy 47.041145 -283.291165) (xy 47.003308 -283.323301)
			(xy 46.96077 -283.348893) (xy 46.914652 -283.367265) (xy 46.866169 -283.377934) (xy 46.816599 -283.380618)
			(xy 46.767248 -283.375248) (xy 46.719416 -283.361964) (xy 46.674363 -283.341116) (xy 46.633276 -283.313255)
			(xy 46.597238 -283.279113) (xy 46.567199 -283.23959) (xy 46.54395 -283.195728) (xy 46.528103 -283.148683)
			(xy 46.520076 -283.099693) (xy 46.519592 -283.074872) (xy 46.519765 -283.060689) (xy 46.522439 -283.032449)
			(xy 46.524926 -283.018484) (xy 46.527212 -283.006038) (xy 46.519846 -282.982416) (xy 46.442376 -282.904946)
			(xy 46.418754 -282.89758) (xy 46.406308 -282.899866) (xy 46.392341 -282.902337) (xy 46.364102 -282.905013)
			(xy 46.34992 -282.9052) (xy 46.335737 -282.905021) (xy 46.307497 -282.90235) (xy 46.293532 -282.899866)
			(xy 46.281086 -282.89758) (xy 46.257464 -282.904946) (xy 46.179994 -282.982416) (xy 46.172628 -283.006038)
			(xy 46.174914 -283.018484) (xy 46.177398 -283.032449) (xy 46.180065 -283.060689) (xy 46.180248 -283.074872)
			(xy 46.179726 -283.100127) (xy 46.171413 -283.149949) (xy 46.155012 -283.197723) (xy 46.130971 -283.242146)
			(xy 46.099947 -283.282006) (xy 46.062785 -283.316216) (xy 46.020499 -283.343842) (xy 45.974243 -283.364132)
			(xy 45.925278 -283.376532) (xy 45.87494 -283.380703) (xy 45.824602 -283.376532) (xy 45.775637 -283.364132)
			(xy 45.729381 -283.343842) (xy 45.687095 -283.316216) (xy 45.649933 -283.282006) (xy 45.618909 -283.242146)
			(xy 45.594868 -283.197723) (xy 45.578467 -283.149949) (xy 45.570154 -283.100127) (xy 45.569632 -283.074872)
			(xy 45.569804 -283.060689) (xy 45.572479 -283.032449) (xy 45.574966 -283.018484) (xy 45.577252 -283.006038)
			(xy 45.569886 -282.982416) (xy 45.492416 -282.904946) (xy 45.468794 -282.89758) (xy 45.456348 -282.899866)
			(xy 45.442383 -282.902345) (xy 45.414143 -282.905015) (xy 45.39996 -282.9052) (xy 45.385777 -282.905029)
			(xy 45.357537 -282.902353) (xy 45.343572 -282.899866) (xy 45.331126 -282.89758) (xy 45.307504 -282.904946)
			(xy 45.230034 -282.982416) (xy 45.222668 -283.006038) (xy 45.224954 -283.018484) (xy 45.227438 -283.032449)
			(xy 45.230105 -283.060689) (xy 45.230288 -283.074872) (xy 45.229852 -283.099695) (xy 45.221825 -283.148689)
			(xy 45.205977 -283.195738) (xy 45.182726 -283.239603) (xy 45.152685 -283.279129) (xy 45.116644 -283.313274)
			(xy 45.075555 -283.341139) (xy 45.030499 -283.361988) (xy 44.982663 -283.375274) (xy 44.933308 -283.380646)
			(xy 44.883734 -283.377962) (xy 44.835247 -283.367294) (xy 44.789125 -283.348922) (xy 44.746583 -283.323329)
			(xy 44.708742 -283.291192) (xy 44.676599 -283.253356) (xy 44.651 -283.210818) (xy 44.63262 -283.164699)
			(xy 44.621944 -283.116214) (xy 44.619253 -283.06664) (xy 42.379988 -283.06664) (xy 42.380154 -283.074872)
			(xy 42.379659 -283.099479) (xy 42.371764 -283.148056) (xy 42.35618 -283.194737) (xy 42.333309 -283.238314)
			(xy 42.303744 -283.277658) (xy 42.268251 -283.31175) (xy 42.227748 -283.339706) (xy 42.183286 -283.360804)
			(xy 42.136015 -283.374496) (xy 42.08716 -283.380428) (xy 42.037985 -283.378447) (xy 41.989766 -283.368603)
			(xy 41.94375 -283.351151) (xy 41.901129 -283.326544) (xy 41.863008 -283.295419) (xy 41.830373 -283.258582)
			(xy 41.80407 -283.216986) (xy 41.784779 -283.17171) (xy 41.773002 -283.123926) (xy 41.769042 -283.074872)
			(xy 41.430194 -283.074872) (xy 41.429699 -283.099479) (xy 41.421804 -283.148056) (xy 41.40622 -283.194737)
			(xy 41.383349 -283.238314) (xy 41.353784 -283.277658) (xy 41.318291 -283.31175) (xy 41.277788 -283.339706)
			(xy 41.233326 -283.360804) (xy 41.186055 -283.374496) (xy 41.1372 -283.380428) (xy 41.088025 -283.378447)
			(xy 41.039806 -283.368603) (xy 40.99379 -283.351151) (xy 40.951169 -283.326544) (xy 40.913048 -283.295419)
			(xy 40.880413 -283.258582) (xy 40.85411 -283.216986) (xy 40.834819 -283.17171) (xy 40.823042 -283.123926)
			(xy 40.819082 -283.074872) (xy 40.480234 -283.074872) (xy 40.479739 -283.099479) (xy 40.471844 -283.148056)
			(xy 40.45626 -283.194737) (xy 40.433389 -283.238314) (xy 40.403824 -283.277658) (xy 40.368331 -283.31175)
			(xy 40.327828 -283.339706) (xy 40.283366 -283.360804) (xy 40.236095 -283.374496) (xy 40.18724 -283.380428)
			(xy 40.138065 -283.378447) (xy 40.089846 -283.368603) (xy 40.04383 -283.351151) (xy 40.001209 -283.326544)
			(xy 39.963088 -283.295419) (xy 39.930453 -283.258582) (xy 39.90415 -283.216986) (xy 39.884859 -283.17171)
			(xy 39.873082 -283.123926) (xy 39.869122 -283.074872) (xy 39.530274 -283.074872) (xy 39.529779 -283.099479)
			(xy 39.521884 -283.148056) (xy 39.5063 -283.194737) (xy 39.483429 -283.238314) (xy 39.453864 -283.277658)
			(xy 39.418371 -283.31175) (xy 39.377868 -283.339706) (xy 39.333406 -283.360804) (xy 39.286135 -283.374496)
			(xy 39.23728 -283.380428) (xy 39.188105 -283.378447) (xy 39.139886 -283.368603) (xy 39.09387 -283.351151)
			(xy 39.051249 -283.326544) (xy 39.013128 -283.295419) (xy 38.980493 -283.258582) (xy 38.95419 -283.216986)
			(xy 38.934899 -283.17171) (xy 38.923122 -283.123926) (xy 38.919162 -283.074872) (xy 38.580314 -283.074872)
			(xy 38.579819 -283.099479) (xy 38.571924 -283.148056) (xy 38.55634 -283.194737) (xy 38.533469 -283.238314)
			(xy 38.503904 -283.277658) (xy 38.468411 -283.31175) (xy 38.427908 -283.339706) (xy 38.383446 -283.360804)
			(xy 38.336175 -283.374496) (xy 38.28732 -283.380428) (xy 38.238145 -283.378447) (xy 38.189926 -283.368603)
			(xy 38.14391 -283.351151) (xy 38.101289 -283.326544) (xy 38.063168 -283.295419) (xy 38.030533 -283.258582)
			(xy 38.00423 -283.216986) (xy 37.984939 -283.17171) (xy 37.973162 -283.123926) (xy 37.969202 -283.074872)
			(xy 37.6301 -283.074872) (xy 37.629605 -283.099479) (xy 37.62171 -283.148056) (xy 37.606126 -283.194737)
			(xy 37.583255 -283.238314) (xy 37.55369 -283.277658) (xy 37.518197 -283.31175) (xy 37.477694 -283.339706)
			(xy 37.433232 -283.360804) (xy 37.385961 -283.374496) (xy 37.337106 -283.380428) (xy 37.287931 -283.378447)
			(xy 37.239712 -283.368603) (xy 37.193696 -283.351151) (xy 37.151075 -283.326544) (xy 37.112954 -283.295419)
			(xy 37.080319 -283.258582) (xy 37.054016 -283.216986) (xy 37.034725 -283.17171) (xy 37.022948 -283.123926)
			(xy 37.018988 -283.074872) (xy 36.68014 -283.074872) (xy 36.679645 -283.099479) (xy 36.67175 -283.148056)
			(xy 36.656166 -283.194737) (xy 36.633295 -283.238314) (xy 36.60373 -283.277658) (xy 36.568237 -283.31175)
			(xy 36.527734 -283.339706) (xy 36.483272 -283.360804) (xy 36.436001 -283.374496) (xy 36.387146 -283.380428)
			(xy 36.337971 -283.378447) (xy 36.289752 -283.368603) (xy 36.243736 -283.351151) (xy 36.201115 -283.326544)
			(xy 36.162994 -283.295419) (xy 36.130359 -283.258582) (xy 36.104056 -283.216986) (xy 36.084765 -283.17171)
			(xy 36.072988 -283.123926) (xy 36.069028 -283.074872) (xy 34.39033 -283.074872) (xy 34.39033 -283.549852)
			(xy 73.593972 -283.549852) (xy 73.597932 -283.500798) (xy 73.609709 -283.453014) (xy 73.629 -283.407738)
			(xy 73.655303 -283.366142) (xy 73.687938 -283.329305) (xy 73.726059 -283.29818) (xy 73.76868 -283.273573)
			(xy 73.814696 -283.256121) (xy 73.862915 -283.246277) (xy 73.91209 -283.244296) (xy 73.960945 -283.250228)
			(xy 74.008216 -283.26392) (xy 74.052678 -283.285018) (xy 74.093181 -283.312974) (xy 74.128674 -283.347066)
			(xy 74.158239 -283.38641) (xy 74.18111 -283.429987) (xy 74.196694 -283.476668) (xy 74.204589 -283.525245)
			(xy 74.205084 -283.549852) (xy 74.543932 -283.549852) (xy 74.547892 -283.500798) (xy 74.559669 -283.453014)
			(xy 74.57896 -283.407738) (xy 74.605263 -283.366142) (xy 74.637898 -283.329305) (xy 74.676019 -283.29818)
			(xy 74.71864 -283.273573) (xy 74.764656 -283.256121) (xy 74.812875 -283.246277) (xy 74.86205 -283.244296)
			(xy 74.910905 -283.250228) (xy 74.958176 -283.26392) (xy 75.002638 -283.285018) (xy 75.043141 -283.312974)
			(xy 75.078634 -283.347066) (xy 75.108199 -283.38641) (xy 75.13107 -283.429987) (xy 75.146654 -283.476668)
			(xy 75.154549 -283.525245) (xy 75.155044 -283.549852) (xy 75.494146 -283.549852) (xy 75.498106 -283.500798)
			(xy 75.509883 -283.453014) (xy 75.529174 -283.407738) (xy 75.555477 -283.366142) (xy 75.588112 -283.329305)
			(xy 75.626233 -283.29818) (xy 75.668854 -283.273573) (xy 75.71487 -283.256121) (xy 75.763089 -283.246277)
			(xy 75.812264 -283.244296) (xy 75.861119 -283.250228) (xy 75.90839 -283.26392) (xy 75.952852 -283.285018)
			(xy 75.993355 -283.312974) (xy 76.028848 -283.347066) (xy 76.058413 -283.38641) (xy 76.081284 -283.429987)
			(xy 76.096868 -283.476668) (xy 76.104763 -283.525245) (xy 76.105258 -283.549852) (xy 76.104763 -283.574459)
			(xy 76.096868 -283.623036) (xy 76.081284 -283.669717) (xy 76.058413 -283.713294) (xy 76.028848 -283.752638)
			(xy 75.993355 -283.78673) (xy 75.952852 -283.814686) (xy 75.90839 -283.835784) (xy 75.861119 -283.849476)
			(xy 75.812264 -283.855408) (xy 75.763089 -283.853427) (xy 75.71487 -283.843583) (xy 75.668854 -283.826131)
			(xy 75.626233 -283.801524) (xy 75.588112 -283.770399) (xy 75.555477 -283.733562) (xy 75.529174 -283.691966)
			(xy 75.509883 -283.64669) (xy 75.498106 -283.598906) (xy 75.494146 -283.549852) (xy 75.155044 -283.549852)
			(xy 75.154549 -283.574459) (xy 75.146654 -283.623036) (xy 75.13107 -283.669717) (xy 75.108199 -283.713294)
			(xy 75.078634 -283.752638) (xy 75.043141 -283.78673) (xy 75.002638 -283.814686) (xy 74.958176 -283.835784)
			(xy 74.910905 -283.849476) (xy 74.86205 -283.855408) (xy 74.812875 -283.853427) (xy 74.764656 -283.843583)
			(xy 74.71864 -283.826131) (xy 74.676019 -283.801524) (xy 74.637898 -283.770399) (xy 74.605263 -283.733562)
			(xy 74.57896 -283.691966) (xy 74.559669 -283.64669) (xy 74.547892 -283.598906) (xy 74.543932 -283.549852)
			(xy 74.205084 -283.549852) (xy 74.204589 -283.574459) (xy 74.196694 -283.623036) (xy 74.18111 -283.669717)
			(xy 74.158239 -283.713294) (xy 74.128674 -283.752638) (xy 74.093181 -283.78673) (xy 74.052678 -283.814686)
			(xy 74.008216 -283.835784) (xy 73.960945 -283.849476) (xy 73.91209 -283.855408) (xy 73.862915 -283.853427)
			(xy 73.814696 -283.843583) (xy 73.76868 -283.826131) (xy 73.726059 -283.801524) (xy 73.687938 -283.770399)
			(xy 73.655303 -283.733562) (xy 73.629 -283.691966) (xy 73.609709 -283.64669) (xy 73.597932 -283.598906)
			(xy 73.593972 -283.549852) (xy 34.39033 -283.549852) (xy 34.39033 -284.024832) (xy 36.069028 -284.024832)
			(xy 36.072988 -283.975778) (xy 36.084765 -283.927994) (xy 36.104056 -283.882718) (xy 36.130359 -283.841122)
			(xy 36.162994 -283.804285) (xy 36.201115 -283.77316) (xy 36.243736 -283.748553) (xy 36.289752 -283.731101)
			(xy 36.337971 -283.721257) (xy 36.387146 -283.719276) (xy 36.436001 -283.725208) (xy 36.483272 -283.7389)
			(xy 36.527734 -283.759998) (xy 36.568237 -283.787954) (xy 36.60373 -283.822046) (xy 36.633295 -283.86139)
			(xy 36.656166 -283.904967) (xy 36.67175 -283.951648) (xy 36.679645 -284.000225) (xy 36.68014 -284.024832)
			(xy 37.018988 -284.024832) (xy 37.022948 -283.975778) (xy 37.034725 -283.927994) (xy 37.054016 -283.882718)
			(xy 37.080319 -283.841122) (xy 37.112954 -283.804285) (xy 37.151075 -283.77316) (xy 37.193696 -283.748553)
			(xy 37.239712 -283.731101) (xy 37.287931 -283.721257) (xy 37.337106 -283.719276) (xy 37.385961 -283.725208)
			(xy 37.433232 -283.7389) (xy 37.477694 -283.759998) (xy 37.518197 -283.787954) (xy 37.55369 -283.822046)
			(xy 37.583255 -283.86139) (xy 37.606126 -283.904967) (xy 37.62171 -283.951648) (xy 37.629605 -284.000225)
			(xy 37.6301 -284.024832) (xy 37.969202 -284.024832) (xy 37.973162 -283.975778) (xy 37.984939 -283.927994)
			(xy 38.00423 -283.882718) (xy 38.030533 -283.841122) (xy 38.063168 -283.804285) (xy 38.101289 -283.77316)
			(xy 38.14391 -283.748553) (xy 38.189926 -283.731101) (xy 38.238145 -283.721257) (xy 38.28732 -283.719276)
			(xy 38.336175 -283.725208) (xy 38.383446 -283.7389) (xy 38.427908 -283.759998) (xy 38.468411 -283.787954)
			(xy 38.503904 -283.822046) (xy 38.533469 -283.86139) (xy 38.55634 -283.904967) (xy 38.571924 -283.951648)
			(xy 38.579819 -284.000225) (xy 38.580314 -284.024832) (xy 38.919162 -284.024832) (xy 38.923122 -283.975778)
			(xy 38.934899 -283.927994) (xy 38.95419 -283.882718) (xy 38.980493 -283.841122) (xy 39.013128 -283.804285)
			(xy 39.051249 -283.77316) (xy 39.09387 -283.748553) (xy 39.139886 -283.731101) (xy 39.188105 -283.721257)
			(xy 39.23728 -283.719276) (xy 39.286135 -283.725208) (xy 39.333406 -283.7389) (xy 39.377868 -283.759998)
			(xy 39.418371 -283.787954) (xy 39.453864 -283.822046) (xy 39.483429 -283.86139) (xy 39.5063 -283.904967)
			(xy 39.521884 -283.951648) (xy 39.529779 -284.000225) (xy 39.530274 -284.024832) (xy 39.869122 -284.024832)
			(xy 39.873082 -283.975778) (xy 39.884859 -283.927994) (xy 39.90415 -283.882718) (xy 39.930453 -283.841122)
			(xy 39.963088 -283.804285) (xy 40.001209 -283.77316) (xy 40.04383 -283.748553) (xy 40.089846 -283.731101)
			(xy 40.138065 -283.721257) (xy 40.18724 -283.719276) (xy 40.236095 -283.725208) (xy 40.283366 -283.7389)
			(xy 40.327828 -283.759998) (xy 40.368331 -283.787954) (xy 40.403824 -283.822046) (xy 40.433389 -283.86139)
			(xy 40.45626 -283.904967) (xy 40.471844 -283.951648) (xy 40.479739 -284.000225) (xy 40.480234 -284.024832)
			(xy 40.819082 -284.024832) (xy 40.823042 -283.975778) (xy 40.834819 -283.927994) (xy 40.85411 -283.882718)
			(xy 40.880413 -283.841122) (xy 40.913048 -283.804285) (xy 40.951169 -283.77316) (xy 40.99379 -283.748553)
			(xy 41.039806 -283.731101) (xy 41.088025 -283.721257) (xy 41.1372 -283.719276) (xy 41.186055 -283.725208)
			(xy 41.233326 -283.7389) (xy 41.277788 -283.759998) (xy 41.318291 -283.787954) (xy 41.353784 -283.822046)
			(xy 41.383349 -283.86139) (xy 41.40622 -283.904967) (xy 41.421804 -283.951648) (xy 41.429699 -284.000225)
			(xy 41.430194 -284.024832) (xy 44.619176 -284.024832) (xy 44.623136 -283.975778) (xy 44.634913 -283.927994)
			(xy 44.654204 -283.882718) (xy 44.680507 -283.841122) (xy 44.713142 -283.804285) (xy 44.751263 -283.77316)
			(xy 44.793884 -283.748553) (xy 44.8399 -283.731101) (xy 44.888119 -283.721257) (xy 44.937294 -283.719276)
			(xy 44.986149 -283.725208) (xy 45.03342 -283.7389) (xy 45.077882 -283.759998) (xy 45.118385 -283.787954)
			(xy 45.153878 -283.822046) (xy 45.183443 -283.86139) (xy 45.206314 -283.904967) (xy 45.221898 -283.951648)
			(xy 45.229793 -284.000225) (xy 45.230288 -284.024832) (xy 45.569136 -284.024832) (xy 45.573096 -283.975778)
			(xy 45.584873 -283.927994) (xy 45.604164 -283.882718) (xy 45.630467 -283.841122) (xy 45.663102 -283.804285)
			(xy 45.701223 -283.77316) (xy 45.743844 -283.748553) (xy 45.78986 -283.731101) (xy 45.838079 -283.721257)
			(xy 45.887254 -283.719276) (xy 45.936109 -283.725208) (xy 45.98338 -283.7389) (xy 46.027842 -283.759998)
			(xy 46.068345 -283.787954) (xy 46.103838 -283.822046) (xy 46.133403 -283.86139) (xy 46.156274 -283.904967)
			(xy 46.171858 -283.951648) (xy 46.179753 -284.000225) (xy 46.180248 -284.024832) (xy 46.519096 -284.024832)
			(xy 46.523056 -283.975778) (xy 46.534833 -283.927994) (xy 46.554124 -283.882718) (xy 46.580427 -283.841122)
			(xy 46.613062 -283.804285) (xy 46.651183 -283.77316) (xy 46.693804 -283.748553) (xy 46.73982 -283.731101)
			(xy 46.788039 -283.721257) (xy 46.837214 -283.719276) (xy 46.886069 -283.725208) (xy 46.93334 -283.7389)
			(xy 46.977802 -283.759998) (xy 47.018305 -283.787954) (xy 47.053798 -283.822046) (xy 47.083363 -283.86139)
			(xy 47.106234 -283.904967) (xy 47.121818 -283.951648) (xy 47.129713 -284.000225) (xy 47.130208 -284.024832)
			(xy 47.469056 -284.024832) (xy 47.473016 -283.975778) (xy 47.484793 -283.927994) (xy 47.504084 -283.882718)
			(xy 47.530387 -283.841122) (xy 47.563022 -283.804285) (xy 47.601143 -283.77316) (xy 47.643764 -283.748553)
			(xy 47.68978 -283.731101) (xy 47.737999 -283.721257) (xy 47.787174 -283.719276) (xy 47.836029 -283.725208)
			(xy 47.8833 -283.7389) (xy 47.927762 -283.759998) (xy 47.968265 -283.787954) (xy 48.003758 -283.822046)
			(xy 48.033323 -283.86139) (xy 48.056194 -283.904967) (xy 48.071778 -283.951648) (xy 48.079673 -284.000225)
			(xy 48.080168 -284.024832) (xy 48.419016 -284.024832) (xy 48.422976 -283.975778) (xy 48.434753 -283.927994)
			(xy 48.454044 -283.882718) (xy 48.480347 -283.841122) (xy 48.512982 -283.804285) (xy 48.551103 -283.77316)
			(xy 48.593724 -283.748553) (xy 48.63974 -283.731101) (xy 48.687959 -283.721257) (xy 48.737134 -283.719276)
			(xy 48.785989 -283.725208) (xy 48.83326 -283.7389) (xy 48.877722 -283.759998) (xy 48.918225 -283.787954)
			(xy 48.953718 -283.822046) (xy 48.983283 -283.86139) (xy 49.006154 -283.904967) (xy 49.021738 -283.951648)
			(xy 49.029633 -284.000225) (xy 49.030128 -284.024832) (xy 49.368976 -284.024832) (xy 49.372936 -283.975778)
			(xy 49.384713 -283.927994) (xy 49.404004 -283.882718) (xy 49.430307 -283.841122) (xy 49.462942 -283.804285)
			(xy 49.501063 -283.77316) (xy 49.543684 -283.748553) (xy 49.5897 -283.731101) (xy 49.637919 -283.721257)
			(xy 49.687094 -283.719276) (xy 49.735949 -283.725208) (xy 49.78322 -283.7389) (xy 49.827682 -283.759998)
			(xy 49.868185 -283.787954) (xy 49.903678 -283.822046) (xy 49.933243 -283.86139) (xy 49.956114 -283.904967)
			(xy 49.971698 -283.951648) (xy 49.979593 -284.000225) (xy 49.980088 -284.024832) (xy 50.31919 -284.024832)
			(xy 50.32315 -283.975778) (xy 50.334927 -283.927994) (xy 50.354218 -283.882718) (xy 50.380521 -283.841122)
			(xy 50.413156 -283.804285) (xy 50.451277 -283.77316) (xy 50.493898 -283.748553) (xy 50.539914 -283.731101)
			(xy 50.588133 -283.721257) (xy 50.637308 -283.719276) (xy 50.686163 -283.725208) (xy 50.733434 -283.7389)
			(xy 50.777896 -283.759998) (xy 50.818399 -283.787954) (xy 50.853892 -283.822046) (xy 50.883457 -283.86139)
			(xy 50.906328 -283.904967) (xy 50.921912 -283.951648) (xy 50.929807 -284.000225) (xy 50.930302 -284.024832)
			(xy 51.26915 -284.024832) (xy 51.27311 -283.975778) (xy 51.284887 -283.927994) (xy 51.304178 -283.882718)
			(xy 51.330481 -283.841122) (xy 51.363116 -283.804285) (xy 51.401237 -283.77316) (xy 51.443858 -283.748553)
			(xy 51.489874 -283.731101) (xy 51.538093 -283.721257) (xy 51.587268 -283.719276) (xy 51.636123 -283.725208)
			(xy 51.683394 -283.7389) (xy 51.727856 -283.759998) (xy 51.768359 -283.787954) (xy 51.803852 -283.822046)
			(xy 51.833417 -283.86139) (xy 51.856288 -283.904967) (xy 51.871872 -283.951648) (xy 51.879767 -284.000225)
			(xy 51.880262 -284.024832) (xy 52.21911 -284.024832) (xy 52.22307 -283.975778) (xy 52.234847 -283.927994)
			(xy 52.254138 -283.882718) (xy 52.280441 -283.841122) (xy 52.313076 -283.804285) (xy 52.351197 -283.77316)
			(xy 52.393818 -283.748553) (xy 52.439834 -283.731101) (xy 52.488053 -283.721257) (xy 52.537228 -283.719276)
			(xy 52.586083 -283.725208) (xy 52.633354 -283.7389) (xy 52.677816 -283.759998) (xy 52.718319 -283.787954)
			(xy 52.753812 -283.822046) (xy 52.783377 -283.86139) (xy 52.806248 -283.904967) (xy 52.821832 -283.951648)
			(xy 52.829727 -284.000225) (xy 52.830222 -284.024832) (xy 53.16907 -284.024832) (xy 53.17303 -283.975778)
			(xy 53.184807 -283.927994) (xy 53.204098 -283.882718) (xy 53.230401 -283.841122) (xy 53.263036 -283.804285)
			(xy 53.301157 -283.77316) (xy 53.343778 -283.748553) (xy 53.389794 -283.731101) (xy 53.438013 -283.721257)
			(xy 53.487188 -283.719276) (xy 53.536043 -283.725208) (xy 53.583314 -283.7389) (xy 53.627776 -283.759998)
			(xy 53.668279 -283.787954) (xy 53.703772 -283.822046) (xy 53.733337 -283.86139) (xy 53.756208 -283.904967)
			(xy 53.771792 -283.951648) (xy 53.779687 -284.000225) (xy 53.780182 -284.024832) (xy 54.11903 -284.024832)
			(xy 54.12299 -283.975778) (xy 54.134767 -283.927994) (xy 54.154058 -283.882718) (xy 54.180361 -283.841122)
			(xy 54.212996 -283.804285) (xy 54.251117 -283.77316) (xy 54.293738 -283.748553) (xy 54.339754 -283.731101)
			(xy 54.387973 -283.721257) (xy 54.437148 -283.719276) (xy 54.486003 -283.725208) (xy 54.533274 -283.7389)
			(xy 54.577736 -283.759998) (xy 54.618239 -283.787954) (xy 54.653732 -283.822046) (xy 54.683297 -283.86139)
			(xy 54.706168 -283.904967) (xy 54.721752 -283.951648) (xy 54.729647 -284.000225) (xy 54.730142 -284.024832)
			(xy 55.06899 -284.024832) (xy 55.07295 -283.975778) (xy 55.084727 -283.927994) (xy 55.104018 -283.882718)
			(xy 55.130321 -283.841122) (xy 55.162956 -283.804285) (xy 55.201077 -283.77316) (xy 55.243698 -283.748553)
			(xy 55.289714 -283.731101) (xy 55.337933 -283.721257) (xy 55.387108 -283.719276) (xy 55.435963 -283.725208)
			(xy 55.483234 -283.7389) (xy 55.527696 -283.759998) (xy 55.568199 -283.787954) (xy 55.603692 -283.822046)
			(xy 55.633257 -283.86139) (xy 55.656128 -283.904967) (xy 55.671712 -283.951648) (xy 55.679607 -284.000225)
			(xy 55.680102 -284.024832) (xy 56.01895 -284.024832) (xy 56.02291 -283.975778) (xy 56.034687 -283.927994)
			(xy 56.053978 -283.882718) (xy 56.080281 -283.841122) (xy 56.112916 -283.804285) (xy 56.151037 -283.77316)
			(xy 56.193658 -283.748553) (xy 56.239674 -283.731101) (xy 56.287893 -283.721257) (xy 56.337068 -283.719276)
			(xy 56.385923 -283.725208) (xy 56.433194 -283.7389) (xy 56.477656 -283.759998) (xy 56.518159 -283.787954)
			(xy 56.553652 -283.822046) (xy 56.583217 -283.86139) (xy 56.606088 -283.904967) (xy 56.621672 -283.951648)
			(xy 56.629567 -284.000225) (xy 56.630062 -284.024832) (xy 56.969164 -284.024832) (xy 56.973124 -283.975778)
			(xy 56.984901 -283.927994) (xy 57.004192 -283.882718) (xy 57.030495 -283.841122) (xy 57.06313 -283.804285)
			(xy 57.101251 -283.77316) (xy 57.143872 -283.748553) (xy 57.189888 -283.731101) (xy 57.238107 -283.721257)
			(xy 57.287282 -283.719276) (xy 57.336137 -283.725208) (xy 57.383408 -283.7389) (xy 57.42787 -283.759998)
			(xy 57.468373 -283.787954) (xy 57.503866 -283.822046) (xy 57.533431 -283.86139) (xy 57.556302 -283.904967)
			(xy 57.571886 -283.951648) (xy 57.579781 -284.000225) (xy 57.580276 -284.024832) (xy 57.919124 -284.024832)
			(xy 57.923084 -283.975778) (xy 57.934861 -283.927994) (xy 57.954152 -283.882718) (xy 57.980455 -283.841122)
			(xy 58.01309 -283.804285) (xy 58.051211 -283.77316) (xy 58.093832 -283.748553) (xy 58.139848 -283.731101)
			(xy 58.188067 -283.721257) (xy 58.237242 -283.719276) (xy 58.286097 -283.725208) (xy 58.333368 -283.7389)
			(xy 58.37783 -283.759998) (xy 58.418333 -283.787954) (xy 58.453826 -283.822046) (xy 58.483391 -283.86139)
			(xy 58.506262 -283.904967) (xy 58.521846 -283.951648) (xy 58.529741 -284.000225) (xy 58.530236 -284.024832)
			(xy 59.819044 -284.024832) (xy 59.823004 -283.975778) (xy 59.834781 -283.927994) (xy 59.854072 -283.882718)
			(xy 59.880375 -283.841122) (xy 59.91301 -283.804285) (xy 59.951131 -283.77316) (xy 59.993752 -283.748553)
			(xy 60.039768 -283.731101) (xy 60.087987 -283.721257) (xy 60.137162 -283.719276) (xy 60.186017 -283.725208)
			(xy 60.233288 -283.7389) (xy 60.27775 -283.759998) (xy 60.318253 -283.787954) (xy 60.353746 -283.822046)
			(xy 60.383311 -283.86139) (xy 60.406182 -283.904967) (xy 60.421766 -283.951648) (xy 60.429661 -284.000225)
			(xy 60.430156 -284.024832) (xy 60.769004 -284.024832) (xy 60.772964 -283.975778) (xy 60.784741 -283.927994)
			(xy 60.804032 -283.882718) (xy 60.830335 -283.841122) (xy 60.86297 -283.804285) (xy 60.901091 -283.77316)
			(xy 60.943712 -283.748553) (xy 60.989728 -283.731101) (xy 61.037947 -283.721257) (xy 61.087122 -283.719276)
			(xy 61.135977 -283.725208) (xy 61.183248 -283.7389) (xy 61.22771 -283.759998) (xy 61.268213 -283.787954)
			(xy 61.303706 -283.822046) (xy 61.333271 -283.86139) (xy 61.356142 -283.904967) (xy 61.371726 -283.951648)
			(xy 61.379621 -284.000225) (xy 61.380116 -284.024832) (xy 61.718964 -284.024832) (xy 61.722924 -283.975778)
			(xy 61.734701 -283.927994) (xy 61.753992 -283.882718) (xy 61.780295 -283.841122) (xy 61.81293 -283.804285)
			(xy 61.851051 -283.77316) (xy 61.893672 -283.748553) (xy 61.939688 -283.731101) (xy 61.987907 -283.721257)
			(xy 62.037082 -283.719276) (xy 62.085937 -283.725208) (xy 62.133208 -283.7389) (xy 62.17767 -283.759998)
			(xy 62.218173 -283.787954) (xy 62.253666 -283.822046) (xy 62.283231 -283.86139) (xy 62.306102 -283.904967)
			(xy 62.321686 -283.951648) (xy 62.329581 -284.000225) (xy 62.330076 -284.024832) (xy 62.669178 -284.024832)
			(xy 62.673138 -283.975778) (xy 62.684915 -283.927994) (xy 62.704206 -283.882718) (xy 62.730509 -283.841122)
			(xy 62.763144 -283.804285) (xy 62.801265 -283.77316) (xy 62.843886 -283.748553) (xy 62.889902 -283.731101)
			(xy 62.938121 -283.721257) (xy 62.987296 -283.719276) (xy 63.036151 -283.725208) (xy 63.083422 -283.7389)
			(xy 63.127884 -283.759998) (xy 63.168387 -283.787954) (xy 63.20388 -283.822046) (xy 63.233445 -283.86139)
			(xy 63.256316 -283.904967) (xy 63.2719 -283.951648) (xy 63.279795 -284.000225) (xy 63.28029 -284.024832)
			(xy 63.619138 -284.024832) (xy 63.623098 -283.975778) (xy 63.634875 -283.927994) (xy 63.654166 -283.882718)
			(xy 63.680469 -283.841122) (xy 63.713104 -283.804285) (xy 63.751225 -283.77316) (xy 63.793846 -283.748553)
			(xy 63.839862 -283.731101) (xy 63.888081 -283.721257) (xy 63.937256 -283.719276) (xy 63.986111 -283.725208)
			(xy 64.033382 -283.7389) (xy 64.077844 -283.759998) (xy 64.118347 -283.787954) (xy 64.15384 -283.822046)
			(xy 64.183405 -283.86139) (xy 64.206276 -283.904967) (xy 64.22186 -283.951648) (xy 64.229755 -284.000225)
			(xy 64.23025 -284.024832) (xy 64.569098 -284.024832) (xy 64.573058 -283.975778) (xy 64.584835 -283.927994)
			(xy 64.604126 -283.882718) (xy 64.630429 -283.841122) (xy 64.663064 -283.804285) (xy 64.701185 -283.77316)
			(xy 64.743806 -283.748553) (xy 64.789822 -283.731101) (xy 64.838041 -283.721257) (xy 64.887216 -283.719276)
			(xy 64.936071 -283.725208) (xy 64.983342 -283.7389) (xy 65.027804 -283.759998) (xy 65.068307 -283.787954)
			(xy 65.1038 -283.822046) (xy 65.133365 -283.86139) (xy 65.156236 -283.904967) (xy 65.17182 -283.951648)
			(xy 65.179715 -284.000225) (xy 65.18021 -284.024832) (xy 65.519058 -284.024832) (xy 65.523018 -283.975778)
			(xy 65.534795 -283.927994) (xy 65.554086 -283.882718) (xy 65.580389 -283.841122) (xy 65.613024 -283.804285)
			(xy 65.651145 -283.77316) (xy 65.693766 -283.748553) (xy 65.739782 -283.731101) (xy 65.788001 -283.721257)
			(xy 65.837176 -283.719276) (xy 65.886031 -283.725208) (xy 65.933302 -283.7389) (xy 65.977764 -283.759998)
			(xy 66.018267 -283.787954) (xy 66.05376 -283.822046) (xy 66.083325 -283.86139) (xy 66.106196 -283.904967)
			(xy 66.12178 -283.951648) (xy 66.129675 -284.000225) (xy 66.13017 -284.024832) (xy 66.469018 -284.024832)
			(xy 66.472978 -283.975778) (xy 66.484755 -283.927994) (xy 66.504046 -283.882718) (xy 66.530349 -283.841122)
			(xy 66.562984 -283.804285) (xy 66.601105 -283.77316) (xy 66.643726 -283.748553) (xy 66.689742 -283.731101)
			(xy 66.737961 -283.721257) (xy 66.787136 -283.719276) (xy 66.835991 -283.725208) (xy 66.883262 -283.7389)
			(xy 66.927724 -283.759998) (xy 66.968227 -283.787954) (xy 67.00372 -283.822046) (xy 67.033285 -283.86139)
			(xy 67.056156 -283.904967) (xy 67.07174 -283.951648) (xy 67.079635 -284.000225) (xy 67.08013 -284.024832)
			(xy 68.368938 -284.024832) (xy 68.372898 -283.975778) (xy 68.384675 -283.927994) (xy 68.403966 -283.882718)
			(xy 68.430269 -283.841122) (xy 68.462904 -283.804285) (xy 68.501025 -283.77316) (xy 68.543646 -283.748553)
			(xy 68.589662 -283.731101) (xy 68.637881 -283.721257) (xy 68.687056 -283.719276) (xy 68.735911 -283.725208)
			(xy 68.783182 -283.7389) (xy 68.827644 -283.759998) (xy 68.868147 -283.787954) (xy 68.90364 -283.822046)
			(xy 68.933205 -283.86139) (xy 68.956076 -283.904967) (xy 68.97166 -283.951648) (xy 68.979555 -284.000225)
			(xy 68.98005 -284.024832) (xy 69.319152 -284.024832) (xy 69.323112 -283.975778) (xy 69.334889 -283.927994)
			(xy 69.35418 -283.882718) (xy 69.380483 -283.841122) (xy 69.413118 -283.804285) (xy 69.451239 -283.77316)
			(xy 69.49386 -283.748553) (xy 69.539876 -283.731101) (xy 69.588095 -283.721257) (xy 69.63727 -283.719276)
			(xy 69.686125 -283.725208) (xy 69.733396 -283.7389) (xy 69.777858 -283.759998) (xy 69.818361 -283.787954)
			(xy 69.853854 -283.822046) (xy 69.883419 -283.86139) (xy 69.90629 -283.904967) (xy 69.921874 -283.951648)
			(xy 69.929769 -284.000225) (xy 69.930264 -284.024832) (xy 70.269112 -284.024832) (xy 70.273072 -283.975778)
			(xy 70.284849 -283.927994) (xy 70.30414 -283.882718) (xy 70.330443 -283.841122) (xy 70.363078 -283.804285)
			(xy 70.401199 -283.77316) (xy 70.44382 -283.748553) (xy 70.489836 -283.731101) (xy 70.538055 -283.721257)
			(xy 70.58723 -283.719276) (xy 70.636085 -283.725208) (xy 70.683356 -283.7389) (xy 70.727818 -283.759998)
			(xy 70.768321 -283.787954) (xy 70.803814 -283.822046) (xy 70.833379 -283.86139) (xy 70.85625 -283.904967)
			(xy 70.871834 -283.951648) (xy 70.879729 -284.000225) (xy 70.880224 -284.024832) (xy 71.219072 -284.024832)
			(xy 71.223032 -283.975778) (xy 71.234809 -283.927994) (xy 71.2541 -283.882718) (xy 71.280403 -283.841122)
			(xy 71.313038 -283.804285) (xy 71.351159 -283.77316) (xy 71.39378 -283.748553) (xy 71.439796 -283.731101)
			(xy 71.488015 -283.721257) (xy 71.53719 -283.719276) (xy 71.586045 -283.725208) (xy 71.633316 -283.7389)
			(xy 71.677778 -283.759998) (xy 71.718281 -283.787954) (xy 71.753774 -283.822046) (xy 71.783339 -283.86139)
			(xy 71.80621 -283.904967) (xy 71.821794 -283.951648) (xy 71.829689 -284.000225) (xy 71.830184 -284.024832)
			(xy 72.169032 -284.024832) (xy 72.172992 -283.975778) (xy 72.184769 -283.927994) (xy 72.20406 -283.882718)
			(xy 72.230363 -283.841122) (xy 72.262998 -283.804285) (xy 72.301119 -283.77316) (xy 72.34374 -283.748553)
			(xy 72.389756 -283.731101) (xy 72.437975 -283.721257) (xy 72.48715 -283.719276) (xy 72.536005 -283.725208)
			(xy 72.583276 -283.7389) (xy 72.627738 -283.759998) (xy 72.668241 -283.787954) (xy 72.703734 -283.822046)
			(xy 72.733299 -283.86139) (xy 72.75617 -283.904967) (xy 72.771754 -283.951648) (xy 72.779649 -284.000225)
			(xy 72.780144 -284.024832) (xy 72.779649 -284.049439) (xy 72.771754 -284.098016) (xy 72.75617 -284.144697)
			(xy 72.733299 -284.188274) (xy 72.703734 -284.227618) (xy 72.668241 -284.26171) (xy 72.627738 -284.289666)
			(xy 72.583276 -284.310764) (xy 72.536005 -284.324456) (xy 72.48715 -284.330388) (xy 72.437975 -284.328407)
			(xy 72.389756 -284.318563) (xy 72.34374 -284.301111) (xy 72.301119 -284.276504) (xy 72.262998 -284.245379)
			(xy 72.230363 -284.208542) (xy 72.20406 -284.166946) (xy 72.184769 -284.12167) (xy 72.172992 -284.073886)
			(xy 72.169032 -284.024832) (xy 71.830184 -284.024832) (xy 71.829689 -284.049439) (xy 71.821794 -284.098016)
			(xy 71.80621 -284.144697) (xy 71.783339 -284.188274) (xy 71.753774 -284.227618) (xy 71.718281 -284.26171)
			(xy 71.677778 -284.289666) (xy 71.633316 -284.310764) (xy 71.586045 -284.324456) (xy 71.53719 -284.330388)
			(xy 71.488015 -284.328407) (xy 71.439796 -284.318563) (xy 71.39378 -284.301111) (xy 71.351159 -284.276504)
			(xy 71.313038 -284.245379) (xy 71.280403 -284.208542) (xy 71.2541 -284.166946) (xy 71.234809 -284.12167)
			(xy 71.223032 -284.073886) (xy 71.219072 -284.024832) (xy 70.880224 -284.024832) (xy 70.879729 -284.049439)
			(xy 70.871834 -284.098016) (xy 70.85625 -284.144697) (xy 70.833379 -284.188274) (xy 70.803814 -284.227618)
			(xy 70.768321 -284.26171) (xy 70.727818 -284.289666) (xy 70.683356 -284.310764) (xy 70.636085 -284.324456)
			(xy 70.58723 -284.330388) (xy 70.538055 -284.328407) (xy 70.489836 -284.318563) (xy 70.44382 -284.301111)
			(xy 70.401199 -284.276504) (xy 70.363078 -284.245379) (xy 70.330443 -284.208542) (xy 70.30414 -284.166946)
			(xy 70.284849 -284.12167) (xy 70.273072 -284.073886) (xy 70.269112 -284.024832) (xy 69.930264 -284.024832)
			(xy 69.929769 -284.049439) (xy 69.921874 -284.098016) (xy 69.90629 -284.144697) (xy 69.883419 -284.188274)
			(xy 69.853854 -284.227618) (xy 69.818361 -284.26171) (xy 69.777858 -284.289666) (xy 69.733396 -284.310764)
			(xy 69.686125 -284.324456) (xy 69.63727 -284.330388) (xy 69.588095 -284.328407) (xy 69.539876 -284.318563)
			(xy 69.49386 -284.301111) (xy 69.451239 -284.276504) (xy 69.413118 -284.245379) (xy 69.380483 -284.208542)
			(xy 69.35418 -284.166946) (xy 69.334889 -284.12167) (xy 69.323112 -284.073886) (xy 69.319152 -284.024832)
			(xy 68.98005 -284.024832) (xy 68.979555 -284.049439) (xy 68.97166 -284.098016) (xy 68.956076 -284.144697)
			(xy 68.933205 -284.188274) (xy 68.90364 -284.227618) (xy 68.868147 -284.26171) (xy 68.827644 -284.289666)
			(xy 68.783182 -284.310764) (xy 68.735911 -284.324456) (xy 68.687056 -284.330388) (xy 68.637881 -284.328407)
			(xy 68.589662 -284.318563) (xy 68.543646 -284.301111) (xy 68.501025 -284.276504) (xy 68.462904 -284.245379)
			(xy 68.430269 -284.208542) (xy 68.403966 -284.166946) (xy 68.384675 -284.12167) (xy 68.372898 -284.073886)
			(xy 68.368938 -284.024832) (xy 67.08013 -284.024832) (xy 67.079635 -284.049439) (xy 67.07174 -284.098016)
			(xy 67.056156 -284.144697) (xy 67.033285 -284.188274) (xy 67.00372 -284.227618) (xy 66.968227 -284.26171)
			(xy 66.927724 -284.289666) (xy 66.883262 -284.310764) (xy 66.835991 -284.324456) (xy 66.787136 -284.330388)
			(xy 66.737961 -284.328407) (xy 66.689742 -284.318563) (xy 66.643726 -284.301111) (xy 66.601105 -284.276504)
			(xy 66.562984 -284.245379) (xy 66.530349 -284.208542) (xy 66.504046 -284.166946) (xy 66.484755 -284.12167)
			(xy 66.472978 -284.073886) (xy 66.469018 -284.024832) (xy 66.13017 -284.024832) (xy 66.129675 -284.049439)
			(xy 66.12178 -284.098016) (xy 66.106196 -284.144697) (xy 66.083325 -284.188274) (xy 66.05376 -284.227618)
			(xy 66.018267 -284.26171) (xy 65.977764 -284.289666) (xy 65.933302 -284.310764) (xy 65.886031 -284.324456)
			(xy 65.837176 -284.330388) (xy 65.788001 -284.328407) (xy 65.739782 -284.318563) (xy 65.693766 -284.301111)
			(xy 65.651145 -284.276504) (xy 65.613024 -284.245379) (xy 65.580389 -284.208542) (xy 65.554086 -284.166946)
			(xy 65.534795 -284.12167) (xy 65.523018 -284.073886) (xy 65.519058 -284.024832) (xy 65.18021 -284.024832)
			(xy 65.179715 -284.049439) (xy 65.17182 -284.098016) (xy 65.156236 -284.144697) (xy 65.133365 -284.188274)
			(xy 65.1038 -284.227618) (xy 65.068307 -284.26171) (xy 65.027804 -284.289666) (xy 64.983342 -284.310764)
			(xy 64.936071 -284.324456) (xy 64.887216 -284.330388) (xy 64.838041 -284.328407) (xy 64.789822 -284.318563)
			(xy 64.743806 -284.301111) (xy 64.701185 -284.276504) (xy 64.663064 -284.245379) (xy 64.630429 -284.208542)
			(xy 64.604126 -284.166946) (xy 64.584835 -284.12167) (xy 64.573058 -284.073886) (xy 64.569098 -284.024832)
			(xy 64.23025 -284.024832) (xy 64.229755 -284.049439) (xy 64.22186 -284.098016) (xy 64.206276 -284.144697)
			(xy 64.183405 -284.188274) (xy 64.15384 -284.227618) (xy 64.118347 -284.26171) (xy 64.077844 -284.289666)
			(xy 64.033382 -284.310764) (xy 63.986111 -284.324456) (xy 63.937256 -284.330388) (xy 63.888081 -284.328407)
			(xy 63.839862 -284.318563) (xy 63.793846 -284.301111) (xy 63.751225 -284.276504) (xy 63.713104 -284.245379)
			(xy 63.680469 -284.208542) (xy 63.654166 -284.166946) (xy 63.634875 -284.12167) (xy 63.623098 -284.073886)
			(xy 63.619138 -284.024832) (xy 63.28029 -284.024832) (xy 63.279795 -284.049439) (xy 63.2719 -284.098016)
			(xy 63.256316 -284.144697) (xy 63.233445 -284.188274) (xy 63.20388 -284.227618) (xy 63.168387 -284.26171)
			(xy 63.127884 -284.289666) (xy 63.083422 -284.310764) (xy 63.036151 -284.324456) (xy 62.987296 -284.330388)
			(xy 62.938121 -284.328407) (xy 62.889902 -284.318563) (xy 62.843886 -284.301111) (xy 62.801265 -284.276504)
			(xy 62.763144 -284.245379) (xy 62.730509 -284.208542) (xy 62.704206 -284.166946) (xy 62.684915 -284.12167)
			(xy 62.673138 -284.073886) (xy 62.669178 -284.024832) (xy 62.330076 -284.024832) (xy 62.329581 -284.049439)
			(xy 62.321686 -284.098016) (xy 62.306102 -284.144697) (xy 62.283231 -284.188274) (xy 62.253666 -284.227618)
			(xy 62.218173 -284.26171) (xy 62.17767 -284.289666) (xy 62.133208 -284.310764) (xy 62.085937 -284.324456)
			(xy 62.037082 -284.330388) (xy 61.987907 -284.328407) (xy 61.939688 -284.318563) (xy 61.893672 -284.301111)
			(xy 61.851051 -284.276504) (xy 61.81293 -284.245379) (xy 61.780295 -284.208542) (xy 61.753992 -284.166946)
			(xy 61.734701 -284.12167) (xy 61.722924 -284.073886) (xy 61.718964 -284.024832) (xy 61.380116 -284.024832)
			(xy 61.379621 -284.049439) (xy 61.371726 -284.098016) (xy 61.356142 -284.144697) (xy 61.333271 -284.188274)
			(xy 61.303706 -284.227618) (xy 61.268213 -284.26171) (xy 61.22771 -284.289666) (xy 61.183248 -284.310764)
			(xy 61.135977 -284.324456) (xy 61.087122 -284.330388) (xy 61.037947 -284.328407) (xy 60.989728 -284.318563)
			(xy 60.943712 -284.301111) (xy 60.901091 -284.276504) (xy 60.86297 -284.245379) (xy 60.830335 -284.208542)
			(xy 60.804032 -284.166946) (xy 60.784741 -284.12167) (xy 60.772964 -284.073886) (xy 60.769004 -284.024832)
			(xy 60.430156 -284.024832) (xy 60.429661 -284.049439) (xy 60.421766 -284.098016) (xy 60.406182 -284.144697)
			(xy 60.383311 -284.188274) (xy 60.353746 -284.227618) (xy 60.318253 -284.26171) (xy 60.27775 -284.289666)
			(xy 60.233288 -284.310764) (xy 60.186017 -284.324456) (xy 60.137162 -284.330388) (xy 60.087987 -284.328407)
			(xy 60.039768 -284.318563) (xy 59.993752 -284.301111) (xy 59.951131 -284.276504) (xy 59.91301 -284.245379)
			(xy 59.880375 -284.208542) (xy 59.854072 -284.166946) (xy 59.834781 -284.12167) (xy 59.823004 -284.073886)
			(xy 59.819044 -284.024832) (xy 58.530236 -284.024832) (xy 58.529741 -284.049439) (xy 58.521846 -284.098016)
			(xy 58.506262 -284.144697) (xy 58.483391 -284.188274) (xy 58.453826 -284.227618) (xy 58.418333 -284.26171)
			(xy 58.37783 -284.289666) (xy 58.333368 -284.310764) (xy 58.286097 -284.324456) (xy 58.237242 -284.330388)
			(xy 58.188067 -284.328407) (xy 58.139848 -284.318563) (xy 58.093832 -284.301111) (xy 58.051211 -284.276504)
			(xy 58.01309 -284.245379) (xy 57.980455 -284.208542) (xy 57.954152 -284.166946) (xy 57.934861 -284.12167)
			(xy 57.923084 -284.073886) (xy 57.919124 -284.024832) (xy 57.580276 -284.024832) (xy 57.579781 -284.049439)
			(xy 57.571886 -284.098016) (xy 57.556302 -284.144697) (xy 57.533431 -284.188274) (xy 57.503866 -284.227618)
			(xy 57.468373 -284.26171) (xy 57.42787 -284.289666) (xy 57.383408 -284.310764) (xy 57.336137 -284.324456)
			(xy 57.287282 -284.330388) (xy 57.238107 -284.328407) (xy 57.189888 -284.318563) (xy 57.143872 -284.301111)
			(xy 57.101251 -284.276504) (xy 57.06313 -284.245379) (xy 57.030495 -284.208542) (xy 57.004192 -284.166946)
			(xy 56.984901 -284.12167) (xy 56.973124 -284.073886) (xy 56.969164 -284.024832) (xy 56.630062 -284.024832)
			(xy 56.629567 -284.049439) (xy 56.621672 -284.098016) (xy 56.606088 -284.144697) (xy 56.583217 -284.188274)
			(xy 56.553652 -284.227618) (xy 56.518159 -284.26171) (xy 56.477656 -284.289666) (xy 56.433194 -284.310764)
			(xy 56.385923 -284.324456) (xy 56.337068 -284.330388) (xy 56.287893 -284.328407) (xy 56.239674 -284.318563)
			(xy 56.193658 -284.301111) (xy 56.151037 -284.276504) (xy 56.112916 -284.245379) (xy 56.080281 -284.208542)
			(xy 56.053978 -284.166946) (xy 56.034687 -284.12167) (xy 56.02291 -284.073886) (xy 56.01895 -284.024832)
			(xy 55.680102 -284.024832) (xy 55.679607 -284.049439) (xy 55.671712 -284.098016) (xy 55.656128 -284.144697)
			(xy 55.633257 -284.188274) (xy 55.603692 -284.227618) (xy 55.568199 -284.26171) (xy 55.527696 -284.289666)
			(xy 55.483234 -284.310764) (xy 55.435963 -284.324456) (xy 55.387108 -284.330388) (xy 55.337933 -284.328407)
			(xy 55.289714 -284.318563) (xy 55.243698 -284.301111) (xy 55.201077 -284.276504) (xy 55.162956 -284.245379)
			(xy 55.130321 -284.208542) (xy 55.104018 -284.166946) (xy 55.084727 -284.12167) (xy 55.07295 -284.073886)
			(xy 55.06899 -284.024832) (xy 54.730142 -284.024832) (xy 54.729647 -284.049439) (xy 54.721752 -284.098016)
			(xy 54.706168 -284.144697) (xy 54.683297 -284.188274) (xy 54.653732 -284.227618) (xy 54.618239 -284.26171)
			(xy 54.577736 -284.289666) (xy 54.533274 -284.310764) (xy 54.486003 -284.324456) (xy 54.437148 -284.330388)
			(xy 54.387973 -284.328407) (xy 54.339754 -284.318563) (xy 54.293738 -284.301111) (xy 54.251117 -284.276504)
			(xy 54.212996 -284.245379) (xy 54.180361 -284.208542) (xy 54.154058 -284.166946) (xy 54.134767 -284.12167)
			(xy 54.12299 -284.073886) (xy 54.11903 -284.024832) (xy 53.780182 -284.024832) (xy 53.779687 -284.049439)
			(xy 53.771792 -284.098016) (xy 53.756208 -284.144697) (xy 53.733337 -284.188274) (xy 53.703772 -284.227618)
			(xy 53.668279 -284.26171) (xy 53.627776 -284.289666) (xy 53.583314 -284.310764) (xy 53.536043 -284.324456)
			(xy 53.487188 -284.330388) (xy 53.438013 -284.328407) (xy 53.389794 -284.318563) (xy 53.343778 -284.301111)
			(xy 53.301157 -284.276504) (xy 53.263036 -284.245379) (xy 53.230401 -284.208542) (xy 53.204098 -284.166946)
			(xy 53.184807 -284.12167) (xy 53.17303 -284.073886) (xy 53.16907 -284.024832) (xy 52.830222 -284.024832)
			(xy 52.829727 -284.049439) (xy 52.821832 -284.098016) (xy 52.806248 -284.144697) (xy 52.783377 -284.188274)
			(xy 52.753812 -284.227618) (xy 52.718319 -284.26171) (xy 52.677816 -284.289666) (xy 52.633354 -284.310764)
			(xy 52.586083 -284.324456) (xy 52.537228 -284.330388) (xy 52.488053 -284.328407) (xy 52.439834 -284.318563)
			(xy 52.393818 -284.301111) (xy 52.351197 -284.276504) (xy 52.313076 -284.245379) (xy 52.280441 -284.208542)
			(xy 52.254138 -284.166946) (xy 52.234847 -284.12167) (xy 52.22307 -284.073886) (xy 52.21911 -284.024832)
			(xy 51.880262 -284.024832) (xy 51.879767 -284.049439) (xy 51.871872 -284.098016) (xy 51.856288 -284.144697)
			(xy 51.833417 -284.188274) (xy 51.803852 -284.227618) (xy 51.768359 -284.26171) (xy 51.727856 -284.289666)
			(xy 51.683394 -284.310764) (xy 51.636123 -284.324456) (xy 51.587268 -284.330388) (xy 51.538093 -284.328407)
			(xy 51.489874 -284.318563) (xy 51.443858 -284.301111) (xy 51.401237 -284.276504) (xy 51.363116 -284.245379)
			(xy 51.330481 -284.208542) (xy 51.304178 -284.166946) (xy 51.284887 -284.12167) (xy 51.27311 -284.073886)
			(xy 51.26915 -284.024832) (xy 50.930302 -284.024832) (xy 50.929807 -284.049439) (xy 50.921912 -284.098016)
			(xy 50.906328 -284.144697) (xy 50.883457 -284.188274) (xy 50.853892 -284.227618) (xy 50.818399 -284.26171)
			(xy 50.777896 -284.289666) (xy 50.733434 -284.310764) (xy 50.686163 -284.324456) (xy 50.637308 -284.330388)
			(xy 50.588133 -284.328407) (xy 50.539914 -284.318563) (xy 50.493898 -284.301111) (xy 50.451277 -284.276504)
			(xy 50.413156 -284.245379) (xy 50.380521 -284.208542) (xy 50.354218 -284.166946) (xy 50.334927 -284.12167)
			(xy 50.32315 -284.073886) (xy 50.31919 -284.024832) (xy 49.980088 -284.024832) (xy 49.979593 -284.049439)
			(xy 49.971698 -284.098016) (xy 49.956114 -284.144697) (xy 49.933243 -284.188274) (xy 49.903678 -284.227618)
			(xy 49.868185 -284.26171) (xy 49.827682 -284.289666) (xy 49.78322 -284.310764) (xy 49.735949 -284.324456)
			(xy 49.687094 -284.330388) (xy 49.637919 -284.328407) (xy 49.5897 -284.318563) (xy 49.543684 -284.301111)
			(xy 49.501063 -284.276504) (xy 49.462942 -284.245379) (xy 49.430307 -284.208542) (xy 49.404004 -284.166946)
			(xy 49.384713 -284.12167) (xy 49.372936 -284.073886) (xy 49.368976 -284.024832) (xy 49.030128 -284.024832)
			(xy 49.029633 -284.049439) (xy 49.021738 -284.098016) (xy 49.006154 -284.144697) (xy 48.983283 -284.188274)
			(xy 48.953718 -284.227618) (xy 48.918225 -284.26171) (xy 48.877722 -284.289666) (xy 48.83326 -284.310764)
			(xy 48.785989 -284.324456) (xy 48.737134 -284.330388) (xy 48.687959 -284.328407) (xy 48.63974 -284.318563)
			(xy 48.593724 -284.301111) (xy 48.551103 -284.276504) (xy 48.512982 -284.245379) (xy 48.480347 -284.208542)
			(xy 48.454044 -284.166946) (xy 48.434753 -284.12167) (xy 48.422976 -284.073886) (xy 48.419016 -284.024832)
			(xy 48.080168 -284.024832) (xy 48.079673 -284.049439) (xy 48.071778 -284.098016) (xy 48.056194 -284.144697)
			(xy 48.033323 -284.188274) (xy 48.003758 -284.227618) (xy 47.968265 -284.26171) (xy 47.927762 -284.289666)
			(xy 47.8833 -284.310764) (xy 47.836029 -284.324456) (xy 47.787174 -284.330388) (xy 47.737999 -284.328407)
			(xy 47.68978 -284.318563) (xy 47.643764 -284.301111) (xy 47.601143 -284.276504) (xy 47.563022 -284.245379)
			(xy 47.530387 -284.208542) (xy 47.504084 -284.166946) (xy 47.484793 -284.12167) (xy 47.473016 -284.073886)
			(xy 47.469056 -284.024832) (xy 47.130208 -284.024832) (xy 47.129713 -284.049439) (xy 47.121818 -284.098016)
			(xy 47.106234 -284.144697) (xy 47.083363 -284.188274) (xy 47.053798 -284.227618) (xy 47.018305 -284.26171)
			(xy 46.977802 -284.289666) (xy 46.93334 -284.310764) (xy 46.886069 -284.324456) (xy 46.837214 -284.330388)
			(xy 46.788039 -284.328407) (xy 46.73982 -284.318563) (xy 46.693804 -284.301111) (xy 46.651183 -284.276504)
			(xy 46.613062 -284.245379) (xy 46.580427 -284.208542) (xy 46.554124 -284.166946) (xy 46.534833 -284.12167)
			(xy 46.523056 -284.073886) (xy 46.519096 -284.024832) (xy 46.180248 -284.024832) (xy 46.179753 -284.049439)
			(xy 46.171858 -284.098016) (xy 46.156274 -284.144697) (xy 46.133403 -284.188274) (xy 46.103838 -284.227618)
			(xy 46.068345 -284.26171) (xy 46.027842 -284.289666) (xy 45.98338 -284.310764) (xy 45.936109 -284.324456)
			(xy 45.887254 -284.330388) (xy 45.838079 -284.328407) (xy 45.78986 -284.318563) (xy 45.743844 -284.301111)
			(xy 45.701223 -284.276504) (xy 45.663102 -284.245379) (xy 45.630467 -284.208542) (xy 45.604164 -284.166946)
			(xy 45.584873 -284.12167) (xy 45.573096 -284.073886) (xy 45.569136 -284.024832) (xy 45.230288 -284.024832)
			(xy 45.229793 -284.049439) (xy 45.221898 -284.098016) (xy 45.206314 -284.144697) (xy 45.183443 -284.188274)
			(xy 45.153878 -284.227618) (xy 45.118385 -284.26171) (xy 45.077882 -284.289666) (xy 45.03342 -284.310764)
			(xy 44.986149 -284.324456) (xy 44.937294 -284.330388) (xy 44.888119 -284.328407) (xy 44.8399 -284.318563)
			(xy 44.793884 -284.301111) (xy 44.751263 -284.276504) (xy 44.713142 -284.245379) (xy 44.680507 -284.208542)
			(xy 44.654204 -284.166946) (xy 44.634913 -284.12167) (xy 44.623136 -284.073886) (xy 44.619176 -284.024832)
			(xy 41.430194 -284.024832) (xy 41.429699 -284.049439) (xy 41.421804 -284.098016) (xy 41.40622 -284.144697)
			(xy 41.383349 -284.188274) (xy 41.353784 -284.227618) (xy 41.318291 -284.26171) (xy 41.277788 -284.289666)
			(xy 41.233326 -284.310764) (xy 41.186055 -284.324456) (xy 41.1372 -284.330388) (xy 41.088025 -284.328407)
			(xy 41.039806 -284.318563) (xy 40.99379 -284.301111) (xy 40.951169 -284.276504) (xy 40.913048 -284.245379)
			(xy 40.880413 -284.208542) (xy 40.85411 -284.166946) (xy 40.834819 -284.12167) (xy 40.823042 -284.073886)
			(xy 40.819082 -284.024832) (xy 40.480234 -284.024832) (xy 40.479739 -284.049439) (xy 40.471844 -284.098016)
			(xy 40.45626 -284.144697) (xy 40.433389 -284.188274) (xy 40.403824 -284.227618) (xy 40.368331 -284.26171)
			(xy 40.327828 -284.289666) (xy 40.283366 -284.310764) (xy 40.236095 -284.324456) (xy 40.18724 -284.330388)
			(xy 40.138065 -284.328407) (xy 40.089846 -284.318563) (xy 40.04383 -284.301111) (xy 40.001209 -284.276504)
			(xy 39.963088 -284.245379) (xy 39.930453 -284.208542) (xy 39.90415 -284.166946) (xy 39.884859 -284.12167)
			(xy 39.873082 -284.073886) (xy 39.869122 -284.024832) (xy 39.530274 -284.024832) (xy 39.529779 -284.049439)
			(xy 39.521884 -284.098016) (xy 39.5063 -284.144697) (xy 39.483429 -284.188274) (xy 39.453864 -284.227618)
			(xy 39.418371 -284.26171) (xy 39.377868 -284.289666) (xy 39.333406 -284.310764) (xy 39.286135 -284.324456)
			(xy 39.23728 -284.330388) (xy 39.188105 -284.328407) (xy 39.139886 -284.318563) (xy 39.09387 -284.301111)
			(xy 39.051249 -284.276504) (xy 39.013128 -284.245379) (xy 38.980493 -284.208542) (xy 38.95419 -284.166946)
			(xy 38.934899 -284.12167) (xy 38.923122 -284.073886) (xy 38.919162 -284.024832) (xy 38.580314 -284.024832)
			(xy 38.579819 -284.049439) (xy 38.571924 -284.098016) (xy 38.55634 -284.144697) (xy 38.533469 -284.188274)
			(xy 38.503904 -284.227618) (xy 38.468411 -284.26171) (xy 38.427908 -284.289666) (xy 38.383446 -284.310764)
			(xy 38.336175 -284.324456) (xy 38.28732 -284.330388) (xy 38.238145 -284.328407) (xy 38.189926 -284.318563)
			(xy 38.14391 -284.301111) (xy 38.101289 -284.276504) (xy 38.063168 -284.245379) (xy 38.030533 -284.208542)
			(xy 38.00423 -284.166946) (xy 37.984939 -284.12167) (xy 37.973162 -284.073886) (xy 37.969202 -284.024832)
			(xy 37.6301 -284.024832) (xy 37.629605 -284.049439) (xy 37.62171 -284.098016) (xy 37.606126 -284.144697)
			(xy 37.583255 -284.188274) (xy 37.55369 -284.227618) (xy 37.518197 -284.26171) (xy 37.477694 -284.289666)
			(xy 37.433232 -284.310764) (xy 37.385961 -284.324456) (xy 37.337106 -284.330388) (xy 37.287931 -284.328407)
			(xy 37.239712 -284.318563) (xy 37.193696 -284.301111) (xy 37.151075 -284.276504) (xy 37.112954 -284.245379)
			(xy 37.080319 -284.208542) (xy 37.054016 -284.166946) (xy 37.034725 -284.12167) (xy 37.022948 -284.073886)
			(xy 37.018988 -284.024832) (xy 36.68014 -284.024832) (xy 36.679645 -284.049439) (xy 36.67175 -284.098016)
			(xy 36.656166 -284.144697) (xy 36.633295 -284.188274) (xy 36.60373 -284.227618) (xy 36.568237 -284.26171)
			(xy 36.527734 -284.289666) (xy 36.483272 -284.310764) (xy 36.436001 -284.324456) (xy 36.387146 -284.330388)
			(xy 36.337971 -284.328407) (xy 36.289752 -284.318563) (xy 36.243736 -284.301111) (xy 36.201115 -284.276504)
			(xy 36.162994 -284.245379) (xy 36.130359 -284.208542) (xy 36.104056 -284.166946) (xy 36.084765 -284.12167)
			(xy 36.072988 -284.073886) (xy 36.069028 -284.024832) (xy 34.39033 -284.024832) (xy 34.39033 -284.499812)
			(xy 73.593972 -284.499812) (xy 73.597932 -284.450758) (xy 73.609709 -284.402974) (xy 73.629 -284.357698)
			(xy 73.655303 -284.316102) (xy 73.687938 -284.279265) (xy 73.726059 -284.24814) (xy 73.76868 -284.223533)
			(xy 73.814696 -284.206081) (xy 73.862915 -284.196237) (xy 73.91209 -284.194256) (xy 73.960945 -284.200188)
			(xy 74.008216 -284.21388) (xy 74.052678 -284.234978) (xy 74.093181 -284.262934) (xy 74.128674 -284.297026)
			(xy 74.158239 -284.33637) (xy 74.18111 -284.379947) (xy 74.196694 -284.426628) (xy 74.204589 -284.475205)
			(xy 74.205084 -284.499812) (xy 74.543932 -284.499812) (xy 74.547892 -284.450758) (xy 74.559669 -284.402974)
			(xy 74.57896 -284.357698) (xy 74.605263 -284.316102) (xy 74.637898 -284.279265) (xy 74.676019 -284.24814)
			(xy 74.71864 -284.223533) (xy 74.764656 -284.206081) (xy 74.812875 -284.196237) (xy 74.86205 -284.194256)
			(xy 74.910905 -284.200188) (xy 74.958176 -284.21388) (xy 75.002638 -284.234978) (xy 75.043141 -284.262934)
			(xy 75.078634 -284.297026) (xy 75.108199 -284.33637) (xy 75.13107 -284.379947) (xy 75.146654 -284.426628)
			(xy 75.154549 -284.475205) (xy 75.155044 -284.499812) (xy 75.494146 -284.499812) (xy 75.498106 -284.450758)
			(xy 75.509883 -284.402974) (xy 75.529174 -284.357698) (xy 75.555477 -284.316102) (xy 75.588112 -284.279265)
			(xy 75.626233 -284.24814) (xy 75.668854 -284.223533) (xy 75.71487 -284.206081) (xy 75.763089 -284.196237)
			(xy 75.812264 -284.194256) (xy 75.861119 -284.200188) (xy 75.90839 -284.21388) (xy 75.952852 -284.234978)
			(xy 75.993355 -284.262934) (xy 76.028848 -284.297026) (xy 76.058413 -284.33637) (xy 76.081284 -284.379947)
			(xy 76.096868 -284.426628) (xy 76.104763 -284.475205) (xy 76.105258 -284.499812) (xy 76.104763 -284.524419)
			(xy 76.096868 -284.572996) (xy 76.081284 -284.619677) (xy 76.058413 -284.663254) (xy 76.028848 -284.702598)
			(xy 75.993355 -284.73669) (xy 75.952852 -284.764646) (xy 75.90839 -284.785744) (xy 75.861119 -284.799436)
			(xy 75.812264 -284.805368) (xy 75.763089 -284.803387) (xy 75.71487 -284.793543) (xy 75.668854 -284.776091)
			(xy 75.626233 -284.751484) (xy 75.588112 -284.720359) (xy 75.555477 -284.683522) (xy 75.529174 -284.641926)
			(xy 75.509883 -284.59665) (xy 75.498106 -284.548866) (xy 75.494146 -284.499812) (xy 75.155044 -284.499812)
			(xy 75.154549 -284.524419) (xy 75.146654 -284.572996) (xy 75.13107 -284.619677) (xy 75.108199 -284.663254)
			(xy 75.078634 -284.702598) (xy 75.043141 -284.73669) (xy 75.002638 -284.764646) (xy 74.958176 -284.785744)
			(xy 74.910905 -284.799436) (xy 74.86205 -284.805368) (xy 74.812875 -284.803387) (xy 74.764656 -284.793543)
			(xy 74.71864 -284.776091) (xy 74.676019 -284.751484) (xy 74.637898 -284.720359) (xy 74.605263 -284.683522)
			(xy 74.57896 -284.641926) (xy 74.559669 -284.59665) (xy 74.547892 -284.548866) (xy 74.543932 -284.499812)
			(xy 74.205084 -284.499812) (xy 74.204589 -284.524419) (xy 74.196694 -284.572996) (xy 74.18111 -284.619677)
			(xy 74.158239 -284.663254) (xy 74.128674 -284.702598) (xy 74.093181 -284.73669) (xy 74.052678 -284.764646)
			(xy 74.008216 -284.785744) (xy 73.960945 -284.799436) (xy 73.91209 -284.805368) (xy 73.862915 -284.803387)
			(xy 73.814696 -284.793543) (xy 73.76868 -284.776091) (xy 73.726059 -284.751484) (xy 73.687938 -284.720359)
			(xy 73.655303 -284.683522) (xy 73.629 -284.641926) (xy 73.609709 -284.59665) (xy 73.597932 -284.548866)
			(xy 73.593972 -284.499812) (xy 34.39033 -284.499812) (xy 34.39033 -284.974792) (xy 36.069028 -284.974792)
			(xy 36.072988 -284.925738) (xy 36.084765 -284.877954) (xy 36.104056 -284.832678) (xy 36.130359 -284.791082)
			(xy 36.162994 -284.754245) (xy 36.201115 -284.72312) (xy 36.243736 -284.698513) (xy 36.289752 -284.681061)
			(xy 36.337971 -284.671217) (xy 36.387146 -284.669236) (xy 36.436001 -284.675168) (xy 36.483272 -284.68886)
			(xy 36.527734 -284.709958) (xy 36.568237 -284.737914) (xy 36.60373 -284.772006) (xy 36.633295 -284.81135)
			(xy 36.656166 -284.854927) (xy 36.67175 -284.901608) (xy 36.679645 -284.950185) (xy 36.68014 -284.974792)
			(xy 37.018988 -284.974792) (xy 37.022948 -284.925738) (xy 37.034725 -284.877954) (xy 37.054016 -284.832678)
			(xy 37.080319 -284.791082) (xy 37.112954 -284.754245) (xy 37.151075 -284.72312) (xy 37.193696 -284.698513)
			(xy 37.239712 -284.681061) (xy 37.287931 -284.671217) (xy 37.337106 -284.669236) (xy 37.385961 -284.675168)
			(xy 37.433232 -284.68886) (xy 37.477694 -284.709958) (xy 37.518197 -284.737914) (xy 37.55369 -284.772006)
			(xy 37.583255 -284.81135) (xy 37.606126 -284.854927) (xy 37.62171 -284.901608) (xy 37.629605 -284.950185)
			(xy 37.6301 -284.974792) (xy 37.969202 -284.974792) (xy 37.973162 -284.925738) (xy 37.984939 -284.877954)
			(xy 38.00423 -284.832678) (xy 38.030533 -284.791082) (xy 38.063168 -284.754245) (xy 38.101289 -284.72312)
			(xy 38.14391 -284.698513) (xy 38.189926 -284.681061) (xy 38.238145 -284.671217) (xy 38.28732 -284.669236)
			(xy 38.336175 -284.675168) (xy 38.383446 -284.68886) (xy 38.427908 -284.709958) (xy 38.468411 -284.737914)
			(xy 38.503904 -284.772006) (xy 38.533469 -284.81135) (xy 38.55634 -284.854927) (xy 38.571924 -284.901608)
			(xy 38.579819 -284.950185) (xy 38.580314 -284.974792) (xy 38.919162 -284.974792) (xy 38.923122 -284.925738)
			(xy 38.934899 -284.877954) (xy 38.95419 -284.832678) (xy 38.980493 -284.791082) (xy 39.013128 -284.754245)
			(xy 39.051249 -284.72312) (xy 39.09387 -284.698513) (xy 39.139886 -284.681061) (xy 39.188105 -284.671217)
			(xy 39.23728 -284.669236) (xy 39.286135 -284.675168) (xy 39.333406 -284.68886) (xy 39.377868 -284.709958)
			(xy 39.418371 -284.737914) (xy 39.453864 -284.772006) (xy 39.483429 -284.81135) (xy 39.5063 -284.854927)
			(xy 39.521884 -284.901608) (xy 39.529779 -284.950185) (xy 39.530274 -284.974792) (xy 39.869122 -284.974792)
			(xy 39.873082 -284.925738) (xy 39.884859 -284.877954) (xy 39.90415 -284.832678) (xy 39.930453 -284.791082)
			(xy 39.963088 -284.754245) (xy 40.001209 -284.72312) (xy 40.04383 -284.698513) (xy 40.089846 -284.681061)
			(xy 40.138065 -284.671217) (xy 40.18724 -284.669236) (xy 40.236095 -284.675168) (xy 40.283366 -284.68886)
			(xy 40.327828 -284.709958) (xy 40.368331 -284.737914) (xy 40.403824 -284.772006) (xy 40.433389 -284.81135)
			(xy 40.45626 -284.854927) (xy 40.471844 -284.901608) (xy 40.479739 -284.950185) (xy 40.480234 -284.974792)
			(xy 40.819082 -284.974792) (xy 40.823042 -284.925738) (xy 40.834819 -284.877954) (xy 40.85411 -284.832678)
			(xy 40.880413 -284.791082) (xy 40.913048 -284.754245) (xy 40.951169 -284.72312) (xy 40.99379 -284.698513)
			(xy 41.039806 -284.681061) (xy 41.088025 -284.671217) (xy 41.1372 -284.669236) (xy 41.186055 -284.675168)
			(xy 41.233326 -284.68886) (xy 41.277788 -284.709958) (xy 41.318291 -284.737914) (xy 41.353784 -284.772006)
			(xy 41.383349 -284.81135) (xy 41.40622 -284.854927) (xy 41.421804 -284.901608) (xy 41.429699 -284.950185)
			(xy 41.430194 -284.974792) (xy 42.719002 -284.974792) (xy 42.722962 -284.925738) (xy 42.734739 -284.877954)
			(xy 42.75403 -284.832678) (xy 42.780333 -284.791082) (xy 42.812968 -284.754245) (xy 42.851089 -284.72312)
			(xy 42.89371 -284.698513) (xy 42.939726 -284.681061) (xy 42.987945 -284.671217) (xy 43.03712 -284.669236)
			(xy 43.085975 -284.675168) (xy 43.133246 -284.68886) (xy 43.177708 -284.709958) (xy 43.218211 -284.737914)
			(xy 43.253704 -284.772006) (xy 43.283269 -284.81135) (xy 43.30614 -284.854927) (xy 43.321724 -284.901608)
			(xy 43.329619 -284.950185) (xy 43.330114 -284.974792) (xy 44.619176 -284.974792) (xy 44.623136 -284.925738)
			(xy 44.634913 -284.877954) (xy 44.654204 -284.832678) (xy 44.680507 -284.791082) (xy 44.713142 -284.754245)
			(xy 44.751263 -284.72312) (xy 44.793884 -284.698513) (xy 44.8399 -284.681061) (xy 44.888119 -284.671217)
			(xy 44.937294 -284.669236) (xy 44.986149 -284.675168) (xy 45.03342 -284.68886) (xy 45.077882 -284.709958)
			(xy 45.118385 -284.737914) (xy 45.153878 -284.772006) (xy 45.183443 -284.81135) (xy 45.206314 -284.854927)
			(xy 45.221898 -284.901608) (xy 45.229793 -284.950185) (xy 45.230288 -284.974792) (xy 45.569136 -284.974792)
			(xy 45.573096 -284.925738) (xy 45.584873 -284.877954) (xy 45.604164 -284.832678) (xy 45.630467 -284.791082)
			(xy 45.663102 -284.754245) (xy 45.701223 -284.72312) (xy 45.743844 -284.698513) (xy 45.78986 -284.681061)
			(xy 45.838079 -284.671217) (xy 45.887254 -284.669236) (xy 45.936109 -284.675168) (xy 45.98338 -284.68886)
			(xy 46.027842 -284.709958) (xy 46.068345 -284.737914) (xy 46.103838 -284.772006) (xy 46.133403 -284.81135)
			(xy 46.156274 -284.854927) (xy 46.171858 -284.901608) (xy 46.179753 -284.950185) (xy 46.180248 -284.974792)
			(xy 46.519096 -284.974792) (xy 46.523056 -284.925738) (xy 46.534833 -284.877954) (xy 46.554124 -284.832678)
			(xy 46.580427 -284.791082) (xy 46.613062 -284.754245) (xy 46.651183 -284.72312) (xy 46.693804 -284.698513)
			(xy 46.73982 -284.681061) (xy 46.788039 -284.671217) (xy 46.837214 -284.669236) (xy 46.886069 -284.675168)
			(xy 46.93334 -284.68886) (xy 46.977802 -284.709958) (xy 47.018305 -284.737914) (xy 47.053798 -284.772006)
			(xy 47.083363 -284.81135) (xy 47.106234 -284.854927) (xy 47.121818 -284.901608) (xy 47.129713 -284.950185)
			(xy 47.130208 -284.974792) (xy 47.469056 -284.974792) (xy 47.473016 -284.925738) (xy 47.484793 -284.877954)
			(xy 47.504084 -284.832678) (xy 47.530387 -284.791082) (xy 47.563022 -284.754245) (xy 47.601143 -284.72312)
			(xy 47.643764 -284.698513) (xy 47.68978 -284.681061) (xy 47.737999 -284.671217) (xy 47.787174 -284.669236)
			(xy 47.836029 -284.675168) (xy 47.8833 -284.68886) (xy 47.927762 -284.709958) (xy 47.968265 -284.737914)
			(xy 48.003758 -284.772006) (xy 48.033323 -284.81135) (xy 48.056194 -284.854927) (xy 48.071778 -284.901608)
			(xy 48.079673 -284.950185) (xy 48.080168 -284.974792) (xy 48.419016 -284.974792) (xy 48.422976 -284.925738)
			(xy 48.434753 -284.877954) (xy 48.454044 -284.832678) (xy 48.480347 -284.791082) (xy 48.512982 -284.754245)
			(xy 48.551103 -284.72312) (xy 48.593724 -284.698513) (xy 48.63974 -284.681061) (xy 48.687959 -284.671217)
			(xy 48.737134 -284.669236) (xy 48.785989 -284.675168) (xy 48.83326 -284.68886) (xy 48.877722 -284.709958)
			(xy 48.918225 -284.737914) (xy 48.953718 -284.772006) (xy 48.983283 -284.81135) (xy 49.006154 -284.854927)
			(xy 49.021738 -284.901608) (xy 49.029633 -284.950185) (xy 49.030128 -284.974792) (xy 49.368976 -284.974792)
			(xy 49.372936 -284.925738) (xy 49.384713 -284.877954) (xy 49.404004 -284.832678) (xy 49.430307 -284.791082)
			(xy 49.462942 -284.754245) (xy 49.501063 -284.72312) (xy 49.543684 -284.698513) (xy 49.5897 -284.681061)
			(xy 49.637919 -284.671217) (xy 49.687094 -284.669236) (xy 49.735949 -284.675168) (xy 49.78322 -284.68886)
			(xy 49.827682 -284.709958) (xy 49.868185 -284.737914) (xy 49.903678 -284.772006) (xy 49.933243 -284.81135)
			(xy 49.956114 -284.854927) (xy 49.971698 -284.901608) (xy 49.979593 -284.950185) (xy 49.980088 -284.974792)
			(xy 50.31919 -284.974792) (xy 50.32315 -284.925738) (xy 50.334927 -284.877954) (xy 50.354218 -284.832678)
			(xy 50.380521 -284.791082) (xy 50.413156 -284.754245) (xy 50.451277 -284.72312) (xy 50.493898 -284.698513)
			(xy 50.539914 -284.681061) (xy 50.588133 -284.671217) (xy 50.637308 -284.669236) (xy 50.686163 -284.675168)
			(xy 50.733434 -284.68886) (xy 50.777896 -284.709958) (xy 50.818399 -284.737914) (xy 50.853892 -284.772006)
			(xy 50.883457 -284.81135) (xy 50.906328 -284.854927) (xy 50.921912 -284.901608) (xy 50.929807 -284.950185)
			(xy 50.930302 -284.974792) (xy 51.26915 -284.974792) (xy 51.27311 -284.925738) (xy 51.284887 -284.877954)
			(xy 51.304178 -284.832678) (xy 51.330481 -284.791082) (xy 51.363116 -284.754245) (xy 51.401237 -284.72312)
			(xy 51.443858 -284.698513) (xy 51.489874 -284.681061) (xy 51.538093 -284.671217) (xy 51.587268 -284.669236)
			(xy 51.636123 -284.675168) (xy 51.683394 -284.68886) (xy 51.727856 -284.709958) (xy 51.768359 -284.737914)
			(xy 51.803852 -284.772006) (xy 51.833417 -284.81135) (xy 51.856288 -284.854927) (xy 51.871872 -284.901608)
			(xy 51.879767 -284.950185) (xy 51.880262 -284.974792) (xy 52.21911 -284.974792) (xy 52.22307 -284.925738)
			(xy 52.234847 -284.877954) (xy 52.254138 -284.832678) (xy 52.280441 -284.791082) (xy 52.313076 -284.754245)
			(xy 52.351197 -284.72312) (xy 52.393818 -284.698513) (xy 52.439834 -284.681061) (xy 52.488053 -284.671217)
			(xy 52.537228 -284.669236) (xy 52.586083 -284.675168) (xy 52.633354 -284.68886) (xy 52.677816 -284.709958)
			(xy 52.718319 -284.737914) (xy 52.753812 -284.772006) (xy 52.783377 -284.81135) (xy 52.806248 -284.854927)
			(xy 52.821832 -284.901608) (xy 52.829727 -284.950185) (xy 52.830222 -284.974792) (xy 53.16907 -284.974792)
			(xy 53.17303 -284.925738) (xy 53.184807 -284.877954) (xy 53.204098 -284.832678) (xy 53.230401 -284.791082)
			(xy 53.263036 -284.754245) (xy 53.301157 -284.72312) (xy 53.343778 -284.698513) (xy 53.389794 -284.681061)
			(xy 53.438013 -284.671217) (xy 53.487188 -284.669236) (xy 53.536043 -284.675168) (xy 53.583314 -284.68886)
			(xy 53.627776 -284.709958) (xy 53.668279 -284.737914) (xy 53.703772 -284.772006) (xy 53.733337 -284.81135)
			(xy 53.756208 -284.854927) (xy 53.771792 -284.901608) (xy 53.779687 -284.950185) (xy 53.780182 -284.974792)
			(xy 54.11903 -284.974792) (xy 54.12299 -284.925738) (xy 54.134767 -284.877954) (xy 54.154058 -284.832678)
			(xy 54.180361 -284.791082) (xy 54.212996 -284.754245) (xy 54.251117 -284.72312) (xy 54.293738 -284.698513)
			(xy 54.339754 -284.681061) (xy 54.387973 -284.671217) (xy 54.437148 -284.669236) (xy 54.486003 -284.675168)
			(xy 54.533274 -284.68886) (xy 54.577736 -284.709958) (xy 54.618239 -284.737914) (xy 54.653732 -284.772006)
			(xy 54.683297 -284.81135) (xy 54.706168 -284.854927) (xy 54.721752 -284.901608) (xy 54.729647 -284.950185)
			(xy 54.730142 -284.974792) (xy 55.06899 -284.974792) (xy 55.07295 -284.925738) (xy 55.084727 -284.877954)
			(xy 55.104018 -284.832678) (xy 55.130321 -284.791082) (xy 55.162956 -284.754245) (xy 55.201077 -284.72312)
			(xy 55.243698 -284.698513) (xy 55.289714 -284.681061) (xy 55.337933 -284.671217) (xy 55.387108 -284.669236)
			(xy 55.435963 -284.675168) (xy 55.483234 -284.68886) (xy 55.527696 -284.709958) (xy 55.568199 -284.737914)
			(xy 55.603692 -284.772006) (xy 55.633257 -284.81135) (xy 55.656128 -284.854927) (xy 55.671712 -284.901608)
			(xy 55.679607 -284.950185) (xy 55.680102 -284.974792) (xy 56.01895 -284.974792) (xy 56.02291 -284.925738)
			(xy 56.034687 -284.877954) (xy 56.053978 -284.832678) (xy 56.080281 -284.791082) (xy 56.112916 -284.754245)
			(xy 56.151037 -284.72312) (xy 56.193658 -284.698513) (xy 56.239674 -284.681061) (xy 56.287893 -284.671217)
			(xy 56.337068 -284.669236) (xy 56.385923 -284.675168) (xy 56.433194 -284.68886) (xy 56.477656 -284.709958)
			(xy 56.518159 -284.737914) (xy 56.553652 -284.772006) (xy 56.583217 -284.81135) (xy 56.606088 -284.854927)
			(xy 56.621672 -284.901608) (xy 56.629567 -284.950185) (xy 56.630062 -284.974792) (xy 56.969164 -284.974792)
			(xy 56.973124 -284.925738) (xy 56.984901 -284.877954) (xy 57.004192 -284.832678) (xy 57.030495 -284.791082)
			(xy 57.06313 -284.754245) (xy 57.101251 -284.72312) (xy 57.143872 -284.698513) (xy 57.189888 -284.681061)
			(xy 57.238107 -284.671217) (xy 57.287282 -284.669236) (xy 57.336137 -284.675168) (xy 57.383408 -284.68886)
			(xy 57.42787 -284.709958) (xy 57.468373 -284.737914) (xy 57.503866 -284.772006) (xy 57.533431 -284.81135)
			(xy 57.556302 -284.854927) (xy 57.571886 -284.901608) (xy 57.579781 -284.950185) (xy 57.580276 -284.974792)
			(xy 57.919124 -284.974792) (xy 57.923084 -284.925738) (xy 57.934861 -284.877954) (xy 57.954152 -284.832678)
			(xy 57.980455 -284.791082) (xy 58.01309 -284.754245) (xy 58.051211 -284.72312) (xy 58.093832 -284.698513)
			(xy 58.139848 -284.681061) (xy 58.188067 -284.671217) (xy 58.237242 -284.669236) (xy 58.286097 -284.675168)
			(xy 58.333368 -284.68886) (xy 58.37783 -284.709958) (xy 58.418333 -284.737914) (xy 58.453826 -284.772006)
			(xy 58.483391 -284.81135) (xy 58.506262 -284.854927) (xy 58.521846 -284.901608) (xy 58.529741 -284.950185)
			(xy 58.530236 -284.974792) (xy 59.819044 -284.974792) (xy 59.823004 -284.925738) (xy 59.834781 -284.877954)
			(xy 59.854072 -284.832678) (xy 59.880375 -284.791082) (xy 59.91301 -284.754245) (xy 59.951131 -284.72312)
			(xy 59.993752 -284.698513) (xy 60.039768 -284.681061) (xy 60.087987 -284.671217) (xy 60.137162 -284.669236)
			(xy 60.186017 -284.675168) (xy 60.233288 -284.68886) (xy 60.27775 -284.709958) (xy 60.318253 -284.737914)
			(xy 60.353746 -284.772006) (xy 60.383311 -284.81135) (xy 60.406182 -284.854927) (xy 60.421766 -284.901608)
			(xy 60.429661 -284.950185) (xy 60.430156 -284.974792) (xy 60.769004 -284.974792) (xy 60.772964 -284.925738)
			(xy 60.784741 -284.877954) (xy 60.804032 -284.832678) (xy 60.830335 -284.791082) (xy 60.86297 -284.754245)
			(xy 60.901091 -284.72312) (xy 60.943712 -284.698513) (xy 60.989728 -284.681061) (xy 61.037947 -284.671217)
			(xy 61.087122 -284.669236) (xy 61.135977 -284.675168) (xy 61.183248 -284.68886) (xy 61.22771 -284.709958)
			(xy 61.268213 -284.737914) (xy 61.303706 -284.772006) (xy 61.333271 -284.81135) (xy 61.356142 -284.854927)
			(xy 61.371726 -284.901608) (xy 61.379621 -284.950185) (xy 61.380116 -284.974792) (xy 61.718964 -284.974792)
			(xy 61.722924 -284.925738) (xy 61.734701 -284.877954) (xy 61.753992 -284.832678) (xy 61.780295 -284.791082)
			(xy 61.81293 -284.754245) (xy 61.851051 -284.72312) (xy 61.893672 -284.698513) (xy 61.939688 -284.681061)
			(xy 61.987907 -284.671217) (xy 62.037082 -284.669236) (xy 62.085937 -284.675168) (xy 62.133208 -284.68886)
			(xy 62.17767 -284.709958) (xy 62.218173 -284.737914) (xy 62.253666 -284.772006) (xy 62.283231 -284.81135)
			(xy 62.306102 -284.854927) (xy 62.321686 -284.901608) (xy 62.329581 -284.950185) (xy 62.330076 -284.974792)
			(xy 62.669178 -284.974792) (xy 62.673138 -284.925738) (xy 62.684915 -284.877954) (xy 62.704206 -284.832678)
			(xy 62.730509 -284.791082) (xy 62.763144 -284.754245) (xy 62.801265 -284.72312) (xy 62.843886 -284.698513)
			(xy 62.889902 -284.681061) (xy 62.938121 -284.671217) (xy 62.987296 -284.669236) (xy 63.036151 -284.675168)
			(xy 63.083422 -284.68886) (xy 63.127884 -284.709958) (xy 63.168387 -284.737914) (xy 63.20388 -284.772006)
			(xy 63.233445 -284.81135) (xy 63.256316 -284.854927) (xy 63.2719 -284.901608) (xy 63.279795 -284.950185)
			(xy 63.28029 -284.974792) (xy 63.619138 -284.974792) (xy 63.623098 -284.925738) (xy 63.634875 -284.877954)
			(xy 63.654166 -284.832678) (xy 63.680469 -284.791082) (xy 63.713104 -284.754245) (xy 63.751225 -284.72312)
			(xy 63.793846 -284.698513) (xy 63.839862 -284.681061) (xy 63.888081 -284.671217) (xy 63.937256 -284.669236)
			(xy 63.986111 -284.675168) (xy 64.033382 -284.68886) (xy 64.077844 -284.709958) (xy 64.118347 -284.737914)
			(xy 64.15384 -284.772006) (xy 64.183405 -284.81135) (xy 64.206276 -284.854927) (xy 64.22186 -284.901608)
			(xy 64.229755 -284.950185) (xy 64.23025 -284.974792) (xy 64.569098 -284.974792) (xy 64.573058 -284.925738)
			(xy 64.584835 -284.877954) (xy 64.604126 -284.832678) (xy 64.630429 -284.791082) (xy 64.663064 -284.754245)
			(xy 64.701185 -284.72312) (xy 64.743806 -284.698513) (xy 64.789822 -284.681061) (xy 64.838041 -284.671217)
			(xy 64.887216 -284.669236) (xy 64.936071 -284.675168) (xy 64.983342 -284.68886) (xy 65.027804 -284.709958)
			(xy 65.068307 -284.737914) (xy 65.1038 -284.772006) (xy 65.133365 -284.81135) (xy 65.156236 -284.854927)
			(xy 65.17182 -284.901608) (xy 65.179715 -284.950185) (xy 65.18021 -284.974792) (xy 65.519058 -284.974792)
			(xy 65.523018 -284.925738) (xy 65.534795 -284.877954) (xy 65.554086 -284.832678) (xy 65.580389 -284.791082)
			(xy 65.613024 -284.754245) (xy 65.651145 -284.72312) (xy 65.693766 -284.698513) (xy 65.739782 -284.681061)
			(xy 65.788001 -284.671217) (xy 65.837176 -284.669236) (xy 65.886031 -284.675168) (xy 65.933302 -284.68886)
			(xy 65.977764 -284.709958) (xy 66.018267 -284.737914) (xy 66.05376 -284.772006) (xy 66.083325 -284.81135)
			(xy 66.106196 -284.854927) (xy 66.12178 -284.901608) (xy 66.129675 -284.950185) (xy 66.13017 -284.974792)
			(xy 66.469018 -284.974792) (xy 66.472978 -284.925738) (xy 66.484755 -284.877954) (xy 66.504046 -284.832678)
			(xy 66.530349 -284.791082) (xy 66.562984 -284.754245) (xy 66.601105 -284.72312) (xy 66.643726 -284.698513)
			(xy 66.689742 -284.681061) (xy 66.737961 -284.671217) (xy 66.787136 -284.669236) (xy 66.835991 -284.675168)
			(xy 66.883262 -284.68886) (xy 66.927724 -284.709958) (xy 66.968227 -284.737914) (xy 67.00372 -284.772006)
			(xy 67.033285 -284.81135) (xy 67.056156 -284.854927) (xy 67.07174 -284.901608) (xy 67.079635 -284.950185)
			(xy 67.08013 -284.974792) (xy 67.418978 -284.974792) (xy 67.422938 -284.925738) (xy 67.434715 -284.877954)
			(xy 67.454006 -284.832678) (xy 67.480309 -284.791082) (xy 67.512944 -284.754245) (xy 67.551065 -284.72312)
			(xy 67.593686 -284.698513) (xy 67.639702 -284.681061) (xy 67.687921 -284.671217) (xy 67.737096 -284.669236)
			(xy 67.785951 -284.675168) (xy 67.833222 -284.68886) (xy 67.877684 -284.709958) (xy 67.918187 -284.737914)
			(xy 67.95368 -284.772006) (xy 67.983245 -284.81135) (xy 68.006116 -284.854927) (xy 68.0217 -284.901608)
			(xy 68.029595 -284.950185) (xy 68.03009 -284.974792) (xy 68.368938 -284.974792) (xy 68.372898 -284.925738)
			(xy 68.384675 -284.877954) (xy 68.403966 -284.832678) (xy 68.430269 -284.791082) (xy 68.462904 -284.754245)
			(xy 68.501025 -284.72312) (xy 68.543646 -284.698513) (xy 68.589662 -284.681061) (xy 68.637881 -284.671217)
			(xy 68.687056 -284.669236) (xy 68.735911 -284.675168) (xy 68.783182 -284.68886) (xy 68.827644 -284.709958)
			(xy 68.868147 -284.737914) (xy 68.90364 -284.772006) (xy 68.933205 -284.81135) (xy 68.956076 -284.854927)
			(xy 68.97166 -284.901608) (xy 68.979555 -284.950185) (xy 68.98005 -284.974792) (xy 69.319152 -284.974792)
			(xy 69.323112 -284.925738) (xy 69.334889 -284.877954) (xy 69.35418 -284.832678) (xy 69.380483 -284.791082)
			(xy 69.413118 -284.754245) (xy 69.451239 -284.72312) (xy 69.49386 -284.698513) (xy 69.539876 -284.681061)
			(xy 69.588095 -284.671217) (xy 69.63727 -284.669236) (xy 69.686125 -284.675168) (xy 69.733396 -284.68886)
			(xy 69.777858 -284.709958) (xy 69.818361 -284.737914) (xy 69.853854 -284.772006) (xy 69.883419 -284.81135)
			(xy 69.90629 -284.854927) (xy 69.921874 -284.901608) (xy 69.929769 -284.950185) (xy 69.930264 -284.974792)
			(xy 70.269112 -284.974792) (xy 70.273072 -284.925738) (xy 70.284849 -284.877954) (xy 70.30414 -284.832678)
			(xy 70.330443 -284.791082) (xy 70.363078 -284.754245) (xy 70.401199 -284.72312) (xy 70.44382 -284.698513)
			(xy 70.489836 -284.681061) (xy 70.538055 -284.671217) (xy 70.58723 -284.669236) (xy 70.636085 -284.675168)
			(xy 70.683356 -284.68886) (xy 70.727818 -284.709958) (xy 70.768321 -284.737914) (xy 70.803814 -284.772006)
			(xy 70.833379 -284.81135) (xy 70.85625 -284.854927) (xy 70.871834 -284.901608) (xy 70.879729 -284.950185)
			(xy 70.880224 -284.974792) (xy 70.879729 -284.999399) (xy 70.871834 -285.047976) (xy 70.85625 -285.094657)
			(xy 70.833379 -285.138234) (xy 70.803814 -285.177578) (xy 70.768321 -285.21167) (xy 70.727818 -285.239626)
			(xy 70.683356 -285.260724) (xy 70.636085 -285.274416) (xy 70.58723 -285.280348) (xy 70.538055 -285.278367)
			(xy 70.489836 -285.268523) (xy 70.44382 -285.251071) (xy 70.401199 -285.226464) (xy 70.363078 -285.195339)
			(xy 70.330443 -285.158502) (xy 70.30414 -285.116906) (xy 70.284849 -285.07163) (xy 70.273072 -285.023846)
			(xy 70.269112 -284.974792) (xy 69.930264 -284.974792) (xy 69.929769 -284.999399) (xy 69.921874 -285.047976)
			(xy 69.90629 -285.094657) (xy 69.883419 -285.138234) (xy 69.853854 -285.177578) (xy 69.818361 -285.21167)
			(xy 69.777858 -285.239626) (xy 69.733396 -285.260724) (xy 69.686125 -285.274416) (xy 69.63727 -285.280348)
			(xy 69.588095 -285.278367) (xy 69.539876 -285.268523) (xy 69.49386 -285.251071) (xy 69.451239 -285.226464)
			(xy 69.413118 -285.195339) (xy 69.380483 -285.158502) (xy 69.35418 -285.116906) (xy 69.334889 -285.07163)
			(xy 69.323112 -285.023846) (xy 69.319152 -284.974792) (xy 68.98005 -284.974792) (xy 68.979555 -284.999399)
			(xy 68.97166 -285.047976) (xy 68.956076 -285.094657) (xy 68.933205 -285.138234) (xy 68.90364 -285.177578)
			(xy 68.868147 -285.21167) (xy 68.827644 -285.239626) (xy 68.783182 -285.260724) (xy 68.735911 -285.274416)
			(xy 68.687056 -285.280348) (xy 68.637881 -285.278367) (xy 68.589662 -285.268523) (xy 68.543646 -285.251071)
			(xy 68.501025 -285.226464) (xy 68.462904 -285.195339) (xy 68.430269 -285.158502) (xy 68.403966 -285.116906)
			(xy 68.384675 -285.07163) (xy 68.372898 -285.023846) (xy 68.368938 -284.974792) (xy 68.03009 -284.974792)
			(xy 68.029595 -284.999399) (xy 68.0217 -285.047976) (xy 68.006116 -285.094657) (xy 67.983245 -285.138234)
			(xy 67.95368 -285.177578) (xy 67.918187 -285.21167) (xy 67.877684 -285.239626) (xy 67.833222 -285.260724)
			(xy 67.785951 -285.274416) (xy 67.737096 -285.280348) (xy 67.687921 -285.278367) (xy 67.639702 -285.268523)
			(xy 67.593686 -285.251071) (xy 67.551065 -285.226464) (xy 67.512944 -285.195339) (xy 67.480309 -285.158502)
			(xy 67.454006 -285.116906) (xy 67.434715 -285.07163) (xy 67.422938 -285.023846) (xy 67.418978 -284.974792)
			(xy 67.08013 -284.974792) (xy 67.079635 -284.999399) (xy 67.07174 -285.047976) (xy 67.056156 -285.094657)
			(xy 67.033285 -285.138234) (xy 67.00372 -285.177578) (xy 66.968227 -285.21167) (xy 66.927724 -285.239626)
			(xy 66.883262 -285.260724) (xy 66.835991 -285.274416) (xy 66.787136 -285.280348) (xy 66.737961 -285.278367)
			(xy 66.689742 -285.268523) (xy 66.643726 -285.251071) (xy 66.601105 -285.226464) (xy 66.562984 -285.195339)
			(xy 66.530349 -285.158502) (xy 66.504046 -285.116906) (xy 66.484755 -285.07163) (xy 66.472978 -285.023846)
			(xy 66.469018 -284.974792) (xy 66.13017 -284.974792) (xy 66.129675 -284.999399) (xy 66.12178 -285.047976)
			(xy 66.106196 -285.094657) (xy 66.083325 -285.138234) (xy 66.05376 -285.177578) (xy 66.018267 -285.21167)
			(xy 65.977764 -285.239626) (xy 65.933302 -285.260724) (xy 65.886031 -285.274416) (xy 65.837176 -285.280348)
			(xy 65.788001 -285.278367) (xy 65.739782 -285.268523) (xy 65.693766 -285.251071) (xy 65.651145 -285.226464)
			(xy 65.613024 -285.195339) (xy 65.580389 -285.158502) (xy 65.554086 -285.116906) (xy 65.534795 -285.07163)
			(xy 65.523018 -285.023846) (xy 65.519058 -284.974792) (xy 65.18021 -284.974792) (xy 65.179715 -284.999399)
			(xy 65.17182 -285.047976) (xy 65.156236 -285.094657) (xy 65.133365 -285.138234) (xy 65.1038 -285.177578)
			(xy 65.068307 -285.21167) (xy 65.027804 -285.239626) (xy 64.983342 -285.260724) (xy 64.936071 -285.274416)
			(xy 64.887216 -285.280348) (xy 64.838041 -285.278367) (xy 64.789822 -285.268523) (xy 64.743806 -285.251071)
			(xy 64.701185 -285.226464) (xy 64.663064 -285.195339) (xy 64.630429 -285.158502) (xy 64.604126 -285.116906)
			(xy 64.584835 -285.07163) (xy 64.573058 -285.023846) (xy 64.569098 -284.974792) (xy 64.23025 -284.974792)
			(xy 64.229755 -284.999399) (xy 64.22186 -285.047976) (xy 64.206276 -285.094657) (xy 64.183405 -285.138234)
			(xy 64.15384 -285.177578) (xy 64.118347 -285.21167) (xy 64.077844 -285.239626) (xy 64.033382 -285.260724)
			(xy 63.986111 -285.274416) (xy 63.937256 -285.280348) (xy 63.888081 -285.278367) (xy 63.839862 -285.268523)
			(xy 63.793846 -285.251071) (xy 63.751225 -285.226464) (xy 63.713104 -285.195339) (xy 63.680469 -285.158502)
			(xy 63.654166 -285.116906) (xy 63.634875 -285.07163) (xy 63.623098 -285.023846) (xy 63.619138 -284.974792)
			(xy 63.28029 -284.974792) (xy 63.279795 -284.999399) (xy 63.2719 -285.047976) (xy 63.256316 -285.094657)
			(xy 63.233445 -285.138234) (xy 63.20388 -285.177578) (xy 63.168387 -285.21167) (xy 63.127884 -285.239626)
			(xy 63.083422 -285.260724) (xy 63.036151 -285.274416) (xy 62.987296 -285.280348) (xy 62.938121 -285.278367)
			(xy 62.889902 -285.268523) (xy 62.843886 -285.251071) (xy 62.801265 -285.226464) (xy 62.763144 -285.195339)
			(xy 62.730509 -285.158502) (xy 62.704206 -285.116906) (xy 62.684915 -285.07163) (xy 62.673138 -285.023846)
			(xy 62.669178 -284.974792) (xy 62.330076 -284.974792) (xy 62.329581 -284.999399) (xy 62.321686 -285.047976)
			(xy 62.306102 -285.094657) (xy 62.283231 -285.138234) (xy 62.253666 -285.177578) (xy 62.218173 -285.21167)
			(xy 62.17767 -285.239626) (xy 62.133208 -285.260724) (xy 62.085937 -285.274416) (xy 62.037082 -285.280348)
			(xy 61.987907 -285.278367) (xy 61.939688 -285.268523) (xy 61.893672 -285.251071) (xy 61.851051 -285.226464)
			(xy 61.81293 -285.195339) (xy 61.780295 -285.158502) (xy 61.753992 -285.116906) (xy 61.734701 -285.07163)
			(xy 61.722924 -285.023846) (xy 61.718964 -284.974792) (xy 61.380116 -284.974792) (xy 61.379621 -284.999399)
			(xy 61.371726 -285.047976) (xy 61.356142 -285.094657) (xy 61.333271 -285.138234) (xy 61.303706 -285.177578)
			(xy 61.268213 -285.21167) (xy 61.22771 -285.239626) (xy 61.183248 -285.260724) (xy 61.135977 -285.274416)
			(xy 61.087122 -285.280348) (xy 61.037947 -285.278367) (xy 60.989728 -285.268523) (xy 60.943712 -285.251071)
			(xy 60.901091 -285.226464) (xy 60.86297 -285.195339) (xy 60.830335 -285.158502) (xy 60.804032 -285.116906)
			(xy 60.784741 -285.07163) (xy 60.772964 -285.023846) (xy 60.769004 -284.974792) (xy 60.430156 -284.974792)
			(xy 60.429661 -284.999399) (xy 60.421766 -285.047976) (xy 60.406182 -285.094657) (xy 60.383311 -285.138234)
			(xy 60.353746 -285.177578) (xy 60.318253 -285.21167) (xy 60.27775 -285.239626) (xy 60.233288 -285.260724)
			(xy 60.186017 -285.274416) (xy 60.137162 -285.280348) (xy 60.087987 -285.278367) (xy 60.039768 -285.268523)
			(xy 59.993752 -285.251071) (xy 59.951131 -285.226464) (xy 59.91301 -285.195339) (xy 59.880375 -285.158502)
			(xy 59.854072 -285.116906) (xy 59.834781 -285.07163) (xy 59.823004 -285.023846) (xy 59.819044 -284.974792)
			(xy 58.530236 -284.974792) (xy 58.529741 -284.999399) (xy 58.521846 -285.047976) (xy 58.506262 -285.094657)
			(xy 58.483391 -285.138234) (xy 58.453826 -285.177578) (xy 58.418333 -285.21167) (xy 58.37783 -285.239626)
			(xy 58.333368 -285.260724) (xy 58.286097 -285.274416) (xy 58.237242 -285.280348) (xy 58.188067 -285.278367)
			(xy 58.139848 -285.268523) (xy 58.093832 -285.251071) (xy 58.051211 -285.226464) (xy 58.01309 -285.195339)
			(xy 57.980455 -285.158502) (xy 57.954152 -285.116906) (xy 57.934861 -285.07163) (xy 57.923084 -285.023846)
			(xy 57.919124 -284.974792) (xy 57.580276 -284.974792) (xy 57.579781 -284.999399) (xy 57.571886 -285.047976)
			(xy 57.556302 -285.094657) (xy 57.533431 -285.138234) (xy 57.503866 -285.177578) (xy 57.468373 -285.21167)
			(xy 57.42787 -285.239626) (xy 57.383408 -285.260724) (xy 57.336137 -285.274416) (xy 57.287282 -285.280348)
			(xy 57.238107 -285.278367) (xy 57.189888 -285.268523) (xy 57.143872 -285.251071) (xy 57.101251 -285.226464)
			(xy 57.06313 -285.195339) (xy 57.030495 -285.158502) (xy 57.004192 -285.116906) (xy 56.984901 -285.07163)
			(xy 56.973124 -285.023846) (xy 56.969164 -284.974792) (xy 56.630062 -284.974792) (xy 56.629567 -284.999399)
			(xy 56.621672 -285.047976) (xy 56.606088 -285.094657) (xy 56.583217 -285.138234) (xy 56.553652 -285.177578)
			(xy 56.518159 -285.21167) (xy 56.477656 -285.239626) (xy 56.433194 -285.260724) (xy 56.385923 -285.274416)
			(xy 56.337068 -285.280348) (xy 56.287893 -285.278367) (xy 56.239674 -285.268523) (xy 56.193658 -285.251071)
			(xy 56.151037 -285.226464) (xy 56.112916 -285.195339) (xy 56.080281 -285.158502) (xy 56.053978 -285.116906)
			(xy 56.034687 -285.07163) (xy 56.02291 -285.023846) (xy 56.01895 -284.974792) (xy 55.680102 -284.974792)
			(xy 55.679607 -284.999399) (xy 55.671712 -285.047976) (xy 55.656128 -285.094657) (xy 55.633257 -285.138234)
			(xy 55.603692 -285.177578) (xy 55.568199 -285.21167) (xy 55.527696 -285.239626) (xy 55.483234 -285.260724)
			(xy 55.435963 -285.274416) (xy 55.387108 -285.280348) (xy 55.337933 -285.278367) (xy 55.289714 -285.268523)
			(xy 55.243698 -285.251071) (xy 55.201077 -285.226464) (xy 55.162956 -285.195339) (xy 55.130321 -285.158502)
			(xy 55.104018 -285.116906) (xy 55.084727 -285.07163) (xy 55.07295 -285.023846) (xy 55.06899 -284.974792)
			(xy 54.730142 -284.974792) (xy 54.729647 -284.999399) (xy 54.721752 -285.047976) (xy 54.706168 -285.094657)
			(xy 54.683297 -285.138234) (xy 54.653732 -285.177578) (xy 54.618239 -285.21167) (xy 54.577736 -285.239626)
			(xy 54.533274 -285.260724) (xy 54.486003 -285.274416) (xy 54.437148 -285.280348) (xy 54.387973 -285.278367)
			(xy 54.339754 -285.268523) (xy 54.293738 -285.251071) (xy 54.251117 -285.226464) (xy 54.212996 -285.195339)
			(xy 54.180361 -285.158502) (xy 54.154058 -285.116906) (xy 54.134767 -285.07163) (xy 54.12299 -285.023846)
			(xy 54.11903 -284.974792) (xy 53.780182 -284.974792) (xy 53.779687 -284.999399) (xy 53.771792 -285.047976)
			(xy 53.756208 -285.094657) (xy 53.733337 -285.138234) (xy 53.703772 -285.177578) (xy 53.668279 -285.21167)
			(xy 53.627776 -285.239626) (xy 53.583314 -285.260724) (xy 53.536043 -285.274416) (xy 53.487188 -285.280348)
			(xy 53.438013 -285.278367) (xy 53.389794 -285.268523) (xy 53.343778 -285.251071) (xy 53.301157 -285.226464)
			(xy 53.263036 -285.195339) (xy 53.230401 -285.158502) (xy 53.204098 -285.116906) (xy 53.184807 -285.07163)
			(xy 53.17303 -285.023846) (xy 53.16907 -284.974792) (xy 52.830222 -284.974792) (xy 52.829727 -284.999399)
			(xy 52.821832 -285.047976) (xy 52.806248 -285.094657) (xy 52.783377 -285.138234) (xy 52.753812 -285.177578)
			(xy 52.718319 -285.21167) (xy 52.677816 -285.239626) (xy 52.633354 -285.260724) (xy 52.586083 -285.274416)
			(xy 52.537228 -285.280348) (xy 52.488053 -285.278367) (xy 52.439834 -285.268523) (xy 52.393818 -285.251071)
			(xy 52.351197 -285.226464) (xy 52.313076 -285.195339) (xy 52.280441 -285.158502) (xy 52.254138 -285.116906)
			(xy 52.234847 -285.07163) (xy 52.22307 -285.023846) (xy 52.21911 -284.974792) (xy 51.880262 -284.974792)
			(xy 51.879767 -284.999399) (xy 51.871872 -285.047976) (xy 51.856288 -285.094657) (xy 51.833417 -285.138234)
			(xy 51.803852 -285.177578) (xy 51.768359 -285.21167) (xy 51.727856 -285.239626) (xy 51.683394 -285.260724)
			(xy 51.636123 -285.274416) (xy 51.587268 -285.280348) (xy 51.538093 -285.278367) (xy 51.489874 -285.268523)
			(xy 51.443858 -285.251071) (xy 51.401237 -285.226464) (xy 51.363116 -285.195339) (xy 51.330481 -285.158502)
			(xy 51.304178 -285.116906) (xy 51.284887 -285.07163) (xy 51.27311 -285.023846) (xy 51.26915 -284.974792)
			(xy 50.930302 -284.974792) (xy 50.929807 -284.999399) (xy 50.921912 -285.047976) (xy 50.906328 -285.094657)
			(xy 50.883457 -285.138234) (xy 50.853892 -285.177578) (xy 50.818399 -285.21167) (xy 50.777896 -285.239626)
			(xy 50.733434 -285.260724) (xy 50.686163 -285.274416) (xy 50.637308 -285.280348) (xy 50.588133 -285.278367)
			(xy 50.539914 -285.268523) (xy 50.493898 -285.251071) (xy 50.451277 -285.226464) (xy 50.413156 -285.195339)
			(xy 50.380521 -285.158502) (xy 50.354218 -285.116906) (xy 50.334927 -285.07163) (xy 50.32315 -285.023846)
			(xy 50.31919 -284.974792) (xy 49.980088 -284.974792) (xy 49.979593 -284.999399) (xy 49.971698 -285.047976)
			(xy 49.956114 -285.094657) (xy 49.933243 -285.138234) (xy 49.903678 -285.177578) (xy 49.868185 -285.21167)
			(xy 49.827682 -285.239626) (xy 49.78322 -285.260724) (xy 49.735949 -285.274416) (xy 49.687094 -285.280348)
			(xy 49.637919 -285.278367) (xy 49.5897 -285.268523) (xy 49.543684 -285.251071) (xy 49.501063 -285.226464)
			(xy 49.462942 -285.195339) (xy 49.430307 -285.158502) (xy 49.404004 -285.116906) (xy 49.384713 -285.07163)
			(xy 49.372936 -285.023846) (xy 49.368976 -284.974792) (xy 49.030128 -284.974792) (xy 49.029633 -284.999399)
			(xy 49.021738 -285.047976) (xy 49.006154 -285.094657) (xy 48.983283 -285.138234) (xy 48.953718 -285.177578)
			(xy 48.918225 -285.21167) (xy 48.877722 -285.239626) (xy 48.83326 -285.260724) (xy 48.785989 -285.274416)
			(xy 48.737134 -285.280348) (xy 48.687959 -285.278367) (xy 48.63974 -285.268523) (xy 48.593724 -285.251071)
			(xy 48.551103 -285.226464) (xy 48.512982 -285.195339) (xy 48.480347 -285.158502) (xy 48.454044 -285.116906)
			(xy 48.434753 -285.07163) (xy 48.422976 -285.023846) (xy 48.419016 -284.974792) (xy 48.080168 -284.974792)
			(xy 48.079673 -284.999399) (xy 48.071778 -285.047976) (xy 48.056194 -285.094657) (xy 48.033323 -285.138234)
			(xy 48.003758 -285.177578) (xy 47.968265 -285.21167) (xy 47.927762 -285.239626) (xy 47.8833 -285.260724)
			(xy 47.836029 -285.274416) (xy 47.787174 -285.280348) (xy 47.737999 -285.278367) (xy 47.68978 -285.268523)
			(xy 47.643764 -285.251071) (xy 47.601143 -285.226464) (xy 47.563022 -285.195339) (xy 47.530387 -285.158502)
			(xy 47.504084 -285.116906) (xy 47.484793 -285.07163) (xy 47.473016 -285.023846) (xy 47.469056 -284.974792)
			(xy 47.130208 -284.974792) (xy 47.129713 -284.999399) (xy 47.121818 -285.047976) (xy 47.106234 -285.094657)
			(xy 47.083363 -285.138234) (xy 47.053798 -285.177578) (xy 47.018305 -285.21167) (xy 46.977802 -285.239626)
			(xy 46.93334 -285.260724) (xy 46.886069 -285.274416) (xy 46.837214 -285.280348) (xy 46.788039 -285.278367)
			(xy 46.73982 -285.268523) (xy 46.693804 -285.251071) (xy 46.651183 -285.226464) (xy 46.613062 -285.195339)
			(xy 46.580427 -285.158502) (xy 46.554124 -285.116906) (xy 46.534833 -285.07163) (xy 46.523056 -285.023846)
			(xy 46.519096 -284.974792) (xy 46.180248 -284.974792) (xy 46.179753 -284.999399) (xy 46.171858 -285.047976)
			(xy 46.156274 -285.094657) (xy 46.133403 -285.138234) (xy 46.103838 -285.177578) (xy 46.068345 -285.21167)
			(xy 46.027842 -285.239626) (xy 45.98338 -285.260724) (xy 45.936109 -285.274416) (xy 45.887254 -285.280348)
			(xy 45.838079 -285.278367) (xy 45.78986 -285.268523) (xy 45.743844 -285.251071) (xy 45.701223 -285.226464)
			(xy 45.663102 -285.195339) (xy 45.630467 -285.158502) (xy 45.604164 -285.116906) (xy 45.584873 -285.07163)
			(xy 45.573096 -285.023846) (xy 45.569136 -284.974792) (xy 45.230288 -284.974792) (xy 45.229793 -284.999399)
			(xy 45.221898 -285.047976) (xy 45.206314 -285.094657) (xy 45.183443 -285.138234) (xy 45.153878 -285.177578)
			(xy 45.118385 -285.21167) (xy 45.077882 -285.239626) (xy 45.03342 -285.260724) (xy 44.986149 -285.274416)
			(xy 44.937294 -285.280348) (xy 44.888119 -285.278367) (xy 44.8399 -285.268523) (xy 44.793884 -285.251071)
			(xy 44.751263 -285.226464) (xy 44.713142 -285.195339) (xy 44.680507 -285.158502) (xy 44.654204 -285.116906)
			(xy 44.634913 -285.07163) (xy 44.623136 -285.023846) (xy 44.619176 -284.974792) (xy 43.330114 -284.974792)
			(xy 43.329619 -284.999399) (xy 43.321724 -285.047976) (xy 43.30614 -285.094657) (xy 43.283269 -285.138234)
			(xy 43.253704 -285.177578) (xy 43.218211 -285.21167) (xy 43.177708 -285.239626) (xy 43.133246 -285.260724)
			(xy 43.085975 -285.274416) (xy 43.03712 -285.280348) (xy 42.987945 -285.278367) (xy 42.939726 -285.268523)
			(xy 42.89371 -285.251071) (xy 42.851089 -285.226464) (xy 42.812968 -285.195339) (xy 42.780333 -285.158502)
			(xy 42.75403 -285.116906) (xy 42.734739 -285.07163) (xy 42.722962 -285.023846) (xy 42.719002 -284.974792)
			(xy 41.430194 -284.974792) (xy 41.429699 -284.999399) (xy 41.421804 -285.047976) (xy 41.40622 -285.094657)
			(xy 41.383349 -285.138234) (xy 41.353784 -285.177578) (xy 41.318291 -285.21167) (xy 41.277788 -285.239626)
			(xy 41.233326 -285.260724) (xy 41.186055 -285.274416) (xy 41.1372 -285.280348) (xy 41.088025 -285.278367)
			(xy 41.039806 -285.268523) (xy 40.99379 -285.251071) (xy 40.951169 -285.226464) (xy 40.913048 -285.195339)
			(xy 40.880413 -285.158502) (xy 40.85411 -285.116906) (xy 40.834819 -285.07163) (xy 40.823042 -285.023846)
			(xy 40.819082 -284.974792) (xy 40.480234 -284.974792) (xy 40.479739 -284.999399) (xy 40.471844 -285.047976)
			(xy 40.45626 -285.094657) (xy 40.433389 -285.138234) (xy 40.403824 -285.177578) (xy 40.368331 -285.21167)
			(xy 40.327828 -285.239626) (xy 40.283366 -285.260724) (xy 40.236095 -285.274416) (xy 40.18724 -285.280348)
			(xy 40.138065 -285.278367) (xy 40.089846 -285.268523) (xy 40.04383 -285.251071) (xy 40.001209 -285.226464)
			(xy 39.963088 -285.195339) (xy 39.930453 -285.158502) (xy 39.90415 -285.116906) (xy 39.884859 -285.07163)
			(xy 39.873082 -285.023846) (xy 39.869122 -284.974792) (xy 39.530274 -284.974792) (xy 39.529779 -284.999399)
			(xy 39.521884 -285.047976) (xy 39.5063 -285.094657) (xy 39.483429 -285.138234) (xy 39.453864 -285.177578)
			(xy 39.418371 -285.21167) (xy 39.377868 -285.239626) (xy 39.333406 -285.260724) (xy 39.286135 -285.274416)
			(xy 39.23728 -285.280348) (xy 39.188105 -285.278367) (xy 39.139886 -285.268523) (xy 39.09387 -285.251071)
			(xy 39.051249 -285.226464) (xy 39.013128 -285.195339) (xy 38.980493 -285.158502) (xy 38.95419 -285.116906)
			(xy 38.934899 -285.07163) (xy 38.923122 -285.023846) (xy 38.919162 -284.974792) (xy 38.580314 -284.974792)
			(xy 38.579819 -284.999399) (xy 38.571924 -285.047976) (xy 38.55634 -285.094657) (xy 38.533469 -285.138234)
			(xy 38.503904 -285.177578) (xy 38.468411 -285.21167) (xy 38.427908 -285.239626) (xy 38.383446 -285.260724)
			(xy 38.336175 -285.274416) (xy 38.28732 -285.280348) (xy 38.238145 -285.278367) (xy 38.189926 -285.268523)
			(xy 38.14391 -285.251071) (xy 38.101289 -285.226464) (xy 38.063168 -285.195339) (xy 38.030533 -285.158502)
			(xy 38.00423 -285.116906) (xy 37.984939 -285.07163) (xy 37.973162 -285.023846) (xy 37.969202 -284.974792)
			(xy 37.6301 -284.974792) (xy 37.629605 -284.999399) (xy 37.62171 -285.047976) (xy 37.606126 -285.094657)
			(xy 37.583255 -285.138234) (xy 37.55369 -285.177578) (xy 37.518197 -285.21167) (xy 37.477694 -285.239626)
			(xy 37.433232 -285.260724) (xy 37.385961 -285.274416) (xy 37.337106 -285.280348) (xy 37.287931 -285.278367)
			(xy 37.239712 -285.268523) (xy 37.193696 -285.251071) (xy 37.151075 -285.226464) (xy 37.112954 -285.195339)
			(xy 37.080319 -285.158502) (xy 37.054016 -285.116906) (xy 37.034725 -285.07163) (xy 37.022948 -285.023846)
			(xy 37.018988 -284.974792) (xy 36.68014 -284.974792) (xy 36.679645 -284.999399) (xy 36.67175 -285.047976)
			(xy 36.656166 -285.094657) (xy 36.633295 -285.138234) (xy 36.60373 -285.177578) (xy 36.568237 -285.21167)
			(xy 36.527734 -285.239626) (xy 36.483272 -285.260724) (xy 36.436001 -285.274416) (xy 36.387146 -285.280348)
			(xy 36.337971 -285.278367) (xy 36.289752 -285.268523) (xy 36.243736 -285.251071) (xy 36.201115 -285.226464)
			(xy 36.162994 -285.195339) (xy 36.130359 -285.158502) (xy 36.104056 -285.116906) (xy 36.084765 -285.07163)
			(xy 36.072988 -285.023846) (xy 36.069028 -284.974792) (xy 34.39033 -284.974792) (xy 34.39033 -285.449772)
			(xy 73.593972 -285.449772) (xy 73.597932 -285.400718) (xy 73.609709 -285.352934) (xy 73.629 -285.307658)
			(xy 73.655303 -285.266062) (xy 73.687938 -285.229225) (xy 73.726059 -285.1981) (xy 73.76868 -285.173493)
			(xy 73.814696 -285.156041) (xy 73.862915 -285.146197) (xy 73.91209 -285.144216) (xy 73.960945 -285.150148)
			(xy 74.008216 -285.16384) (xy 74.052678 -285.184938) (xy 74.093181 -285.212894) (xy 74.128674 -285.246986)
			(xy 74.158239 -285.28633) (xy 74.18111 -285.329907) (xy 74.196694 -285.376588) (xy 74.204589 -285.425165)
			(xy 74.205084 -285.449772) (xy 74.543932 -285.449772) (xy 74.547892 -285.400718) (xy 74.559669 -285.352934)
			(xy 74.57896 -285.307658) (xy 74.605263 -285.266062) (xy 74.637898 -285.229225) (xy 74.676019 -285.1981)
			(xy 74.71864 -285.173493) (xy 74.764656 -285.156041) (xy 74.812875 -285.146197) (xy 74.86205 -285.144216)
			(xy 74.910905 -285.150148) (xy 74.958176 -285.16384) (xy 75.002638 -285.184938) (xy 75.043141 -285.212894)
			(xy 75.078634 -285.246986) (xy 75.108199 -285.28633) (xy 75.13107 -285.329907) (xy 75.146654 -285.376588)
			(xy 75.154549 -285.425165) (xy 75.155044 -285.449772) (xy 75.494146 -285.449772) (xy 75.498106 -285.400718)
			(xy 75.509883 -285.352934) (xy 75.529174 -285.307658) (xy 75.555477 -285.266062) (xy 75.588112 -285.229225)
			(xy 75.626233 -285.1981) (xy 75.668854 -285.173493) (xy 75.71487 -285.156041) (xy 75.763089 -285.146197)
			(xy 75.812264 -285.144216) (xy 75.861119 -285.150148) (xy 75.90839 -285.16384) (xy 75.952852 -285.184938)
			(xy 75.993355 -285.212894) (xy 76.028848 -285.246986) (xy 76.058413 -285.28633) (xy 76.081284 -285.329907)
			(xy 76.096868 -285.376588) (xy 76.104763 -285.425165) (xy 76.105258 -285.449772) (xy 76.104763 -285.474379)
			(xy 76.096868 -285.522956) (xy 76.081284 -285.569637) (xy 76.058413 -285.613214) (xy 76.028848 -285.652558)
			(xy 75.993355 -285.68665) (xy 75.952852 -285.714606) (xy 75.90839 -285.735704) (xy 75.861119 -285.749396)
			(xy 75.812264 -285.755328) (xy 75.763089 -285.753347) (xy 75.71487 -285.743503) (xy 75.668854 -285.726051)
			(xy 75.626233 -285.701444) (xy 75.588112 -285.670319) (xy 75.555477 -285.633482) (xy 75.529174 -285.591886)
			(xy 75.509883 -285.54661) (xy 75.498106 -285.498826) (xy 75.494146 -285.449772) (xy 75.155044 -285.449772)
			(xy 75.154549 -285.474379) (xy 75.146654 -285.522956) (xy 75.13107 -285.569637) (xy 75.108199 -285.613214)
			(xy 75.078634 -285.652558) (xy 75.043141 -285.68665) (xy 75.002638 -285.714606) (xy 74.958176 -285.735704)
			(xy 74.910905 -285.749396) (xy 74.86205 -285.755328) (xy 74.812875 -285.753347) (xy 74.764656 -285.743503)
			(xy 74.71864 -285.726051) (xy 74.676019 -285.701444) (xy 74.637898 -285.670319) (xy 74.605263 -285.633482)
			(xy 74.57896 -285.591886) (xy 74.559669 -285.54661) (xy 74.547892 -285.498826) (xy 74.543932 -285.449772)
			(xy 74.205084 -285.449772) (xy 74.204589 -285.474379) (xy 74.196694 -285.522956) (xy 74.18111 -285.569637)
			(xy 74.158239 -285.613214) (xy 74.128674 -285.652558) (xy 74.093181 -285.68665) (xy 74.052678 -285.714606)
			(xy 74.008216 -285.735704) (xy 73.960945 -285.749396) (xy 73.91209 -285.755328) (xy 73.862915 -285.753347)
			(xy 73.814696 -285.743503) (xy 73.76868 -285.726051) (xy 73.726059 -285.701444) (xy 73.687938 -285.670319)
			(xy 73.655303 -285.633482) (xy 73.629 -285.591886) (xy 73.609709 -285.54661) (xy 73.597932 -285.498826)
			(xy 73.593972 -285.449772) (xy 34.39033 -285.449772) (xy 34.39033 -285.924752) (xy 36.069028 -285.924752)
			(xy 36.072988 -285.875698) (xy 36.084765 -285.827914) (xy 36.104056 -285.782638) (xy 36.130359 -285.741042)
			(xy 36.162994 -285.704205) (xy 36.201115 -285.67308) (xy 36.243736 -285.648473) (xy 36.289752 -285.631021)
			(xy 36.337971 -285.621177) (xy 36.387146 -285.619196) (xy 36.436001 -285.625128) (xy 36.483272 -285.63882)
			(xy 36.527734 -285.659918) (xy 36.568237 -285.687874) (xy 36.60373 -285.721966) (xy 36.633295 -285.76131)
			(xy 36.656166 -285.804887) (xy 36.67175 -285.851568) (xy 36.679645 -285.900145) (xy 36.68014 -285.924752)
			(xy 37.018988 -285.924752) (xy 37.022948 -285.875698) (xy 37.034725 -285.827914) (xy 37.054016 -285.782638)
			(xy 37.080319 -285.741042) (xy 37.112954 -285.704205) (xy 37.151075 -285.67308) (xy 37.193696 -285.648473)
			(xy 37.239712 -285.631021) (xy 37.287931 -285.621177) (xy 37.337106 -285.619196) (xy 37.385961 -285.625128)
			(xy 37.433232 -285.63882) (xy 37.477694 -285.659918) (xy 37.518197 -285.687874) (xy 37.55369 -285.721966)
			(xy 37.583255 -285.76131) (xy 37.606126 -285.804887) (xy 37.62171 -285.851568) (xy 37.629605 -285.900145)
			(xy 37.6301 -285.924752) (xy 37.969202 -285.924752) (xy 37.973162 -285.875698) (xy 37.984939 -285.827914)
			(xy 38.00423 -285.782638) (xy 38.030533 -285.741042) (xy 38.063168 -285.704205) (xy 38.101289 -285.67308)
			(xy 38.14391 -285.648473) (xy 38.189926 -285.631021) (xy 38.238145 -285.621177) (xy 38.28732 -285.619196)
			(xy 38.336175 -285.625128) (xy 38.383446 -285.63882) (xy 38.427908 -285.659918) (xy 38.468411 -285.687874)
			(xy 38.503904 -285.721966) (xy 38.533469 -285.76131) (xy 38.55634 -285.804887) (xy 38.571924 -285.851568)
			(xy 38.579819 -285.900145) (xy 38.580314 -285.924752) (xy 38.919162 -285.924752) (xy 38.923122 -285.875698)
			(xy 38.934899 -285.827914) (xy 38.95419 -285.782638) (xy 38.980493 -285.741042) (xy 39.013128 -285.704205)
			(xy 39.051249 -285.67308) (xy 39.09387 -285.648473) (xy 39.139886 -285.631021) (xy 39.188105 -285.621177)
			(xy 39.23728 -285.619196) (xy 39.286135 -285.625128) (xy 39.333406 -285.63882) (xy 39.377868 -285.659918)
			(xy 39.418371 -285.687874) (xy 39.453864 -285.721966) (xy 39.483429 -285.76131) (xy 39.5063 -285.804887)
			(xy 39.521884 -285.851568) (xy 39.529779 -285.900145) (xy 39.530274 -285.924752) (xy 39.869122 -285.924752)
			(xy 39.873082 -285.875698) (xy 39.884859 -285.827914) (xy 39.90415 -285.782638) (xy 39.930453 -285.741042)
			(xy 39.963088 -285.704205) (xy 40.001209 -285.67308) (xy 40.04383 -285.648473) (xy 40.089846 -285.631021)
			(xy 40.138065 -285.621177) (xy 40.18724 -285.619196) (xy 40.236095 -285.625128) (xy 40.283366 -285.63882)
			(xy 40.327828 -285.659918) (xy 40.368331 -285.687874) (xy 40.403824 -285.721966) (xy 40.433389 -285.76131)
			(xy 40.45626 -285.804887) (xy 40.471844 -285.851568) (xy 40.479739 -285.900145) (xy 40.480234 -285.924752)
			(xy 40.819082 -285.924752) (xy 40.823042 -285.875698) (xy 40.834819 -285.827914) (xy 40.85411 -285.782638)
			(xy 40.880413 -285.741042) (xy 40.913048 -285.704205) (xy 40.951169 -285.67308) (xy 40.99379 -285.648473)
			(xy 41.039806 -285.631021) (xy 41.088025 -285.621177) (xy 41.1372 -285.619196) (xy 41.186055 -285.625128)
			(xy 41.233326 -285.63882) (xy 41.277788 -285.659918) (xy 41.318291 -285.687874) (xy 41.353784 -285.721966)
			(xy 41.383349 -285.76131) (xy 41.40622 -285.804887) (xy 41.421804 -285.851568) (xy 41.429699 -285.900145)
			(xy 41.430194 -285.924752) (xy 44.619176 -285.924752) (xy 44.623136 -285.875698) (xy 44.634913 -285.827914)
			(xy 44.654204 -285.782638) (xy 44.680507 -285.741042) (xy 44.713142 -285.704205) (xy 44.751263 -285.67308)
			(xy 44.793884 -285.648473) (xy 44.8399 -285.631021) (xy 44.888119 -285.621177) (xy 44.937294 -285.619196)
			(xy 44.986149 -285.625128) (xy 45.03342 -285.63882) (xy 45.077882 -285.659918) (xy 45.118385 -285.687874)
			(xy 45.153878 -285.721966) (xy 45.183443 -285.76131) (xy 45.206314 -285.804887) (xy 45.221898 -285.851568)
			(xy 45.229793 -285.900145) (xy 45.230288 -285.924752) (xy 45.569136 -285.924752) (xy 45.573096 -285.875698)
			(xy 45.584873 -285.827914) (xy 45.604164 -285.782638) (xy 45.630467 -285.741042) (xy 45.663102 -285.704205)
			(xy 45.701223 -285.67308) (xy 45.743844 -285.648473) (xy 45.78986 -285.631021) (xy 45.838079 -285.621177)
			(xy 45.887254 -285.619196) (xy 45.936109 -285.625128) (xy 45.98338 -285.63882) (xy 46.027842 -285.659918)
			(xy 46.068345 -285.687874) (xy 46.103838 -285.721966) (xy 46.133403 -285.76131) (xy 46.156274 -285.804887)
			(xy 46.171858 -285.851568) (xy 46.179753 -285.900145) (xy 46.180248 -285.924752) (xy 46.519096 -285.924752)
			(xy 46.523056 -285.875698) (xy 46.534833 -285.827914) (xy 46.554124 -285.782638) (xy 46.580427 -285.741042)
			(xy 46.613062 -285.704205) (xy 46.651183 -285.67308) (xy 46.693804 -285.648473) (xy 46.73982 -285.631021)
			(xy 46.788039 -285.621177) (xy 46.837214 -285.619196) (xy 46.886069 -285.625128) (xy 46.93334 -285.63882)
			(xy 46.977802 -285.659918) (xy 47.018305 -285.687874) (xy 47.053798 -285.721966) (xy 47.083363 -285.76131)
			(xy 47.106234 -285.804887) (xy 47.121818 -285.851568) (xy 47.129713 -285.900145) (xy 47.130208 -285.924752)
			(xy 47.469056 -285.924752) (xy 47.473016 -285.875698) (xy 47.484793 -285.827914) (xy 47.504084 -285.782638)
			(xy 47.530387 -285.741042) (xy 47.563022 -285.704205) (xy 47.601143 -285.67308) (xy 47.643764 -285.648473)
			(xy 47.68978 -285.631021) (xy 47.737999 -285.621177) (xy 47.787174 -285.619196) (xy 47.836029 -285.625128)
			(xy 47.8833 -285.63882) (xy 47.927762 -285.659918) (xy 47.968265 -285.687874) (xy 48.003758 -285.721966)
			(xy 48.033323 -285.76131) (xy 48.056194 -285.804887) (xy 48.071778 -285.851568) (xy 48.079673 -285.900145)
			(xy 48.080168 -285.924752) (xy 48.419016 -285.924752) (xy 48.422976 -285.875698) (xy 48.434753 -285.827914)
			(xy 48.454044 -285.782638) (xy 48.480347 -285.741042) (xy 48.512982 -285.704205) (xy 48.551103 -285.67308)
			(xy 48.593724 -285.648473) (xy 48.63974 -285.631021) (xy 48.687959 -285.621177) (xy 48.737134 -285.619196)
			(xy 48.785989 -285.625128) (xy 48.83326 -285.63882) (xy 48.877722 -285.659918) (xy 48.918225 -285.687874)
			(xy 48.953718 -285.721966) (xy 48.983283 -285.76131) (xy 49.006154 -285.804887) (xy 49.021738 -285.851568)
			(xy 49.029633 -285.900145) (xy 49.030128 -285.924752) (xy 49.368976 -285.924752) (xy 49.372936 -285.875698)
			(xy 49.384713 -285.827914) (xy 49.404004 -285.782638) (xy 49.430307 -285.741042) (xy 49.462942 -285.704205)
			(xy 49.501063 -285.67308) (xy 49.543684 -285.648473) (xy 49.5897 -285.631021) (xy 49.637919 -285.621177)
			(xy 49.687094 -285.619196) (xy 49.735949 -285.625128) (xy 49.78322 -285.63882) (xy 49.827682 -285.659918)
			(xy 49.868185 -285.687874) (xy 49.903678 -285.721966) (xy 49.933243 -285.76131) (xy 49.956114 -285.804887)
			(xy 49.971698 -285.851568) (xy 49.979593 -285.900145) (xy 49.980088 -285.924752) (xy 50.31919 -285.924752)
			(xy 50.32315 -285.875698) (xy 50.334927 -285.827914) (xy 50.354218 -285.782638) (xy 50.380521 -285.741042)
			(xy 50.413156 -285.704205) (xy 50.451277 -285.67308) (xy 50.493898 -285.648473) (xy 50.539914 -285.631021)
			(xy 50.588133 -285.621177) (xy 50.637308 -285.619196) (xy 50.686163 -285.625128) (xy 50.733434 -285.63882)
			(xy 50.777896 -285.659918) (xy 50.818399 -285.687874) (xy 50.853892 -285.721966) (xy 50.883457 -285.76131)
			(xy 50.906328 -285.804887) (xy 50.921912 -285.851568) (xy 50.929807 -285.900145) (xy 50.930302 -285.924752)
			(xy 51.26915 -285.924752) (xy 51.27311 -285.875698) (xy 51.284887 -285.827914) (xy 51.304178 -285.782638)
			(xy 51.330481 -285.741042) (xy 51.363116 -285.704205) (xy 51.401237 -285.67308) (xy 51.443858 -285.648473)
			(xy 51.489874 -285.631021) (xy 51.538093 -285.621177) (xy 51.587268 -285.619196) (xy 51.636123 -285.625128)
			(xy 51.683394 -285.63882) (xy 51.727856 -285.659918) (xy 51.768359 -285.687874) (xy 51.803852 -285.721966)
			(xy 51.833417 -285.76131) (xy 51.856288 -285.804887) (xy 51.871872 -285.851568) (xy 51.879767 -285.900145)
			(xy 51.880262 -285.924752) (xy 52.21911 -285.924752) (xy 52.22307 -285.875698) (xy 52.234847 -285.827914)
			(xy 52.254138 -285.782638) (xy 52.280441 -285.741042) (xy 52.313076 -285.704205) (xy 52.351197 -285.67308)
			(xy 52.393818 -285.648473) (xy 52.439834 -285.631021) (xy 52.488053 -285.621177) (xy 52.537228 -285.619196)
			(xy 52.586083 -285.625128) (xy 52.633354 -285.63882) (xy 52.677816 -285.659918) (xy 52.718319 -285.687874)
			(xy 52.753812 -285.721966) (xy 52.783377 -285.76131) (xy 52.806248 -285.804887) (xy 52.821832 -285.851568)
			(xy 52.829727 -285.900145) (xy 52.830222 -285.924752) (xy 53.16907 -285.924752) (xy 53.17303 -285.875698)
			(xy 53.184807 -285.827914) (xy 53.204098 -285.782638) (xy 53.230401 -285.741042) (xy 53.263036 -285.704205)
			(xy 53.301157 -285.67308) (xy 53.343778 -285.648473) (xy 53.389794 -285.631021) (xy 53.438013 -285.621177)
			(xy 53.487188 -285.619196) (xy 53.536043 -285.625128) (xy 53.583314 -285.63882) (xy 53.627776 -285.659918)
			(xy 53.668279 -285.687874) (xy 53.703772 -285.721966) (xy 53.733337 -285.76131) (xy 53.756208 -285.804887)
			(xy 53.771792 -285.851568) (xy 53.779687 -285.900145) (xy 53.780182 -285.924752) (xy 54.11903 -285.924752)
			(xy 54.12299 -285.875698) (xy 54.134767 -285.827914) (xy 54.154058 -285.782638) (xy 54.180361 -285.741042)
			(xy 54.212996 -285.704205) (xy 54.251117 -285.67308) (xy 54.293738 -285.648473) (xy 54.339754 -285.631021)
			(xy 54.387973 -285.621177) (xy 54.437148 -285.619196) (xy 54.486003 -285.625128) (xy 54.533274 -285.63882)
			(xy 54.577736 -285.659918) (xy 54.618239 -285.687874) (xy 54.653732 -285.721966) (xy 54.683297 -285.76131)
			(xy 54.706168 -285.804887) (xy 54.721752 -285.851568) (xy 54.729647 -285.900145) (xy 54.730142 -285.924752)
			(xy 55.06899 -285.924752) (xy 55.07295 -285.875698) (xy 55.084727 -285.827914) (xy 55.104018 -285.782638)
			(xy 55.130321 -285.741042) (xy 55.162956 -285.704205) (xy 55.201077 -285.67308) (xy 55.243698 -285.648473)
			(xy 55.289714 -285.631021) (xy 55.337933 -285.621177) (xy 55.387108 -285.619196) (xy 55.435963 -285.625128)
			(xy 55.483234 -285.63882) (xy 55.527696 -285.659918) (xy 55.568199 -285.687874) (xy 55.603692 -285.721966)
			(xy 55.633257 -285.76131) (xy 55.656128 -285.804887) (xy 55.671712 -285.851568) (xy 55.679607 -285.900145)
			(xy 55.680102 -285.924752) (xy 56.01895 -285.924752) (xy 56.02291 -285.875698) (xy 56.034687 -285.827914)
			(xy 56.053978 -285.782638) (xy 56.080281 -285.741042) (xy 56.112916 -285.704205) (xy 56.151037 -285.67308)
			(xy 56.193658 -285.648473) (xy 56.239674 -285.631021) (xy 56.287893 -285.621177) (xy 56.337068 -285.619196)
			(xy 56.385923 -285.625128) (xy 56.433194 -285.63882) (xy 56.477656 -285.659918) (xy 56.518159 -285.687874)
			(xy 56.553652 -285.721966) (xy 56.583217 -285.76131) (xy 56.606088 -285.804887) (xy 56.621672 -285.851568)
			(xy 56.629567 -285.900145) (xy 56.630062 -285.924752) (xy 56.969164 -285.924752) (xy 56.973124 -285.875698)
			(xy 56.984901 -285.827914) (xy 57.004192 -285.782638) (xy 57.030495 -285.741042) (xy 57.06313 -285.704205)
			(xy 57.101251 -285.67308) (xy 57.143872 -285.648473) (xy 57.189888 -285.631021) (xy 57.238107 -285.621177)
			(xy 57.287282 -285.619196) (xy 57.336137 -285.625128) (xy 57.383408 -285.63882) (xy 57.42787 -285.659918)
			(xy 57.468373 -285.687874) (xy 57.503866 -285.721966) (xy 57.533431 -285.76131) (xy 57.556302 -285.804887)
			(xy 57.571886 -285.851568) (xy 57.579781 -285.900145) (xy 57.580276 -285.924752) (xy 57.919124 -285.924752)
			(xy 57.923084 -285.875698) (xy 57.934861 -285.827914) (xy 57.954152 -285.782638) (xy 57.980455 -285.741042)
			(xy 58.01309 -285.704205) (xy 58.051211 -285.67308) (xy 58.093832 -285.648473) (xy 58.139848 -285.631021)
			(xy 58.188067 -285.621177) (xy 58.237242 -285.619196) (xy 58.286097 -285.625128) (xy 58.333368 -285.63882)
			(xy 58.37783 -285.659918) (xy 58.418333 -285.687874) (xy 58.453826 -285.721966) (xy 58.483391 -285.76131)
			(xy 58.506262 -285.804887) (xy 58.521846 -285.851568) (xy 58.529741 -285.900145) (xy 58.530236 -285.924752)
			(xy 59.819044 -285.924752) (xy 59.823004 -285.875698) (xy 59.834781 -285.827914) (xy 59.854072 -285.782638)
			(xy 59.880375 -285.741042) (xy 59.91301 -285.704205) (xy 59.951131 -285.67308) (xy 59.993752 -285.648473)
			(xy 60.039768 -285.631021) (xy 60.087987 -285.621177) (xy 60.137162 -285.619196) (xy 60.186017 -285.625128)
			(xy 60.233288 -285.63882) (xy 60.27775 -285.659918) (xy 60.318253 -285.687874) (xy 60.353746 -285.721966)
			(xy 60.383311 -285.76131) (xy 60.406182 -285.804887) (xy 60.421766 -285.851568) (xy 60.429661 -285.900145)
			(xy 60.430156 -285.924752) (xy 60.769004 -285.924752) (xy 60.772964 -285.875698) (xy 60.784741 -285.827914)
			(xy 60.804032 -285.782638) (xy 60.830335 -285.741042) (xy 60.86297 -285.704205) (xy 60.901091 -285.67308)
			(xy 60.943712 -285.648473) (xy 60.989728 -285.631021) (xy 61.037947 -285.621177) (xy 61.087122 -285.619196)
			(xy 61.135977 -285.625128) (xy 61.183248 -285.63882) (xy 61.22771 -285.659918) (xy 61.268213 -285.687874)
			(xy 61.303706 -285.721966) (xy 61.333271 -285.76131) (xy 61.356142 -285.804887) (xy 61.371726 -285.851568)
			(xy 61.379621 -285.900145) (xy 61.380116 -285.924752) (xy 61.718964 -285.924752) (xy 61.722924 -285.875698)
			(xy 61.734701 -285.827914) (xy 61.753992 -285.782638) (xy 61.780295 -285.741042) (xy 61.81293 -285.704205)
			(xy 61.851051 -285.67308) (xy 61.893672 -285.648473) (xy 61.939688 -285.631021) (xy 61.987907 -285.621177)
			(xy 62.037082 -285.619196) (xy 62.085937 -285.625128) (xy 62.133208 -285.63882) (xy 62.17767 -285.659918)
			(xy 62.218173 -285.687874) (xy 62.253666 -285.721966) (xy 62.283231 -285.76131) (xy 62.306102 -285.804887)
			(xy 62.321686 -285.851568) (xy 62.329581 -285.900145) (xy 62.330076 -285.924752) (xy 62.669178 -285.924752)
			(xy 62.673138 -285.875698) (xy 62.684915 -285.827914) (xy 62.704206 -285.782638) (xy 62.730509 -285.741042)
			(xy 62.763144 -285.704205) (xy 62.801265 -285.67308) (xy 62.843886 -285.648473) (xy 62.889902 -285.631021)
			(xy 62.938121 -285.621177) (xy 62.987296 -285.619196) (xy 63.036151 -285.625128) (xy 63.083422 -285.63882)
			(xy 63.127884 -285.659918) (xy 63.168387 -285.687874) (xy 63.20388 -285.721966) (xy 63.233445 -285.76131)
			(xy 63.256316 -285.804887) (xy 63.2719 -285.851568) (xy 63.279795 -285.900145) (xy 63.28029 -285.924752)
			(xy 63.619138 -285.924752) (xy 63.623098 -285.875698) (xy 63.634875 -285.827914) (xy 63.654166 -285.782638)
			(xy 63.680469 -285.741042) (xy 63.713104 -285.704205) (xy 63.751225 -285.67308) (xy 63.793846 -285.648473)
			(xy 63.839862 -285.631021) (xy 63.888081 -285.621177) (xy 63.937256 -285.619196) (xy 63.986111 -285.625128)
			(xy 64.033382 -285.63882) (xy 64.077844 -285.659918) (xy 64.118347 -285.687874) (xy 64.15384 -285.721966)
			(xy 64.183405 -285.76131) (xy 64.206276 -285.804887) (xy 64.22186 -285.851568) (xy 64.229755 -285.900145)
			(xy 64.23025 -285.924752) (xy 64.569098 -285.924752) (xy 64.573058 -285.875698) (xy 64.584835 -285.827914)
			(xy 64.604126 -285.782638) (xy 64.630429 -285.741042) (xy 64.663064 -285.704205) (xy 64.701185 -285.67308)
			(xy 64.743806 -285.648473) (xy 64.789822 -285.631021) (xy 64.838041 -285.621177) (xy 64.887216 -285.619196)
			(xy 64.936071 -285.625128) (xy 64.983342 -285.63882) (xy 65.027804 -285.659918) (xy 65.068307 -285.687874)
			(xy 65.1038 -285.721966) (xy 65.133365 -285.76131) (xy 65.156236 -285.804887) (xy 65.17182 -285.851568)
			(xy 65.179715 -285.900145) (xy 65.18021 -285.924752) (xy 65.519058 -285.924752) (xy 65.523018 -285.875698)
			(xy 65.534795 -285.827914) (xy 65.554086 -285.782638) (xy 65.580389 -285.741042) (xy 65.613024 -285.704205)
			(xy 65.651145 -285.67308) (xy 65.693766 -285.648473) (xy 65.739782 -285.631021) (xy 65.788001 -285.621177)
			(xy 65.837176 -285.619196) (xy 65.886031 -285.625128) (xy 65.933302 -285.63882) (xy 65.977764 -285.659918)
			(xy 66.018267 -285.687874) (xy 66.05376 -285.721966) (xy 66.083325 -285.76131) (xy 66.106196 -285.804887)
			(xy 66.12178 -285.851568) (xy 66.129675 -285.900145) (xy 66.13017 -285.924752) (xy 66.469018 -285.924752)
			(xy 66.472978 -285.875698) (xy 66.484755 -285.827914) (xy 66.504046 -285.782638) (xy 66.530349 -285.741042)
			(xy 66.562984 -285.704205) (xy 66.601105 -285.67308) (xy 66.643726 -285.648473) (xy 66.689742 -285.631021)
			(xy 66.737961 -285.621177) (xy 66.787136 -285.619196) (xy 66.835991 -285.625128) (xy 66.883262 -285.63882)
			(xy 66.927724 -285.659918) (xy 66.968227 -285.687874) (xy 67.00372 -285.721966) (xy 67.033285 -285.76131)
			(xy 67.056156 -285.804887) (xy 67.07174 -285.851568) (xy 67.079635 -285.900145) (xy 67.08013 -285.924752)
			(xy 67.418978 -285.924752) (xy 67.422938 -285.875698) (xy 67.434715 -285.827914) (xy 67.454006 -285.782638)
			(xy 67.480309 -285.741042) (xy 67.512944 -285.704205) (xy 67.551065 -285.67308) (xy 67.593686 -285.648473)
			(xy 67.639702 -285.631021) (xy 67.687921 -285.621177) (xy 67.737096 -285.619196) (xy 67.785951 -285.625128)
			(xy 67.833222 -285.63882) (xy 67.877684 -285.659918) (xy 67.918187 -285.687874) (xy 67.95368 -285.721966)
			(xy 67.983245 -285.76131) (xy 68.006116 -285.804887) (xy 68.0217 -285.851568) (xy 68.029595 -285.900145)
			(xy 68.03009 -285.924752) (xy 68.368938 -285.924752) (xy 68.372898 -285.875698) (xy 68.384675 -285.827914)
			(xy 68.403966 -285.782638) (xy 68.430269 -285.741042) (xy 68.462904 -285.704205) (xy 68.501025 -285.67308)
			(xy 68.543646 -285.648473) (xy 68.589662 -285.631021) (xy 68.637881 -285.621177) (xy 68.687056 -285.619196)
			(xy 68.735911 -285.625128) (xy 68.783182 -285.63882) (xy 68.827644 -285.659918) (xy 68.868147 -285.687874)
			(xy 68.90364 -285.721966) (xy 68.933205 -285.76131) (xy 68.956076 -285.804887) (xy 68.97166 -285.851568)
			(xy 68.979555 -285.900145) (xy 68.98005 -285.924752) (xy 69.319152 -285.924752) (xy 69.323112 -285.875698)
			(xy 69.334889 -285.827914) (xy 69.35418 -285.782638) (xy 69.380483 -285.741042) (xy 69.413118 -285.704205)
			(xy 69.451239 -285.67308) (xy 69.49386 -285.648473) (xy 69.539876 -285.631021) (xy 69.588095 -285.621177)
			(xy 69.63727 -285.619196) (xy 69.686125 -285.625128) (xy 69.733396 -285.63882) (xy 69.777858 -285.659918)
			(xy 69.818361 -285.687874) (xy 69.853854 -285.721966) (xy 69.883419 -285.76131) (xy 69.90629 -285.804887)
			(xy 69.921874 -285.851568) (xy 69.929769 -285.900145) (xy 69.930264 -285.924752) (xy 70.269112 -285.924752)
			(xy 70.273072 -285.875698) (xy 70.284849 -285.827914) (xy 70.30414 -285.782638) (xy 70.330443 -285.741042)
			(xy 70.363078 -285.704205) (xy 70.401199 -285.67308) (xy 70.44382 -285.648473) (xy 70.489836 -285.631021)
			(xy 70.538055 -285.621177) (xy 70.58723 -285.619196) (xy 70.636085 -285.625128) (xy 70.683356 -285.63882)
			(xy 70.727818 -285.659918) (xy 70.768321 -285.687874) (xy 70.803814 -285.721966) (xy 70.833379 -285.76131)
			(xy 70.85625 -285.804887) (xy 70.871834 -285.851568) (xy 70.879729 -285.900145) (xy 70.880224 -285.924752)
			(xy 70.879729 -285.949359) (xy 70.871834 -285.997936) (xy 70.85625 -286.044617) (xy 70.833379 -286.088194)
			(xy 70.803814 -286.127538) (xy 70.768321 -286.16163) (xy 70.727818 -286.189586) (xy 70.683356 -286.210684)
			(xy 70.636085 -286.224376) (xy 70.58723 -286.230308) (xy 70.538055 -286.228327) (xy 70.489836 -286.218483)
			(xy 70.44382 -286.201031) (xy 70.401199 -286.176424) (xy 70.363078 -286.145299) (xy 70.330443 -286.108462)
			(xy 70.30414 -286.066866) (xy 70.284849 -286.02159) (xy 70.273072 -285.973806) (xy 70.269112 -285.924752)
			(xy 69.930264 -285.924752) (xy 69.929769 -285.949359) (xy 69.921874 -285.997936) (xy 69.90629 -286.044617)
			(xy 69.883419 -286.088194) (xy 69.853854 -286.127538) (xy 69.818361 -286.16163) (xy 69.777858 -286.189586)
			(xy 69.733396 -286.210684) (xy 69.686125 -286.224376) (xy 69.63727 -286.230308) (xy 69.588095 -286.228327)
			(xy 69.539876 -286.218483) (xy 69.49386 -286.201031) (xy 69.451239 -286.176424) (xy 69.413118 -286.145299)
			(xy 69.380483 -286.108462) (xy 69.35418 -286.066866) (xy 69.334889 -286.02159) (xy 69.323112 -285.973806)
			(xy 69.319152 -285.924752) (xy 68.98005 -285.924752) (xy 68.979555 -285.949359) (xy 68.97166 -285.997936)
			(xy 68.956076 -286.044617) (xy 68.933205 -286.088194) (xy 68.90364 -286.127538) (xy 68.868147 -286.16163)
			(xy 68.827644 -286.189586) (xy 68.783182 -286.210684) (xy 68.735911 -286.224376) (xy 68.687056 -286.230308)
			(xy 68.637881 -286.228327) (xy 68.589662 -286.218483) (xy 68.543646 -286.201031) (xy 68.501025 -286.176424)
			(xy 68.462904 -286.145299) (xy 68.430269 -286.108462) (xy 68.403966 -286.066866) (xy 68.384675 -286.02159)
			(xy 68.372898 -285.973806) (xy 68.368938 -285.924752) (xy 68.03009 -285.924752) (xy 68.029595 -285.949359)
			(xy 68.0217 -285.997936) (xy 68.006116 -286.044617) (xy 67.983245 -286.088194) (xy 67.95368 -286.127538)
			(xy 67.918187 -286.16163) (xy 67.877684 -286.189586) (xy 67.833222 -286.210684) (xy 67.785951 -286.224376)
			(xy 67.737096 -286.230308) (xy 67.687921 -286.228327) (xy 67.639702 -286.218483) (xy 67.593686 -286.201031)
			(xy 67.551065 -286.176424) (xy 67.512944 -286.145299) (xy 67.480309 -286.108462) (xy 67.454006 -286.066866)
			(xy 67.434715 -286.02159) (xy 67.422938 -285.973806) (xy 67.418978 -285.924752) (xy 67.08013 -285.924752)
			(xy 67.079635 -285.949359) (xy 67.07174 -285.997936) (xy 67.056156 -286.044617) (xy 67.033285 -286.088194)
			(xy 67.00372 -286.127538) (xy 66.968227 -286.16163) (xy 66.927724 -286.189586) (xy 66.883262 -286.210684)
			(xy 66.835991 -286.224376) (xy 66.787136 -286.230308) (xy 66.737961 -286.228327) (xy 66.689742 -286.218483)
			(xy 66.643726 -286.201031) (xy 66.601105 -286.176424) (xy 66.562984 -286.145299) (xy 66.530349 -286.108462)
			(xy 66.504046 -286.066866) (xy 66.484755 -286.02159) (xy 66.472978 -285.973806) (xy 66.469018 -285.924752)
			(xy 66.13017 -285.924752) (xy 66.129675 -285.949359) (xy 66.12178 -285.997936) (xy 66.106196 -286.044617)
			(xy 66.083325 -286.088194) (xy 66.05376 -286.127538) (xy 66.018267 -286.16163) (xy 65.977764 -286.189586)
			(xy 65.933302 -286.210684) (xy 65.886031 -286.224376) (xy 65.837176 -286.230308) (xy 65.788001 -286.228327)
			(xy 65.739782 -286.218483) (xy 65.693766 -286.201031) (xy 65.651145 -286.176424) (xy 65.613024 -286.145299)
			(xy 65.580389 -286.108462) (xy 65.554086 -286.066866) (xy 65.534795 -286.02159) (xy 65.523018 -285.973806)
			(xy 65.519058 -285.924752) (xy 65.18021 -285.924752) (xy 65.179715 -285.949359) (xy 65.17182 -285.997936)
			(xy 65.156236 -286.044617) (xy 65.133365 -286.088194) (xy 65.1038 -286.127538) (xy 65.068307 -286.16163)
			(xy 65.027804 -286.189586) (xy 64.983342 -286.210684) (xy 64.936071 -286.224376) (xy 64.887216 -286.230308)
			(xy 64.838041 -286.228327) (xy 64.789822 -286.218483) (xy 64.743806 -286.201031) (xy 64.701185 -286.176424)
			(xy 64.663064 -286.145299) (xy 64.630429 -286.108462) (xy 64.604126 -286.066866) (xy 64.584835 -286.02159)
			(xy 64.573058 -285.973806) (xy 64.569098 -285.924752) (xy 64.23025 -285.924752) (xy 64.229755 -285.949359)
			(xy 64.22186 -285.997936) (xy 64.206276 -286.044617) (xy 64.183405 -286.088194) (xy 64.15384 -286.127538)
			(xy 64.118347 -286.16163) (xy 64.077844 -286.189586) (xy 64.033382 -286.210684) (xy 63.986111 -286.224376)
			(xy 63.937256 -286.230308) (xy 63.888081 -286.228327) (xy 63.839862 -286.218483) (xy 63.793846 -286.201031)
			(xy 63.751225 -286.176424) (xy 63.713104 -286.145299) (xy 63.680469 -286.108462) (xy 63.654166 -286.066866)
			(xy 63.634875 -286.02159) (xy 63.623098 -285.973806) (xy 63.619138 -285.924752) (xy 63.28029 -285.924752)
			(xy 63.279795 -285.949359) (xy 63.2719 -285.997936) (xy 63.256316 -286.044617) (xy 63.233445 -286.088194)
			(xy 63.20388 -286.127538) (xy 63.168387 -286.16163) (xy 63.127884 -286.189586) (xy 63.083422 -286.210684)
			(xy 63.036151 -286.224376) (xy 62.987296 -286.230308) (xy 62.938121 -286.228327) (xy 62.889902 -286.218483)
			(xy 62.843886 -286.201031) (xy 62.801265 -286.176424) (xy 62.763144 -286.145299) (xy 62.730509 -286.108462)
			(xy 62.704206 -286.066866) (xy 62.684915 -286.02159) (xy 62.673138 -285.973806) (xy 62.669178 -285.924752)
			(xy 62.330076 -285.924752) (xy 62.329581 -285.949359) (xy 62.321686 -285.997936) (xy 62.306102 -286.044617)
			(xy 62.283231 -286.088194) (xy 62.253666 -286.127538) (xy 62.218173 -286.16163) (xy 62.17767 -286.189586)
			(xy 62.133208 -286.210684) (xy 62.085937 -286.224376) (xy 62.037082 -286.230308) (xy 61.987907 -286.228327)
			(xy 61.939688 -286.218483) (xy 61.893672 -286.201031) (xy 61.851051 -286.176424) (xy 61.81293 -286.145299)
			(xy 61.780295 -286.108462) (xy 61.753992 -286.066866) (xy 61.734701 -286.02159) (xy 61.722924 -285.973806)
			(xy 61.718964 -285.924752) (xy 61.380116 -285.924752) (xy 61.379621 -285.949359) (xy 61.371726 -285.997936)
			(xy 61.356142 -286.044617) (xy 61.333271 -286.088194) (xy 61.303706 -286.127538) (xy 61.268213 -286.16163)
			(xy 61.22771 -286.189586) (xy 61.183248 -286.210684) (xy 61.135977 -286.224376) (xy 61.087122 -286.230308)
			(xy 61.037947 -286.228327) (xy 60.989728 -286.218483) (xy 60.943712 -286.201031) (xy 60.901091 -286.176424)
			(xy 60.86297 -286.145299) (xy 60.830335 -286.108462) (xy 60.804032 -286.066866) (xy 60.784741 -286.02159)
			(xy 60.772964 -285.973806) (xy 60.769004 -285.924752) (xy 60.430156 -285.924752) (xy 60.429661 -285.949359)
			(xy 60.421766 -285.997936) (xy 60.406182 -286.044617) (xy 60.383311 -286.088194) (xy 60.353746 -286.127538)
			(xy 60.318253 -286.16163) (xy 60.27775 -286.189586) (xy 60.233288 -286.210684) (xy 60.186017 -286.224376)
			(xy 60.137162 -286.230308) (xy 60.087987 -286.228327) (xy 60.039768 -286.218483) (xy 59.993752 -286.201031)
			(xy 59.951131 -286.176424) (xy 59.91301 -286.145299) (xy 59.880375 -286.108462) (xy 59.854072 -286.066866)
			(xy 59.834781 -286.02159) (xy 59.823004 -285.973806) (xy 59.819044 -285.924752) (xy 58.530236 -285.924752)
			(xy 58.529741 -285.949359) (xy 58.521846 -285.997936) (xy 58.506262 -286.044617) (xy 58.483391 -286.088194)
			(xy 58.453826 -286.127538) (xy 58.418333 -286.16163) (xy 58.37783 -286.189586) (xy 58.333368 -286.210684)
			(xy 58.286097 -286.224376) (xy 58.237242 -286.230308) (xy 58.188067 -286.228327) (xy 58.139848 -286.218483)
			(xy 58.093832 -286.201031) (xy 58.051211 -286.176424) (xy 58.01309 -286.145299) (xy 57.980455 -286.108462)
			(xy 57.954152 -286.066866) (xy 57.934861 -286.02159) (xy 57.923084 -285.973806) (xy 57.919124 -285.924752)
			(xy 57.580276 -285.924752) (xy 57.579781 -285.949359) (xy 57.571886 -285.997936) (xy 57.556302 -286.044617)
			(xy 57.533431 -286.088194) (xy 57.503866 -286.127538) (xy 57.468373 -286.16163) (xy 57.42787 -286.189586)
			(xy 57.383408 -286.210684) (xy 57.336137 -286.224376) (xy 57.287282 -286.230308) (xy 57.238107 -286.228327)
			(xy 57.189888 -286.218483) (xy 57.143872 -286.201031) (xy 57.101251 -286.176424) (xy 57.06313 -286.145299)
			(xy 57.030495 -286.108462) (xy 57.004192 -286.066866) (xy 56.984901 -286.02159) (xy 56.973124 -285.973806)
			(xy 56.969164 -285.924752) (xy 56.630062 -285.924752) (xy 56.629567 -285.949359) (xy 56.621672 -285.997936)
			(xy 56.606088 -286.044617) (xy 56.583217 -286.088194) (xy 56.553652 -286.127538) (xy 56.518159 -286.16163)
			(xy 56.477656 -286.189586) (xy 56.433194 -286.210684) (xy 56.385923 -286.224376) (xy 56.337068 -286.230308)
			(xy 56.287893 -286.228327) (xy 56.239674 -286.218483) (xy 56.193658 -286.201031) (xy 56.151037 -286.176424)
			(xy 56.112916 -286.145299) (xy 56.080281 -286.108462) (xy 56.053978 -286.066866) (xy 56.034687 -286.02159)
			(xy 56.02291 -285.973806) (xy 56.01895 -285.924752) (xy 55.680102 -285.924752) (xy 55.679607 -285.949359)
			(xy 55.671712 -285.997936) (xy 55.656128 -286.044617) (xy 55.633257 -286.088194) (xy 55.603692 -286.127538)
			(xy 55.568199 -286.16163) (xy 55.527696 -286.189586) (xy 55.483234 -286.210684) (xy 55.435963 -286.224376)
			(xy 55.387108 -286.230308) (xy 55.337933 -286.228327) (xy 55.289714 -286.218483) (xy 55.243698 -286.201031)
			(xy 55.201077 -286.176424) (xy 55.162956 -286.145299) (xy 55.130321 -286.108462) (xy 55.104018 -286.066866)
			(xy 55.084727 -286.02159) (xy 55.07295 -285.973806) (xy 55.06899 -285.924752) (xy 54.730142 -285.924752)
			(xy 54.729647 -285.949359) (xy 54.721752 -285.997936) (xy 54.706168 -286.044617) (xy 54.683297 -286.088194)
			(xy 54.653732 -286.127538) (xy 54.618239 -286.16163) (xy 54.577736 -286.189586) (xy 54.533274 -286.210684)
			(xy 54.486003 -286.224376) (xy 54.437148 -286.230308) (xy 54.387973 -286.228327) (xy 54.339754 -286.218483)
			(xy 54.293738 -286.201031) (xy 54.251117 -286.176424) (xy 54.212996 -286.145299) (xy 54.180361 -286.108462)
			(xy 54.154058 -286.066866) (xy 54.134767 -286.02159) (xy 54.12299 -285.973806) (xy 54.11903 -285.924752)
			(xy 53.780182 -285.924752) (xy 53.779687 -285.949359) (xy 53.771792 -285.997936) (xy 53.756208 -286.044617)
			(xy 53.733337 -286.088194) (xy 53.703772 -286.127538) (xy 53.668279 -286.16163) (xy 53.627776 -286.189586)
			(xy 53.583314 -286.210684) (xy 53.536043 -286.224376) (xy 53.487188 -286.230308) (xy 53.438013 -286.228327)
			(xy 53.389794 -286.218483) (xy 53.343778 -286.201031) (xy 53.301157 -286.176424) (xy 53.263036 -286.145299)
			(xy 53.230401 -286.108462) (xy 53.204098 -286.066866) (xy 53.184807 -286.02159) (xy 53.17303 -285.973806)
			(xy 53.16907 -285.924752) (xy 52.830222 -285.924752) (xy 52.829727 -285.949359) (xy 52.821832 -285.997936)
			(xy 52.806248 -286.044617) (xy 52.783377 -286.088194) (xy 52.753812 -286.127538) (xy 52.718319 -286.16163)
			(xy 52.677816 -286.189586) (xy 52.633354 -286.210684) (xy 52.586083 -286.224376) (xy 52.537228 -286.230308)
			(xy 52.488053 -286.228327) (xy 52.439834 -286.218483) (xy 52.393818 -286.201031) (xy 52.351197 -286.176424)
			(xy 52.313076 -286.145299) (xy 52.280441 -286.108462) (xy 52.254138 -286.066866) (xy 52.234847 -286.02159)
			(xy 52.22307 -285.973806) (xy 52.21911 -285.924752) (xy 51.880262 -285.924752) (xy 51.879767 -285.949359)
			(xy 51.871872 -285.997936) (xy 51.856288 -286.044617) (xy 51.833417 -286.088194) (xy 51.803852 -286.127538)
			(xy 51.768359 -286.16163) (xy 51.727856 -286.189586) (xy 51.683394 -286.210684) (xy 51.636123 -286.224376)
			(xy 51.587268 -286.230308) (xy 51.538093 -286.228327) (xy 51.489874 -286.218483) (xy 51.443858 -286.201031)
			(xy 51.401237 -286.176424) (xy 51.363116 -286.145299) (xy 51.330481 -286.108462) (xy 51.304178 -286.066866)
			(xy 51.284887 -286.02159) (xy 51.27311 -285.973806) (xy 51.26915 -285.924752) (xy 50.930302 -285.924752)
			(xy 50.929807 -285.949359) (xy 50.921912 -285.997936) (xy 50.906328 -286.044617) (xy 50.883457 -286.088194)
			(xy 50.853892 -286.127538) (xy 50.818399 -286.16163) (xy 50.777896 -286.189586) (xy 50.733434 -286.210684)
			(xy 50.686163 -286.224376) (xy 50.637308 -286.230308) (xy 50.588133 -286.228327) (xy 50.539914 -286.218483)
			(xy 50.493898 -286.201031) (xy 50.451277 -286.176424) (xy 50.413156 -286.145299) (xy 50.380521 -286.108462)
			(xy 50.354218 -286.066866) (xy 50.334927 -286.02159) (xy 50.32315 -285.973806) (xy 50.31919 -285.924752)
			(xy 49.980088 -285.924752) (xy 49.979593 -285.949359) (xy 49.971698 -285.997936) (xy 49.956114 -286.044617)
			(xy 49.933243 -286.088194) (xy 49.903678 -286.127538) (xy 49.868185 -286.16163) (xy 49.827682 -286.189586)
			(xy 49.78322 -286.210684) (xy 49.735949 -286.224376) (xy 49.687094 -286.230308) (xy 49.637919 -286.228327)
			(xy 49.5897 -286.218483) (xy 49.543684 -286.201031) (xy 49.501063 -286.176424) (xy 49.462942 -286.145299)
			(xy 49.430307 -286.108462) (xy 49.404004 -286.066866) (xy 49.384713 -286.02159) (xy 49.372936 -285.973806)
			(xy 49.368976 -285.924752) (xy 49.030128 -285.924752) (xy 49.029633 -285.949359) (xy 49.021738 -285.997936)
			(xy 49.006154 -286.044617) (xy 48.983283 -286.088194) (xy 48.953718 -286.127538) (xy 48.918225 -286.16163)
			(xy 48.877722 -286.189586) (xy 48.83326 -286.210684) (xy 48.785989 -286.224376) (xy 48.737134 -286.230308)
			(xy 48.687959 -286.228327) (xy 48.63974 -286.218483) (xy 48.593724 -286.201031) (xy 48.551103 -286.176424)
			(xy 48.512982 -286.145299) (xy 48.480347 -286.108462) (xy 48.454044 -286.066866) (xy 48.434753 -286.02159)
			(xy 48.422976 -285.973806) (xy 48.419016 -285.924752) (xy 48.080168 -285.924752) (xy 48.079673 -285.949359)
			(xy 48.071778 -285.997936) (xy 48.056194 -286.044617) (xy 48.033323 -286.088194) (xy 48.003758 -286.127538)
			(xy 47.968265 -286.16163) (xy 47.927762 -286.189586) (xy 47.8833 -286.210684) (xy 47.836029 -286.224376)
			(xy 47.787174 -286.230308) (xy 47.737999 -286.228327) (xy 47.68978 -286.218483) (xy 47.643764 -286.201031)
			(xy 47.601143 -286.176424) (xy 47.563022 -286.145299) (xy 47.530387 -286.108462) (xy 47.504084 -286.066866)
			(xy 47.484793 -286.02159) (xy 47.473016 -285.973806) (xy 47.469056 -285.924752) (xy 47.130208 -285.924752)
			(xy 47.129713 -285.949359) (xy 47.121818 -285.997936) (xy 47.106234 -286.044617) (xy 47.083363 -286.088194)
			(xy 47.053798 -286.127538) (xy 47.018305 -286.16163) (xy 46.977802 -286.189586) (xy 46.93334 -286.210684)
			(xy 46.886069 -286.224376) (xy 46.837214 -286.230308) (xy 46.788039 -286.228327) (xy 46.73982 -286.218483)
			(xy 46.693804 -286.201031) (xy 46.651183 -286.176424) (xy 46.613062 -286.145299) (xy 46.580427 -286.108462)
			(xy 46.554124 -286.066866) (xy 46.534833 -286.02159) (xy 46.523056 -285.973806) (xy 46.519096 -285.924752)
			(xy 46.180248 -285.924752) (xy 46.179753 -285.949359) (xy 46.171858 -285.997936) (xy 46.156274 -286.044617)
			(xy 46.133403 -286.088194) (xy 46.103838 -286.127538) (xy 46.068345 -286.16163) (xy 46.027842 -286.189586)
			(xy 45.98338 -286.210684) (xy 45.936109 -286.224376) (xy 45.887254 -286.230308) (xy 45.838079 -286.228327)
			(xy 45.78986 -286.218483) (xy 45.743844 -286.201031) (xy 45.701223 -286.176424) (xy 45.663102 -286.145299)
			(xy 45.630467 -286.108462) (xy 45.604164 -286.066866) (xy 45.584873 -286.02159) (xy 45.573096 -285.973806)
			(xy 45.569136 -285.924752) (xy 45.230288 -285.924752) (xy 45.229793 -285.949359) (xy 45.221898 -285.997936)
			(xy 45.206314 -286.044617) (xy 45.183443 -286.088194) (xy 45.153878 -286.127538) (xy 45.118385 -286.16163)
			(xy 45.077882 -286.189586) (xy 45.03342 -286.210684) (xy 44.986149 -286.224376) (xy 44.937294 -286.230308)
			(xy 44.888119 -286.228327) (xy 44.8399 -286.218483) (xy 44.793884 -286.201031) (xy 44.751263 -286.176424)
			(xy 44.713142 -286.145299) (xy 44.680507 -286.108462) (xy 44.654204 -286.066866) (xy 44.634913 -286.02159)
			(xy 44.623136 -285.973806) (xy 44.619176 -285.924752) (xy 41.430194 -285.924752) (xy 41.429699 -285.949359)
			(xy 41.421804 -285.997936) (xy 41.40622 -286.044617) (xy 41.383349 -286.088194) (xy 41.353784 -286.127538)
			(xy 41.318291 -286.16163) (xy 41.277788 -286.189586) (xy 41.233326 -286.210684) (xy 41.186055 -286.224376)
			(xy 41.1372 -286.230308) (xy 41.088025 -286.228327) (xy 41.039806 -286.218483) (xy 40.99379 -286.201031)
			(xy 40.951169 -286.176424) (xy 40.913048 -286.145299) (xy 40.880413 -286.108462) (xy 40.85411 -286.066866)
			(xy 40.834819 -286.02159) (xy 40.823042 -285.973806) (xy 40.819082 -285.924752) (xy 40.480234 -285.924752)
			(xy 40.479739 -285.949359) (xy 40.471844 -285.997936) (xy 40.45626 -286.044617) (xy 40.433389 -286.088194)
			(xy 40.403824 -286.127538) (xy 40.368331 -286.16163) (xy 40.327828 -286.189586) (xy 40.283366 -286.210684)
			(xy 40.236095 -286.224376) (xy 40.18724 -286.230308) (xy 40.138065 -286.228327) (xy 40.089846 -286.218483)
			(xy 40.04383 -286.201031) (xy 40.001209 -286.176424) (xy 39.963088 -286.145299) (xy 39.930453 -286.108462)
			(xy 39.90415 -286.066866) (xy 39.884859 -286.02159) (xy 39.873082 -285.973806) (xy 39.869122 -285.924752)
			(xy 39.530274 -285.924752) (xy 39.529779 -285.949359) (xy 39.521884 -285.997936) (xy 39.5063 -286.044617)
			(xy 39.483429 -286.088194) (xy 39.453864 -286.127538) (xy 39.418371 -286.16163) (xy 39.377868 -286.189586)
			(xy 39.333406 -286.210684) (xy 39.286135 -286.224376) (xy 39.23728 -286.230308) (xy 39.188105 -286.228327)
			(xy 39.139886 -286.218483) (xy 39.09387 -286.201031) (xy 39.051249 -286.176424) (xy 39.013128 -286.145299)
			(xy 38.980493 -286.108462) (xy 38.95419 -286.066866) (xy 38.934899 -286.02159) (xy 38.923122 -285.973806)
			(xy 38.919162 -285.924752) (xy 38.580314 -285.924752) (xy 38.579819 -285.949359) (xy 38.571924 -285.997936)
			(xy 38.55634 -286.044617) (xy 38.533469 -286.088194) (xy 38.503904 -286.127538) (xy 38.468411 -286.16163)
			(xy 38.427908 -286.189586) (xy 38.383446 -286.210684) (xy 38.336175 -286.224376) (xy 38.28732 -286.230308)
			(xy 38.238145 -286.228327) (xy 38.189926 -286.218483) (xy 38.14391 -286.201031) (xy 38.101289 -286.176424)
			(xy 38.063168 -286.145299) (xy 38.030533 -286.108462) (xy 38.00423 -286.066866) (xy 37.984939 -286.02159)
			(xy 37.973162 -285.973806) (xy 37.969202 -285.924752) (xy 37.6301 -285.924752) (xy 37.629605 -285.949359)
			(xy 37.62171 -285.997936) (xy 37.606126 -286.044617) (xy 37.583255 -286.088194) (xy 37.55369 -286.127538)
			(xy 37.518197 -286.16163) (xy 37.477694 -286.189586) (xy 37.433232 -286.210684) (xy 37.385961 -286.224376)
			(xy 37.337106 -286.230308) (xy 37.287931 -286.228327) (xy 37.239712 -286.218483) (xy 37.193696 -286.201031)
			(xy 37.151075 -286.176424) (xy 37.112954 -286.145299) (xy 37.080319 -286.108462) (xy 37.054016 -286.066866)
			(xy 37.034725 -286.02159) (xy 37.022948 -285.973806) (xy 37.018988 -285.924752) (xy 36.68014 -285.924752)
			(xy 36.679645 -285.949359) (xy 36.67175 -285.997936) (xy 36.656166 -286.044617) (xy 36.633295 -286.088194)
			(xy 36.60373 -286.127538) (xy 36.568237 -286.16163) (xy 36.527734 -286.189586) (xy 36.483272 -286.210684)
			(xy 36.436001 -286.224376) (xy 36.387146 -286.230308) (xy 36.337971 -286.228327) (xy 36.289752 -286.218483)
			(xy 36.243736 -286.201031) (xy 36.201115 -286.176424) (xy 36.162994 -286.145299) (xy 36.130359 -286.108462)
			(xy 36.104056 -286.066866) (xy 36.084765 -286.02159) (xy 36.072988 -285.973806) (xy 36.069028 -285.924752)
			(xy 34.39033 -285.924752) (xy 34.39033 -286.399732) (xy 73.593972 -286.399732) (xy 73.597932 -286.350678)
			(xy 73.609709 -286.302894) (xy 73.629 -286.257618) (xy 73.655303 -286.216022) (xy 73.687938 -286.179185)
			(xy 73.726059 -286.14806) (xy 73.76868 -286.123453) (xy 73.814696 -286.106001) (xy 73.862915 -286.096157)
			(xy 73.91209 -286.094176) (xy 73.960945 -286.100108) (xy 74.008216 -286.1138) (xy 74.052678 -286.134898)
			(xy 74.093181 -286.162854) (xy 74.128674 -286.196946) (xy 74.158239 -286.23629) (xy 74.18111 -286.279867)
			(xy 74.196694 -286.326548) (xy 74.204589 -286.375125) (xy 74.205084 -286.399732) (xy 74.544186 -286.399732)
			(xy 74.548146 -286.350678) (xy 74.559923 -286.302894) (xy 74.579214 -286.257618) (xy 74.605517 -286.216022)
			(xy 74.638152 -286.179185) (xy 74.676273 -286.14806) (xy 74.718894 -286.123453) (xy 74.76491 -286.106001)
			(xy 74.813129 -286.096157) (xy 74.862304 -286.094176) (xy 74.911159 -286.100108) (xy 74.95843 -286.1138)
			(xy 75.002892 -286.134898) (xy 75.043395 -286.162854) (xy 75.078888 -286.196946) (xy 75.108453 -286.23629)
			(xy 75.131324 -286.279867) (xy 75.146908 -286.326548) (xy 75.154803 -286.375125) (xy 75.155298 -286.399732)
			(xy 75.494146 -286.399732) (xy 75.498106 -286.350678) (xy 75.509883 -286.302894) (xy 75.529174 -286.257618)
			(xy 75.555477 -286.216022) (xy 75.588112 -286.179185) (xy 75.626233 -286.14806) (xy 75.668854 -286.123453)
			(xy 75.71487 -286.106001) (xy 75.763089 -286.096157) (xy 75.812264 -286.094176) (xy 75.861119 -286.100108)
			(xy 75.90839 -286.1138) (xy 75.952852 -286.134898) (xy 75.993355 -286.162854) (xy 76.028848 -286.196946)
			(xy 76.058413 -286.23629) (xy 76.081284 -286.279867) (xy 76.096868 -286.326548) (xy 76.104763 -286.375125)
			(xy 76.105258 -286.399732) (xy 76.104763 -286.424339) (xy 76.096868 -286.472916) (xy 76.081284 -286.519597)
			(xy 76.058413 -286.563174) (xy 76.028848 -286.602518) (xy 75.993355 -286.63661) (xy 75.952852 -286.664566)
			(xy 75.90839 -286.685664) (xy 75.861119 -286.699356) (xy 75.812264 -286.705288) (xy 75.763089 -286.703307)
			(xy 75.71487 -286.693463) (xy 75.668854 -286.676011) (xy 75.626233 -286.651404) (xy 75.588112 -286.620279)
			(xy 75.555477 -286.583442) (xy 75.529174 -286.541846) (xy 75.509883 -286.49657) (xy 75.498106 -286.448786)
			(xy 75.494146 -286.399732) (xy 75.155298 -286.399732) (xy 75.154803 -286.424339) (xy 75.146908 -286.472916)
			(xy 75.131324 -286.519597) (xy 75.108453 -286.563174) (xy 75.078888 -286.602518) (xy 75.043395 -286.63661)
			(xy 75.002892 -286.664566) (xy 74.95843 -286.685664) (xy 74.911159 -286.699356) (xy 74.862304 -286.705288)
			(xy 74.813129 -286.703307) (xy 74.76491 -286.693463) (xy 74.718894 -286.676011) (xy 74.676273 -286.651404)
			(xy 74.638152 -286.620279) (xy 74.605517 -286.583442) (xy 74.579214 -286.541846) (xy 74.559923 -286.49657)
			(xy 74.548146 -286.448786) (xy 74.544186 -286.399732) (xy 74.205084 -286.399732) (xy 74.204589 -286.424339)
			(xy 74.196694 -286.472916) (xy 74.18111 -286.519597) (xy 74.158239 -286.563174) (xy 74.128674 -286.602518)
			(xy 74.093181 -286.63661) (xy 74.052678 -286.664566) (xy 74.008216 -286.685664) (xy 73.960945 -286.699356)
			(xy 73.91209 -286.705288) (xy 73.862915 -286.703307) (xy 73.814696 -286.693463) (xy 73.76868 -286.676011)
			(xy 73.726059 -286.651404) (xy 73.687938 -286.620279) (xy 73.655303 -286.583442) (xy 73.629 -286.541846)
			(xy 73.609709 -286.49657) (xy 73.597932 -286.448786) (xy 73.593972 -286.399732) (xy 34.39033 -286.399732)
			(xy 34.39033 -286.874966) (xy 36.069028 -286.874966) (xy 36.072988 -286.825912) (xy 36.084765 -286.778128)
			(xy 36.104056 -286.732852) (xy 36.130359 -286.691256) (xy 36.162994 -286.654419) (xy 36.201115 -286.623294)
			(xy 36.243736 -286.598687) (xy 36.289752 -286.581235) (xy 36.337971 -286.571391) (xy 36.387146 -286.56941)
			(xy 36.436001 -286.575342) (xy 36.483272 -286.589034) (xy 36.527734 -286.610132) (xy 36.568237 -286.638088)
			(xy 36.60373 -286.67218) (xy 36.633295 -286.711524) (xy 36.656166 -286.755101) (xy 36.67175 -286.801782)
			(xy 36.679645 -286.850359) (xy 36.68014 -286.874966) (xy 37.018988 -286.874966) (xy 37.022948 -286.825912)
			(xy 37.034725 -286.778128) (xy 37.054016 -286.732852) (xy 37.080319 -286.691256) (xy 37.112954 -286.654419)
			(xy 37.151075 -286.623294) (xy 37.193696 -286.598687) (xy 37.239712 -286.581235) (xy 37.287931 -286.571391)
			(xy 37.337106 -286.56941) (xy 37.385961 -286.575342) (xy 37.433232 -286.589034) (xy 37.477694 -286.610132)
			(xy 37.518197 -286.638088) (xy 37.55369 -286.67218) (xy 37.583255 -286.711524) (xy 37.606126 -286.755101)
			(xy 37.62171 -286.801782) (xy 37.629605 -286.850359) (xy 37.6301 -286.874966) (xy 37.969202 -286.874966)
			(xy 37.973162 -286.825912) (xy 37.984939 -286.778128) (xy 38.00423 -286.732852) (xy 38.030533 -286.691256)
			(xy 38.063168 -286.654419) (xy 38.101289 -286.623294) (xy 38.14391 -286.598687) (xy 38.189926 -286.581235)
			(xy 38.238145 -286.571391) (xy 38.28732 -286.56941) (xy 38.336175 -286.575342) (xy 38.383446 -286.589034)
			(xy 38.427908 -286.610132) (xy 38.468411 -286.638088) (xy 38.503904 -286.67218) (xy 38.533469 -286.711524)
			(xy 38.55634 -286.755101) (xy 38.571924 -286.801782) (xy 38.579819 -286.850359) (xy 38.580314 -286.874966)
			(xy 38.919162 -286.874966) (xy 38.923122 -286.825912) (xy 38.934899 -286.778128) (xy 38.95419 -286.732852)
			(xy 38.980493 -286.691256) (xy 39.013128 -286.654419) (xy 39.051249 -286.623294) (xy 39.09387 -286.598687)
			(xy 39.139886 -286.581235) (xy 39.188105 -286.571391) (xy 39.23728 -286.56941) (xy 39.286135 -286.575342)
			(xy 39.333406 -286.589034) (xy 39.377868 -286.610132) (xy 39.418371 -286.638088) (xy 39.453864 -286.67218)
			(xy 39.483429 -286.711524) (xy 39.5063 -286.755101) (xy 39.521884 -286.801782) (xy 39.529779 -286.850359)
			(xy 39.530274 -286.874966) (xy 39.869122 -286.874966) (xy 39.873082 -286.825912) (xy 39.884859 -286.778128)
			(xy 39.90415 -286.732852) (xy 39.930453 -286.691256) (xy 39.963088 -286.654419) (xy 40.001209 -286.623294)
			(xy 40.04383 -286.598687) (xy 40.089846 -286.581235) (xy 40.138065 -286.571391) (xy 40.18724 -286.56941)
			(xy 40.236095 -286.575342) (xy 40.283366 -286.589034) (xy 40.327828 -286.610132) (xy 40.368331 -286.638088)
			(xy 40.403824 -286.67218) (xy 40.433389 -286.711524) (xy 40.45626 -286.755101) (xy 40.471844 -286.801782)
			(xy 40.479739 -286.850359) (xy 40.480234 -286.874966) (xy 40.819082 -286.874966) (xy 40.823042 -286.825912)
			(xy 40.834819 -286.778128) (xy 40.85411 -286.732852) (xy 40.880413 -286.691256) (xy 40.913048 -286.654419)
			(xy 40.951169 -286.623294) (xy 40.99379 -286.598687) (xy 41.039806 -286.581235) (xy 41.088025 -286.571391)
			(xy 41.1372 -286.56941) (xy 41.186055 -286.575342) (xy 41.233326 -286.589034) (xy 41.277788 -286.610132)
			(xy 41.318291 -286.638088) (xy 41.353784 -286.67218) (xy 41.383349 -286.711524) (xy 41.40622 -286.755101)
			(xy 41.421804 -286.801782) (xy 41.429699 -286.850359) (xy 41.430194 -286.874966) (xy 41.769042 -286.874966)
			(xy 41.773002 -286.825912) (xy 41.784779 -286.778128) (xy 41.80407 -286.732852) (xy 41.830373 -286.691256)
			(xy 41.863008 -286.654419) (xy 41.901129 -286.623294) (xy 41.94375 -286.598687) (xy 41.989766 -286.581235)
			(xy 42.037985 -286.571391) (xy 42.08716 -286.56941) (xy 42.136015 -286.575342) (xy 42.183286 -286.589034)
			(xy 42.227748 -286.610132) (xy 42.268251 -286.638088) (xy 42.303744 -286.67218) (xy 42.333309 -286.711524)
			(xy 42.35618 -286.755101) (xy 42.371764 -286.801782) (xy 42.379659 -286.850359) (xy 42.380149 -286.874712)
			(xy 42.719002 -286.874712) (xy 42.722962 -286.825658) (xy 42.734739 -286.777874) (xy 42.75403 -286.732598)
			(xy 42.780333 -286.691002) (xy 42.812968 -286.654165) (xy 42.851089 -286.62304) (xy 42.89371 -286.598433)
			(xy 42.939726 -286.580981) (xy 42.987945 -286.571137) (xy 43.03712 -286.569156) (xy 43.085975 -286.575088)
			(xy 43.133246 -286.58878) (xy 43.177708 -286.609878) (xy 43.218211 -286.637834) (xy 43.253704 -286.671926)
			(xy 43.283269 -286.71127) (xy 43.30614 -286.754847) (xy 43.321724 -286.801528) (xy 43.329619 -286.850105)
			(xy 43.330114 -286.874712) (xy 43.668962 -286.874712) (xy 43.672922 -286.825658) (xy 43.684699 -286.777874)
			(xy 43.70399 -286.732598) (xy 43.730293 -286.691002) (xy 43.762928 -286.654165) (xy 43.801049 -286.62304)
			(xy 43.84367 -286.598433) (xy 43.889686 -286.580981) (xy 43.937905 -286.571137) (xy 43.98708 -286.569156)
			(xy 44.035935 -286.575088) (xy 44.083206 -286.58878) (xy 44.127668 -286.609878) (xy 44.168171 -286.637834)
			(xy 44.203664 -286.671926) (xy 44.233229 -286.71127) (xy 44.2561 -286.754847) (xy 44.271684 -286.801528)
			(xy 44.279579 -286.850105) (xy 44.280074 -286.874712) (xy 44.280069 -286.874966) (xy 44.619176 -286.874966)
			(xy 44.623136 -286.825912) (xy 44.634913 -286.778128) (xy 44.654204 -286.732852) (xy 44.680507 -286.691256)
			(xy 44.713142 -286.654419) (xy 44.751263 -286.623294) (xy 44.793884 -286.598687) (xy 44.8399 -286.581235)
			(xy 44.888119 -286.571391) (xy 44.937294 -286.56941) (xy 44.986149 -286.575342) (xy 45.03342 -286.589034)
			(xy 45.077882 -286.610132) (xy 45.118385 -286.638088) (xy 45.153878 -286.67218) (xy 45.183443 -286.711524)
			(xy 45.206314 -286.755101) (xy 45.221898 -286.801782) (xy 45.229793 -286.850359) (xy 45.230288 -286.874966)
			(xy 45.569136 -286.874966) (xy 45.573096 -286.825912) (xy 45.584873 -286.778128) (xy 45.604164 -286.732852)
			(xy 45.630467 -286.691256) (xy 45.663102 -286.654419) (xy 45.701223 -286.623294) (xy 45.743844 -286.598687)
			(xy 45.78986 -286.581235) (xy 45.838079 -286.571391) (xy 45.887254 -286.56941) (xy 45.936109 -286.575342)
			(xy 45.98338 -286.589034) (xy 46.027842 -286.610132) (xy 46.068345 -286.638088) (xy 46.103838 -286.67218)
			(xy 46.133403 -286.711524) (xy 46.156274 -286.755101) (xy 46.171858 -286.801782) (xy 46.179753 -286.850359)
			(xy 46.180248 -286.874966) (xy 46.519096 -286.874966) (xy 46.523056 -286.825912) (xy 46.534833 -286.778128)
			(xy 46.554124 -286.732852) (xy 46.580427 -286.691256) (xy 46.613062 -286.654419) (xy 46.651183 -286.623294)
			(xy 46.693804 -286.598687) (xy 46.73982 -286.581235) (xy 46.788039 -286.571391) (xy 46.837214 -286.56941)
			(xy 46.886069 -286.575342) (xy 46.93334 -286.589034) (xy 46.977802 -286.610132) (xy 47.018305 -286.638088)
			(xy 47.053798 -286.67218) (xy 47.083363 -286.711524) (xy 47.106234 -286.755101) (xy 47.121818 -286.801782)
			(xy 47.129713 -286.850359) (xy 47.130208 -286.874966) (xy 47.469056 -286.874966) (xy 47.473016 -286.825912)
			(xy 47.484793 -286.778128) (xy 47.504084 -286.732852) (xy 47.530387 -286.691256) (xy 47.563022 -286.654419)
			(xy 47.601143 -286.623294) (xy 47.643764 -286.598687) (xy 47.68978 -286.581235) (xy 47.737999 -286.571391)
			(xy 47.787174 -286.56941) (xy 47.836029 -286.575342) (xy 47.8833 -286.589034) (xy 47.927762 -286.610132)
			(xy 47.968265 -286.638088) (xy 48.003758 -286.67218) (xy 48.033323 -286.711524) (xy 48.056194 -286.755101)
			(xy 48.071778 -286.801782) (xy 48.079673 -286.850359) (xy 48.080168 -286.874966) (xy 48.419016 -286.874966)
			(xy 48.422976 -286.825912) (xy 48.434753 -286.778128) (xy 48.454044 -286.732852) (xy 48.480347 -286.691256)
			(xy 48.512982 -286.654419) (xy 48.551103 -286.623294) (xy 48.593724 -286.598687) (xy 48.63974 -286.581235)
			(xy 48.687959 -286.571391) (xy 48.737134 -286.56941) (xy 48.785989 -286.575342) (xy 48.83326 -286.589034)
			(xy 48.877722 -286.610132) (xy 48.918225 -286.638088) (xy 48.953718 -286.67218) (xy 48.983283 -286.711524)
			(xy 49.006154 -286.755101) (xy 49.021738 -286.801782) (xy 49.029633 -286.850359) (xy 49.030128 -286.874966)
			(xy 49.368976 -286.874966) (xy 49.372936 -286.825912) (xy 49.384713 -286.778128) (xy 49.404004 -286.732852)
			(xy 49.430307 -286.691256) (xy 49.462942 -286.654419) (xy 49.501063 -286.623294) (xy 49.543684 -286.598687)
			(xy 49.5897 -286.581235) (xy 49.637919 -286.571391) (xy 49.687094 -286.56941) (xy 49.735949 -286.575342)
			(xy 49.78322 -286.589034) (xy 49.827682 -286.610132) (xy 49.868185 -286.638088) (xy 49.903678 -286.67218)
			(xy 49.933243 -286.711524) (xy 49.956114 -286.755101) (xy 49.971698 -286.801782) (xy 49.979593 -286.850359)
			(xy 49.980088 -286.874966) (xy 50.31919 -286.874966) (xy 50.32315 -286.825912) (xy 50.334927 -286.778128)
			(xy 50.354218 -286.732852) (xy 50.380521 -286.691256) (xy 50.413156 -286.654419) (xy 50.451277 -286.623294)
			(xy 50.493898 -286.598687) (xy 50.539914 -286.581235) (xy 50.588133 -286.571391) (xy 50.637308 -286.56941)
			(xy 50.686163 -286.575342) (xy 50.733434 -286.589034) (xy 50.777896 -286.610132) (xy 50.818399 -286.638088)
			(xy 50.853892 -286.67218) (xy 50.883457 -286.711524) (xy 50.906328 -286.755101) (xy 50.921912 -286.801782)
			(xy 50.929807 -286.850359) (xy 50.930302 -286.874966) (xy 51.26915 -286.874966) (xy 51.27311 -286.825912)
			(xy 51.284887 -286.778128) (xy 51.304178 -286.732852) (xy 51.330481 -286.691256) (xy 51.363116 -286.654419)
			(xy 51.401237 -286.623294) (xy 51.443858 -286.598687) (xy 51.489874 -286.581235) (xy 51.538093 -286.571391)
			(xy 51.587268 -286.56941) (xy 51.636123 -286.575342) (xy 51.683394 -286.589034) (xy 51.727856 -286.610132)
			(xy 51.768359 -286.638088) (xy 51.803852 -286.67218) (xy 51.833417 -286.711524) (xy 51.856288 -286.755101)
			(xy 51.871872 -286.801782) (xy 51.879767 -286.850359) (xy 51.880262 -286.874966) (xy 52.21911 -286.874966)
			(xy 52.22307 -286.825912) (xy 52.234847 -286.778128) (xy 52.254138 -286.732852) (xy 52.280441 -286.691256)
			(xy 52.313076 -286.654419) (xy 52.351197 -286.623294) (xy 52.393818 -286.598687) (xy 52.439834 -286.581235)
			(xy 52.488053 -286.571391) (xy 52.537228 -286.56941) (xy 52.586083 -286.575342) (xy 52.633354 -286.589034)
			(xy 52.677816 -286.610132) (xy 52.718319 -286.638088) (xy 52.753812 -286.67218) (xy 52.783377 -286.711524)
			(xy 52.806248 -286.755101) (xy 52.821832 -286.801782) (xy 52.829727 -286.850359) (xy 52.830222 -286.874966)
			(xy 53.16907 -286.874966) (xy 53.17303 -286.825912) (xy 53.184807 -286.778128) (xy 53.204098 -286.732852)
			(xy 53.230401 -286.691256) (xy 53.263036 -286.654419) (xy 53.301157 -286.623294) (xy 53.343778 -286.598687)
			(xy 53.389794 -286.581235) (xy 53.438013 -286.571391) (xy 53.487188 -286.56941) (xy 53.536043 -286.575342)
			(xy 53.583314 -286.589034) (xy 53.627776 -286.610132) (xy 53.668279 -286.638088) (xy 53.703772 -286.67218)
			(xy 53.733337 -286.711524) (xy 53.756208 -286.755101) (xy 53.771792 -286.801782) (xy 53.779687 -286.850359)
			(xy 53.780182 -286.874966) (xy 54.11903 -286.874966) (xy 54.12299 -286.825912) (xy 54.134767 -286.778128)
			(xy 54.154058 -286.732852) (xy 54.180361 -286.691256) (xy 54.212996 -286.654419) (xy 54.251117 -286.623294)
			(xy 54.293738 -286.598687) (xy 54.339754 -286.581235) (xy 54.387973 -286.571391) (xy 54.437148 -286.56941)
			(xy 54.486003 -286.575342) (xy 54.533274 -286.589034) (xy 54.577736 -286.610132) (xy 54.618239 -286.638088)
			(xy 54.653732 -286.67218) (xy 54.683297 -286.711524) (xy 54.706168 -286.755101) (xy 54.721752 -286.801782)
			(xy 54.729647 -286.850359) (xy 54.730142 -286.874966) (xy 55.06899 -286.874966) (xy 55.07295 -286.825912)
			(xy 55.084727 -286.778128) (xy 55.104018 -286.732852) (xy 55.130321 -286.691256) (xy 55.162956 -286.654419)
			(xy 55.201077 -286.623294) (xy 55.243698 -286.598687) (xy 55.289714 -286.581235) (xy 55.337933 -286.571391)
			(xy 55.387108 -286.56941) (xy 55.435963 -286.575342) (xy 55.483234 -286.589034) (xy 55.527696 -286.610132)
			(xy 55.568199 -286.638088) (xy 55.603692 -286.67218) (xy 55.633257 -286.711524) (xy 55.656128 -286.755101)
			(xy 55.671712 -286.801782) (xy 55.679607 -286.850359) (xy 55.680102 -286.874966) (xy 56.01895 -286.874966)
			(xy 56.02291 -286.825912) (xy 56.034687 -286.778128) (xy 56.053978 -286.732852) (xy 56.080281 -286.691256)
			(xy 56.112916 -286.654419) (xy 56.151037 -286.623294) (xy 56.193658 -286.598687) (xy 56.239674 -286.581235)
			(xy 56.287893 -286.571391) (xy 56.337068 -286.56941) (xy 56.385923 -286.575342) (xy 56.433194 -286.589034)
			(xy 56.477656 -286.610132) (xy 56.518159 -286.638088) (xy 56.553652 -286.67218) (xy 56.583217 -286.711524)
			(xy 56.606088 -286.755101) (xy 56.621672 -286.801782) (xy 56.629567 -286.850359) (xy 56.630062 -286.874966)
			(xy 56.969164 -286.874966) (xy 56.973124 -286.825912) (xy 56.984901 -286.778128) (xy 57.004192 -286.732852)
			(xy 57.030495 -286.691256) (xy 57.06313 -286.654419) (xy 57.101251 -286.623294) (xy 57.143872 -286.598687)
			(xy 57.189888 -286.581235) (xy 57.238107 -286.571391) (xy 57.287282 -286.56941) (xy 57.336137 -286.575342)
			(xy 57.383408 -286.589034) (xy 57.42787 -286.610132) (xy 57.468373 -286.638088) (xy 57.503866 -286.67218)
			(xy 57.533431 -286.711524) (xy 57.556302 -286.755101) (xy 57.571886 -286.801782) (xy 57.579781 -286.850359)
			(xy 57.580276 -286.874966) (xy 57.919124 -286.874966) (xy 57.923084 -286.825912) (xy 57.934861 -286.778128)
			(xy 57.954152 -286.732852) (xy 57.980455 -286.691256) (xy 58.01309 -286.654419) (xy 58.051211 -286.623294)
			(xy 58.093832 -286.598687) (xy 58.139848 -286.581235) (xy 58.188067 -286.571391) (xy 58.237242 -286.56941)
			(xy 58.286097 -286.575342) (xy 58.333368 -286.589034) (xy 58.37783 -286.610132) (xy 58.418333 -286.638088)
			(xy 58.453826 -286.67218) (xy 58.483391 -286.711524) (xy 58.506262 -286.755101) (xy 58.521846 -286.801782)
			(xy 58.529741 -286.850359) (xy 58.530236 -286.874966) (xy 59.819044 -286.874966) (xy 59.823004 -286.825912)
			(xy 59.834781 -286.778128) (xy 59.854072 -286.732852) (xy 59.880375 -286.691256) (xy 59.91301 -286.654419)
			(xy 59.951131 -286.623294) (xy 59.993752 -286.598687) (xy 60.039768 -286.581235) (xy 60.087987 -286.571391)
			(xy 60.137162 -286.56941) (xy 60.186017 -286.575342) (xy 60.233288 -286.589034) (xy 60.27775 -286.610132)
			(xy 60.318253 -286.638088) (xy 60.353746 -286.67218) (xy 60.383311 -286.711524) (xy 60.406182 -286.755101)
			(xy 60.421766 -286.801782) (xy 60.429661 -286.850359) (xy 60.430156 -286.874966) (xy 60.769004 -286.874966)
			(xy 60.772964 -286.825912) (xy 60.784741 -286.778128) (xy 60.804032 -286.732852) (xy 60.830335 -286.691256)
			(xy 60.86297 -286.654419) (xy 60.901091 -286.623294) (xy 60.943712 -286.598687) (xy 60.989728 -286.581235)
			(xy 61.037947 -286.571391) (xy 61.087122 -286.56941) (xy 61.135977 -286.575342) (xy 61.183248 -286.589034)
			(xy 61.22771 -286.610132) (xy 61.268213 -286.638088) (xy 61.303706 -286.67218) (xy 61.333271 -286.711524)
			(xy 61.356142 -286.755101) (xy 61.371726 -286.801782) (xy 61.379621 -286.850359) (xy 61.380116 -286.874966)
			(xy 61.718964 -286.874966) (xy 61.722924 -286.825912) (xy 61.734701 -286.778128) (xy 61.753992 -286.732852)
			(xy 61.780295 -286.691256) (xy 61.81293 -286.654419) (xy 61.851051 -286.623294) (xy 61.893672 -286.598687)
			(xy 61.939688 -286.581235) (xy 61.987907 -286.571391) (xy 62.037082 -286.56941) (xy 62.085937 -286.575342)
			(xy 62.133208 -286.589034) (xy 62.17767 -286.610132) (xy 62.218173 -286.638088) (xy 62.253666 -286.67218)
			(xy 62.283231 -286.711524) (xy 62.306102 -286.755101) (xy 62.321686 -286.801782) (xy 62.329581 -286.850359)
			(xy 62.330076 -286.874966) (xy 62.669178 -286.874966) (xy 62.673138 -286.825912) (xy 62.684915 -286.778128)
			(xy 62.704206 -286.732852) (xy 62.730509 -286.691256) (xy 62.763144 -286.654419) (xy 62.801265 -286.623294)
			(xy 62.843886 -286.598687) (xy 62.889902 -286.581235) (xy 62.938121 -286.571391) (xy 62.987296 -286.56941)
			(xy 63.036151 -286.575342) (xy 63.083422 -286.589034) (xy 63.127884 -286.610132) (xy 63.168387 -286.638088)
			(xy 63.20388 -286.67218) (xy 63.233445 -286.711524) (xy 63.256316 -286.755101) (xy 63.2719 -286.801782)
			(xy 63.279795 -286.850359) (xy 63.28029 -286.874966) (xy 63.619138 -286.874966) (xy 63.623098 -286.825912)
			(xy 63.634875 -286.778128) (xy 63.654166 -286.732852) (xy 63.680469 -286.691256) (xy 63.713104 -286.654419)
			(xy 63.751225 -286.623294) (xy 63.793846 -286.598687) (xy 63.839862 -286.581235) (xy 63.888081 -286.571391)
			(xy 63.937256 -286.56941) (xy 63.986111 -286.575342) (xy 64.033382 -286.589034) (xy 64.077844 -286.610132)
			(xy 64.118347 -286.638088) (xy 64.15384 -286.67218) (xy 64.183405 -286.711524) (xy 64.206276 -286.755101)
			(xy 64.22186 -286.801782) (xy 64.229755 -286.850359) (xy 64.23025 -286.874966) (xy 64.569098 -286.874966)
			(xy 64.573058 -286.825912) (xy 64.584835 -286.778128) (xy 64.604126 -286.732852) (xy 64.630429 -286.691256)
			(xy 64.663064 -286.654419) (xy 64.701185 -286.623294) (xy 64.743806 -286.598687) (xy 64.789822 -286.581235)
			(xy 64.838041 -286.571391) (xy 64.887216 -286.56941) (xy 64.936071 -286.575342) (xy 64.983342 -286.589034)
			(xy 65.027804 -286.610132) (xy 65.068307 -286.638088) (xy 65.1038 -286.67218) (xy 65.133365 -286.711524)
			(xy 65.156236 -286.755101) (xy 65.17182 -286.801782) (xy 65.179715 -286.850359) (xy 65.18021 -286.874966)
			(xy 65.519058 -286.874966) (xy 65.523018 -286.825912) (xy 65.534795 -286.778128) (xy 65.554086 -286.732852)
			(xy 65.580389 -286.691256) (xy 65.613024 -286.654419) (xy 65.651145 -286.623294) (xy 65.693766 -286.598687)
			(xy 65.739782 -286.581235) (xy 65.788001 -286.571391) (xy 65.837176 -286.56941) (xy 65.886031 -286.575342)
			(xy 65.933302 -286.589034) (xy 65.977764 -286.610132) (xy 66.018267 -286.638088) (xy 66.05376 -286.67218)
			(xy 66.083325 -286.711524) (xy 66.106196 -286.755101) (xy 66.12178 -286.801782) (xy 66.129675 -286.850359)
			(xy 66.13017 -286.874966) (xy 66.469018 -286.874966) (xy 66.472978 -286.825912) (xy 66.484755 -286.778128)
			(xy 66.504046 -286.732852) (xy 66.530349 -286.691256) (xy 66.562984 -286.654419) (xy 66.601105 -286.623294)
			(xy 66.643726 -286.598687) (xy 66.689742 -286.581235) (xy 66.737961 -286.571391) (xy 66.787136 -286.56941)
			(xy 66.835991 -286.575342) (xy 66.883262 -286.589034) (xy 66.927724 -286.610132) (xy 66.968227 -286.638088)
			(xy 67.00372 -286.67218) (xy 67.033285 -286.711524) (xy 67.056156 -286.755101) (xy 67.07174 -286.801782)
			(xy 67.079635 -286.850359) (xy 67.08013 -286.874966) (xy 67.418978 -286.874966) (xy 67.422938 -286.825912)
			(xy 67.434715 -286.778128) (xy 67.454006 -286.732852) (xy 67.480309 -286.691256) (xy 67.512944 -286.654419)
			(xy 67.551065 -286.623294) (xy 67.593686 -286.598687) (xy 67.639702 -286.581235) (xy 67.687921 -286.571391)
			(xy 67.737096 -286.56941) (xy 67.785951 -286.575342) (xy 67.833222 -286.589034) (xy 67.877684 -286.610132)
			(xy 67.918187 -286.638088) (xy 67.95368 -286.67218) (xy 67.983245 -286.711524) (xy 68.006116 -286.755101)
			(xy 68.0217 -286.801782) (xy 68.029595 -286.850359) (xy 68.03009 -286.874966) (xy 68.368938 -286.874966)
			(xy 68.372898 -286.825912) (xy 68.384675 -286.778128) (xy 68.403966 -286.732852) (xy 68.430269 -286.691256)
			(xy 68.462904 -286.654419) (xy 68.501025 -286.623294) (xy 68.543646 -286.598687) (xy 68.589662 -286.581235)
			(xy 68.637881 -286.571391) (xy 68.687056 -286.56941) (xy 68.735911 -286.575342) (xy 68.783182 -286.589034)
			(xy 68.827644 -286.610132) (xy 68.868147 -286.638088) (xy 68.90364 -286.67218) (xy 68.933205 -286.711524)
			(xy 68.956076 -286.755101) (xy 68.97166 -286.801782) (xy 68.979555 -286.850359) (xy 68.98005 -286.874966)
			(xy 70.269112 -286.874966) (xy 70.273072 -286.825912) (xy 70.284849 -286.778128) (xy 70.30414 -286.732852)
			(xy 70.330443 -286.691256) (xy 70.363078 -286.654419) (xy 70.401199 -286.623294) (xy 70.44382 -286.598687)
			(xy 70.489836 -286.581235) (xy 70.538055 -286.571391) (xy 70.58723 -286.56941) (xy 70.636085 -286.575342)
			(xy 70.683356 -286.589034) (xy 70.727818 -286.610132) (xy 70.768321 -286.638088) (xy 70.803814 -286.67218)
			(xy 70.833379 -286.711524) (xy 70.85625 -286.755101) (xy 70.871834 -286.801782) (xy 70.879729 -286.850359)
			(xy 70.880224 -286.874966) (xy 70.879729 -286.899573) (xy 70.871834 -286.94815) (xy 70.85625 -286.994831)
			(xy 70.833379 -287.038408) (xy 70.803814 -287.077752) (xy 70.768321 -287.111844) (xy 70.727818 -287.1398)
			(xy 70.683356 -287.160898) (xy 70.636085 -287.17459) (xy 70.58723 -287.180522) (xy 70.538055 -287.178541)
			(xy 70.489836 -287.168697) (xy 70.44382 -287.151245) (xy 70.401199 -287.126638) (xy 70.363078 -287.095513)
			(xy 70.330443 -287.058676) (xy 70.30414 -287.01708) (xy 70.284849 -286.971804) (xy 70.273072 -286.92402)
			(xy 70.269112 -286.874966) (xy 68.98005 -286.874966) (xy 68.979555 -286.899573) (xy 68.97166 -286.94815)
			(xy 68.956076 -286.994831) (xy 68.933205 -287.038408) (xy 68.90364 -287.077752) (xy 68.868147 -287.111844)
			(xy 68.827644 -287.1398) (xy 68.783182 -287.160898) (xy 68.735911 -287.17459) (xy 68.687056 -287.180522)
			(xy 68.637881 -287.178541) (xy 68.589662 -287.168697) (xy 68.543646 -287.151245) (xy 68.501025 -287.126638)
			(xy 68.462904 -287.095513) (xy 68.430269 -287.058676) (xy 68.403966 -287.01708) (xy 68.384675 -286.971804)
			(xy 68.372898 -286.92402) (xy 68.368938 -286.874966) (xy 68.03009 -286.874966) (xy 68.029595 -286.899573)
			(xy 68.0217 -286.94815) (xy 68.006116 -286.994831) (xy 67.983245 -287.038408) (xy 67.95368 -287.077752)
			(xy 67.918187 -287.111844) (xy 67.877684 -287.1398) (xy 67.833222 -287.160898) (xy 67.785951 -287.17459)
			(xy 67.737096 -287.180522) (xy 67.687921 -287.178541) (xy 67.639702 -287.168697) (xy 67.593686 -287.151245)
			(xy 67.551065 -287.126638) (xy 67.512944 -287.095513) (xy 67.480309 -287.058676) (xy 67.454006 -287.01708)
			(xy 67.434715 -286.971804) (xy 67.422938 -286.92402) (xy 67.418978 -286.874966) (xy 67.08013 -286.874966)
			(xy 67.079635 -286.899573) (xy 67.07174 -286.94815) (xy 67.056156 -286.994831) (xy 67.033285 -287.038408)
			(xy 67.00372 -287.077752) (xy 66.968227 -287.111844) (xy 66.927724 -287.1398) (xy 66.883262 -287.160898)
			(xy 66.835991 -287.17459) (xy 66.787136 -287.180522) (xy 66.737961 -287.178541) (xy 66.689742 -287.168697)
			(xy 66.643726 -287.151245) (xy 66.601105 -287.126638) (xy 66.562984 -287.095513) (xy 66.530349 -287.058676)
			(xy 66.504046 -287.01708) (xy 66.484755 -286.971804) (xy 66.472978 -286.92402) (xy 66.469018 -286.874966)
			(xy 66.13017 -286.874966) (xy 66.129675 -286.899573) (xy 66.12178 -286.94815) (xy 66.106196 -286.994831)
			(xy 66.083325 -287.038408) (xy 66.05376 -287.077752) (xy 66.018267 -287.111844) (xy 65.977764 -287.1398)
			(xy 65.933302 -287.160898) (xy 65.886031 -287.17459) (xy 65.837176 -287.180522) (xy 65.788001 -287.178541)
			(xy 65.739782 -287.168697) (xy 65.693766 -287.151245) (xy 65.651145 -287.126638) (xy 65.613024 -287.095513)
			(xy 65.580389 -287.058676) (xy 65.554086 -287.01708) (xy 65.534795 -286.971804) (xy 65.523018 -286.92402)
			(xy 65.519058 -286.874966) (xy 65.18021 -286.874966) (xy 65.179715 -286.899573) (xy 65.17182 -286.94815)
			(xy 65.156236 -286.994831) (xy 65.133365 -287.038408) (xy 65.1038 -287.077752) (xy 65.068307 -287.111844)
			(xy 65.027804 -287.1398) (xy 64.983342 -287.160898) (xy 64.936071 -287.17459) (xy 64.887216 -287.180522)
			(xy 64.838041 -287.178541) (xy 64.789822 -287.168697) (xy 64.743806 -287.151245) (xy 64.701185 -287.126638)
			(xy 64.663064 -287.095513) (xy 64.630429 -287.058676) (xy 64.604126 -287.01708) (xy 64.584835 -286.971804)
			(xy 64.573058 -286.92402) (xy 64.569098 -286.874966) (xy 64.23025 -286.874966) (xy 64.229755 -286.899573)
			(xy 64.22186 -286.94815) (xy 64.206276 -286.994831) (xy 64.183405 -287.038408) (xy 64.15384 -287.077752)
			(xy 64.118347 -287.111844) (xy 64.077844 -287.1398) (xy 64.033382 -287.160898) (xy 63.986111 -287.17459)
			(xy 63.937256 -287.180522) (xy 63.888081 -287.178541) (xy 63.839862 -287.168697) (xy 63.793846 -287.151245)
			(xy 63.751225 -287.126638) (xy 63.713104 -287.095513) (xy 63.680469 -287.058676) (xy 63.654166 -287.01708)
			(xy 63.634875 -286.971804) (xy 63.623098 -286.92402) (xy 63.619138 -286.874966) (xy 63.28029 -286.874966)
			(xy 63.279795 -286.899573) (xy 63.2719 -286.94815) (xy 63.256316 -286.994831) (xy 63.233445 -287.038408)
			(xy 63.20388 -287.077752) (xy 63.168387 -287.111844) (xy 63.127884 -287.1398) (xy 63.083422 -287.160898)
			(xy 63.036151 -287.17459) (xy 62.987296 -287.180522) (xy 62.938121 -287.178541) (xy 62.889902 -287.168697)
			(xy 62.843886 -287.151245) (xy 62.801265 -287.126638) (xy 62.763144 -287.095513) (xy 62.730509 -287.058676)
			(xy 62.704206 -287.01708) (xy 62.684915 -286.971804) (xy 62.673138 -286.92402) (xy 62.669178 -286.874966)
			(xy 62.330076 -286.874966) (xy 62.329581 -286.899573) (xy 62.321686 -286.94815) (xy 62.306102 -286.994831)
			(xy 62.283231 -287.038408) (xy 62.253666 -287.077752) (xy 62.218173 -287.111844) (xy 62.17767 -287.1398)
			(xy 62.133208 -287.160898) (xy 62.085937 -287.17459) (xy 62.037082 -287.180522) (xy 61.987907 -287.178541)
			(xy 61.939688 -287.168697) (xy 61.893672 -287.151245) (xy 61.851051 -287.126638) (xy 61.81293 -287.095513)
			(xy 61.780295 -287.058676) (xy 61.753992 -287.01708) (xy 61.734701 -286.971804) (xy 61.722924 -286.92402)
			(xy 61.718964 -286.874966) (xy 61.380116 -286.874966) (xy 61.379621 -286.899573) (xy 61.371726 -286.94815)
			(xy 61.356142 -286.994831) (xy 61.333271 -287.038408) (xy 61.303706 -287.077752) (xy 61.268213 -287.111844)
			(xy 61.22771 -287.1398) (xy 61.183248 -287.160898) (xy 61.135977 -287.17459) (xy 61.087122 -287.180522)
			(xy 61.037947 -287.178541) (xy 60.989728 -287.168697) (xy 60.943712 -287.151245) (xy 60.901091 -287.126638)
			(xy 60.86297 -287.095513) (xy 60.830335 -287.058676) (xy 60.804032 -287.01708) (xy 60.784741 -286.971804)
			(xy 60.772964 -286.92402) (xy 60.769004 -286.874966) (xy 60.430156 -286.874966) (xy 60.429661 -286.899573)
			(xy 60.421766 -286.94815) (xy 60.406182 -286.994831) (xy 60.383311 -287.038408) (xy 60.353746 -287.077752)
			(xy 60.318253 -287.111844) (xy 60.27775 -287.1398) (xy 60.233288 -287.160898) (xy 60.186017 -287.17459)
			(xy 60.137162 -287.180522) (xy 60.087987 -287.178541) (xy 60.039768 -287.168697) (xy 59.993752 -287.151245)
			(xy 59.951131 -287.126638) (xy 59.91301 -287.095513) (xy 59.880375 -287.058676) (xy 59.854072 -287.01708)
			(xy 59.834781 -286.971804) (xy 59.823004 -286.92402) (xy 59.819044 -286.874966) (xy 58.530236 -286.874966)
			(xy 58.529741 -286.899573) (xy 58.521846 -286.94815) (xy 58.506262 -286.994831) (xy 58.483391 -287.038408)
			(xy 58.453826 -287.077752) (xy 58.418333 -287.111844) (xy 58.37783 -287.1398) (xy 58.333368 -287.160898)
			(xy 58.286097 -287.17459) (xy 58.237242 -287.180522) (xy 58.188067 -287.178541) (xy 58.139848 -287.168697)
			(xy 58.093832 -287.151245) (xy 58.051211 -287.126638) (xy 58.01309 -287.095513) (xy 57.980455 -287.058676)
			(xy 57.954152 -287.01708) (xy 57.934861 -286.971804) (xy 57.923084 -286.92402) (xy 57.919124 -286.874966)
			(xy 57.580276 -286.874966) (xy 57.579781 -286.899573) (xy 57.571886 -286.94815) (xy 57.556302 -286.994831)
			(xy 57.533431 -287.038408) (xy 57.503866 -287.077752) (xy 57.468373 -287.111844) (xy 57.42787 -287.1398)
			(xy 57.383408 -287.160898) (xy 57.336137 -287.17459) (xy 57.287282 -287.180522) (xy 57.238107 -287.178541)
			(xy 57.189888 -287.168697) (xy 57.143872 -287.151245) (xy 57.101251 -287.126638) (xy 57.06313 -287.095513)
			(xy 57.030495 -287.058676) (xy 57.004192 -287.01708) (xy 56.984901 -286.971804) (xy 56.973124 -286.92402)
			(xy 56.969164 -286.874966) (xy 56.630062 -286.874966) (xy 56.629567 -286.899573) (xy 56.621672 -286.94815)
			(xy 56.606088 -286.994831) (xy 56.583217 -287.038408) (xy 56.553652 -287.077752) (xy 56.518159 -287.111844)
			(xy 56.477656 -287.1398) (xy 56.433194 -287.160898) (xy 56.385923 -287.17459) (xy 56.337068 -287.180522)
			(xy 56.287893 -287.178541) (xy 56.239674 -287.168697) (xy 56.193658 -287.151245) (xy 56.151037 -287.126638)
			(xy 56.112916 -287.095513) (xy 56.080281 -287.058676) (xy 56.053978 -287.01708) (xy 56.034687 -286.971804)
			(xy 56.02291 -286.92402) (xy 56.01895 -286.874966) (xy 55.680102 -286.874966) (xy 55.679607 -286.899573)
			(xy 55.671712 -286.94815) (xy 55.656128 -286.994831) (xy 55.633257 -287.038408) (xy 55.603692 -287.077752)
			(xy 55.568199 -287.111844) (xy 55.527696 -287.1398) (xy 55.483234 -287.160898) (xy 55.435963 -287.17459)
			(xy 55.387108 -287.180522) (xy 55.337933 -287.178541) (xy 55.289714 -287.168697) (xy 55.243698 -287.151245)
			(xy 55.201077 -287.126638) (xy 55.162956 -287.095513) (xy 55.130321 -287.058676) (xy 55.104018 -287.01708)
			(xy 55.084727 -286.971804) (xy 55.07295 -286.92402) (xy 55.06899 -286.874966) (xy 54.730142 -286.874966)
			(xy 54.729647 -286.899573) (xy 54.721752 -286.94815) (xy 54.706168 -286.994831) (xy 54.683297 -287.038408)
			(xy 54.653732 -287.077752) (xy 54.618239 -287.111844) (xy 54.577736 -287.1398) (xy 54.533274 -287.160898)
			(xy 54.486003 -287.17459) (xy 54.437148 -287.180522) (xy 54.387973 -287.178541) (xy 54.339754 -287.168697)
			(xy 54.293738 -287.151245) (xy 54.251117 -287.126638) (xy 54.212996 -287.095513) (xy 54.180361 -287.058676)
			(xy 54.154058 -287.01708) (xy 54.134767 -286.971804) (xy 54.12299 -286.92402) (xy 54.11903 -286.874966)
			(xy 53.780182 -286.874966) (xy 53.779687 -286.899573) (xy 53.771792 -286.94815) (xy 53.756208 -286.994831)
			(xy 53.733337 -287.038408) (xy 53.703772 -287.077752) (xy 53.668279 -287.111844) (xy 53.627776 -287.1398)
			(xy 53.583314 -287.160898) (xy 53.536043 -287.17459) (xy 53.487188 -287.180522) (xy 53.438013 -287.178541)
			(xy 53.389794 -287.168697) (xy 53.343778 -287.151245) (xy 53.301157 -287.126638) (xy 53.263036 -287.095513)
			(xy 53.230401 -287.058676) (xy 53.204098 -287.01708) (xy 53.184807 -286.971804) (xy 53.17303 -286.92402)
			(xy 53.16907 -286.874966) (xy 52.830222 -286.874966) (xy 52.829727 -286.899573) (xy 52.821832 -286.94815)
			(xy 52.806248 -286.994831) (xy 52.783377 -287.038408) (xy 52.753812 -287.077752) (xy 52.718319 -287.111844)
			(xy 52.677816 -287.1398) (xy 52.633354 -287.160898) (xy 52.586083 -287.17459) (xy 52.537228 -287.180522)
			(xy 52.488053 -287.178541) (xy 52.439834 -287.168697) (xy 52.393818 -287.151245) (xy 52.351197 -287.126638)
			(xy 52.313076 -287.095513) (xy 52.280441 -287.058676) (xy 52.254138 -287.01708) (xy 52.234847 -286.971804)
			(xy 52.22307 -286.92402) (xy 52.21911 -286.874966) (xy 51.880262 -286.874966) (xy 51.879767 -286.899573)
			(xy 51.871872 -286.94815) (xy 51.856288 -286.994831) (xy 51.833417 -287.038408) (xy 51.803852 -287.077752)
			(xy 51.768359 -287.111844) (xy 51.727856 -287.1398) (xy 51.683394 -287.160898) (xy 51.636123 -287.17459)
			(xy 51.587268 -287.180522) (xy 51.538093 -287.178541) (xy 51.489874 -287.168697) (xy 51.443858 -287.151245)
			(xy 51.401237 -287.126638) (xy 51.363116 -287.095513) (xy 51.330481 -287.058676) (xy 51.304178 -287.01708)
			(xy 51.284887 -286.971804) (xy 51.27311 -286.92402) (xy 51.26915 -286.874966) (xy 50.930302 -286.874966)
			(xy 50.929807 -286.899573) (xy 50.921912 -286.94815) (xy 50.906328 -286.994831) (xy 50.883457 -287.038408)
			(xy 50.853892 -287.077752) (xy 50.818399 -287.111844) (xy 50.777896 -287.1398) (xy 50.733434 -287.160898)
			(xy 50.686163 -287.17459) (xy 50.637308 -287.180522) (xy 50.588133 -287.178541) (xy 50.539914 -287.168697)
			(xy 50.493898 -287.151245) (xy 50.451277 -287.126638) (xy 50.413156 -287.095513) (xy 50.380521 -287.058676)
			(xy 50.354218 -287.01708) (xy 50.334927 -286.971804) (xy 50.32315 -286.92402) (xy 50.31919 -286.874966)
			(xy 49.980088 -286.874966) (xy 49.979593 -286.899573) (xy 49.971698 -286.94815) (xy 49.956114 -286.994831)
			(xy 49.933243 -287.038408) (xy 49.903678 -287.077752) (xy 49.868185 -287.111844) (xy 49.827682 -287.1398)
			(xy 49.78322 -287.160898) (xy 49.735949 -287.17459) (xy 49.687094 -287.180522) (xy 49.637919 -287.178541)
			(xy 49.5897 -287.168697) (xy 49.543684 -287.151245) (xy 49.501063 -287.126638) (xy 49.462942 -287.095513)
			(xy 49.430307 -287.058676) (xy 49.404004 -287.01708) (xy 49.384713 -286.971804) (xy 49.372936 -286.92402)
			(xy 49.368976 -286.874966) (xy 49.030128 -286.874966) (xy 49.029633 -286.899573) (xy 49.021738 -286.94815)
			(xy 49.006154 -286.994831) (xy 48.983283 -287.038408) (xy 48.953718 -287.077752) (xy 48.918225 -287.111844)
			(xy 48.877722 -287.1398) (xy 48.83326 -287.160898) (xy 48.785989 -287.17459) (xy 48.737134 -287.180522)
			(xy 48.687959 -287.178541) (xy 48.63974 -287.168697) (xy 48.593724 -287.151245) (xy 48.551103 -287.126638)
			(xy 48.512982 -287.095513) (xy 48.480347 -287.058676) (xy 48.454044 -287.01708) (xy 48.434753 -286.971804)
			(xy 48.422976 -286.92402) (xy 48.419016 -286.874966) (xy 48.080168 -286.874966) (xy 48.079673 -286.899573)
			(xy 48.071778 -286.94815) (xy 48.056194 -286.994831) (xy 48.033323 -287.038408) (xy 48.003758 -287.077752)
			(xy 47.968265 -287.111844) (xy 47.927762 -287.1398) (xy 47.8833 -287.160898) (xy 47.836029 -287.17459)
			(xy 47.787174 -287.180522) (xy 47.737999 -287.178541) (xy 47.68978 -287.168697) (xy 47.643764 -287.151245)
			(xy 47.601143 -287.126638) (xy 47.563022 -287.095513) (xy 47.530387 -287.058676) (xy 47.504084 -287.01708)
			(xy 47.484793 -286.971804) (xy 47.473016 -286.92402) (xy 47.469056 -286.874966) (xy 47.130208 -286.874966)
			(xy 47.129713 -286.899573) (xy 47.121818 -286.94815) (xy 47.106234 -286.994831) (xy 47.083363 -287.038408)
			(xy 47.053798 -287.077752) (xy 47.018305 -287.111844) (xy 46.977802 -287.1398) (xy 46.93334 -287.160898)
			(xy 46.886069 -287.17459) (xy 46.837214 -287.180522) (xy 46.788039 -287.178541) (xy 46.73982 -287.168697)
			(xy 46.693804 -287.151245) (xy 46.651183 -287.126638) (xy 46.613062 -287.095513) (xy 46.580427 -287.058676)
			(xy 46.554124 -287.01708) (xy 46.534833 -286.971804) (xy 46.523056 -286.92402) (xy 46.519096 -286.874966)
			(xy 46.180248 -286.874966) (xy 46.179753 -286.899573) (xy 46.171858 -286.94815) (xy 46.156274 -286.994831)
			(xy 46.133403 -287.038408) (xy 46.103838 -287.077752) (xy 46.068345 -287.111844) (xy 46.027842 -287.1398)
			(xy 45.98338 -287.160898) (xy 45.936109 -287.17459) (xy 45.887254 -287.180522) (xy 45.838079 -287.178541)
			(xy 45.78986 -287.168697) (xy 45.743844 -287.151245) (xy 45.701223 -287.126638) (xy 45.663102 -287.095513)
			(xy 45.630467 -287.058676) (xy 45.604164 -287.01708) (xy 45.584873 -286.971804) (xy 45.573096 -286.92402)
			(xy 45.569136 -286.874966) (xy 45.230288 -286.874966) (xy 45.229793 -286.899573) (xy 45.221898 -286.94815)
			(xy 45.206314 -286.994831) (xy 45.183443 -287.038408) (xy 45.153878 -287.077752) (xy 45.118385 -287.111844)
			(xy 45.077882 -287.1398) (xy 45.03342 -287.160898) (xy 44.986149 -287.17459) (xy 44.937294 -287.180522)
			(xy 44.888119 -287.178541) (xy 44.8399 -287.168697) (xy 44.793884 -287.151245) (xy 44.751263 -287.126638)
			(xy 44.713142 -287.095513) (xy 44.680507 -287.058676) (xy 44.654204 -287.01708) (xy 44.634913 -286.971804)
			(xy 44.623136 -286.92402) (xy 44.619176 -286.874966) (xy 44.280069 -286.874966) (xy 44.279579 -286.899319)
			(xy 44.271684 -286.947896) (xy 44.2561 -286.994577) (xy 44.233229 -287.038154) (xy 44.203664 -287.077498)
			(xy 44.168171 -287.11159) (xy 44.127668 -287.139546) (xy 44.083206 -287.160644) (xy 44.035935 -287.174336)
			(xy 43.98708 -287.180268) (xy 43.937905 -287.178287) (xy 43.889686 -287.168443) (xy 43.84367 -287.150991)
			(xy 43.801049 -287.126384) (xy 43.762928 -287.095259) (xy 43.730293 -287.058422) (xy 43.70399 -287.016826)
			(xy 43.684699 -286.97155) (xy 43.672922 -286.923766) (xy 43.668962 -286.874712) (xy 43.330114 -286.874712)
			(xy 43.329619 -286.899319) (xy 43.321724 -286.947896) (xy 43.30614 -286.994577) (xy 43.283269 -287.038154)
			(xy 43.253704 -287.077498) (xy 43.218211 -287.11159) (xy 43.177708 -287.139546) (xy 43.133246 -287.160644)
			(xy 43.085975 -287.174336) (xy 43.03712 -287.180268) (xy 42.987945 -287.178287) (xy 42.939726 -287.168443)
			(xy 42.89371 -287.150991) (xy 42.851089 -287.126384) (xy 42.812968 -287.095259) (xy 42.780333 -287.058422)
			(xy 42.75403 -287.016826) (xy 42.734739 -286.97155) (xy 42.722962 -286.923766) (xy 42.719002 -286.874712)
			(xy 42.380149 -286.874712) (xy 42.380154 -286.874966) (xy 42.379659 -286.899573) (xy 42.371764 -286.94815)
			(xy 42.35618 -286.994831) (xy 42.333309 -287.038408) (xy 42.303744 -287.077752) (xy 42.268251 -287.111844)
			(xy 42.227748 -287.1398) (xy 42.183286 -287.160898) (xy 42.136015 -287.17459) (xy 42.08716 -287.180522)
			(xy 42.037985 -287.178541) (xy 41.989766 -287.168697) (xy 41.94375 -287.151245) (xy 41.901129 -287.126638)
			(xy 41.863008 -287.095513) (xy 41.830373 -287.058676) (xy 41.80407 -287.01708) (xy 41.784779 -286.971804)
			(xy 41.773002 -286.92402) (xy 41.769042 -286.874966) (xy 41.430194 -286.874966) (xy 41.429699 -286.899573)
			(xy 41.421804 -286.94815) (xy 41.40622 -286.994831) (xy 41.383349 -287.038408) (xy 41.353784 -287.077752)
			(xy 41.318291 -287.111844) (xy 41.277788 -287.1398) (xy 41.233326 -287.160898) (xy 41.186055 -287.17459)
			(xy 41.1372 -287.180522) (xy 41.088025 -287.178541) (xy 41.039806 -287.168697) (xy 40.99379 -287.151245)
			(xy 40.951169 -287.126638) (xy 40.913048 -287.095513) (xy 40.880413 -287.058676) (xy 40.85411 -287.01708)
			(xy 40.834819 -286.971804) (xy 40.823042 -286.92402) (xy 40.819082 -286.874966) (xy 40.480234 -286.874966)
			(xy 40.479739 -286.899573) (xy 40.471844 -286.94815) (xy 40.45626 -286.994831) (xy 40.433389 -287.038408)
			(xy 40.403824 -287.077752) (xy 40.368331 -287.111844) (xy 40.327828 -287.1398) (xy 40.283366 -287.160898)
			(xy 40.236095 -287.17459) (xy 40.18724 -287.180522) (xy 40.138065 -287.178541) (xy 40.089846 -287.168697)
			(xy 40.04383 -287.151245) (xy 40.001209 -287.126638) (xy 39.963088 -287.095513) (xy 39.930453 -287.058676)
			(xy 39.90415 -287.01708) (xy 39.884859 -286.971804) (xy 39.873082 -286.92402) (xy 39.869122 -286.874966)
			(xy 39.530274 -286.874966) (xy 39.529779 -286.899573) (xy 39.521884 -286.94815) (xy 39.5063 -286.994831)
			(xy 39.483429 -287.038408) (xy 39.453864 -287.077752) (xy 39.418371 -287.111844) (xy 39.377868 -287.1398)
			(xy 39.333406 -287.160898) (xy 39.286135 -287.17459) (xy 39.23728 -287.180522) (xy 39.188105 -287.178541)
			(xy 39.139886 -287.168697) (xy 39.09387 -287.151245) (xy 39.051249 -287.126638) (xy 39.013128 -287.095513)
			(xy 38.980493 -287.058676) (xy 38.95419 -287.01708) (xy 38.934899 -286.971804) (xy 38.923122 -286.92402)
			(xy 38.919162 -286.874966) (xy 38.580314 -286.874966) (xy 38.579819 -286.899573) (xy 38.571924 -286.94815)
			(xy 38.55634 -286.994831) (xy 38.533469 -287.038408) (xy 38.503904 -287.077752) (xy 38.468411 -287.111844)
			(xy 38.427908 -287.1398) (xy 38.383446 -287.160898) (xy 38.336175 -287.17459) (xy 38.28732 -287.180522)
			(xy 38.238145 -287.178541) (xy 38.189926 -287.168697) (xy 38.14391 -287.151245) (xy 38.101289 -287.126638)
			(xy 38.063168 -287.095513) (xy 38.030533 -287.058676) (xy 38.00423 -287.01708) (xy 37.984939 -286.971804)
			(xy 37.973162 -286.92402) (xy 37.969202 -286.874966) (xy 37.6301 -286.874966) (xy 37.629605 -286.899573)
			(xy 37.62171 -286.94815) (xy 37.606126 -286.994831) (xy 37.583255 -287.038408) (xy 37.55369 -287.077752)
			(xy 37.518197 -287.111844) (xy 37.477694 -287.1398) (xy 37.433232 -287.160898) (xy 37.385961 -287.17459)
			(xy 37.337106 -287.180522) (xy 37.287931 -287.178541) (xy 37.239712 -287.168697) (xy 37.193696 -287.151245)
			(xy 37.151075 -287.126638) (xy 37.112954 -287.095513) (xy 37.080319 -287.058676) (xy 37.054016 -287.01708)
			(xy 37.034725 -286.971804) (xy 37.022948 -286.92402) (xy 37.018988 -286.874966) (xy 36.68014 -286.874966)
			(xy 36.679645 -286.899573) (xy 36.67175 -286.94815) (xy 36.656166 -286.994831) (xy 36.633295 -287.038408)
			(xy 36.60373 -287.077752) (xy 36.568237 -287.111844) (xy 36.527734 -287.1398) (xy 36.483272 -287.160898)
			(xy 36.436001 -287.17459) (xy 36.387146 -287.180522) (xy 36.337971 -287.178541) (xy 36.289752 -287.168697)
			(xy 36.243736 -287.151245) (xy 36.201115 -287.126638) (xy 36.162994 -287.095513) (xy 36.130359 -287.058676)
			(xy 36.104056 -287.01708) (xy 36.084765 -286.971804) (xy 36.072988 -286.92402) (xy 36.069028 -286.874966)
			(xy 34.39033 -286.874966) (xy 34.39033 -287.349946) (xy 73.593972 -287.349946) (xy 73.597932 -287.300892)
			(xy 73.609709 -287.253108) (xy 73.629 -287.207832) (xy 73.655303 -287.166236) (xy 73.687938 -287.129399)
			(xy 73.726059 -287.098274) (xy 73.76868 -287.073667) (xy 73.814696 -287.056215) (xy 73.862915 -287.046371)
			(xy 73.91209 -287.04439) (xy 73.960945 -287.050322) (xy 74.008216 -287.064014) (xy 74.052678 -287.085112)
			(xy 74.093181 -287.113068) (xy 74.128674 -287.14716) (xy 74.158239 -287.186504) (xy 74.18111 -287.230081)
			(xy 74.196694 -287.276762) (xy 74.204589 -287.325339) (xy 74.205084 -287.349946) (xy 74.543932 -287.349946)
			(xy 74.547892 -287.300892) (xy 74.559669 -287.253108) (xy 74.57896 -287.207832) (xy 74.605263 -287.166236)
			(xy 74.637898 -287.129399) (xy 74.676019 -287.098274) (xy 74.71864 -287.073667) (xy 74.764656 -287.056215)
			(xy 74.812875 -287.046371) (xy 74.86205 -287.04439) (xy 74.910905 -287.050322) (xy 74.958176 -287.064014)
			(xy 75.002638 -287.085112) (xy 75.043141 -287.113068) (xy 75.078634 -287.14716) (xy 75.108199 -287.186504)
			(xy 75.13107 -287.230081) (xy 75.146654 -287.276762) (xy 75.154549 -287.325339) (xy 75.155044 -287.349946)
			(xy 75.494146 -287.349946) (xy 75.498106 -287.300892) (xy 75.509883 -287.253108) (xy 75.529174 -287.207832)
			(xy 75.555477 -287.166236) (xy 75.588112 -287.129399) (xy 75.626233 -287.098274) (xy 75.668854 -287.073667)
			(xy 75.71487 -287.056215) (xy 75.763089 -287.046371) (xy 75.812264 -287.04439) (xy 75.861119 -287.050322)
			(xy 75.90839 -287.064014) (xy 75.952852 -287.085112) (xy 75.993355 -287.113068) (xy 76.028848 -287.14716)
			(xy 76.058413 -287.186504) (xy 76.081284 -287.230081) (xy 76.096868 -287.276762) (xy 76.104763 -287.325339)
			(xy 76.105258 -287.349946) (xy 76.104763 -287.374553) (xy 76.096868 -287.42313) (xy 76.081284 -287.469811)
			(xy 76.058413 -287.513388) (xy 76.028848 -287.552732) (xy 75.993355 -287.586824) (xy 75.952852 -287.61478)
			(xy 75.90839 -287.635878) (xy 75.861119 -287.64957) (xy 75.812264 -287.655502) (xy 75.763089 -287.653521)
			(xy 75.71487 -287.643677) (xy 75.668854 -287.626225) (xy 75.626233 -287.601618) (xy 75.588112 -287.570493)
			(xy 75.555477 -287.533656) (xy 75.529174 -287.49206) (xy 75.509883 -287.446784) (xy 75.498106 -287.399)
			(xy 75.494146 -287.349946) (xy 75.155044 -287.349946) (xy 75.154549 -287.374553) (xy 75.146654 -287.42313)
			(xy 75.13107 -287.469811) (xy 75.108199 -287.513388) (xy 75.078634 -287.552732) (xy 75.043141 -287.586824)
			(xy 75.002638 -287.61478) (xy 74.958176 -287.635878) (xy 74.910905 -287.64957) (xy 74.86205 -287.655502)
			(xy 74.812875 -287.653521) (xy 74.764656 -287.643677) (xy 74.71864 -287.626225) (xy 74.676019 -287.601618)
			(xy 74.637898 -287.570493) (xy 74.605263 -287.533656) (xy 74.57896 -287.49206) (xy 74.559669 -287.446784)
			(xy 74.547892 -287.399) (xy 74.543932 -287.349946) (xy 74.205084 -287.349946) (xy 74.204589 -287.374553)
			(xy 74.196694 -287.42313) (xy 74.18111 -287.469811) (xy 74.158239 -287.513388) (xy 74.128674 -287.552732)
			(xy 74.093181 -287.586824) (xy 74.052678 -287.61478) (xy 74.008216 -287.635878) (xy 73.960945 -287.64957)
			(xy 73.91209 -287.655502) (xy 73.862915 -287.653521) (xy 73.814696 -287.643677) (xy 73.76868 -287.626225)
			(xy 73.726059 -287.601618) (xy 73.687938 -287.570493) (xy 73.655303 -287.533656) (xy 73.629 -287.49206)
			(xy 73.609709 -287.446784) (xy 73.597932 -287.399) (xy 73.593972 -287.349946) (xy 34.39033 -287.349946)
			(xy 34.39033 -287.824926) (xy 36.069028 -287.824926) (xy 36.072988 -287.775872) (xy 36.084765 -287.728088)
			(xy 36.104056 -287.682812) (xy 36.130359 -287.641216) (xy 36.162994 -287.604379) (xy 36.201115 -287.573254)
			(xy 36.243736 -287.548647) (xy 36.289752 -287.531195) (xy 36.337971 -287.521351) (xy 36.387146 -287.51937)
			(xy 36.436001 -287.525302) (xy 36.483272 -287.538994) (xy 36.527734 -287.560092) (xy 36.568237 -287.588048)
			(xy 36.60373 -287.62214) (xy 36.633295 -287.661484) (xy 36.656166 -287.705061) (xy 36.67175 -287.751742)
			(xy 36.679645 -287.800319) (xy 36.68014 -287.824926) (xy 37.018988 -287.824926) (xy 37.022948 -287.775872)
			(xy 37.034725 -287.728088) (xy 37.054016 -287.682812) (xy 37.080319 -287.641216) (xy 37.112954 -287.604379)
			(xy 37.151075 -287.573254) (xy 37.193696 -287.548647) (xy 37.239712 -287.531195) (xy 37.287931 -287.521351)
			(xy 37.337106 -287.51937) (xy 37.385961 -287.525302) (xy 37.433232 -287.538994) (xy 37.477694 -287.560092)
			(xy 37.518197 -287.588048) (xy 37.55369 -287.62214) (xy 37.583255 -287.661484) (xy 37.606126 -287.705061)
			(xy 37.62171 -287.751742) (xy 37.629605 -287.800319) (xy 37.6301 -287.824926) (xy 37.629605 -287.849533)
			(xy 37.629463 -287.850408) (xy 37.944539 -287.850408) (xy 37.944539 -287.798392) (xy 37.952677 -287.747016)
			(xy 37.968751 -287.697546) (xy 37.992366 -287.651199) (xy 38.02294 -287.609117) (xy 38.059722 -287.572337)
			(xy 38.101804 -287.541763) (xy 38.148151 -287.518148) (xy 38.197622 -287.502075) (xy 38.248998 -287.493939)
			(xy 38.275006 -287.493456) (xy 39.224966 -287.493456) (xy 39.250978 -287.493901) (xy 39.302363 -287.502035)
			(xy 39.351843 -287.518107) (xy 39.398199 -287.541722) (xy 39.44029 -287.572299) (xy 39.477079 -287.609084)
			(xy 39.50766 -287.651172) (xy 39.53128 -287.697525) (xy 39.547357 -287.747004) (xy 39.555496 -287.798388)
			(xy 39.555496 -287.824926) (xy 39.869122 -287.824926) (xy 39.873082 -287.775872) (xy 39.884859 -287.728088)
			(xy 39.90415 -287.682812) (xy 39.930453 -287.641216) (xy 39.963088 -287.604379) (xy 40.001209 -287.573254)
			(xy 40.04383 -287.548647) (xy 40.089846 -287.531195) (xy 40.138065 -287.521351) (xy 40.18724 -287.51937)
			(xy 40.236095 -287.525302) (xy 40.283366 -287.538994) (xy 40.327828 -287.560092) (xy 40.368331 -287.588048)
			(xy 40.403824 -287.62214) (xy 40.433389 -287.661484) (xy 40.45626 -287.705061) (xy 40.471844 -287.751742)
			(xy 40.479739 -287.800319) (xy 40.480234 -287.824926) (xy 40.479739 -287.849533) (xy 40.479597 -287.850405)
			(xy 40.794466 -287.850405) (xy 40.794466 -287.798395) (xy 40.802602 -287.747025) (xy 40.818674 -287.697561)
			(xy 40.842285 -287.651219) (xy 40.872855 -287.609142) (xy 40.909631 -287.572364) (xy 40.951707 -287.541792)
			(xy 40.998048 -287.518179) (xy 41.047512 -287.502105) (xy 41.098881 -287.493967) (xy 41.124886 -287.493456)
			(xy 42.074846 -287.493456) (xy 42.100852 -287.493934) (xy 42.152223 -287.502077) (xy 42.201688 -287.518155)
			(xy 42.248029 -287.541773) (xy 42.290106 -287.572348) (xy 42.326882 -287.609129) (xy 42.357451 -287.65121)
			(xy 42.381063 -287.697554) (xy 42.397134 -287.747022) (xy 42.40527 -287.798394) (xy 42.40527 -287.824926)
			(xy 42.719002 -287.824926) (xy 42.722962 -287.775872) (xy 42.734739 -287.728088) (xy 42.75403 -287.682812)
			(xy 42.780333 -287.641216) (xy 42.812968 -287.604379) (xy 42.851089 -287.573254) (xy 42.89371 -287.548647)
			(xy 42.939726 -287.531195) (xy 42.987945 -287.521351) (xy 43.03712 -287.51937) (xy 43.085975 -287.525302)
			(xy 43.133246 -287.538994) (xy 43.177708 -287.560092) (xy 43.218211 -287.588048) (xy 43.253704 -287.62214)
			(xy 43.283269 -287.661484) (xy 43.30614 -287.705061) (xy 43.321724 -287.751742) (xy 43.329619 -287.800319)
			(xy 43.330114 -287.824926) (xy 43.668962 -287.824926) (xy 43.672922 -287.775872) (xy 43.684699 -287.728088)
			(xy 43.70399 -287.682812) (xy 43.730293 -287.641216) (xy 43.762928 -287.604379) (xy 43.801049 -287.573254)
			(xy 43.84367 -287.548647) (xy 43.889686 -287.531195) (xy 43.937905 -287.521351) (xy 43.98708 -287.51937)
			(xy 44.035935 -287.525302) (xy 44.083206 -287.538994) (xy 44.127668 -287.560092) (xy 44.168171 -287.588048)
			(xy 44.203664 -287.62214) (xy 44.233229 -287.661484) (xy 44.2561 -287.705061) (xy 44.271684 -287.751742)
			(xy 44.279579 -287.800319) (xy 44.280074 -287.824926) (xy 44.619176 -287.824926) (xy 44.623136 -287.775872)
			(xy 44.634913 -287.728088) (xy 44.654204 -287.682812) (xy 44.680507 -287.641216) (xy 44.713142 -287.604379)
			(xy 44.751263 -287.573254) (xy 44.793884 -287.548647) (xy 44.8399 -287.531195) (xy 44.888119 -287.521351)
			(xy 44.937294 -287.51937) (xy 44.986149 -287.525302) (xy 45.03342 -287.538994) (xy 45.077882 -287.560092)
			(xy 45.118385 -287.588048) (xy 45.153878 -287.62214) (xy 45.183443 -287.661484) (xy 45.206314 -287.705061)
			(xy 45.221898 -287.751742) (xy 45.229793 -287.800319) (xy 45.230288 -287.824926) (xy 45.569136 -287.824926)
			(xy 45.573096 -287.775872) (xy 45.584873 -287.728088) (xy 45.604164 -287.682812) (xy 45.630467 -287.641216)
			(xy 45.663102 -287.604379) (xy 45.701223 -287.573254) (xy 45.743844 -287.548647) (xy 45.78986 -287.531195)
			(xy 45.838079 -287.521351) (xy 45.887254 -287.51937) (xy 45.936109 -287.525302) (xy 45.98338 -287.538994)
			(xy 46.027842 -287.560092) (xy 46.068345 -287.588048) (xy 46.103838 -287.62214) (xy 46.133403 -287.661484)
			(xy 46.156274 -287.705061) (xy 46.171858 -287.751742) (xy 46.179753 -287.800319) (xy 46.180248 -287.824926)
			(xy 46.519096 -287.824926) (xy 46.523056 -287.775872) (xy 46.534833 -287.728088) (xy 46.554124 -287.682812)
			(xy 46.580427 -287.641216) (xy 46.613062 -287.604379) (xy 46.651183 -287.573254) (xy 46.693804 -287.548647)
			(xy 46.73982 -287.531195) (xy 46.788039 -287.521351) (xy 46.837214 -287.51937) (xy 46.886069 -287.525302)
			(xy 46.93334 -287.538994) (xy 46.977802 -287.560092) (xy 47.018305 -287.588048) (xy 47.053798 -287.62214)
			(xy 47.083363 -287.661484) (xy 47.106234 -287.705061) (xy 47.121818 -287.751742) (xy 47.129713 -287.800319)
			(xy 47.130208 -287.824926) (xy 47.469056 -287.824926) (xy 47.473016 -287.775872) (xy 47.484793 -287.728088)
			(xy 47.504084 -287.682812) (xy 47.530387 -287.641216) (xy 47.563022 -287.604379) (xy 47.601143 -287.573254)
			(xy 47.643764 -287.548647) (xy 47.68978 -287.531195) (xy 47.737999 -287.521351) (xy 47.787174 -287.51937)
			(xy 47.836029 -287.525302) (xy 47.8833 -287.538994) (xy 47.927762 -287.560092) (xy 47.968265 -287.588048)
			(xy 48.003758 -287.62214) (xy 48.033323 -287.661484) (xy 48.056194 -287.705061) (xy 48.071778 -287.751742)
			(xy 48.079673 -287.800319) (xy 48.080168 -287.824926) (xy 48.419016 -287.824926) (xy 48.422976 -287.775872)
			(xy 48.434753 -287.728088) (xy 48.454044 -287.682812) (xy 48.480347 -287.641216) (xy 48.512982 -287.604379)
			(xy 48.551103 -287.573254) (xy 48.593724 -287.548647) (xy 48.63974 -287.531195) (xy 48.687959 -287.521351)
			(xy 48.737134 -287.51937) (xy 48.785989 -287.525302) (xy 48.83326 -287.538994) (xy 48.877722 -287.560092)
			(xy 48.918225 -287.588048) (xy 48.953718 -287.62214) (xy 48.983283 -287.661484) (xy 49.006154 -287.705061)
			(xy 49.021738 -287.751742) (xy 49.029633 -287.800319) (xy 49.030128 -287.824926) (xy 49.368976 -287.824926)
			(xy 49.372936 -287.775872) (xy 49.384713 -287.728088) (xy 49.404004 -287.682812) (xy 49.430307 -287.641216)
			(xy 49.462942 -287.604379) (xy 49.501063 -287.573254) (xy 49.543684 -287.548647) (xy 49.5897 -287.531195)
			(xy 49.637919 -287.521351) (xy 49.687094 -287.51937) (xy 49.735949 -287.525302) (xy 49.78322 -287.538994)
			(xy 49.827682 -287.560092) (xy 49.868185 -287.588048) (xy 49.903678 -287.62214) (xy 49.933243 -287.661484)
			(xy 49.956114 -287.705061) (xy 49.971698 -287.751742) (xy 49.979593 -287.800319) (xy 49.980088 -287.824926)
			(xy 49.979593 -287.849533) (xy 49.971698 -287.89811) (xy 49.956114 -287.944791) (xy 49.933243 -287.988368)
			(xy 49.903678 -288.027712) (xy 49.868185 -288.061804) (xy 49.827682 -288.08976) (xy 49.78322 -288.110858)
			(xy 49.735949 -288.12455) (xy 49.687094 -288.130482) (xy 49.637919 -288.128501) (xy 49.5897 -288.118657)
			(xy 49.543684 -288.101205) (xy 49.501063 -288.076598) (xy 49.462942 -288.045473) (xy 49.430307 -288.008636)
			(xy 49.404004 -287.96704) (xy 49.384713 -287.921764) (xy 49.372936 -287.87398) (xy 49.368976 -287.824926)
			(xy 49.030128 -287.824926) (xy 49.029633 -287.849533) (xy 49.021738 -287.89811) (xy 49.006154 -287.944791)
			(xy 48.983283 -287.988368) (xy 48.953718 -288.027712) (xy 48.918225 -288.061804) (xy 48.877722 -288.08976)
			(xy 48.83326 -288.110858) (xy 48.785989 -288.12455) (xy 48.737134 -288.130482) (xy 48.687959 -288.128501)
			(xy 48.63974 -288.118657) (xy 48.593724 -288.101205) (xy 48.551103 -288.076598) (xy 48.512982 -288.045473)
			(xy 48.480347 -288.008636) (xy 48.454044 -287.96704) (xy 48.434753 -287.921764) (xy 48.422976 -287.87398)
			(xy 48.419016 -287.824926) (xy 48.080168 -287.824926) (xy 48.079673 -287.849533) (xy 48.071778 -287.89811)
			(xy 48.056194 -287.944791) (xy 48.033323 -287.988368) (xy 48.003758 -288.027712) (xy 47.968265 -288.061804)
			(xy 47.927762 -288.08976) (xy 47.8833 -288.110858) (xy 47.836029 -288.12455) (xy 47.787174 -288.130482)
			(xy 47.737999 -288.128501) (xy 47.68978 -288.118657) (xy 47.643764 -288.101205) (xy 47.601143 -288.076598)
			(xy 47.563022 -288.045473) (xy 47.530387 -288.008636) (xy 47.504084 -287.96704) (xy 47.484793 -287.921764)
			(xy 47.473016 -287.87398) (xy 47.469056 -287.824926) (xy 47.130208 -287.824926) (xy 47.129713 -287.849533)
			(xy 47.121818 -287.89811) (xy 47.106234 -287.944791) (xy 47.083363 -287.988368) (xy 47.053798 -288.027712)
			(xy 47.018305 -288.061804) (xy 46.977802 -288.08976) (xy 46.93334 -288.110858) (xy 46.886069 -288.12455)
			(xy 46.837214 -288.130482) (xy 46.788039 -288.128501) (xy 46.73982 -288.118657) (xy 46.693804 -288.101205)
			(xy 46.651183 -288.076598) (xy 46.613062 -288.045473) (xy 46.580427 -288.008636) (xy 46.554124 -287.96704)
			(xy 46.534833 -287.921764) (xy 46.523056 -287.87398) (xy 46.519096 -287.824926) (xy 46.180248 -287.824926)
			(xy 46.179753 -287.849533) (xy 46.171858 -287.89811) (xy 46.156274 -287.944791) (xy 46.133403 -287.988368)
			(xy 46.103838 -288.027712) (xy 46.068345 -288.061804) (xy 46.027842 -288.08976) (xy 45.98338 -288.110858)
			(xy 45.936109 -288.12455) (xy 45.887254 -288.130482) (xy 45.838079 -288.128501) (xy 45.78986 -288.118657)
			(xy 45.743844 -288.101205) (xy 45.701223 -288.076598) (xy 45.663102 -288.045473) (xy 45.630467 -288.008636)
			(xy 45.604164 -287.96704) (xy 45.584873 -287.921764) (xy 45.573096 -287.87398) (xy 45.569136 -287.824926)
			(xy 45.230288 -287.824926) (xy 45.229793 -287.849533) (xy 45.221898 -287.89811) (xy 45.206314 -287.944791)
			(xy 45.183443 -287.988368) (xy 45.153878 -288.027712) (xy 45.118385 -288.061804) (xy 45.077882 -288.08976)
			(xy 45.03342 -288.110858) (xy 44.986149 -288.12455) (xy 44.937294 -288.130482) (xy 44.888119 -288.128501)
			(xy 44.8399 -288.118657) (xy 44.793884 -288.101205) (xy 44.751263 -288.076598) (xy 44.713142 -288.045473)
			(xy 44.680507 -288.008636) (xy 44.654204 -287.96704) (xy 44.634913 -287.921764) (xy 44.623136 -287.87398)
			(xy 44.619176 -287.824926) (xy 44.280074 -287.824926) (xy 44.279579 -287.849533) (xy 44.271684 -287.89811)
			(xy 44.2561 -287.944791) (xy 44.233229 -287.988368) (xy 44.203664 -288.027712) (xy 44.168171 -288.061804)
			(xy 44.127668 -288.08976) (xy 44.083206 -288.110858) (xy 44.035935 -288.12455) (xy 43.98708 -288.130482)
			(xy 43.937905 -288.128501) (xy 43.889686 -288.118657) (xy 43.84367 -288.101205) (xy 43.801049 -288.076598)
			(xy 43.762928 -288.045473) (xy 43.730293 -288.008636) (xy 43.70399 -287.96704) (xy 43.684699 -287.921764)
			(xy 43.672922 -287.87398) (xy 43.668962 -287.824926) (xy 43.330114 -287.824926) (xy 43.329619 -287.849533)
			(xy 43.321724 -287.89811) (xy 43.30614 -287.944791) (xy 43.283269 -287.988368) (xy 43.253704 -288.027712)
			(xy 43.218211 -288.061804) (xy 43.177708 -288.08976) (xy 43.133246 -288.110858) (xy 43.085975 -288.12455)
			(xy 43.03712 -288.130482) (xy 42.987945 -288.128501) (xy 42.939726 -288.118657) (xy 42.89371 -288.101205)
			(xy 42.851089 -288.076598) (xy 42.812968 -288.045473) (xy 42.780333 -288.008636) (xy 42.75403 -287.96704)
			(xy 42.734739 -287.921764) (xy 42.722962 -287.87398) (xy 42.719002 -287.824926) (xy 42.40527 -287.824926)
			(xy 42.40527 -287.850406) (xy 42.397134 -287.901778) (xy 42.381063 -287.951246) (xy 42.357451 -287.99759)
			(xy 42.326882 -288.039671) (xy 42.290106 -288.076452) (xy 42.248029 -288.107027) (xy 42.201688 -288.130645)
			(xy 42.152223 -288.146723) (xy 42.100852 -288.154866) (xy 42.074846 -288.15538) (xy 41.124886 -288.15538)
			(xy 41.098881 -288.154833) (xy 41.047512 -288.146695) (xy 40.998048 -288.130621) (xy 40.951707 -288.107008)
			(xy 40.909631 -288.076436) (xy 40.872855 -288.039658) (xy 40.842285 -287.997581) (xy 40.818674 -287.951239)
			(xy 40.802602 -287.901775) (xy 40.794466 -287.850405) (xy 40.479597 -287.850405) (xy 40.471844 -287.89811)
			(xy 40.45626 -287.944791) (xy 40.433389 -287.988368) (xy 40.403824 -288.027712) (xy 40.368331 -288.061804)
			(xy 40.327828 -288.08976) (xy 40.283366 -288.110858) (xy 40.236095 -288.12455) (xy 40.18724 -288.130482)
			(xy 40.138065 -288.128501) (xy 40.089846 -288.118657) (xy 40.04383 -288.101205) (xy 40.001209 -288.076598)
			(xy 39.963088 -288.045473) (xy 39.930453 -288.008636) (xy 39.90415 -287.96704) (xy 39.884859 -287.921764)
			(xy 39.873082 -287.87398) (xy 39.869122 -287.824926) (xy 39.555496 -287.824926) (xy 39.555496 -287.850412)
			(xy 39.547357 -287.901796) (xy 39.53128 -287.951275) (xy 39.50766 -287.997628) (xy 39.477079 -288.039716)
			(xy 39.44029 -288.076501) (xy 39.398199 -288.107078) (xy 39.351843 -288.130693) (xy 39.302363 -288.146765)
			(xy 39.250978 -288.154899) (xy 39.224966 -288.15538) (xy 38.275006 -288.15538) (xy 38.248998 -288.154861)
			(xy 38.197622 -288.146725) (xy 38.148151 -288.130652) (xy 38.101804 -288.107037) (xy 38.059722 -288.076463)
			(xy 38.02294 -288.039683) (xy 37.992366 -287.997601) (xy 37.968751 -287.951254) (xy 37.952677 -287.901784)
			(xy 37.944539 -287.850408) (xy 37.629463 -287.850408) (xy 37.62171 -287.89811) (xy 37.606126 -287.944791)
			(xy 37.583255 -287.988368) (xy 37.55369 -288.027712) (xy 37.518197 -288.061804) (xy 37.477694 -288.08976)
			(xy 37.433232 -288.110858) (xy 37.385961 -288.12455) (xy 37.337106 -288.130482) (xy 37.287931 -288.128501)
			(xy 37.239712 -288.118657) (xy 37.193696 -288.101205) (xy 37.151075 -288.076598) (xy 37.112954 -288.045473)
			(xy 37.080319 -288.008636) (xy 37.054016 -287.96704) (xy 37.034725 -287.921764) (xy 37.022948 -287.87398)
			(xy 37.018988 -287.824926) (xy 36.68014 -287.824926) (xy 36.679645 -287.849533) (xy 36.67175 -287.89811)
			(xy 36.656166 -287.944791) (xy 36.633295 -287.988368) (xy 36.60373 -288.027712) (xy 36.568237 -288.061804)
			(xy 36.527734 -288.08976) (xy 36.483272 -288.110858) (xy 36.436001 -288.12455) (xy 36.387146 -288.130482)
			(xy 36.337971 -288.128501) (xy 36.289752 -288.118657) (xy 36.243736 -288.101205) (xy 36.201115 -288.076598)
			(xy 36.162994 -288.045473) (xy 36.130359 -288.008636) (xy 36.104056 -287.96704) (xy 36.084765 -287.921764)
			(xy 36.072988 -287.87398) (xy 36.069028 -287.824926) (xy 34.39033 -287.824926) (xy 34.39033 -288.774886)
			(xy 35.119068 -288.774886) (xy 35.123028 -288.725832) (xy 35.134805 -288.678048) (xy 35.154096 -288.632772)
			(xy 35.180399 -288.591176) (xy 35.213034 -288.554339) (xy 35.251155 -288.523214) (xy 35.293776 -288.498607)
			(xy 35.339792 -288.481155) (xy 35.388011 -288.471311) (xy 35.437186 -288.46933) (xy 35.486041 -288.475262)
			(xy 35.533312 -288.488954) (xy 35.577774 -288.510052) (xy 35.618277 -288.538008) (xy 35.65377 -288.5721)
			(xy 35.683335 -288.611444) (xy 35.706206 -288.655021) (xy 35.72179 -288.701702) (xy 35.729685 -288.750279)
			(xy 35.73018 -288.774886) (xy 35.729685 -288.799493) (xy 35.729535 -288.800413) (xy 36.0443 -288.800413)
			(xy 36.0443 -288.748387) (xy 36.052439 -288.697003) (xy 36.068516 -288.647524) (xy 36.092136 -288.60117)
			(xy 36.122718 -288.559082) (xy 36.159507 -288.522297) (xy 36.201598 -288.49172) (xy 36.247954 -288.468104)
			(xy 36.297434 -288.452031) (xy 36.348819 -288.443897) (xy 36.374832 -288.443416) (xy 37.324792 -288.443416)
			(xy 37.3508 -288.443943) (xy 37.402175 -288.452079) (xy 37.451646 -288.468151) (xy 37.497993 -288.491765)
			(xy 37.540075 -288.522339) (xy 37.576856 -288.559119) (xy 37.60743 -288.601201) (xy 37.631045 -288.647547)
			(xy 37.647119 -288.697017) (xy 37.655257 -288.748392) (xy 37.655257 -288.774886) (xy 37.969202 -288.774886)
			(xy 37.973162 -288.725832) (xy 37.984939 -288.678048) (xy 38.00423 -288.632772) (xy 38.030533 -288.591176)
			(xy 38.063168 -288.554339) (xy 38.101289 -288.523214) (xy 38.14391 -288.498607) (xy 38.189926 -288.481155)
			(xy 38.238145 -288.471311) (xy 38.28732 -288.46933) (xy 38.336175 -288.475262) (xy 38.383446 -288.488954)
			(xy 38.427908 -288.510052) (xy 38.468411 -288.538008) (xy 38.503904 -288.5721) (xy 38.533469 -288.611444)
			(xy 38.55634 -288.655021) (xy 38.571924 -288.701702) (xy 38.579819 -288.750279) (xy 38.580314 -288.774886)
			(xy 41.769042 -288.774886) (xy 41.773002 -288.725832) (xy 41.784779 -288.678048) (xy 41.80407 -288.632772)
			(xy 41.830373 -288.591176) (xy 41.863008 -288.554339) (xy 41.901129 -288.523214) (xy 41.94375 -288.498607)
			(xy 41.989766 -288.481155) (xy 42.037985 -288.471311) (xy 42.08716 -288.46933) (xy 42.136015 -288.475262)
			(xy 42.183286 -288.488954) (xy 42.227748 -288.510052) (xy 42.268251 -288.538008) (xy 42.303744 -288.5721)
			(xy 42.333309 -288.611444) (xy 42.35618 -288.655021) (xy 42.371764 -288.701702) (xy 42.379659 -288.750279)
			(xy 42.380154 -288.774886) (xy 42.379659 -288.799493) (xy 42.371764 -288.84807) (xy 42.35618 -288.894751)
			(xy 42.333309 -288.938328) (xy 42.303744 -288.977672) (xy 42.268251 -289.011764) (xy 42.227748 -289.03972)
			(xy 42.183286 -289.060818) (xy 42.136015 -289.07451) (xy 42.08716 -289.080442) (xy 42.037985 -289.078461)
			(xy 41.989766 -289.068617) (xy 41.94375 -289.051165) (xy 41.901129 -289.026558) (xy 41.863008 -288.995433)
			(xy 41.830373 -288.958596) (xy 41.80407 -288.917) (xy 41.784779 -288.871724) (xy 41.773002 -288.82394)
			(xy 41.769042 -288.774886) (xy 38.580314 -288.774886) (xy 38.579819 -288.799493) (xy 38.571924 -288.84807)
			(xy 38.55634 -288.894751) (xy 38.533469 -288.938328) (xy 38.503904 -288.977672) (xy 38.468411 -289.011764)
			(xy 38.427908 -289.03972) (xy 38.383446 -289.060818) (xy 38.336175 -289.07451) (xy 38.28732 -289.080442)
			(xy 38.238145 -289.078461) (xy 38.189926 -289.068617) (xy 38.14391 -289.051165) (xy 38.101289 -289.026558)
			(xy 38.063168 -288.995433) (xy 38.030533 -288.958596) (xy 38.00423 -288.917) (xy 37.984939 -288.871724)
			(xy 37.973162 -288.82394) (xy 37.969202 -288.774886) (xy 37.655257 -288.774886) (xy 37.655257 -288.800408)
			(xy 37.647119 -288.851783) (xy 37.631045 -288.901253) (xy 37.60743 -288.947599) (xy 37.576856 -288.989681)
			(xy 37.540075 -289.026461) (xy 37.497993 -289.057035) (xy 37.451646 -289.080649) (xy 37.402175 -289.096721)
			(xy 37.3508 -289.104857) (xy 37.324792 -289.10534) (xy 36.374832 -289.10534) (xy 36.348819 -289.104903)
			(xy 36.297434 -289.096769) (xy 36.247954 -289.080696) (xy 36.201598 -289.05708) (xy 36.159507 -289.026503)
			(xy 36.122718 -288.989718) (xy 36.092136 -288.94763) (xy 36.068516 -288.901276) (xy 36.052439 -288.851797)
			(xy 36.0443 -288.800413) (xy 35.729535 -288.800413) (xy 35.72179 -288.84807) (xy 35.706206 -288.894751)
			(xy 35.683335 -288.938328) (xy 35.65377 -288.977672) (xy 35.618277 -289.011764) (xy 35.577774 -289.03972)
			(xy 35.533312 -289.060818) (xy 35.486041 -289.07451) (xy 35.437186 -289.080442) (xy 35.388011 -289.078461)
			(xy 35.339792 -289.068617) (xy 35.293776 -289.051165) (xy 35.251155 -289.026558) (xy 35.213034 -288.995433)
			(xy 35.180399 -288.958596) (xy 35.154096 -288.917) (xy 35.134805 -288.871724) (xy 35.123028 -288.82394)
			(xy 35.119068 -288.774886) (xy 34.39033 -288.774886) (xy 34.39033 -289.724846) (xy 36.069028 -289.724846)
			(xy 36.072988 -289.675792) (xy 36.084765 -289.628008) (xy 36.104056 -289.582732) (xy 36.130359 -289.541136)
			(xy 36.162994 -289.504299) (xy 36.201115 -289.473174) (xy 36.243736 -289.448567) (xy 36.289752 -289.431115)
			(xy 36.337971 -289.421271) (xy 36.387146 -289.41929) (xy 36.436001 -289.425222) (xy 36.483272 -289.438914)
			(xy 36.527734 -289.460012) (xy 36.568237 -289.487968) (xy 36.60373 -289.52206) (xy 36.633295 -289.561404)
			(xy 36.656166 -289.604981) (xy 36.67175 -289.651662) (xy 36.679645 -289.700239) (xy 36.68014 -289.724846)
			(xy 37.018988 -289.724846) (xy 37.022948 -289.675792) (xy 37.034725 -289.628008) (xy 37.054016 -289.582732)
			(xy 37.080319 -289.541136) (xy 37.112954 -289.504299) (xy 37.151075 -289.473174) (xy 37.193696 -289.448567)
			(xy 37.239712 -289.431115) (xy 37.287931 -289.421271) (xy 37.337106 -289.41929) (xy 37.385961 -289.425222)
			(xy 37.433232 -289.438914) (xy 37.477694 -289.460012) (xy 37.518197 -289.487968) (xy 37.55369 -289.52206)
			(xy 37.583255 -289.561404) (xy 37.606126 -289.604981) (xy 37.62171 -289.651662) (xy 37.629605 -289.700239)
			(xy 37.6301 -289.724846) (xy 37.969202 -289.724846) (xy 37.973162 -289.675792) (xy 37.984939 -289.628008)
			(xy 38.00423 -289.582732) (xy 38.030533 -289.541136) (xy 38.063168 -289.504299) (xy 38.101289 -289.473174)
			(xy 38.14391 -289.448567) (xy 38.189926 -289.431115) (xy 38.238145 -289.421271) (xy 38.28732 -289.41929)
			(xy 38.336175 -289.425222) (xy 38.383446 -289.438914) (xy 38.427908 -289.460012) (xy 38.468411 -289.487968)
			(xy 38.503904 -289.52206) (xy 38.533469 -289.561404) (xy 38.55634 -289.604981) (xy 38.571924 -289.651662)
			(xy 38.579819 -289.700239) (xy 38.580314 -289.724846) (xy 38.919162 -289.724846) (xy 38.923122 -289.675792)
			(xy 38.934899 -289.628008) (xy 38.95419 -289.582732) (xy 38.980493 -289.541136) (xy 39.013128 -289.504299)
			(xy 39.051249 -289.473174) (xy 39.09387 -289.448567) (xy 39.139886 -289.431115) (xy 39.188105 -289.421271)
			(xy 39.23728 -289.41929) (xy 39.286135 -289.425222) (xy 39.333406 -289.438914) (xy 39.377868 -289.460012)
			(xy 39.418371 -289.487968) (xy 39.453864 -289.52206) (xy 39.483429 -289.561404) (xy 39.5063 -289.604981)
			(xy 39.521884 -289.651662) (xy 39.529779 -289.700239) (xy 39.530274 -289.724846) (xy 39.869122 -289.724846)
			(xy 39.873082 -289.675792) (xy 39.884859 -289.628008) (xy 39.90415 -289.582732) (xy 39.930453 -289.541136)
			(xy 39.963088 -289.504299) (xy 40.001209 -289.473174) (xy 40.04383 -289.448567) (xy 40.089846 -289.431115)
			(xy 40.138065 -289.421271) (xy 40.18724 -289.41929) (xy 40.236095 -289.425222) (xy 40.283366 -289.438914)
			(xy 40.327828 -289.460012) (xy 40.368331 -289.487968) (xy 40.403824 -289.52206) (xy 40.433389 -289.561404)
			(xy 40.45626 -289.604981) (xy 40.471844 -289.651662) (xy 40.479739 -289.700239) (xy 40.480234 -289.724846)
			(xy 40.819082 -289.724846) (xy 40.823042 -289.675792) (xy 40.834819 -289.628008) (xy 40.85411 -289.582732)
			(xy 40.880413 -289.541136) (xy 40.913048 -289.504299) (xy 40.951169 -289.473174) (xy 40.99379 -289.448567)
			(xy 41.039806 -289.431115) (xy 41.088025 -289.421271) (xy 41.1372 -289.41929) (xy 41.186055 -289.425222)
			(xy 41.233326 -289.438914) (xy 41.277788 -289.460012) (xy 41.318291 -289.487968) (xy 41.353784 -289.52206)
			(xy 41.383349 -289.561404) (xy 41.40622 -289.604981) (xy 41.421804 -289.651662) (xy 41.429699 -289.700239)
			(xy 41.430194 -289.724846) (xy 41.769042 -289.724846) (xy 41.773002 -289.675792) (xy 41.784779 -289.628008)
			(xy 41.80407 -289.582732) (xy 41.830373 -289.541136) (xy 41.863008 -289.504299) (xy 41.901129 -289.473174)
			(xy 41.94375 -289.448567) (xy 41.989766 -289.431115) (xy 42.037985 -289.421271) (xy 42.08716 -289.41929)
			(xy 42.136015 -289.425222) (xy 42.183286 -289.438914) (xy 42.227748 -289.460012) (xy 42.268251 -289.487968)
			(xy 42.303744 -289.52206) (xy 42.333309 -289.561404) (xy 42.35618 -289.604981) (xy 42.371764 -289.651662)
			(xy 42.379659 -289.700239) (xy 42.380154 -289.724846) (xy 42.379659 -289.749453) (xy 42.371764 -289.79803)
			(xy 42.35618 -289.844711) (xy 42.333309 -289.888288) (xy 42.303744 -289.927632) (xy 42.268251 -289.961724)
			(xy 42.227748 -289.98968) (xy 42.183286 -290.010778) (xy 42.136015 -290.02447) (xy 42.08716 -290.030402)
			(xy 42.037985 -290.028421) (xy 41.989766 -290.018577) (xy 41.94375 -290.001125) (xy 41.901129 -289.976518)
			(xy 41.863008 -289.945393) (xy 41.830373 -289.908556) (xy 41.80407 -289.86696) (xy 41.784779 -289.821684)
			(xy 41.773002 -289.7739) (xy 41.769042 -289.724846) (xy 41.430194 -289.724846) (xy 41.429699 -289.749453)
			(xy 41.421804 -289.79803) (xy 41.40622 -289.844711) (xy 41.383349 -289.888288) (xy 41.353784 -289.927632)
			(xy 41.318291 -289.961724) (xy 41.277788 -289.98968) (xy 41.233326 -290.010778) (xy 41.186055 -290.02447)
			(xy 41.1372 -290.030402) (xy 41.088025 -290.028421) (xy 41.039806 -290.018577) (xy 40.99379 -290.001125)
			(xy 40.951169 -289.976518) (xy 40.913048 -289.945393) (xy 40.880413 -289.908556) (xy 40.85411 -289.86696)
			(xy 40.834819 -289.821684) (xy 40.823042 -289.7739) (xy 40.819082 -289.724846) (xy 40.480234 -289.724846)
			(xy 40.479739 -289.749453) (xy 40.471844 -289.79803) (xy 40.45626 -289.844711) (xy 40.433389 -289.888288)
			(xy 40.403824 -289.927632) (xy 40.368331 -289.961724) (xy 40.327828 -289.98968) (xy 40.283366 -290.010778)
			(xy 40.236095 -290.02447) (xy 40.18724 -290.030402) (xy 40.138065 -290.028421) (xy 40.089846 -290.018577)
			(xy 40.04383 -290.001125) (xy 40.001209 -289.976518) (xy 39.963088 -289.945393) (xy 39.930453 -289.908556)
			(xy 39.90415 -289.86696) (xy 39.884859 -289.821684) (xy 39.873082 -289.7739) (xy 39.869122 -289.724846)
			(xy 39.530274 -289.724846) (xy 39.529779 -289.749453) (xy 39.521884 -289.79803) (xy 39.5063 -289.844711)
			(xy 39.483429 -289.888288) (xy 39.453864 -289.927632) (xy 39.418371 -289.961724) (xy 39.377868 -289.98968)
			(xy 39.333406 -290.010778) (xy 39.286135 -290.02447) (xy 39.23728 -290.030402) (xy 39.188105 -290.028421)
			(xy 39.139886 -290.018577) (xy 39.09387 -290.001125) (xy 39.051249 -289.976518) (xy 39.013128 -289.945393)
			(xy 38.980493 -289.908556) (xy 38.95419 -289.86696) (xy 38.934899 -289.821684) (xy 38.923122 -289.7739)
			(xy 38.919162 -289.724846) (xy 38.580314 -289.724846) (xy 38.579819 -289.749453) (xy 38.571924 -289.79803)
			(xy 38.55634 -289.844711) (xy 38.533469 -289.888288) (xy 38.503904 -289.927632) (xy 38.468411 -289.961724)
			(xy 38.427908 -289.98968) (xy 38.383446 -290.010778) (xy 38.336175 -290.02447) (xy 38.28732 -290.030402)
			(xy 38.238145 -290.028421) (xy 38.189926 -290.018577) (xy 38.14391 -290.001125) (xy 38.101289 -289.976518)
			(xy 38.063168 -289.945393) (xy 38.030533 -289.908556) (xy 38.00423 -289.86696) (xy 37.984939 -289.821684)
			(xy 37.973162 -289.7739) (xy 37.969202 -289.724846) (xy 37.6301 -289.724846) (xy 37.629605 -289.749453)
			(xy 37.62171 -289.79803) (xy 37.606126 -289.844711) (xy 37.583255 -289.888288) (xy 37.55369 -289.927632)
			(xy 37.518197 -289.961724) (xy 37.477694 -289.98968) (xy 37.433232 -290.010778) (xy 37.385961 -290.02447)
			(xy 37.337106 -290.030402) (xy 37.287931 -290.028421) (xy 37.239712 -290.018577) (xy 37.193696 -290.001125)
			(xy 37.151075 -289.976518) (xy 37.112954 -289.945393) (xy 37.080319 -289.908556) (xy 37.054016 -289.86696)
			(xy 37.034725 -289.821684) (xy 37.022948 -289.7739) (xy 37.018988 -289.724846) (xy 36.68014 -289.724846)
			(xy 36.679645 -289.749453) (xy 36.67175 -289.79803) (xy 36.656166 -289.844711) (xy 36.633295 -289.888288)
			(xy 36.60373 -289.927632) (xy 36.568237 -289.961724) (xy 36.527734 -289.98968) (xy 36.483272 -290.010778)
			(xy 36.436001 -290.02447) (xy 36.387146 -290.030402) (xy 36.337971 -290.028421) (xy 36.289752 -290.018577)
			(xy 36.243736 -290.001125) (xy 36.201115 -289.976518) (xy 36.162994 -289.945393) (xy 36.130359 -289.908556)
			(xy 36.104056 -289.86696) (xy 36.084765 -289.821684) (xy 36.072988 -289.7739) (xy 36.069028 -289.724846)
			(xy 34.39033 -289.724846) (xy 34.39033 -290.674806) (xy 36.069028 -290.674806) (xy 36.072988 -290.625752)
			(xy 36.084765 -290.577968) (xy 36.104056 -290.532692) (xy 36.130359 -290.491096) (xy 36.162994 -290.454259)
			(xy 36.201115 -290.423134) (xy 36.243736 -290.398527) (xy 36.289752 -290.381075) (xy 36.337971 -290.371231)
			(xy 36.387146 -290.36925) (xy 36.436001 -290.375182) (xy 36.483272 -290.388874) (xy 36.527734 -290.409972)
			(xy 36.568237 -290.437928) (xy 36.60373 -290.47202) (xy 36.633295 -290.511364) (xy 36.656166 -290.554941)
			(xy 36.67175 -290.601622) (xy 36.679645 -290.650199) (xy 36.68014 -290.674806) (xy 37.018988 -290.674806)
			(xy 37.022948 -290.625752) (xy 37.034725 -290.577968) (xy 37.054016 -290.532692) (xy 37.080319 -290.491096)
			(xy 37.112954 -290.454259) (xy 37.151075 -290.423134) (xy 37.193696 -290.398527) (xy 37.239712 -290.381075)
			(xy 37.287931 -290.371231) (xy 37.337106 -290.36925) (xy 37.385961 -290.375182) (xy 37.433232 -290.388874)
			(xy 37.477694 -290.409972) (xy 37.518197 -290.437928) (xy 37.55369 -290.47202) (xy 37.583255 -290.511364)
			(xy 37.606126 -290.554941) (xy 37.62171 -290.601622) (xy 37.629605 -290.650199) (xy 37.6301 -290.674806)
			(xy 37.969202 -290.674806) (xy 37.973162 -290.625752) (xy 37.984939 -290.577968) (xy 38.00423 -290.532692)
			(xy 38.030533 -290.491096) (xy 38.063168 -290.454259) (xy 38.101289 -290.423134) (xy 38.14391 -290.398527)
			(xy 38.189926 -290.381075) (xy 38.238145 -290.371231) (xy 38.28732 -290.36925) (xy 38.336175 -290.375182)
			(xy 38.383446 -290.388874) (xy 38.427908 -290.409972) (xy 38.468411 -290.437928) (xy 38.503904 -290.47202)
			(xy 38.533469 -290.511364) (xy 38.55634 -290.554941) (xy 38.571924 -290.601622) (xy 38.579819 -290.650199)
			(xy 38.580314 -290.674806) (xy 40.819082 -290.674806) (xy 40.823042 -290.625752) (xy 40.834819 -290.577968)
			(xy 40.85411 -290.532692) (xy 40.880413 -290.491096) (xy 40.913048 -290.454259) (xy 40.951169 -290.423134)
			(xy 40.99379 -290.398527) (xy 41.039806 -290.381075) (xy 41.088025 -290.371231) (xy 41.1372 -290.36925)
			(xy 41.186055 -290.375182) (xy 41.233326 -290.388874) (xy 41.277788 -290.409972) (xy 41.318291 -290.437928)
			(xy 41.353784 -290.47202) (xy 41.383349 -290.511364) (xy 41.40622 -290.554941) (xy 41.421804 -290.601622)
			(xy 41.429699 -290.650199) (xy 41.430194 -290.674806) (xy 41.769042 -290.674806) (xy 41.773002 -290.625752)
			(xy 41.784779 -290.577968) (xy 41.80407 -290.532692) (xy 41.830373 -290.491096) (xy 41.863008 -290.454259)
			(xy 41.901129 -290.423134) (xy 41.94375 -290.398527) (xy 41.989766 -290.381075) (xy 42.037985 -290.371231)
			(xy 42.08716 -290.36925) (xy 42.136015 -290.375182) (xy 42.183286 -290.388874) (xy 42.227748 -290.409972)
			(xy 42.268251 -290.437928) (xy 42.303744 -290.47202) (xy 42.333309 -290.511364) (xy 42.35618 -290.554941)
			(xy 42.371764 -290.601622) (xy 42.379659 -290.650199) (xy 42.380154 -290.674806) (xy 42.379659 -290.699413)
			(xy 42.371764 -290.74799) (xy 42.35618 -290.794671) (xy 42.333309 -290.838248) (xy 42.303744 -290.877592)
			(xy 42.268251 -290.911684) (xy 42.227748 -290.93964) (xy 42.183286 -290.960738) (xy 42.136015 -290.97443)
			(xy 42.08716 -290.980362) (xy 42.037985 -290.978381) (xy 41.989766 -290.968537) (xy 41.94375 -290.951085)
			(xy 41.901129 -290.926478) (xy 41.863008 -290.895353) (xy 41.830373 -290.858516) (xy 41.80407 -290.81692)
			(xy 41.784779 -290.771644) (xy 41.773002 -290.72386) (xy 41.769042 -290.674806) (xy 41.430194 -290.674806)
			(xy 41.429699 -290.699413) (xy 41.421804 -290.74799) (xy 41.40622 -290.794671) (xy 41.383349 -290.838248)
			(xy 41.353784 -290.877592) (xy 41.318291 -290.911684) (xy 41.277788 -290.93964) (xy 41.233326 -290.960738)
			(xy 41.186055 -290.97443) (xy 41.1372 -290.980362) (xy 41.088025 -290.978381) (xy 41.039806 -290.968537)
			(xy 40.99379 -290.951085) (xy 40.951169 -290.926478) (xy 40.913048 -290.895353) (xy 40.880413 -290.858516)
			(xy 40.85411 -290.81692) (xy 40.834819 -290.771644) (xy 40.823042 -290.72386) (xy 40.819082 -290.674806)
			(xy 38.580314 -290.674806) (xy 38.579819 -290.699413) (xy 38.571924 -290.74799) (xy 38.55634 -290.794671)
			(xy 38.533469 -290.838248) (xy 38.503904 -290.877592) (xy 38.468411 -290.911684) (xy 38.427908 -290.93964)
			(xy 38.383446 -290.960738) (xy 38.336175 -290.97443) (xy 38.28732 -290.980362) (xy 38.238145 -290.978381)
			(xy 38.189926 -290.968537) (xy 38.14391 -290.951085) (xy 38.101289 -290.926478) (xy 38.063168 -290.895353)
			(xy 38.030533 -290.858516) (xy 38.00423 -290.81692) (xy 37.984939 -290.771644) (xy 37.973162 -290.72386)
			(xy 37.969202 -290.674806) (xy 37.6301 -290.674806) (xy 37.629605 -290.699413) (xy 37.62171 -290.74799)
			(xy 37.606126 -290.794671) (xy 37.583255 -290.838248) (xy 37.55369 -290.877592) (xy 37.518197 -290.911684)
			(xy 37.477694 -290.93964) (xy 37.433232 -290.960738) (xy 37.385961 -290.97443) (xy 37.337106 -290.980362)
			(xy 37.287931 -290.978381) (xy 37.239712 -290.968537) (xy 37.193696 -290.951085) (xy 37.151075 -290.926478)
			(xy 37.112954 -290.895353) (xy 37.080319 -290.858516) (xy 37.054016 -290.81692) (xy 37.034725 -290.771644)
			(xy 37.022948 -290.72386) (xy 37.018988 -290.674806) (xy 36.68014 -290.674806) (xy 36.679645 -290.699413)
			(xy 36.67175 -290.74799) (xy 36.656166 -290.794671) (xy 36.633295 -290.838248) (xy 36.60373 -290.877592)
			(xy 36.568237 -290.911684) (xy 36.527734 -290.93964) (xy 36.483272 -290.960738) (xy 36.436001 -290.97443)
			(xy 36.387146 -290.980362) (xy 36.337971 -290.978381) (xy 36.289752 -290.968537) (xy 36.243736 -290.951085)
			(xy 36.201115 -290.926478) (xy 36.162994 -290.895353) (xy 36.130359 -290.858516) (xy 36.104056 -290.81692)
			(xy 36.084765 -290.771644) (xy 36.072988 -290.72386) (xy 36.069028 -290.674806) (xy 34.39033 -290.674806)
			(xy 34.39033 -291.624766) (xy 36.069028 -291.624766) (xy 36.072988 -291.575712) (xy 36.084765 -291.527928)
			(xy 36.104056 -291.482652) (xy 36.130359 -291.441056) (xy 36.162994 -291.404219) (xy 36.201115 -291.373094)
			(xy 36.243736 -291.348487) (xy 36.289752 -291.331035) (xy 36.337971 -291.321191) (xy 36.387146 -291.31921)
			(xy 36.436001 -291.325142) (xy 36.483272 -291.338834) (xy 36.527734 -291.359932) (xy 36.568237 -291.387888)
			(xy 36.60373 -291.42198) (xy 36.633295 -291.461324) (xy 36.656166 -291.504901) (xy 36.67175 -291.551582)
			(xy 36.679645 -291.600159) (xy 36.68014 -291.624766) (xy 37.018988 -291.624766) (xy 37.022948 -291.575712)
			(xy 37.034725 -291.527928) (xy 37.054016 -291.482652) (xy 37.080319 -291.441056) (xy 37.112954 -291.404219)
			(xy 37.151075 -291.373094) (xy 37.193696 -291.348487) (xy 37.239712 -291.331035) (xy 37.287931 -291.321191)
			(xy 37.337106 -291.31921) (xy 37.385961 -291.325142) (xy 37.433232 -291.338834) (xy 37.477694 -291.359932)
			(xy 37.518197 -291.387888) (xy 37.55369 -291.42198) (xy 37.583255 -291.461324) (xy 37.606126 -291.504901)
			(xy 37.62171 -291.551582) (xy 37.629605 -291.600159) (xy 37.6301 -291.624766) (xy 37.969202 -291.624766)
			(xy 37.973162 -291.575712) (xy 37.984939 -291.527928) (xy 38.00423 -291.482652) (xy 38.030533 -291.441056)
			(xy 38.063168 -291.404219) (xy 38.101289 -291.373094) (xy 38.14391 -291.348487) (xy 38.189926 -291.331035)
			(xy 38.238145 -291.321191) (xy 38.28732 -291.31921) (xy 38.336175 -291.325142) (xy 38.383446 -291.338834)
			(xy 38.427908 -291.359932) (xy 38.468411 -291.387888) (xy 38.503904 -291.42198) (xy 38.533469 -291.461324)
			(xy 38.55634 -291.504901) (xy 38.571924 -291.551582) (xy 38.579819 -291.600159) (xy 38.580314 -291.624766)
			(xy 40.819082 -291.624766) (xy 40.823042 -291.575712) (xy 40.834819 -291.527928) (xy 40.85411 -291.482652)
			(xy 40.880413 -291.441056) (xy 40.913048 -291.404219) (xy 40.951169 -291.373094) (xy 40.99379 -291.348487)
			(xy 41.039806 -291.331035) (xy 41.088025 -291.321191) (xy 41.1372 -291.31921) (xy 41.186055 -291.325142)
			(xy 41.233326 -291.338834) (xy 41.277788 -291.359932) (xy 41.318291 -291.387888) (xy 41.353784 -291.42198)
			(xy 41.383349 -291.461324) (xy 41.40622 -291.504901) (xy 41.421804 -291.551582) (xy 41.429699 -291.600159)
			(xy 41.430194 -291.624766) (xy 41.769042 -291.624766) (xy 41.773002 -291.575712) (xy 41.784779 -291.527928)
			(xy 41.80407 -291.482652) (xy 41.830373 -291.441056) (xy 41.863008 -291.404219) (xy 41.901129 -291.373094)
			(xy 41.94375 -291.348487) (xy 41.989766 -291.331035) (xy 42.037985 -291.321191) (xy 42.08716 -291.31921)
			(xy 42.136015 -291.325142) (xy 42.183286 -291.338834) (xy 42.227748 -291.359932) (xy 42.268251 -291.387888)
			(xy 42.303744 -291.42198) (xy 42.333309 -291.461324) (xy 42.35618 -291.504901) (xy 42.371764 -291.551582)
			(xy 42.379659 -291.600159) (xy 42.380154 -291.624766) (xy 42.379659 -291.649373) (xy 42.371764 -291.69795)
			(xy 42.35618 -291.744631) (xy 42.333309 -291.788208) (xy 42.303744 -291.827552) (xy 42.268251 -291.861644)
			(xy 42.227748 -291.8896) (xy 42.183286 -291.910698) (xy 42.136015 -291.92439) (xy 42.08716 -291.930322)
			(xy 42.037985 -291.928341) (xy 41.989766 -291.918497) (xy 41.94375 -291.901045) (xy 41.901129 -291.876438)
			(xy 41.863008 -291.845313) (xy 41.830373 -291.808476) (xy 41.80407 -291.76688) (xy 41.784779 -291.721604)
			(xy 41.773002 -291.67382) (xy 41.769042 -291.624766) (xy 41.430194 -291.624766) (xy 41.429699 -291.649373)
			(xy 41.421804 -291.69795) (xy 41.40622 -291.744631) (xy 41.383349 -291.788208) (xy 41.353784 -291.827552)
			(xy 41.318291 -291.861644) (xy 41.277788 -291.8896) (xy 41.233326 -291.910698) (xy 41.186055 -291.92439)
			(xy 41.1372 -291.930322) (xy 41.088025 -291.928341) (xy 41.039806 -291.918497) (xy 40.99379 -291.901045)
			(xy 40.951169 -291.876438) (xy 40.913048 -291.845313) (xy 40.880413 -291.808476) (xy 40.85411 -291.76688)
			(xy 40.834819 -291.721604) (xy 40.823042 -291.67382) (xy 40.819082 -291.624766) (xy 38.580314 -291.624766)
			(xy 38.579819 -291.649373) (xy 38.571924 -291.69795) (xy 38.55634 -291.744631) (xy 38.533469 -291.788208)
			(xy 38.503904 -291.827552) (xy 38.468411 -291.861644) (xy 38.427908 -291.8896) (xy 38.383446 -291.910698)
			(xy 38.336175 -291.92439) (xy 38.28732 -291.930322) (xy 38.238145 -291.928341) (xy 38.189926 -291.918497)
			(xy 38.14391 -291.901045) (xy 38.101289 -291.876438) (xy 38.063168 -291.845313) (xy 38.030533 -291.808476)
			(xy 38.00423 -291.76688) (xy 37.984939 -291.721604) (xy 37.973162 -291.67382) (xy 37.969202 -291.624766)
			(xy 37.6301 -291.624766) (xy 37.629605 -291.649373) (xy 37.62171 -291.69795) (xy 37.606126 -291.744631)
			(xy 37.583255 -291.788208) (xy 37.55369 -291.827552) (xy 37.518197 -291.861644) (xy 37.477694 -291.8896)
			(xy 37.433232 -291.910698) (xy 37.385961 -291.92439) (xy 37.337106 -291.930322) (xy 37.287931 -291.928341)
			(xy 37.239712 -291.918497) (xy 37.193696 -291.901045) (xy 37.151075 -291.876438) (xy 37.112954 -291.845313)
			(xy 37.080319 -291.808476) (xy 37.054016 -291.76688) (xy 37.034725 -291.721604) (xy 37.022948 -291.67382)
			(xy 37.018988 -291.624766) (xy 36.68014 -291.624766) (xy 36.679645 -291.649373) (xy 36.67175 -291.69795)
			(xy 36.656166 -291.744631) (xy 36.633295 -291.788208) (xy 36.60373 -291.827552) (xy 36.568237 -291.861644)
			(xy 36.527734 -291.8896) (xy 36.483272 -291.910698) (xy 36.436001 -291.92439) (xy 36.387146 -291.930322)
			(xy 36.337971 -291.928341) (xy 36.289752 -291.918497) (xy 36.243736 -291.901045) (xy 36.201115 -291.876438)
			(xy 36.162994 -291.845313) (xy 36.130359 -291.808476) (xy 36.104056 -291.76688) (xy 36.084765 -291.721604)
			(xy 36.072988 -291.67382) (xy 36.069028 -291.624766) (xy 34.39033 -291.624766) (xy 34.39033 -292.57498)
			(xy 36.069028 -292.57498) (xy 36.072988 -292.525926) (xy 36.084765 -292.478142) (xy 36.104056 -292.432866)
			(xy 36.130359 -292.39127) (xy 36.162994 -292.354433) (xy 36.201115 -292.323308) (xy 36.243736 -292.298701)
			(xy 36.289752 -292.281249) (xy 36.337971 -292.271405) (xy 36.387146 -292.269424) (xy 36.436001 -292.275356)
			(xy 36.483272 -292.289048) (xy 36.527734 -292.310146) (xy 36.568237 -292.338102) (xy 36.60373 -292.372194)
			(xy 36.633295 -292.411538) (xy 36.656166 -292.455115) (xy 36.67175 -292.501796) (xy 36.679645 -292.550373)
			(xy 36.68014 -292.57498) (xy 37.018988 -292.57498) (xy 37.022948 -292.525926) (xy 37.034725 -292.478142)
			(xy 37.054016 -292.432866) (xy 37.080319 -292.39127) (xy 37.112954 -292.354433) (xy 37.151075 -292.323308)
			(xy 37.193696 -292.298701) (xy 37.239712 -292.281249) (xy 37.287931 -292.271405) (xy 37.337106 -292.269424)
			(xy 37.385961 -292.275356) (xy 37.433232 -292.289048) (xy 37.477694 -292.310146) (xy 37.518197 -292.338102)
			(xy 37.55369 -292.372194) (xy 37.583255 -292.411538) (xy 37.606126 -292.455115) (xy 37.62171 -292.501796)
			(xy 37.629605 -292.550373) (xy 37.6301 -292.57498) (xy 37.969202 -292.57498) (xy 37.973162 -292.525926)
			(xy 37.984939 -292.478142) (xy 38.00423 -292.432866) (xy 38.030533 -292.39127) (xy 38.063168 -292.354433)
			(xy 38.101289 -292.323308) (xy 38.14391 -292.298701) (xy 38.189926 -292.281249) (xy 38.238145 -292.271405)
			(xy 38.28732 -292.269424) (xy 38.336175 -292.275356) (xy 38.383446 -292.289048) (xy 38.427908 -292.310146)
			(xy 38.468411 -292.338102) (xy 38.503904 -292.372194) (xy 38.533469 -292.411538) (xy 38.55634 -292.455115)
			(xy 38.571924 -292.501796) (xy 38.579819 -292.550373) (xy 38.580309 -292.574726) (xy 38.919162 -292.574726)
			(xy 38.923122 -292.525672) (xy 38.934899 -292.477888) (xy 38.95419 -292.432612) (xy 38.980493 -292.391016)
			(xy 39.013128 -292.354179) (xy 39.051249 -292.323054) (xy 39.09387 -292.298447) (xy 39.139886 -292.280995)
			(xy 39.188105 -292.271151) (xy 39.23728 -292.26917) (xy 39.286135 -292.275102) (xy 39.333406 -292.288794)
			(xy 39.377868 -292.309892) (xy 39.418371 -292.337848) (xy 39.453864 -292.37194) (xy 39.483429 -292.411284)
			(xy 39.5063 -292.454861) (xy 39.521884 -292.501542) (xy 39.529779 -292.550119) (xy 39.530274 -292.574726)
			(xy 39.869122 -292.574726) (xy 39.873082 -292.525672) (xy 39.884859 -292.477888) (xy 39.90415 -292.432612)
			(xy 39.930453 -292.391016) (xy 39.963088 -292.354179) (xy 40.001209 -292.323054) (xy 40.04383 -292.298447)
			(xy 40.089846 -292.280995) (xy 40.138065 -292.271151) (xy 40.18724 -292.26917) (xy 40.236095 -292.275102)
			(xy 40.283366 -292.288794) (xy 40.327828 -292.309892) (xy 40.368331 -292.337848) (xy 40.403824 -292.37194)
			(xy 40.433389 -292.411284) (xy 40.45626 -292.454861) (xy 40.471844 -292.501542) (xy 40.479739 -292.550119)
			(xy 40.480234 -292.574726) (xy 40.480229 -292.57498) (xy 40.819082 -292.57498) (xy 40.823042 -292.525926)
			(xy 40.834819 -292.478142) (xy 40.85411 -292.432866) (xy 40.880413 -292.39127) (xy 40.913048 -292.354433)
			(xy 40.951169 -292.323308) (xy 40.99379 -292.298701) (xy 41.039806 -292.281249) (xy 41.088025 -292.271405)
			(xy 41.1372 -292.269424) (xy 41.186055 -292.275356) (xy 41.233326 -292.289048) (xy 41.277788 -292.310146)
			(xy 41.318291 -292.338102) (xy 41.353784 -292.372194) (xy 41.383349 -292.411538) (xy 41.40622 -292.455115)
			(xy 41.421804 -292.501796) (xy 41.429699 -292.550373) (xy 41.430194 -292.57498) (xy 41.429699 -292.599587)
			(xy 41.429367 -292.601629) (xy 41.719236 -292.601629) (xy 41.719236 -292.548331) (xy 41.727179 -292.495627)
			(xy 41.742889 -292.444697) (xy 41.766015 -292.396676) (xy 41.796039 -292.352639) (xy 41.832291 -292.313568)
			(xy 41.873962 -292.280337) (xy 41.92012 -292.253688) (xy 41.969734 -292.234216) (xy 42.021696 -292.222356)
			(xy 42.074846 -292.218373) (xy 42.127996 -292.222356) (xy 42.179958 -292.234216) (xy 42.229572 -292.253688)
			(xy 42.27573 -292.280337) (xy 42.317401 -292.313568) (xy 42.353653 -292.352639) (xy 42.383677 -292.396676)
			(xy 42.406803 -292.444697) (xy 42.422513 -292.495627) (xy 42.430456 -292.548331) (xy 42.430954 -292.57498)
			(xy 42.430456 -292.601629) (xy 42.422513 -292.654333) (xy 42.406803 -292.705263) (xy 42.383677 -292.753284)
			(xy 42.353653 -292.797321) (xy 42.317401 -292.836392) (xy 42.27573 -292.869623) (xy 42.229572 -292.896272)
			(xy 42.179958 -292.915744) (xy 42.127996 -292.927604) (xy 42.074846 -292.931588) (xy 42.021696 -292.927604)
			(xy 41.969734 -292.915744) (xy 41.92012 -292.896272) (xy 41.873962 -292.869623) (xy 41.832291 -292.836392)
			(xy 41.796039 -292.797321) (xy 41.766015 -292.753284) (xy 41.742889 -292.705263) (xy 41.727179 -292.654333)
			(xy 41.719236 -292.601629) (xy 41.429367 -292.601629) (xy 41.421804 -292.648164) (xy 41.40622 -292.694845)
			(xy 41.383349 -292.738422) (xy 41.353784 -292.777766) (xy 41.318291 -292.811858) (xy 41.277788 -292.839814)
			(xy 41.233326 -292.860912) (xy 41.186055 -292.874604) (xy 41.1372 -292.880536) (xy 41.088025 -292.878555)
			(xy 41.039806 -292.868711) (xy 40.99379 -292.851259) (xy 40.951169 -292.826652) (xy 40.913048 -292.795527)
			(xy 40.880413 -292.75869) (xy 40.85411 -292.717094) (xy 40.834819 -292.671818) (xy 40.823042 -292.624034)
			(xy 40.819082 -292.57498) (xy 40.480229 -292.57498) (xy 40.479739 -292.599333) (xy 40.471844 -292.64791)
			(xy 40.45626 -292.694591) (xy 40.433389 -292.738168) (xy 40.403824 -292.777512) (xy 40.368331 -292.811604)
			(xy 40.327828 -292.83956) (xy 40.283366 -292.860658) (xy 40.236095 -292.87435) (xy 40.18724 -292.880282)
			(xy 40.138065 -292.878301) (xy 40.089846 -292.868457) (xy 40.04383 -292.851005) (xy 40.001209 -292.826398)
			(xy 39.963088 -292.795273) (xy 39.930453 -292.758436) (xy 39.90415 -292.71684) (xy 39.884859 -292.671564)
			(xy 39.873082 -292.62378) (xy 39.869122 -292.574726) (xy 39.530274 -292.574726) (xy 39.529779 -292.599333)
			(xy 39.521884 -292.64791) (xy 39.5063 -292.694591) (xy 39.483429 -292.738168) (xy 39.453864 -292.777512)
			(xy 39.418371 -292.811604) (xy 39.377868 -292.83956) (xy 39.333406 -292.860658) (xy 39.286135 -292.87435)
			(xy 39.23728 -292.880282) (xy 39.188105 -292.878301) (xy 39.139886 -292.868457) (xy 39.09387 -292.851005)
			(xy 39.051249 -292.826398) (xy 39.013128 -292.795273) (xy 38.980493 -292.758436) (xy 38.95419 -292.71684)
			(xy 38.934899 -292.671564) (xy 38.923122 -292.62378) (xy 38.919162 -292.574726) (xy 38.580309 -292.574726)
			(xy 38.580314 -292.57498) (xy 38.579819 -292.599587) (xy 38.571924 -292.648164) (xy 38.55634 -292.694845)
			(xy 38.533469 -292.738422) (xy 38.503904 -292.777766) (xy 38.468411 -292.811858) (xy 38.427908 -292.839814)
			(xy 38.383446 -292.860912) (xy 38.336175 -292.874604) (xy 38.28732 -292.880536) (xy 38.238145 -292.878555)
			(xy 38.189926 -292.868711) (xy 38.14391 -292.851259) (xy 38.101289 -292.826652) (xy 38.063168 -292.795527)
			(xy 38.030533 -292.75869) (xy 38.00423 -292.717094) (xy 37.984939 -292.671818) (xy 37.973162 -292.624034)
			(xy 37.969202 -292.57498) (xy 37.6301 -292.57498) (xy 37.629605 -292.599587) (xy 37.62171 -292.648164)
			(xy 37.606126 -292.694845) (xy 37.583255 -292.738422) (xy 37.55369 -292.777766) (xy 37.518197 -292.811858)
			(xy 37.477694 -292.839814) (xy 37.433232 -292.860912) (xy 37.385961 -292.874604) (xy 37.337106 -292.880536)
			(xy 37.287931 -292.878555) (xy 37.239712 -292.868711) (xy 37.193696 -292.851259) (xy 37.151075 -292.826652)
			(xy 37.112954 -292.795527) (xy 37.080319 -292.75869) (xy 37.054016 -292.717094) (xy 37.034725 -292.671818)
			(xy 37.022948 -292.624034) (xy 37.018988 -292.57498) (xy 36.68014 -292.57498) (xy 36.679645 -292.599587)
			(xy 36.67175 -292.648164) (xy 36.656166 -292.694845) (xy 36.633295 -292.738422) (xy 36.60373 -292.777766)
			(xy 36.568237 -292.811858) (xy 36.527734 -292.839814) (xy 36.483272 -292.860912) (xy 36.436001 -292.874604)
			(xy 36.387146 -292.880536) (xy 36.337971 -292.878555) (xy 36.289752 -292.868711) (xy 36.243736 -292.851259)
			(xy 36.201115 -292.826652) (xy 36.162994 -292.795527) (xy 36.130359 -292.75869) (xy 36.104056 -292.717094)
			(xy 36.084765 -292.671818) (xy 36.072988 -292.624034) (xy 36.069028 -292.57498) (xy 34.39033 -292.57498)
			(xy 34.39033 -293.52494) (xy 37.969202 -293.52494) (xy 37.973162 -293.475886) (xy 37.984939 -293.428102)
			(xy 38.00423 -293.382826) (xy 38.030533 -293.34123) (xy 38.063168 -293.304393) (xy 38.101289 -293.273268)
			(xy 38.14391 -293.248661) (xy 38.189926 -293.231209) (xy 38.238145 -293.221365) (xy 38.28732 -293.219384)
			(xy 38.336175 -293.225316) (xy 38.383446 -293.239008) (xy 38.427908 -293.260106) (xy 38.468411 -293.288062)
			(xy 38.503904 -293.322154) (xy 38.533469 -293.361498) (xy 38.55634 -293.405075) (xy 38.571924 -293.451756)
			(xy 38.579819 -293.500333) (xy 38.580314 -293.52494) (xy 38.919162 -293.52494) (xy 38.923122 -293.475886)
			(xy 38.934899 -293.428102) (xy 38.95419 -293.382826) (xy 38.980493 -293.34123) (xy 39.013128 -293.304393)
			(xy 39.051249 -293.273268) (xy 39.09387 -293.248661) (xy 39.139886 -293.231209) (xy 39.188105 -293.221365)
			(xy 39.23728 -293.219384) (xy 39.286135 -293.225316) (xy 39.333406 -293.239008) (xy 39.377868 -293.260106)
			(xy 39.418371 -293.288062) (xy 39.453864 -293.322154) (xy 39.483429 -293.361498) (xy 39.5063 -293.405075)
			(xy 39.521884 -293.451756) (xy 39.529779 -293.500333) (xy 39.530274 -293.52494) (xy 39.869122 -293.52494)
			(xy 39.873082 -293.475886) (xy 39.884859 -293.428102) (xy 39.90415 -293.382826) (xy 39.930453 -293.34123)
			(xy 39.963088 -293.304393) (xy 40.001209 -293.273268) (xy 40.04383 -293.248661) (xy 40.089846 -293.231209)
			(xy 40.138065 -293.221365) (xy 40.18724 -293.219384) (xy 40.236095 -293.225316) (xy 40.283366 -293.239008)
			(xy 40.327828 -293.260106) (xy 40.368331 -293.288062) (xy 40.403824 -293.322154) (xy 40.433389 -293.361498)
			(xy 40.45626 -293.405075) (xy 40.471844 -293.451756) (xy 40.479739 -293.500333) (xy 40.480234 -293.52494)
			(xy 40.819082 -293.52494) (xy 40.823042 -293.475886) (xy 40.834819 -293.428102) (xy 40.85411 -293.382826)
			(xy 40.880413 -293.34123) (xy 40.913048 -293.304393) (xy 40.951169 -293.273268) (xy 40.99379 -293.248661)
			(xy 41.039806 -293.231209) (xy 41.088025 -293.221365) (xy 41.1372 -293.219384) (xy 41.186055 -293.225316)
			(xy 41.233326 -293.239008) (xy 41.277788 -293.260106) (xy 41.318291 -293.288062) (xy 41.353784 -293.322154)
			(xy 41.383349 -293.361498) (xy 41.40622 -293.405075) (xy 41.421804 -293.451756) (xy 41.429699 -293.500333)
			(xy 41.430194 -293.52494) (xy 41.769042 -293.52494) (xy 41.773002 -293.475886) (xy 41.784779 -293.428102)
			(xy 41.80407 -293.382826) (xy 41.830373 -293.34123) (xy 41.863008 -293.304393) (xy 41.901129 -293.273268)
			(xy 41.94375 -293.248661) (xy 41.989766 -293.231209) (xy 42.037985 -293.221365) (xy 42.08716 -293.219384)
			(xy 42.136015 -293.225316) (xy 42.183286 -293.239008) (xy 42.227748 -293.260106) (xy 42.268251 -293.288062)
			(xy 42.303744 -293.322154) (xy 42.333309 -293.361498) (xy 42.35618 -293.405075) (xy 42.371764 -293.451756)
			(xy 42.379659 -293.500333) (xy 42.380154 -293.52494) (xy 42.379659 -293.549547) (xy 42.371764 -293.598124)
			(xy 42.35618 -293.644805) (xy 42.333309 -293.688382) (xy 42.303744 -293.727726) (xy 42.268251 -293.761818)
			(xy 42.227748 -293.789774) (xy 42.183286 -293.810872) (xy 42.136015 -293.824564) (xy 42.08716 -293.830496)
			(xy 42.037985 -293.828515) (xy 41.989766 -293.818671) (xy 41.94375 -293.801219) (xy 41.901129 -293.776612)
			(xy 41.863008 -293.745487) (xy 41.830373 -293.70865) (xy 41.80407 -293.667054) (xy 41.784779 -293.621778)
			(xy 41.773002 -293.573994) (xy 41.769042 -293.52494) (xy 41.430194 -293.52494) (xy 41.429699 -293.549547)
			(xy 41.421804 -293.598124) (xy 41.40622 -293.644805) (xy 41.383349 -293.688382) (xy 41.353784 -293.727726)
			(xy 41.318291 -293.761818) (xy 41.277788 -293.789774) (xy 41.233326 -293.810872) (xy 41.186055 -293.824564)
			(xy 41.1372 -293.830496) (xy 41.088025 -293.828515) (xy 41.039806 -293.818671) (xy 40.99379 -293.801219)
			(xy 40.951169 -293.776612) (xy 40.913048 -293.745487) (xy 40.880413 -293.70865) (xy 40.85411 -293.667054)
			(xy 40.834819 -293.621778) (xy 40.823042 -293.573994) (xy 40.819082 -293.52494) (xy 40.480234 -293.52494)
			(xy 40.479739 -293.549547) (xy 40.471844 -293.598124) (xy 40.45626 -293.644805) (xy 40.433389 -293.688382)
			(xy 40.403824 -293.727726) (xy 40.368331 -293.761818) (xy 40.327828 -293.789774) (xy 40.283366 -293.810872)
			(xy 40.236095 -293.824564) (xy 40.18724 -293.830496) (xy 40.138065 -293.828515) (xy 40.089846 -293.818671)
			(xy 40.04383 -293.801219) (xy 40.001209 -293.776612) (xy 39.963088 -293.745487) (xy 39.930453 -293.70865)
			(xy 39.90415 -293.667054) (xy 39.884859 -293.621778) (xy 39.873082 -293.573994) (xy 39.869122 -293.52494)
			(xy 39.530274 -293.52494) (xy 39.529779 -293.549547) (xy 39.521884 -293.598124) (xy 39.5063 -293.644805)
			(xy 39.483429 -293.688382) (xy 39.453864 -293.727726) (xy 39.418371 -293.761818) (xy 39.377868 -293.789774)
			(xy 39.333406 -293.810872) (xy 39.286135 -293.824564) (xy 39.23728 -293.830496) (xy 39.188105 -293.828515)
			(xy 39.139886 -293.818671) (xy 39.09387 -293.801219) (xy 39.051249 -293.776612) (xy 39.013128 -293.745487)
			(xy 38.980493 -293.70865) (xy 38.95419 -293.667054) (xy 38.934899 -293.621778) (xy 38.923122 -293.573994)
			(xy 38.919162 -293.52494) (xy 38.580314 -293.52494) (xy 38.579819 -293.549547) (xy 38.571924 -293.598124)
			(xy 38.55634 -293.644805) (xy 38.533469 -293.688382) (xy 38.503904 -293.727726) (xy 38.468411 -293.761818)
			(xy 38.427908 -293.789774) (xy 38.383446 -293.810872) (xy 38.336175 -293.824564) (xy 38.28732 -293.830496)
			(xy 38.238145 -293.828515) (xy 38.189926 -293.818671) (xy 38.14391 -293.801219) (xy 38.101289 -293.776612)
			(xy 38.063168 -293.745487) (xy 38.030533 -293.70865) (xy 38.00423 -293.667054) (xy 37.984939 -293.621778)
			(xy 37.973162 -293.573994) (xy 37.969202 -293.52494) (xy 34.39033 -293.52494) (xy 34.39033 -294.4749)
			(xy 36.069028 -294.4749) (xy 36.072988 -294.425846) (xy 36.084765 -294.378062) (xy 36.104056 -294.332786)
			(xy 36.130359 -294.29119) (xy 36.162994 -294.254353) (xy 36.201115 -294.223228) (xy 36.243736 -294.198621)
			(xy 36.289752 -294.181169) (xy 36.337971 -294.171325) (xy 36.387146 -294.169344) (xy 36.436001 -294.175276)
			(xy 36.483272 -294.188968) (xy 36.527734 -294.210066) (xy 36.568237 -294.238022) (xy 36.60373 -294.272114)
			(xy 36.633295 -294.311458) (xy 36.656166 -294.355035) (xy 36.67175 -294.401716) (xy 36.679645 -294.450293)
			(xy 36.68014 -294.4749) (xy 37.018988 -294.4749) (xy 37.022948 -294.425846) (xy 37.034725 -294.378062)
			(xy 37.054016 -294.332786) (xy 37.080319 -294.29119) (xy 37.112954 -294.254353) (xy 37.151075 -294.223228)
			(xy 37.193696 -294.198621) (xy 37.239712 -294.181169) (xy 37.287931 -294.171325) (xy 37.337106 -294.169344)
			(xy 37.385961 -294.175276) (xy 37.433232 -294.188968) (xy 37.477694 -294.210066) (xy 37.518197 -294.238022)
			(xy 37.55369 -294.272114) (xy 37.583255 -294.311458) (xy 37.606126 -294.355035) (xy 37.62171 -294.401716)
			(xy 37.629605 -294.450293) (xy 37.6301 -294.4749) (xy 37.969202 -294.4749) (xy 37.973162 -294.425846)
			(xy 37.984939 -294.378062) (xy 38.00423 -294.332786) (xy 38.030533 -294.29119) (xy 38.063168 -294.254353)
			(xy 38.101289 -294.223228) (xy 38.14391 -294.198621) (xy 38.189926 -294.181169) (xy 38.238145 -294.171325)
			(xy 38.28732 -294.169344) (xy 38.336175 -294.175276) (xy 38.383446 -294.188968) (xy 38.427908 -294.210066)
			(xy 38.468411 -294.238022) (xy 38.503904 -294.272114) (xy 38.533469 -294.311458) (xy 38.55634 -294.355035)
			(xy 38.571924 -294.401716) (xy 38.579819 -294.450293) (xy 38.580314 -294.4749) (xy 40.819082 -294.4749)
			(xy 40.823042 -294.425846) (xy 40.834819 -294.378062) (xy 40.85411 -294.332786) (xy 40.880413 -294.29119)
			(xy 40.913048 -294.254353) (xy 40.951169 -294.223228) (xy 40.99379 -294.198621) (xy 41.039806 -294.181169)
			(xy 41.088025 -294.171325) (xy 41.1372 -294.169344) (xy 41.186055 -294.175276) (xy 41.233326 -294.188968)
			(xy 41.277788 -294.210066) (xy 41.318291 -294.238022) (xy 41.353784 -294.272114) (xy 41.383349 -294.311458)
			(xy 41.40622 -294.355035) (xy 41.421804 -294.401716) (xy 41.429699 -294.450293) (xy 41.430194 -294.4749)
			(xy 41.429699 -294.499507) (xy 41.429367 -294.501549) (xy 41.719236 -294.501549) (xy 41.719236 -294.448251)
			(xy 41.727179 -294.395547) (xy 41.742889 -294.344617) (xy 41.766015 -294.296596) (xy 41.796039 -294.252559)
			(xy 41.832291 -294.213488) (xy 41.873962 -294.180257) (xy 41.92012 -294.153608) (xy 41.969734 -294.134136)
			(xy 42.021696 -294.122276) (xy 42.074846 -294.118293) (xy 42.127996 -294.122276) (xy 42.179958 -294.134136)
			(xy 42.229572 -294.153608) (xy 42.27573 -294.180257) (xy 42.317401 -294.213488) (xy 42.353653 -294.252559)
			(xy 42.383677 -294.296596) (xy 42.406803 -294.344617) (xy 42.422513 -294.395547) (xy 42.430456 -294.448251)
			(xy 42.430954 -294.4749) (xy 42.430456 -294.501549) (xy 42.422513 -294.554253) (xy 42.406803 -294.605183)
			(xy 42.383677 -294.653204) (xy 42.353653 -294.697241) (xy 42.317401 -294.736312) (xy 42.27573 -294.769543)
			(xy 42.229572 -294.796192) (xy 42.179958 -294.815664) (xy 42.127996 -294.827524) (xy 42.074846 -294.831508)
			(xy 42.021696 -294.827524) (xy 41.969734 -294.815664) (xy 41.92012 -294.796192) (xy 41.873962 -294.769543)
			(xy 41.832291 -294.736312) (xy 41.796039 -294.697241) (xy 41.766015 -294.653204) (xy 41.742889 -294.605183)
			(xy 41.727179 -294.554253) (xy 41.719236 -294.501549) (xy 41.429367 -294.501549) (xy 41.421804 -294.548084)
			(xy 41.40622 -294.594765) (xy 41.383349 -294.638342) (xy 41.353784 -294.677686) (xy 41.318291 -294.711778)
			(xy 41.277788 -294.739734) (xy 41.233326 -294.760832) (xy 41.186055 -294.774524) (xy 41.1372 -294.780456)
			(xy 41.088025 -294.778475) (xy 41.039806 -294.768631) (xy 40.99379 -294.751179) (xy 40.951169 -294.726572)
			(xy 40.913048 -294.695447) (xy 40.880413 -294.65861) (xy 40.85411 -294.617014) (xy 40.834819 -294.571738)
			(xy 40.823042 -294.523954) (xy 40.819082 -294.4749) (xy 38.580314 -294.4749) (xy 38.579819 -294.499507)
			(xy 38.571924 -294.548084) (xy 38.55634 -294.594765) (xy 38.533469 -294.638342) (xy 38.503904 -294.677686)
			(xy 38.468411 -294.711778) (xy 38.427908 -294.739734) (xy 38.383446 -294.760832) (xy 38.336175 -294.774524)
			(xy 38.28732 -294.780456) (xy 38.238145 -294.778475) (xy 38.189926 -294.768631) (xy 38.14391 -294.751179)
			(xy 38.101289 -294.726572) (xy 38.063168 -294.695447) (xy 38.030533 -294.65861) (xy 38.00423 -294.617014)
			(xy 37.984939 -294.571738) (xy 37.973162 -294.523954) (xy 37.969202 -294.4749) (xy 37.6301 -294.4749)
			(xy 37.629605 -294.499507) (xy 37.62171 -294.548084) (xy 37.606126 -294.594765) (xy 37.583255 -294.638342)
			(xy 37.55369 -294.677686) (xy 37.518197 -294.711778) (xy 37.477694 -294.739734) (xy 37.433232 -294.760832)
			(xy 37.385961 -294.774524) (xy 37.337106 -294.780456) (xy 37.287931 -294.778475) (xy 37.239712 -294.768631)
			(xy 37.193696 -294.751179) (xy 37.151075 -294.726572) (xy 37.112954 -294.695447) (xy 37.080319 -294.65861)
			(xy 37.054016 -294.617014) (xy 37.034725 -294.571738) (xy 37.022948 -294.523954) (xy 37.018988 -294.4749)
			(xy 36.68014 -294.4749) (xy 36.679645 -294.499507) (xy 36.67175 -294.548084) (xy 36.656166 -294.594765)
			(xy 36.633295 -294.638342) (xy 36.60373 -294.677686) (xy 36.568237 -294.711778) (xy 36.527734 -294.739734)
			(xy 36.483272 -294.760832) (xy 36.436001 -294.774524) (xy 36.387146 -294.780456) (xy 36.337971 -294.778475)
			(xy 36.289752 -294.768631) (xy 36.243736 -294.751179) (xy 36.201115 -294.726572) (xy 36.162994 -294.695447)
			(xy 36.130359 -294.65861) (xy 36.104056 -294.617014) (xy 36.084765 -294.571738) (xy 36.072988 -294.523954)
			(xy 36.069028 -294.4749) (xy 34.39033 -294.4749) (xy 34.39033 -296.37482) (xy 37.019242 -296.37482)
			(xy 37.023202 -296.325766) (xy 37.034979 -296.277982) (xy 37.05427 -296.232706) (xy 37.080573 -296.19111)
			(xy 37.113208 -296.154273) (xy 37.151329 -296.123148) (xy 37.19395 -296.098541) (xy 37.239966 -296.081089)
			(xy 37.288185 -296.071245) (xy 37.33736 -296.069264) (xy 37.386215 -296.075196) (xy 37.433486 -296.088888)
			(xy 37.477948 -296.109986) (xy 37.518451 -296.137942) (xy 37.553944 -296.172034) (xy 37.583509 -296.211378)
			(xy 37.60638 -296.254955) (xy 37.621964 -296.301636) (xy 37.629859 -296.350213) (xy 37.630354 -296.37482)
			(xy 37.968948 -296.37482) (xy 37.972908 -296.325766) (xy 37.984685 -296.277982) (xy 38.003976 -296.232706)
			(xy 38.030279 -296.19111) (xy 38.062914 -296.154273) (xy 38.101035 -296.123148) (xy 38.143656 -296.098541)
			(xy 38.189672 -296.081089) (xy 38.237891 -296.071245) (xy 38.287066 -296.069264) (xy 38.335921 -296.075196)
			(xy 38.383192 -296.088888) (xy 38.427654 -296.109986) (xy 38.468157 -296.137942) (xy 38.50365 -296.172034)
			(xy 38.533215 -296.211378) (xy 38.556086 -296.254955) (xy 38.57167 -296.301636) (xy 38.579565 -296.350213)
			(xy 38.58006 -296.37482) (xy 38.919162 -296.37482) (xy 38.923122 -296.325766) (xy 38.934899 -296.277982)
			(xy 38.95419 -296.232706) (xy 38.980493 -296.19111) (xy 39.013128 -296.154273) (xy 39.051249 -296.123148)
			(xy 39.09387 -296.098541) (xy 39.139886 -296.081089) (xy 39.188105 -296.071245) (xy 39.23728 -296.069264)
			(xy 39.286135 -296.075196) (xy 39.333406 -296.088888) (xy 39.377868 -296.109986) (xy 39.418371 -296.137942)
			(xy 39.453864 -296.172034) (xy 39.483429 -296.211378) (xy 39.5063 -296.254955) (xy 39.521884 -296.301636)
			(xy 39.529779 -296.350213) (xy 39.530274 -296.37482) (xy 39.869122 -296.37482) (xy 39.873082 -296.325766)
			(xy 39.884859 -296.277982) (xy 39.90415 -296.232706) (xy 39.930453 -296.19111) (xy 39.963088 -296.154273)
			(xy 40.001209 -296.123148) (xy 40.04383 -296.098541) (xy 40.089846 -296.081089) (xy 40.138065 -296.071245)
			(xy 40.18724 -296.069264) (xy 40.236095 -296.075196) (xy 40.283366 -296.088888) (xy 40.327828 -296.109986)
			(xy 40.368331 -296.137942) (xy 40.403824 -296.172034) (xy 40.433389 -296.211378) (xy 40.45626 -296.254955)
			(xy 40.471844 -296.301636) (xy 40.479739 -296.350213) (xy 40.480234 -296.37482) (xy 41.769042 -296.37482)
			(xy 41.773002 -296.325766) (xy 41.784779 -296.277982) (xy 41.80407 -296.232706) (xy 41.830373 -296.19111)
			(xy 41.863008 -296.154273) (xy 41.901129 -296.123148) (xy 41.94375 -296.098541) (xy 41.989766 -296.081089)
			(xy 42.037985 -296.071245) (xy 42.08716 -296.069264) (xy 42.136015 -296.075196) (xy 42.183286 -296.088888)
			(xy 42.227748 -296.109986) (xy 42.268251 -296.137942) (xy 42.303744 -296.172034) (xy 42.333309 -296.211378)
			(xy 42.35618 -296.254955) (xy 42.371764 -296.301636) (xy 42.379659 -296.350213) (xy 42.380154 -296.37482)
			(xy 42.379659 -296.399427) (xy 42.371764 -296.448004) (xy 42.35618 -296.494685) (xy 42.333309 -296.538262)
			(xy 42.303744 -296.577606) (xy 42.268251 -296.611698) (xy 42.227748 -296.639654) (xy 42.183286 -296.660752)
			(xy 42.136015 -296.674444) (xy 42.08716 -296.680376) (xy 42.037985 -296.678395) (xy 41.989766 -296.668551)
			(xy 41.94375 -296.651099) (xy 41.901129 -296.626492) (xy 41.863008 -296.595367) (xy 41.830373 -296.55853)
			(xy 41.80407 -296.516934) (xy 41.784779 -296.471658) (xy 41.773002 -296.423874) (xy 41.769042 -296.37482)
			(xy 40.480234 -296.37482) (xy 40.479739 -296.399427) (xy 40.471844 -296.448004) (xy 40.45626 -296.494685)
			(xy 40.433389 -296.538262) (xy 40.403824 -296.577606) (xy 40.368331 -296.611698) (xy 40.327828 -296.639654)
			(xy 40.283366 -296.660752) (xy 40.236095 -296.674444) (xy 40.18724 -296.680376) (xy 40.138065 -296.678395)
			(xy 40.089846 -296.668551) (xy 40.04383 -296.651099) (xy 40.001209 -296.626492) (xy 39.963088 -296.595367)
			(xy 39.930453 -296.55853) (xy 39.90415 -296.516934) (xy 39.884859 -296.471658) (xy 39.873082 -296.423874)
			(xy 39.869122 -296.37482) (xy 39.530274 -296.37482) (xy 39.529779 -296.399427) (xy 39.521884 -296.448004)
			(xy 39.5063 -296.494685) (xy 39.483429 -296.538262) (xy 39.453864 -296.577606) (xy 39.418371 -296.611698)
			(xy 39.377868 -296.639654) (xy 39.333406 -296.660752) (xy 39.286135 -296.674444) (xy 39.23728 -296.680376)
			(xy 39.188105 -296.678395) (xy 39.139886 -296.668551) (xy 39.09387 -296.651099) (xy 39.051249 -296.626492)
			(xy 39.013128 -296.595367) (xy 38.980493 -296.55853) (xy 38.95419 -296.516934) (xy 38.934899 -296.471658)
			(xy 38.923122 -296.423874) (xy 38.919162 -296.37482) (xy 38.58006 -296.37482) (xy 38.579565 -296.399427)
			(xy 38.57167 -296.448004) (xy 38.556086 -296.494685) (xy 38.533215 -296.538262) (xy 38.50365 -296.577606)
			(xy 38.468157 -296.611698) (xy 38.427654 -296.639654) (xy 38.383192 -296.660752) (xy 38.335921 -296.674444)
			(xy 38.287066 -296.680376) (xy 38.237891 -296.678395) (xy 38.189672 -296.668551) (xy 38.143656 -296.651099)
			(xy 38.101035 -296.626492) (xy 38.062914 -296.595367) (xy 38.030279 -296.55853) (xy 38.003976 -296.516934)
			(xy 37.984685 -296.471658) (xy 37.972908 -296.423874) (xy 37.968948 -296.37482) (xy 37.630354 -296.37482)
			(xy 37.629859 -296.399427) (xy 37.621964 -296.448004) (xy 37.60638 -296.494685) (xy 37.583509 -296.538262)
			(xy 37.553944 -296.577606) (xy 37.518451 -296.611698) (xy 37.477948 -296.639654) (xy 37.433486 -296.660752)
			(xy 37.386215 -296.674444) (xy 37.33736 -296.680376) (xy 37.288185 -296.678395) (xy 37.239966 -296.668551)
			(xy 37.19395 -296.651099) (xy 37.151329 -296.626492) (xy 37.113208 -296.595367) (xy 37.080573 -296.55853)
			(xy 37.05427 -296.516934) (xy 37.034979 -296.471658) (xy 37.023202 -296.423874) (xy 37.019242 -296.37482)
			(xy 34.39033 -296.37482) (xy 34.39033 -297.3245) (xy 35.433795 -297.3245) (xy 35.437965 -297.274168)
			(xy 35.450363 -297.22521) (xy 35.470649 -297.178959) (xy 35.498271 -297.136678) (xy 35.532475 -297.09952)
			(xy 35.572329 -297.068498) (xy 35.616745 -297.044458) (xy 35.664511 -297.028057) (xy 35.714326 -297.019741)
			(xy 35.739578 -297.019218) (xy 35.764974 -297.019712) (xy 35.815065 -297.028128) (xy 35.863073 -297.044715)
			(xy 35.907676 -297.069017) (xy 35.947643 -297.100363) (xy 35.96513 -297.118786) (xy 35.972904 -297.126532)
			(xy 35.993025 -297.13523) (xy 36.003992 -297.13555) (xy 36.09213 -297.13301) (xy 36.111688 -297.123612)
			(xy 36.1188 -297.114976) (xy 36.134612 -297.096424) (xy 36.17074 -297.063703) (xy 36.211277 -297.036634)
			(xy 36.255344 -297.015802) (xy 36.30199 -297.001658) (xy 36.350206 -296.994507) (xy 36.374578 -296.994072)
			(xy 37.324538 -296.994072) (xy 37.350522 -296.994624) (xy 37.401848 -297.002759) (xy 37.451271 -297.018822)
			(xy 37.497572 -297.042419) (xy 37.539613 -297.072968) (xy 37.576357 -297.109716) (xy 37.606901 -297.15176)
			(xy 37.630492 -297.198064) (xy 37.64655 -297.247489) (xy 37.654679 -297.298816) (xy 37.654679 -297.32478)
			(xy 37.968948 -297.32478) (xy 37.972908 -297.275726) (xy 37.984685 -297.227942) (xy 38.003976 -297.182666)
			(xy 38.030279 -297.14107) (xy 38.062914 -297.104233) (xy 38.101035 -297.073108) (xy 38.143656 -297.048501)
			(xy 38.189672 -297.031049) (xy 38.237891 -297.021205) (xy 38.287066 -297.019224) (xy 38.335921 -297.025156)
			(xy 38.383192 -297.038848) (xy 38.427654 -297.059946) (xy 38.468157 -297.087902) (xy 38.50365 -297.121994)
			(xy 38.533215 -297.161338) (xy 38.556086 -297.204915) (xy 38.57167 -297.251596) (xy 38.579565 -297.300173)
			(xy 38.58006 -297.32478) (xy 38.919162 -297.32478) (xy 38.923122 -297.275726) (xy 38.934899 -297.227942)
			(xy 38.95419 -297.182666) (xy 38.980493 -297.14107) (xy 39.013128 -297.104233) (xy 39.051249 -297.073108)
			(xy 39.09387 -297.048501) (xy 39.139886 -297.031049) (xy 39.188105 -297.021205) (xy 39.23728 -297.019224)
			(xy 39.286135 -297.025156) (xy 39.333406 -297.038848) (xy 39.377868 -297.059946) (xy 39.418371 -297.087902)
			(xy 39.453864 -297.121994) (xy 39.483429 -297.161338) (xy 39.5063 -297.204915) (xy 39.521884 -297.251596)
			(xy 39.529779 -297.300173) (xy 39.530274 -297.32478) (xy 41.769042 -297.32478) (xy 41.773002 -297.275726)
			(xy 41.784779 -297.227942) (xy 41.80407 -297.182666) (xy 41.830373 -297.14107) (xy 41.863008 -297.104233)
			(xy 41.901129 -297.073108) (xy 41.94375 -297.048501) (xy 41.989766 -297.031049) (xy 42.037985 -297.021205)
			(xy 42.08716 -297.019224) (xy 42.136015 -297.025156) (xy 42.183286 -297.038848) (xy 42.227748 -297.059946)
			(xy 42.268251 -297.087902) (xy 42.303744 -297.121994) (xy 42.333309 -297.161338) (xy 42.35618 -297.204915)
			(xy 42.371764 -297.251596) (xy 42.379659 -297.300173) (xy 42.380154 -297.32478) (xy 42.379659 -297.349387)
			(xy 42.371764 -297.397964) (xy 42.35618 -297.444645) (xy 42.333309 -297.488222) (xy 42.303744 -297.527566)
			(xy 42.268251 -297.561658) (xy 42.227748 -297.589614) (xy 42.183286 -297.610712) (xy 42.136015 -297.624404)
			(xy 42.08716 -297.630336) (xy 42.037985 -297.628355) (xy 41.989766 -297.618511) (xy 41.94375 -297.601059)
			(xy 41.901129 -297.576452) (xy 41.863008 -297.545327) (xy 41.830373 -297.50849) (xy 41.80407 -297.466894)
			(xy 41.784779 -297.421618) (xy 41.773002 -297.373834) (xy 41.769042 -297.32478) (xy 39.530274 -297.32478)
			(xy 39.529779 -297.349387) (xy 39.521884 -297.397964) (xy 39.5063 -297.444645) (xy 39.483429 -297.488222)
			(xy 39.453864 -297.527566) (xy 39.418371 -297.561658) (xy 39.377868 -297.589614) (xy 39.333406 -297.610712)
			(xy 39.286135 -297.624404) (xy 39.23728 -297.630336) (xy 39.188105 -297.628355) (xy 39.139886 -297.618511)
			(xy 39.09387 -297.601059) (xy 39.051249 -297.576452) (xy 39.013128 -297.545327) (xy 38.980493 -297.50849)
			(xy 38.95419 -297.466894) (xy 38.934899 -297.421618) (xy 38.923122 -297.373834) (xy 38.919162 -297.32478)
			(xy 38.58006 -297.32478) (xy 38.579565 -297.349387) (xy 38.57167 -297.397964) (xy 38.556086 -297.444645)
			(xy 38.533215 -297.488222) (xy 38.50365 -297.527566) (xy 38.468157 -297.561658) (xy 38.427654 -297.589614)
			(xy 38.383192 -297.610712) (xy 38.335921 -297.624404) (xy 38.287066 -297.630336) (xy 38.237891 -297.628355)
			(xy 38.189672 -297.618511) (xy 38.143656 -297.601059) (xy 38.101035 -297.576452) (xy 38.062914 -297.545327)
			(xy 38.030279 -297.50849) (xy 38.003976 -297.466894) (xy 37.984685 -297.421618) (xy 37.972908 -297.373834)
			(xy 37.968948 -297.32478) (xy 37.654679 -297.32478) (xy 37.654679 -297.350784) (xy 37.64655 -297.402111)
			(xy 37.630492 -297.451536) (xy 37.606901 -297.49784) (xy 37.576357 -297.539884) (xy 37.539613 -297.576632)
			(xy 37.497572 -297.607181) (xy 37.451271 -297.630778) (xy 37.401848 -297.646841) (xy 37.350522 -297.654976)
			(xy 37.324538 -297.655488) (xy 36.374578 -297.655488) (xy 36.350206 -297.655043) (xy 36.301987 -297.647903)
			(xy 36.255338 -297.633766) (xy 36.211267 -297.612937) (xy 36.17073 -297.585868) (xy 36.134603 -297.553144)
			(xy 36.1188 -297.534584) (xy 36.111436 -297.52641) (xy 36.091676 -297.516792) (xy 36.0807 -297.516042)
			(xy 35.992562 -297.513502) (xy 35.972496 -297.522138) (xy 35.96513 -297.530266) (xy 35.947651 -297.548698)
			(xy 35.907685 -297.580046) (xy 35.86308 -297.604346) (xy 35.815069 -297.620927) (xy 35.764975 -297.629331)
			(xy 35.739578 -297.629834) (xy 35.714326 -297.629259) (xy 35.664511 -297.620943) (xy 35.616745 -297.604542)
			(xy 35.572329 -297.580502) (xy 35.532475 -297.54948) (xy 35.498271 -297.512322) (xy 35.470649 -297.470041)
			(xy 35.450363 -297.42379) (xy 35.437965 -297.374832) (xy 35.433795 -297.3245) (xy 34.39033 -297.3245)
			(xy 34.39033 -298.27474) (xy 37.018734 -298.27474) (xy 37.022694 -298.225686) (xy 37.034471 -298.177902)
			(xy 37.053762 -298.132626) (xy 37.080065 -298.09103) (xy 37.1127 -298.054193) (xy 37.150821 -298.023068)
			(xy 37.193442 -297.998461) (xy 37.239458 -297.981009) (xy 37.287677 -297.971165) (xy 37.336852 -297.969184)
			(xy 37.385707 -297.975116) (xy 37.432978 -297.988808) (xy 37.47744 -298.009906) (xy 37.517943 -298.037862)
			(xy 37.553436 -298.071954) (xy 37.583001 -298.111298) (xy 37.605872 -298.154875) (xy 37.621456 -298.201556)
			(xy 37.629351 -298.250133) (xy 37.629846 -298.27474) (xy 37.968948 -298.27474) (xy 37.972908 -298.225686)
			(xy 37.984685 -298.177902) (xy 38.003976 -298.132626) (xy 38.030279 -298.09103) (xy 38.062914 -298.054193)
			(xy 38.101035 -298.023068) (xy 38.143656 -297.998461) (xy 38.189672 -297.981009) (xy 38.237891 -297.971165)
			(xy 38.287066 -297.969184) (xy 38.335921 -297.975116) (xy 38.383192 -297.988808) (xy 38.427654 -298.009906)
			(xy 38.468157 -298.037862) (xy 38.50365 -298.071954) (xy 38.533215 -298.111298) (xy 38.556086 -298.154875)
			(xy 38.57167 -298.201556) (xy 38.579565 -298.250133) (xy 38.58006 -298.27474) (xy 38.579895 -298.282945)
			(xy 38.919314 -298.282945) (xy 38.922007 -298.233382) (xy 38.932683 -298.184907) (xy 38.951061 -298.138798)
			(xy 38.976657 -298.09627) (xy 39.008795 -298.058443) (xy 39.04663 -298.026313) (xy 39.089164 -298.000728)
			(xy 39.135278 -297.982362) (xy 39.183755 -297.971697) (xy 39.233319 -297.969016) (xy 39.282664 -297.974389)
			(xy 39.330489 -297.987674) (xy 39.375535 -298.008522) (xy 39.416615 -298.036382) (xy 39.452647 -298.070522)
			(xy 39.48268 -298.110041) (xy 39.505925 -298.153898) (xy 39.521768 -298.200938) (xy 39.529791 -298.249922)
			(xy 39.530274 -298.27474) (xy 39.530183 -298.283844) (xy 39.529037 -298.302018) (xy 39.527988 -298.311062)
			(xy 39.527988 -298.311316) (xy 39.527314 -298.322987) (xy 39.535235 -298.344951) (xy 39.543228 -298.35348)
			(xy 39.611046 -298.41825) (xy 39.633906 -298.425362) (xy 39.64559 -298.42333) (xy 39.659084 -298.421274)
			(xy 39.686297 -298.419112) (xy 39.699946 -298.419012) (xy 39.770304 -298.419012) (xy 39.781032 -298.418623)
			(xy 39.800637 -298.409918) (xy 39.80815 -298.402248) (xy 39.865808 -298.337732) (xy 39.872412 -298.317412)
			(xy 39.871396 -298.306998) (xy 39.871396 -298.30649) (xy 39.869618 -298.27474) (xy 39.87014 -298.249485)
			(xy 39.878453 -298.199663) (xy 39.894854 -298.151889) (xy 39.918895 -298.107466) (xy 39.949919 -298.067606)
			(xy 39.987081 -298.033396) (xy 40.029367 -298.00577) (xy 40.075623 -297.98548) (xy 40.124588 -297.97308)
			(xy 40.174926 -297.968909) (xy 40.225264 -297.97308) (xy 40.274229 -297.98548) (xy 40.320485 -298.00577)
			(xy 40.362771 -298.033396) (xy 40.399933 -298.067606) (xy 40.430957 -298.107466) (xy 40.454998 -298.151889)
			(xy 40.471399 -298.199663) (xy 40.479712 -298.249485) (xy 40.480234 -298.27474) (xy 40.478456 -298.306744)
			(xy 40.47744 -298.317412) (xy 40.484044 -298.337732) (xy 40.541702 -298.402248) (xy 40.54931 -298.409779)
			(xy 40.568858 -298.418444) (xy 40.579548 -298.419012) (xy 40.649906 -298.419012) (xy 40.663556 -298.419101)
			(xy 40.690769 -298.421263) (xy 40.704262 -298.42333) (xy 40.715946 -298.425362) (xy 40.738806 -298.41825)
			(xy 40.815006 -298.345352) (xy 40.823134 -298.323) (xy 40.821864 -298.311316) (xy 40.821864 -298.310808)
			(xy 40.820822 -298.301827) (xy 40.819681 -298.283781) (xy 40.819578 -298.27474) (xy 40.820035 -298.249915)
			(xy 40.828061 -298.200918) (xy 40.843909 -298.153865) (xy 40.867161 -298.109996) (xy 40.897203 -298.070467)
			(xy 40.933246 -298.036319) (xy 40.974338 -298.008452) (xy 41.019397 -297.9876) (xy 41.067236 -297.974314)
			(xy 41.116595 -297.968942) (xy 41.166172 -297.971626) (xy 41.214662 -297.982296) (xy 41.260787 -298.000671)
			(xy 41.303331 -298.026266) (xy 41.341174 -298.058407) (xy 41.373319 -298.096247) (xy 41.398917 -298.13879)
			(xy 41.417296 -298.184913) (xy 41.42797 -298.233402) (xy 41.430212 -298.27474) (xy 41.769042 -298.27474)
			(xy 41.773002 -298.225686) (xy 41.784779 -298.177902) (xy 41.80407 -298.132626) (xy 41.830373 -298.09103)
			(xy 41.863008 -298.054193) (xy 41.901129 -298.023068) (xy 41.94375 -297.998461) (xy 41.989766 -297.981009)
			(xy 42.037985 -297.971165) (xy 42.08716 -297.969184) (xy 42.136015 -297.975116) (xy 42.183286 -297.988808)
			(xy 42.227748 -298.009906) (xy 42.268251 -298.037862) (xy 42.303744 -298.071954) (xy 42.333309 -298.111298)
			(xy 42.35618 -298.154875) (xy 42.371764 -298.201556) (xy 42.379659 -298.250133) (xy 42.380154 -298.27474)
			(xy 43.668962 -298.27474) (xy 43.672922 -298.225686) (xy 43.684699 -298.177902) (xy 43.70399 -298.132626)
			(xy 43.730293 -298.09103) (xy 43.762928 -298.054193) (xy 43.801049 -298.023068) (xy 43.84367 -297.998461)
			(xy 43.889686 -297.981009) (xy 43.937905 -297.971165) (xy 43.98708 -297.969184) (xy 44.035935 -297.975116)
			(xy 44.083206 -297.988808) (xy 44.127668 -298.009906) (xy 44.168171 -298.037862) (xy 44.203664 -298.071954)
			(xy 44.233229 -298.111298) (xy 44.2561 -298.154875) (xy 44.271684 -298.201556) (xy 44.279579 -298.250133)
			(xy 44.280074 -298.27474) (xy 44.279579 -298.299347) (xy 44.271684 -298.347924) (xy 44.2561 -298.394605)
			(xy 44.233229 -298.438182) (xy 44.203664 -298.477526) (xy 44.168171 -298.511618) (xy 44.127668 -298.539574)
			(xy 44.083206 -298.560672) (xy 44.035935 -298.574364) (xy 43.98708 -298.580296) (xy 43.937905 -298.578315)
			(xy 43.889686 -298.568471) (xy 43.84367 -298.551019) (xy 43.801049 -298.526412) (xy 43.762928 -298.495287)
			(xy 43.730293 -298.45845) (xy 43.70399 -298.416854) (xy 43.684699 -298.371578) (xy 43.672922 -298.323794)
			(xy 43.668962 -298.27474) (xy 42.380154 -298.27474) (xy 42.379659 -298.299347) (xy 42.371764 -298.347924)
			(xy 42.35618 -298.394605) (xy 42.333309 -298.438182) (xy 42.303744 -298.477526) (xy 42.268251 -298.511618)
			(xy 42.227748 -298.539574) (xy 42.183286 -298.560672) (xy 42.136015 -298.574364) (xy 42.08716 -298.580296)
			(xy 42.037985 -298.578315) (xy 41.989766 -298.568471) (xy 41.94375 -298.551019) (xy 41.901129 -298.526412)
			(xy 41.863008 -298.495287) (xy 41.830373 -298.45845) (xy 41.80407 -298.416854) (xy 41.784779 -298.371578)
			(xy 41.773002 -298.323794) (xy 41.769042 -298.27474) (xy 41.430212 -298.27474) (xy 41.430659 -298.282979)
			(xy 41.425291 -298.332338) (xy 41.412009 -298.380179) (xy 41.391161 -298.42524) (xy 41.363298 -298.466334)
			(xy 41.329153 -298.502379) (xy 41.289626 -298.532425) (xy 41.245759 -298.555681) (xy 41.198707 -298.571533)
			(xy 41.149711 -298.579563) (xy 41.124886 -298.580048) (xy 41.115782 -298.579955) (xy 41.097608 -298.578811)
			(xy 41.088564 -298.577762) (xy 41.08831 -298.577762) (xy 41.076639 -298.57705) (xy 41.054672 -298.584999)
			(xy 41.046146 -298.593002) (xy 40.981376 -298.66082) (xy 40.974264 -298.68368) (xy 40.976296 -298.695364)
			(xy 40.978415 -298.708854) (xy 40.980705 -298.736066) (xy 40.980868 -298.74972) (xy 40.980723 -298.763438)
			(xy 40.978434 -298.790779) (xy 40.976296 -298.80433) (xy 40.974264 -298.816014) (xy 40.981376 -298.838874)
			(xy 41.054274 -298.915074) (xy 41.076626 -298.923202) (xy 41.08831 -298.921932) (xy 41.088818 -298.921932)
			(xy 41.0978 -298.920897) (xy 41.115845 -298.919751) (xy 41.124886 -298.919646) (xy 41.149709 -298.920163)
			(xy 41.198701 -298.928193) (xy 41.245749 -298.944043) (xy 41.289613 -298.967297) (xy 41.329136 -298.997341)
			(xy 41.363278 -299.033383) (xy 41.391139 -299.074474) (xy 41.411985 -299.119532) (xy 41.425266 -299.167368)
			(xy 41.430633 -299.216724) (xy 41.4302 -299.2247) (xy 41.769042 -299.2247) (xy 41.773002 -299.175646)
			(xy 41.784779 -299.127862) (xy 41.80407 -299.082586) (xy 41.830373 -299.04099) (xy 41.863008 -299.004153)
			(xy 41.901129 -298.973028) (xy 41.94375 -298.948421) (xy 41.989766 -298.930969) (xy 42.037985 -298.921125)
			(xy 42.08716 -298.919144) (xy 42.136015 -298.925076) (xy 42.183286 -298.938768) (xy 42.227748 -298.959866)
			(xy 42.268251 -298.987822) (xy 42.303744 -299.021914) (xy 42.333309 -299.061258) (xy 42.35618 -299.104835)
			(xy 42.371764 -299.151516) (xy 42.379659 -299.200093) (xy 42.380154 -299.2247) (xy 42.380149 -299.224954)
			(xy 43.668962 -299.224954) (xy 43.672922 -299.1759) (xy 43.684699 -299.128116) (xy 43.70399 -299.08284)
			(xy 43.730293 -299.041244) (xy 43.762928 -299.004407) (xy 43.801049 -298.973282) (xy 43.84367 -298.948675)
			(xy 43.889686 -298.931223) (xy 43.937905 -298.921379) (xy 43.98708 -298.919398) (xy 44.035935 -298.92533)
			(xy 44.083206 -298.939022) (xy 44.127668 -298.96012) (xy 44.168171 -298.988076) (xy 44.203664 -299.022168)
			(xy 44.233229 -299.061512) (xy 44.2561 -299.105089) (xy 44.271684 -299.15177) (xy 44.279579 -299.200347)
			(xy 44.280074 -299.224954) (xy 44.279579 -299.249561) (xy 44.271684 -299.298138) (xy 44.2561 -299.344819)
			(xy 44.233229 -299.388396) (xy 44.203664 -299.42774) (xy 44.168171 -299.461832) (xy 44.127668 -299.489788)
			(xy 44.083206 -299.510886) (xy 44.035935 -299.524578) (xy 43.98708 -299.53051) (xy 43.937905 -299.528529)
			(xy 43.889686 -299.518685) (xy 43.84367 -299.501233) (xy 43.801049 -299.476626) (xy 43.762928 -299.445501)
			(xy 43.730293 -299.408664) (xy 43.70399 -299.367068) (xy 43.684699 -299.321792) (xy 43.672922 -299.274008)
			(xy 43.668962 -299.224954) (xy 42.380149 -299.224954) (xy 42.379659 -299.249307) (xy 42.371764 -299.297884)
			(xy 42.35618 -299.344565) (xy 42.333309 -299.388142) (xy 42.303744 -299.427486) (xy 42.268251 -299.461578)
			(xy 42.227748 -299.489534) (xy 42.183286 -299.510632) (xy 42.136015 -299.524324) (xy 42.08716 -299.530256)
			(xy 42.037985 -299.528275) (xy 41.989766 -299.518431) (xy 41.94375 -299.500979) (xy 41.901129 -299.476372)
			(xy 41.863008 -299.445247) (xy 41.830373 -299.40841) (xy 41.80407 -299.366814) (xy 41.784779 -299.321538)
			(xy 41.773002 -299.273754) (xy 41.769042 -299.2247) (xy 41.4302 -299.2247) (xy 41.427944 -299.266297)
			(xy 41.41727 -299.314782) (xy 41.398893 -299.360901) (xy 41.373296 -299.40344) (xy 41.341154 -299.441276)
			(xy 41.303314 -299.473414) (xy 41.260772 -299.499007) (xy 41.214651 -299.51738) (xy 41.166165 -299.528048)
			(xy 41.116592 -299.530732) (xy 41.067237 -299.52536) (xy 41.019402 -299.512074) (xy 40.974346 -299.491223)
			(xy 40.933258 -299.463358) (xy 40.897219 -299.429212) (xy 40.86718 -299.389686) (xy 40.843931 -299.34582)
			(xy 40.828085 -299.29877) (xy 40.82006 -299.249777) (xy 40.819578 -299.224954) (xy 40.819664 -299.215786)
			(xy 40.820809 -299.197486) (xy 40.821864 -299.188378) (xy 40.823388 -299.17644) (xy 40.81526 -299.154088)
			(xy 40.73906 -299.08119) (xy 40.7162 -299.074078) (xy 40.704262 -299.07611) (xy 40.690769 -299.078172)
			(xy 40.663556 -299.08033) (xy 40.649906 -299.080428) (xy 39.699946 -299.080428) (xy 39.673951 -299.07991)
			(xy 39.6226 -299.071787) (xy 39.573151 -299.055733) (xy 39.526821 -299.032144) (xy 39.48475 -299.0016)
			(xy 39.447973 -298.964853) (xy 39.417395 -298.922806) (xy 39.393769 -298.876495) (xy 39.377675 -298.827059)
			(xy 39.369511 -298.775714) (xy 39.368984 -298.74972) (xy 39.369139 -298.736066) (xy 39.371427 -298.708852)
			(xy 39.373556 -298.695364) (xy 39.375588 -298.68368) (xy 39.368476 -298.66082) (xy 39.295578 -298.58462)
			(xy 39.273226 -298.576492) (xy 39.261542 -298.577762) (xy 39.261034 -298.577762) (xy 39.252053 -298.578801)
			(xy 39.234007 -298.579944) (xy 39.224966 -298.580048) (xy 39.200148 -298.579485) (xy 39.151166 -298.57145)
			(xy 39.10413 -298.555595) (xy 39.060278 -298.53234) (xy 39.020766 -298.502297) (xy 38.986636 -298.466257)
			(xy 38.958785 -298.425171) (xy 38.937949 -298.38012) (xy 38.924675 -298.332291) (xy 38.919314 -298.282945)
			(xy 38.579895 -298.282945) (xy 38.579565 -298.299347) (xy 38.57167 -298.347924) (xy 38.556086 -298.394605)
			(xy 38.533215 -298.438182) (xy 38.50365 -298.477526) (xy 38.468157 -298.511618) (xy 38.427654 -298.539574)
			(xy 38.383192 -298.560672) (xy 38.335921 -298.574364) (xy 38.287066 -298.580296) (xy 38.237891 -298.578315)
			(xy 38.189672 -298.568471) (xy 38.143656 -298.551019) (xy 38.101035 -298.526412) (xy 38.062914 -298.495287)
			(xy 38.030279 -298.45845) (xy 38.003976 -298.416854) (xy 37.984685 -298.371578) (xy 37.972908 -298.323794)
			(xy 37.968948 -298.27474) (xy 37.629846 -298.27474) (xy 37.629351 -298.299347) (xy 37.621456 -298.347924)
			(xy 37.605872 -298.394605) (xy 37.583001 -298.438182) (xy 37.553436 -298.477526) (xy 37.517943 -298.511618)
			(xy 37.47744 -298.539574) (xy 37.432978 -298.560672) (xy 37.385707 -298.574364) (xy 37.336852 -298.580296)
			(xy 37.287677 -298.578315) (xy 37.239458 -298.568471) (xy 37.193442 -298.551019) (xy 37.150821 -298.526412)
			(xy 37.1127 -298.495287) (xy 37.080065 -298.45845) (xy 37.053762 -298.416854) (xy 37.034471 -298.371578)
			(xy 37.022694 -298.323794) (xy 37.018734 -298.27474) (xy 34.39033 -298.27474) (xy 34.39033 -299.432472)
			(xy 34.3905 -299.438481) (xy 34.39333 -299.45016) (xy 34.395918 -299.455586) (xy 34.397756 -299.459061)
			(xy 34.402348 -299.465442) (xy 34.405062 -299.468286) (xy 34.445956 -299.50918) (xy 34.448806 -299.511887)
			(xy 34.455182 -299.516484) (xy 34.458656 -299.518324) (xy 34.464083 -299.520905) (xy 34.475763 -299.523724)
			(xy 34.48177 -299.523912) (xy 35.119564 -299.523912) (xy 35.14471 -299.524166) (xy 35.149282 -299.52442)
			(xy 35.41776 -299.52442) (xy 35.427666 -299.52442) (xy 35.438588 -299.52442) (xy 35.442906 -299.524674)
			(xy 35.448748 -299.524674) (xy 35.453066 -299.524928) (xy 35.456368 -299.524928) (xy 35.467598 -299.523942)
			(xy 35.487637 -299.513672) (xy 35.494976 -299.505116) (xy 35.513772 -299.478954) (xy 35.517315 -299.473614)
			(xy 35.521934 -299.461665) (xy 35.522916 -299.455332) (xy 35.52444 -299.44314) (xy 35.506914 -299.422566)
			(xy 35.48993 -299.401675) (xy 35.462819 -299.355163) (xy 35.444267 -299.304624) (xy 35.434845 -299.251618)
			(xy 35.43427 -299.2247) (xy 35.434741 -299.200708) (xy 35.442247 -299.153315) (xy 35.457074 -299.10768)
			(xy 35.478857 -299.064925) (xy 35.50706 -299.026105) (xy 35.540988 -298.992174) (xy 35.579807 -298.963968)
			(xy 35.622559 -298.942182) (xy 35.668194 -298.927352) (xy 35.715586 -298.919842) (xy 35.739578 -298.919392)
			(xy 35.764975 -298.919895) (xy 35.815068 -298.9283) (xy 35.863078 -298.944882) (xy 35.907681 -298.969184)
			(xy 35.947646 -299.000533) (xy 35.96513 -299.01896) (xy 35.965384 -299.019214) (xy 35.972593 -299.026369)
			(xy 35.991067 -299.03477) (xy 36.001198 -299.03547) (xy 36.0426 -299.034454) (xy 36.080954 -299.033438)
			(xy 36.086357 -299.033169) (xy 36.096864 -299.03061) (xy 36.101782 -299.028358) (xy 36.11118 -299.023786)
			(xy 36.111688 -299.023278) (xy 36.118546 -299.014896) (xy 36.134334 -298.99635) (xy 36.170425 -298.963646)
			(xy 36.210919 -298.936585) (xy 36.254943 -298.915751) (xy 36.301545 -298.901596) (xy 36.349718 -298.894423)
			(xy 36.37407 -298.893992) (xy 37.319966 -298.893992) (xy 37.320474 -298.893992) (xy 37.346884 -298.894207)
			(xy 37.399118 -298.901988) (xy 37.44946 -298.917947) (xy 37.496638 -298.94168) (xy 37.51834 -298.95673)
			(xy 37.53616 -298.970044) (xy 37.568403 -299.000689) (xy 37.596241 -299.035385) (xy 37.608002 -299.054266)
			(xy 37.60851 -299.055282) (xy 37.614098 -299.065442) (xy 37.614606 -299.06595) (xy 37.622799 -299.081298)
			(xy 37.636289 -299.113369) (xy 37.64153 -299.129958) (xy 37.641784 -299.130974) (xy 37.643562 -299.13707)
			(xy 37.644324 -299.139864) (xy 37.644578 -299.140626) (xy 37.64534 -299.143166) (xy 37.645594 -299.144182)
			(xy 37.645594 -299.144436) (xy 37.645848 -299.145452) (xy 37.646102 -299.146214) (xy 37.646356 -299.147992)
			(xy 37.648388 -299.157136) (xy 37.650674 -299.169328) (xy 37.652912 -299.183126) (xy 37.655328 -299.210977)
			(xy 37.6555 -299.224954) (xy 37.654962 -299.251324) (xy 37.646555 -299.303391) (xy 37.630011 -299.35347)
			(xy 37.605745 -299.400298) (xy 37.590476 -299.421804) (xy 37.587174 -299.426122) (xy 37.586412 -299.427392)
			(xy 37.581503 -299.437503) (xy 37.580071 -299.459905) (xy 37.583618 -299.470572) (xy 37.606224 -299.515022)
			(xy 37.606224 -299.51553) (xy 37.612066 -299.526706) (xy 37.612066 -299.527214) (xy 37.626544 -299.555916)
			(xy 37.631109 -299.564096) (xy 37.644948 -299.576695) (xy 37.662399 -299.583457) (xy 37.671756 -299.583856)
			(xy 37.953442 -299.583856) (xy 37.966142 -299.582078) (xy 37.9857 -299.576236) (xy 37.99586 -299.568108)
			(xy 37.998791 -299.565002) (xy 38.003648 -299.55798) (xy 38.005512 -299.554138) (xy 38.016434 -299.530516)
			(xy 38.046406 -299.466) (xy 38.047628 -299.462174) (xy 38.049028 -299.454265) (xy 38.0492 -299.450252)
			(xy 38.043358 -299.433742) (xy 38.043358 -299.433234) (xy 38.038278 -299.418502) (xy 38.033198 -299.412152)
			(xy 38.018302 -299.392099) (xy 37.99455 -299.348158) (xy 37.978252 -299.300941) (xy 37.969842 -299.251704)
			(xy 37.96919 -299.226732) (xy 37.96919 -299.217334) (xy 37.970217 -299.193737) (xy 37.978647 -299.147265)
			(xy 37.994136 -299.102647) (xy 38.016313 -299.060947) (xy 38.04465 -299.023161) (xy 38.078469 -298.990192)
			(xy 38.116963 -298.962826) (xy 38.159213 -298.941717) (xy 38.204211 -298.927368) (xy 38.250883 -298.920123)
			(xy 38.274498 -298.919646) (xy 38.274752 -298.919646) (xy 38.298787 -298.920092) (xy 38.346264 -298.927616)
			(xy 38.391976 -298.942486) (xy 38.434794 -298.964335) (xy 38.473659 -298.992622) (xy 38.507613 -299.02665)
			(xy 38.535815 -299.065577) (xy 38.55757 -299.108442) (xy 38.57234 -299.154187) (xy 38.57976 -299.20168)
			(xy 38.58006 -299.225716) (xy 38.58006 -299.226478) (xy 38.579445 -299.251455) (xy 38.571071 -299.300708)
			(xy 38.554773 -299.347935) (xy 38.530989 -299.39187) (xy 38.516052 -299.411898) (xy 38.510718 -299.418756)
			(xy 38.499796 -299.450252) (xy 38.499928 -299.454269) (xy 38.501336 -299.462181) (xy 38.50259 -299.466)
			(xy 38.532562 -299.530516) (xy 38.543992 -299.555154) (xy 38.547548 -299.56125) (xy 38.550323 -299.565213)
			(xy 38.557104 -299.572112) (xy 38.56101 -299.574966) (xy 38.566598 -299.578268) (xy 38.57625 -299.582078)
			(xy 38.589204 -299.583856) (xy 38.606984 -299.583856) (xy 38.647673 -299.584297) (xy 38.728758 -299.591197)
			(xy 38.808972 -299.604915) (xy 38.887742 -299.625352) (xy 38.926262 -299.638466) (xy 38.946441 -299.645691)
			(xy 38.986206 -299.6617) (xy 39.005764 -299.67047) (xy 39.006018 -299.67047) (xy 39.013384 -299.674026)
			(xy 39.024306 -299.678852) (xy 39.031418 -299.682408) (xy 39.037006 -299.685456) (xy 39.040562 -299.687234)
			(xy 39.040816 -299.687234) (xy 39.043102 -299.688504) (xy 39.045642 -299.689774) (xy 39.046404 -299.690282)
			(xy 39.054278 -299.694346) (xy 39.054532 -299.694346) (xy 39.054786 -299.6946) (xy 39.05504 -299.6946)
			(xy 39.056818 -299.695616) (xy 39.057072 -299.695616) (xy 39.057834 -299.696124) (xy 39.058088 -299.696124)
			(xy 39.058596 -299.696378) (xy 39.06266 -299.698664) (xy 39.063168 -299.698918) (xy 39.08508 -299.710899)
			(xy 39.127773 -299.73682) (xy 39.148512 -299.750734) (xy 39.151814 -299.75302) (xy 39.187499 -299.778128)
			(xy 39.254662 -299.833836) (xy 39.285926 -299.864272) (xy 39.289736 -299.868082) (xy 39.292022 -299.870368)
			(xy 39.29597 -299.874028) (xy 39.30506 -299.879792) (xy 39.310056 -299.881798) (xy 39.31285 -299.88256)
			(xy 39.324112 -299.886062) (xy 39.346107 -299.894584) (xy 39.356792 -299.899578) (xy 39.366468 -299.903685)
			(xy 39.387449 -299.904497) (xy 39.406999 -299.896836) (xy 39.421845 -299.881987) (xy 39.429499 -299.862435)
			(xy 39.428681 -299.841453) (xy 39.42461 -299.83176) (xy 39.415177 -299.811076) (xy 39.401843 -299.767617)
			(xy 39.395084 -299.722663) (xy 39.394638 -299.699934) (xy 39.39516 -299.674679) (xy 39.403473 -299.624857)
			(xy 39.419874 -299.577083) (xy 39.443915 -299.53266) (xy 39.474939 -299.4928) (xy 39.512101 -299.45859)
			(xy 39.554387 -299.430964) (xy 39.600643 -299.410674) (xy 39.649608 -299.398274) (xy 39.699946 -299.394103)
			(xy 39.750284 -299.398274) (xy 39.799249 -299.410674) (xy 39.845505 -299.430964) (xy 39.887791 -299.45859)
			(xy 39.924953 -299.4928) (xy 39.955977 -299.53266) (xy 39.980018 -299.577083) (xy 39.996419 -299.624857)
			(xy 40.004732 -299.674679) (xy 40.005254 -299.699934) (xy 40.005071 -299.714117) (xy 40.002403 -299.742357)
			(xy 39.99992 -299.756322) (xy 39.997634 -299.768768) (xy 40.005 -299.79239) (xy 40.081962 -299.869606)
			(xy 40.106092 -299.876972) (xy 40.118538 -299.874686) (xy 40.132447 -299.872288) (xy 40.160559 -299.869745)
			(xy 40.174672 -299.869606) (xy 40.198666 -299.87005) (xy 40.246064 -299.877553) (xy 40.291705 -299.89238)
			(xy 40.334464 -299.914164) (xy 40.373288 -299.942369) (xy 40.407222 -299.976301) (xy 40.435429 -300.015124)
			(xy 40.457215 -300.057882) (xy 40.472043 -300.103522) (xy 40.479549 -300.15092) (xy 40.47998 -300.174914)
			(xy 40.479759 -300.190392) (xy 40.476578 -300.221185) (xy 40.47363 -300.236382) (xy 40.47363 -300.237398)
			(xy 40.47236 -300.244002) (xy 40.479726 -300.267624) (xy 40.557196 -300.34484) (xy 40.580818 -300.352206)
			(xy 40.593264 -300.34992) (xy 40.607292 -300.347428) (xy 40.63566 -300.344761) (xy 40.649906 -300.344586)
			(xy 40.664088 -300.344773) (xy 40.692328 -300.347447) (xy 40.706294 -300.34992) (xy 40.71874 -300.352206)
			(xy 40.742362 -300.34484) (xy 40.819832 -300.26737) (xy 40.827198 -300.243748) (xy 40.824912 -300.231302)
			(xy 40.822426 -300.217337) (xy 40.819753 -300.189097) (xy 40.819578 -300.174914) (xy 40.8201 -300.149659)
			(xy 40.828413 -300.099837) (xy 40.844814 -300.052063) (xy 40.868855 -300.00764) (xy 40.899879 -299.96778)
			(xy 40.937041 -299.93357) (xy 40.979327 -299.905944) (xy 41.025583 -299.885654) (xy 41.074548 -299.873254)
			(xy 41.124886 -299.869083) (xy 41.175224 -299.873254) (xy 41.224189 -299.885654) (xy 41.270445 -299.905944)
			(xy 41.312731 -299.93357) (xy 41.349893 -299.96778) (xy 41.380917 -300.00764) (xy 41.404958 -300.052063)
			(xy 41.421359 -300.099837) (xy 41.429672 -300.149659) (xy 41.430194 -300.174914) (xy 41.430007 -300.189096)
			(xy 41.427332 -300.217335) (xy 41.42486 -300.231302) (xy 41.422574 -300.243748) (xy 41.42994 -300.26737)
			(xy 41.50741 -300.34484) (xy 41.531032 -300.352206) (xy 41.543478 -300.34992) (xy 41.557443 -300.347433)
			(xy 41.585683 -300.344758) (xy 41.599866 -300.344586) (xy 41.614049 -300.344771) (xy 41.642288 -300.347441)
			(xy 41.656254 -300.34992) (xy 41.6687 -300.352206) (xy 41.692322 -300.34484) (xy 41.769792 -300.26737)
			(xy 41.777158 -300.243748) (xy 41.774872 -300.231302) (xy 41.772386 -300.217337) (xy 41.769712 -300.189097)
			(xy 41.769538 -300.174914) (xy 41.77006 -300.149659) (xy 41.778373 -300.099837) (xy 41.794774 -300.052063)
			(xy 41.818815 -300.00764) (xy 41.849839 -299.96778) (xy 41.887001 -299.93357) (xy 41.929287 -299.905944)
			(xy 41.975543 -299.885654) (xy 42.024508 -299.873254) (xy 42.074846 -299.869083) (xy 42.125184 -299.873254)
			(xy 42.174149 -299.885654) (xy 42.220405 -299.905944) (xy 42.262691 -299.93357) (xy 42.299853 -299.96778)
			(xy 42.330877 -300.00764) (xy 42.354918 -300.052063) (xy 42.371319 -300.099837) (xy 42.379632 -300.149659)
			(xy 42.380154 -300.174914) (xy 43.668962 -300.174914) (xy 43.672922 -300.12586) (xy 43.684699 -300.078076)
			(xy 43.70399 -300.0328) (xy 43.730293 -299.991204) (xy 43.762928 -299.954367) (xy 43.801049 -299.923242)
			(xy 43.84367 -299.898635) (xy 43.889686 -299.881183) (xy 43.937905 -299.871339) (xy 43.98708 -299.869358)
			(xy 44.035935 -299.87529) (xy 44.083206 -299.888982) (xy 44.127668 -299.91008) (xy 44.168171 -299.938036)
			(xy 44.203664 -299.972128) (xy 44.233229 -300.011472) (xy 44.2561 -300.055049) (xy 44.271684 -300.10173)
			(xy 44.279579 -300.150307) (xy 44.280074 -300.174914) (xy 44.279579 -300.199521) (xy 44.271684 -300.248098)
			(xy 44.2561 -300.294779) (xy 44.233229 -300.338356) (xy 44.203664 -300.3777) (xy 44.168171 -300.411792)
			(xy 44.127668 -300.439748) (xy 44.083206 -300.460846) (xy 44.035935 -300.474538) (xy 43.98708 -300.48047)
			(xy 43.937905 -300.478489) (xy 43.889686 -300.468645) (xy 43.84367 -300.451193) (xy 43.801049 -300.426586)
			(xy 43.762928 -300.395461) (xy 43.730293 -300.358624) (xy 43.70399 -300.317028) (xy 43.684699 -300.271752)
			(xy 43.672922 -300.223968) (xy 43.668962 -300.174914) (xy 42.380154 -300.174914) (xy 42.379967 -300.189096)
			(xy 42.377293 -300.217335) (xy 42.37482 -300.231302) (xy 42.372534 -300.243748) (xy 42.3799 -300.26737)
			(xy 42.45737 -300.34484) (xy 42.480992 -300.352206) (xy 42.493438 -300.34992) (xy 42.507403 -300.347436)
			(xy 42.535643 -300.344766) (xy 42.549826 -300.344586) (xy 42.57508 -300.34511) (xy 42.6249 -300.353427)
			(xy 42.672671 -300.36983) (xy 42.717091 -300.393873) (xy 42.756948 -300.424898) (xy 42.791155 -300.46206)
			(xy 42.81878 -300.504345) (xy 42.839068 -300.5506) (xy 42.851466 -300.599564) (xy 42.855637 -300.6499)
			(xy 42.851466 -300.700236) (xy 42.839068 -300.7492) (xy 42.81878 -300.795455) (xy 42.791155 -300.83774)
			(xy 42.756948 -300.874902) (xy 42.717091 -300.905927) (xy 42.672671 -300.92997) (xy 42.6249 -300.946373)
			(xy 42.57508 -300.95469) (xy 42.549826 -300.955202) (xy 42.540722 -300.955103) (xy 42.522549 -300.953958)
			(xy 42.513504 -300.952916) (xy 42.51325 -300.952916) (xy 42.501446 -300.952097) (xy 42.479187 -300.960039)
			(xy 42.470578 -300.968156) (xy 42.406062 -301.03572) (xy 42.39895 -301.058326) (xy 42.399966 -301.06493)
			(xy 42.402549 -301.079782) (xy 42.405346 -301.1098) (xy 42.405554 -301.124874) (xy 42.405333 -301.139757)
			(xy 42.402531 -301.169393) (xy 42.399966 -301.184056) (xy 42.399966 -301.18558) (xy 42.39895 -301.191422)
			(xy 42.406062 -301.214028) (xy 42.470578 -301.281592) (xy 42.479214 -301.289672) (xy 42.501453 -301.297637)
			(xy 42.51325 -301.296832) (xy 42.513504 -301.296832) (xy 42.522548 -301.295785) (xy 42.540722 -301.294642)
			(xy 42.549826 -301.294546) (xy 42.574651 -301.295034) (xy 42.623646 -301.30307) (xy 42.670696 -301.318928)
			(xy 42.71456 -301.342188) (xy 42.754083 -301.372239) (xy 42.788224 -301.408288) (xy 42.816083 -301.449385)
			(xy 42.836925 -301.494449) (xy 42.850203 -301.54229) (xy 42.855566 -301.59165) (xy 42.852873 -301.641226)
			(xy 42.842194 -301.689714) (xy 42.823812 -301.735836) (xy 42.79821 -301.778376) (xy 42.766063 -301.816214)
			(xy 42.728217 -301.848352) (xy 42.685671 -301.873944) (xy 42.639545 -301.892315) (xy 42.591055 -301.902983)
			(xy 42.541478 -301.905664) (xy 42.492119 -301.90029) (xy 42.444281 -301.887001) (xy 42.399223 -301.866147)
			(xy 42.358132 -301.838279) (xy 42.322091 -301.804129) (xy 42.29205 -301.764599) (xy 42.268799 -301.720729)
			(xy 42.252953 -301.673676) (xy 42.244928 -301.624679) (xy 42.244518 -301.599854) (xy 42.244621 -301.590813)
			(xy 42.245763 -301.572767) (xy 42.246804 -301.563786) (xy 42.246804 -301.563278) (xy 42.248074 -301.551594)
			(xy 42.239946 -301.529242) (xy 42.163746 -301.456344) (xy 42.14114 -301.449486) (xy 42.132758 -301.450756)
			(xy 42.118524 -301.453112) (xy 42.089781 -301.455653) (xy 42.075354 -301.455836) (xy 42.004488 -301.455836)
			(xy 41.993796 -301.456398) (xy 41.974242 -301.465058) (xy 41.966642 -301.4726) (xy 41.916096 -301.528734)
			(xy 41.909303 -301.536952) (xy 41.902712 -301.557211) (xy 41.903396 -301.56785) (xy 41.903396 -301.568104)
			(xy 41.905174 -301.599854) (xy 41.904731 -301.623849) (xy 41.89723 -301.671248) (xy 41.882405 -301.716889)
			(xy 41.860622 -301.759649) (xy 41.832416 -301.798474) (xy 41.798484 -301.832408) (xy 41.75966 -301.860615)
			(xy 41.7169 -301.8824) (xy 41.671259 -301.897227) (xy 41.623861 -301.90473) (xy 41.599866 -301.905162)
			(xy 41.590698 -301.905068) (xy 41.572398 -301.903923) (xy 41.56329 -301.902876) (xy 41.563036 -301.902876)
			(xy 41.551232 -301.902059) (xy 41.528975 -301.910002) (xy 41.520364 -301.918116) (xy 41.455848 -301.98568)
			(xy 41.44899 -302.008286) (xy 41.450006 -302.015144) (xy 41.452527 -302.029937) (xy 41.455202 -302.059828)
			(xy 41.45534 -302.074834) (xy 41.455187 -302.089776) (xy 41.45252 -302.11954) (xy 41.450006 -302.13427)
			(xy 41.450006 -302.134778) (xy 41.44899 -302.141382) (xy 41.455848 -302.163988) (xy 41.520364 -302.231552)
			(xy 41.529007 -302.239608) (xy 41.551241 -302.247526) (xy 41.563036 -302.246792) (xy 41.56329 -302.246792)
			(xy 41.572398 -302.245737) (xy 41.590698 -302.244593) (xy 41.599866 -302.244506) (xy 41.62386 -302.24495)
			(xy 41.671259 -302.252452) (xy 41.716901 -302.267278) (xy 41.75966 -302.289062) (xy 41.798486 -302.317267)
			(xy 41.83242 -302.351199) (xy 41.860628 -302.390023) (xy 41.882414 -302.432781) (xy 41.897243 -302.478421)
			(xy 41.904749 -302.52582) (xy 41.905174 -302.549814) (xy 41.903396 -302.58131) (xy 41.903396 -302.581818)
			(xy 41.902887 -302.592436) (xy 41.90946 -302.612627) (xy 41.916096 -302.620934) (xy 41.966642 -302.677068)
			(xy 41.974162 -302.68472) (xy 41.993767 -302.693386) (xy 42.004488 -302.693832) (xy 42.075354 -302.693832)
			(xy 42.089719 -302.694001) (xy 42.118336 -302.696541) (xy 42.132504 -302.698912) (xy 42.133012 -302.698912)
			(xy 42.14114 -302.700182) (xy 42.163746 -302.693324) (xy 42.23131 -302.628554) (xy 42.239377 -302.620059)
			(xy 42.247434 -302.59809) (xy 42.246804 -302.58639) (xy 42.246804 -302.586136) (xy 42.245755 -302.577092)
			(xy 42.24461 -302.558918) (xy 42.244518 -302.549814) (xy 42.245003 -302.524995) (xy 42.253031 -302.476012)
			(xy 42.268878 -302.428972) (xy 42.292126 -302.385116) (xy 42.322163 -302.345599) (xy 42.358197 -302.311462)
			(xy 42.39928 -302.283604) (xy 42.444328 -302.262759) (xy 42.492155 -302.249477) (xy 42.541501 -302.244108)
			(xy 42.591065 -302.246792) (xy 42.639543 -302.25746) (xy 42.685656 -302.275829) (xy 42.728189 -302.301417)
			(xy 42.766023 -302.333549) (xy 42.798159 -302.371378) (xy 42.823753 -302.413909) (xy 42.842129 -302.460019)
			(xy 42.852803 -302.508495) (xy 42.855046 -302.549814) (xy 43.193982 -302.549814) (xy 43.197942 -302.50076)
			(xy 43.209719 -302.452976) (xy 43.22901 -302.4077) (xy 43.255313 -302.366104) (xy 43.287948 -302.329267)
			(xy 43.326069 -302.298142) (xy 43.36869 -302.273535) (xy 43.414706 -302.256083) (xy 43.462925 -302.246239)
			(xy 43.5121 -302.244258) (xy 43.560955 -302.25019) (xy 43.608226 -302.263882) (xy 43.652688 -302.28498)
			(xy 43.693191 -302.312936) (xy 43.728684 -302.347028) (xy 43.758249 -302.386372) (xy 43.78112 -302.429949)
			(xy 43.796704 -302.47663) (xy 43.804599 -302.525207) (xy 43.805094 -302.549814) (xy 44.143942 -302.549814)
			(xy 44.147902 -302.50076) (xy 44.159679 -302.452976) (xy 44.17897 -302.4077) (xy 44.205273 -302.366104)
			(xy 44.237908 -302.329267) (xy 44.276029 -302.298142) (xy 44.31865 -302.273535) (xy 44.364666 -302.256083)
			(xy 44.412885 -302.246239) (xy 44.46206 -302.244258) (xy 44.510915 -302.25019) (xy 44.558186 -302.263882)
			(xy 44.602648 -302.28498) (xy 44.643151 -302.312936) (xy 44.678644 -302.347028) (xy 44.708209 -302.386372)
			(xy 44.73108 -302.429949) (xy 44.746664 -302.47663) (xy 44.754559 -302.525207) (xy 44.755054 -302.549814)
			(xy 45.094156 -302.549814) (xy 45.098116 -302.50076) (xy 45.109893 -302.452976) (xy 45.129184 -302.4077)
			(xy 45.155487 -302.366104) (xy 45.188122 -302.329267) (xy 45.226243 -302.298142) (xy 45.268864 -302.273535)
			(xy 45.31488 -302.256083) (xy 45.363099 -302.246239) (xy 45.412274 -302.244258) (xy 45.461129 -302.25019)
			(xy 45.5084 -302.263882) (xy 45.552862 -302.28498) (xy 45.593365 -302.312936) (xy 45.628858 -302.347028)
			(xy 45.658423 -302.386372) (xy 45.681294 -302.429949) (xy 45.696878 -302.47663) (xy 45.704773 -302.525207)
			(xy 45.705268 -302.549814) (xy 45.704773 -302.574421) (xy 45.696878 -302.622998) (xy 45.681294 -302.669679)
			(xy 45.658423 -302.713256) (xy 45.628858 -302.7526) (xy 45.593365 -302.786692) (xy 45.552862 -302.814648)
			(xy 45.5084 -302.835746) (xy 45.461129 -302.849438) (xy 45.412274 -302.85537) (xy 45.363099 -302.853389)
			(xy 45.31488 -302.843545) (xy 45.268864 -302.826093) (xy 45.226243 -302.801486) (xy 45.188122 -302.770361)
			(xy 45.155487 -302.733524) (xy 45.129184 -302.691928) (xy 45.109893 -302.646652) (xy 45.098116 -302.598868)
			(xy 45.094156 -302.549814) (xy 44.755054 -302.549814) (xy 44.754559 -302.574421) (xy 44.746664 -302.622998)
			(xy 44.73108 -302.669679) (xy 44.708209 -302.713256) (xy 44.678644 -302.7526) (xy 44.643151 -302.786692)
			(xy 44.602648 -302.814648) (xy 44.558186 -302.835746) (xy 44.510915 -302.849438) (xy 44.46206 -302.85537)
			(xy 44.412885 -302.853389) (xy 44.364666 -302.843545) (xy 44.31865 -302.826093) (xy 44.276029 -302.801486)
			(xy 44.237908 -302.770361) (xy 44.205273 -302.733524) (xy 44.17897 -302.691928) (xy 44.159679 -302.646652)
			(xy 44.147902 -302.598868) (xy 44.143942 -302.549814) (xy 43.805094 -302.549814) (xy 43.804599 -302.574421)
			(xy 43.796704 -302.622998) (xy 43.78112 -302.669679) (xy 43.758249 -302.713256) (xy 43.728684 -302.7526)
			(xy 43.693191 -302.786692) (xy 43.652688 -302.814648) (xy 43.608226 -302.835746) (xy 43.560955 -302.849438)
			(xy 43.5121 -302.85537) (xy 43.462925 -302.853389) (xy 43.414706 -302.843545) (xy 43.36869 -302.826093)
			(xy 43.326069 -302.801486) (xy 43.287948 -302.770361) (xy 43.255313 -302.733524) (xy 43.22901 -302.691928)
			(xy 43.209719 -302.646652) (xy 43.197942 -302.598868) (xy 43.193982 -302.549814) (xy 42.855046 -302.549814)
			(xy 42.855493 -302.558059) (xy 42.85013 -302.607405) (xy 42.836855 -302.655234) (xy 42.816016 -302.700285)
			(xy 42.788163 -302.741371) (xy 42.754031 -302.77741) (xy 42.714517 -302.807453) (xy 42.670664 -302.830707)
			(xy 42.623627 -302.84656) (xy 42.574644 -302.854594) (xy 42.549826 -302.855122) (xy 42.540722 -302.855023)
			(xy 42.522549 -302.853877) (xy 42.513504 -302.852836) (xy 42.51325 -302.852836) (xy 42.501446 -302.852016)
			(xy 42.479189 -302.859962) (xy 42.470578 -302.868076) (xy 42.406062 -302.93564) (xy 42.39895 -302.958246)
			(xy 42.399966 -302.96485) (xy 42.402548 -302.979702) (xy 42.405343 -303.00972) (xy 42.405554 -303.024794)
			(xy 42.405337 -303.039678) (xy 42.402542 -303.069315) (xy 42.399966 -303.083976) (xy 42.399966 -303.0855)
			(xy 42.39895 -303.091342) (xy 42.406062 -303.113948) (xy 42.470578 -303.181512) (xy 42.479215 -303.18959)
			(xy 42.501454 -303.197551) (xy 42.51325 -303.196752) (xy 42.513504 -303.196752) (xy 42.522548 -303.195704)
			(xy 42.540722 -303.194562) (xy 42.549826 -303.194466) (xy 42.574649 -303.194954) (xy 42.62364 -303.20299)
			(xy 42.670686 -303.218846) (xy 42.714547 -303.242104) (xy 42.754067 -303.272152) (xy 42.788205 -303.308198)
			(xy 42.816063 -303.349292) (xy 42.836904 -303.394351) (xy 42.850182 -303.442188) (xy 42.855546 -303.491544)
			(xy 42.855099 -303.499774) (xy 43.193982 -303.499774) (xy 43.197942 -303.45072) (xy 43.209719 -303.402936)
			(xy 43.22901 -303.35766) (xy 43.255313 -303.316064) (xy 43.287948 -303.279227) (xy 43.326069 -303.248102)
			(xy 43.36869 -303.223495) (xy 43.414706 -303.206043) (xy 43.462925 -303.196199) (xy 43.5121 -303.194218)
			(xy 43.560955 -303.20015) (xy 43.608226 -303.213842) (xy 43.652688 -303.23494) (xy 43.693191 -303.262896)
			(xy 43.728684 -303.296988) (xy 43.758249 -303.336332) (xy 43.78112 -303.379909) (xy 43.796704 -303.42659)
			(xy 43.804599 -303.475167) (xy 43.805094 -303.499774) (xy 44.143942 -303.499774) (xy 44.147902 -303.45072)
			(xy 44.159679 -303.402936) (xy 44.17897 -303.35766) (xy 44.205273 -303.316064) (xy 44.237908 -303.279227)
			(xy 44.276029 -303.248102) (xy 44.31865 -303.223495) (xy 44.364666 -303.206043) (xy 44.412885 -303.196199)
			(xy 44.46206 -303.194218) (xy 44.510915 -303.20015) (xy 44.558186 -303.213842) (xy 44.602648 -303.23494)
			(xy 44.643151 -303.262896) (xy 44.678644 -303.296988) (xy 44.708209 -303.336332) (xy 44.73108 -303.379909)
			(xy 44.746664 -303.42659) (xy 44.754559 -303.475167) (xy 44.755054 -303.499774) (xy 45.094156 -303.499774)
			(xy 45.098116 -303.45072) (xy 45.109893 -303.402936) (xy 45.129184 -303.35766) (xy 45.155487 -303.316064)
			(xy 45.188122 -303.279227) (xy 45.226243 -303.248102) (xy 45.268864 -303.223495) (xy 45.31488 -303.206043)
			(xy 45.363099 -303.196199) (xy 45.412274 -303.194218) (xy 45.461129 -303.20015) (xy 45.5084 -303.213842)
			(xy 45.552862 -303.23494) (xy 45.593365 -303.262896) (xy 45.628858 -303.296988) (xy 45.658423 -303.336332)
			(xy 45.681294 -303.379909) (xy 45.696878 -303.42659) (xy 45.704773 -303.475167) (xy 45.705268 -303.499774)
			(xy 45.704773 -303.524381) (xy 45.696878 -303.572958) (xy 45.681294 -303.619639) (xy 45.658423 -303.663216)
			(xy 45.628858 -303.70256) (xy 45.593365 -303.736652) (xy 45.552862 -303.764608) (xy 45.5084 -303.785706)
			(xy 45.461129 -303.799398) (xy 45.412274 -303.80533) (xy 45.363099 -303.803349) (xy 45.31488 -303.793505)
			(xy 45.268864 -303.776053) (xy 45.226243 -303.751446) (xy 45.188122 -303.720321) (xy 45.155487 -303.683484)
			(xy 45.129184 -303.641888) (xy 45.109893 -303.596612) (xy 45.098116 -303.548828) (xy 45.094156 -303.499774)
			(xy 44.755054 -303.499774) (xy 44.754559 -303.524381) (xy 44.746664 -303.572958) (xy 44.73108 -303.619639)
			(xy 44.708209 -303.663216) (xy 44.678644 -303.70256) (xy 44.643151 -303.736652) (xy 44.602648 -303.764608)
			(xy 44.558186 -303.785706) (xy 44.510915 -303.799398) (xy 44.46206 -303.80533) (xy 44.412885 -303.803349)
			(xy 44.364666 -303.793505) (xy 44.31865 -303.776053) (xy 44.276029 -303.751446) (xy 44.237908 -303.720321)
			(xy 44.205273 -303.683484) (xy 44.17897 -303.641888) (xy 44.159679 -303.596612) (xy 44.147902 -303.548828)
			(xy 44.143942 -303.499774) (xy 43.805094 -303.499774) (xy 43.804599 -303.524381) (xy 43.796704 -303.572958)
			(xy 43.78112 -303.619639) (xy 43.758249 -303.663216) (xy 43.728684 -303.70256) (xy 43.693191 -303.736652)
			(xy 43.652688 -303.764608) (xy 43.608226 -303.785706) (xy 43.560955 -303.799398) (xy 43.5121 -303.80533)
			(xy 43.462925 -303.803349) (xy 43.414706 -303.793505) (xy 43.36869 -303.776053) (xy 43.326069 -303.751446)
			(xy 43.287948 -303.720321) (xy 43.255313 -303.683484) (xy 43.22901 -303.641888) (xy 43.209719 -303.596612)
			(xy 43.197942 -303.548828) (xy 43.193982 -303.499774) (xy 42.855099 -303.499774) (xy 42.852854 -303.541117)
			(xy 42.842177 -303.589601) (xy 42.823797 -303.635719) (xy 42.798198 -303.678256) (xy 42.766055 -303.716092)
			(xy 42.728214 -303.748229) (xy 42.685673 -303.77382) (xy 42.639551 -303.792192) (xy 42.591065 -303.802861)
			(xy 42.541492 -303.805544) (xy 42.492137 -303.800172) (xy 42.444302 -303.786886) (xy 42.399246 -303.766037)
			(xy 42.358157 -303.738173) (xy 42.322117 -303.704028) (xy 42.292076 -303.664503) (xy 42.268826 -303.620638)
			(xy 42.252977 -303.57359) (xy 42.24495 -303.524597) (xy 42.244518 -303.499774) (xy 42.244624 -303.490733)
			(xy 42.24577 -303.472688) (xy 42.246804 -303.463706) (xy 42.246804 -303.463198) (xy 42.248074 -303.451514)
			(xy 42.239946 -303.429162) (xy 42.163746 -303.356264) (xy 42.14114 -303.349406) (xy 42.132758 -303.350676)
			(xy 42.118524 -303.353032) (xy 42.089781 -303.355573) (xy 42.075354 -303.355756) (xy 42.004488 -303.355756)
			(xy 41.993797 -303.356319) (xy 41.974244 -303.364981) (xy 41.966642 -303.37252) (xy 41.916096 -303.428654)
			(xy 41.909306 -303.436873) (xy 41.902723 -303.457131) (xy 41.903396 -303.46777) (xy 41.903396 -303.468024)
			(xy 41.905174 -303.499774) (xy 41.90473 -303.523768) (xy 41.897226 -303.571164) (xy 41.882399 -303.616803)
			(xy 41.860615 -303.65956) (xy 41.832409 -303.698383) (xy 41.798477 -303.732314) (xy 41.759654 -303.760519)
			(xy 41.716896 -303.782302) (xy 41.671256 -303.797128) (xy 41.62386 -303.80463) (xy 41.599866 -303.805082)
			(xy 41.590635 -303.804997) (xy 41.572207 -303.803855) (xy 41.563036 -303.802796) (xy 41.562782 -303.802796)
			(xy 41.550974 -303.801969) (xy 41.528704 -303.8099) (xy 41.52011 -303.818036) (xy 41.455594 -303.8856)
			(xy 41.448482 -303.90846) (xy 41.450514 -303.920398) (xy 41.45449 -303.947434) (xy 41.454498 -304.002076)
			(xy 41.450514 -304.02911) (xy 41.448482 -304.041048) (xy 41.455594 -304.063908) (xy 41.52011 -304.131472)
			(xy 41.528751 -304.139536) (xy 41.550987 -304.147474) (xy 41.562782 -304.146712) (xy 41.563036 -304.146712)
			(xy 41.572207 -304.145652) (xy 41.590635 -304.144509) (xy 41.599866 -304.144426) (xy 41.62386 -304.14487)
			(xy 41.671258 -304.152372) (xy 41.716898 -304.167198) (xy 41.759656 -304.188982) (xy 41.798479 -304.217188)
			(xy 41.832412 -304.251121) (xy 41.860618 -304.289944) (xy 41.882402 -304.332702) (xy 41.897228 -304.378342)
			(xy 41.90473 -304.42574) (xy 41.905174 -304.449734) (xy 41.903396 -304.481738) (xy 41.903396 -304.482246)
			(xy 41.90238 -304.49266) (xy 41.908984 -304.51298) (xy 41.966642 -304.577496) (xy 41.974164 -304.585145)
			(xy 41.993768 -304.593806) (xy 42.004488 -304.59426) (xy 42.063416 -304.59426) (xy 42.065448 -304.594006)
			(xy 42.074592 -304.594006) (xy 42.089211 -304.594139) (xy 42.118337 -304.596686) (xy 42.132758 -304.599086)
			(xy 42.133266 -304.599086) (xy 42.14114 -304.600356) (xy 42.163746 -304.593498) (xy 42.2402 -304.520854)
			(xy 42.248328 -304.497994) (xy 42.246804 -304.48631) (xy 42.245749 -304.477202) (xy 42.244605 -304.458902)
			(xy 42.244518 -304.449734) (xy 42.245001 -304.424915) (xy 42.253026 -304.37593) (xy 42.26887 -304.328889)
			(xy 42.292116 -304.285031) (xy 42.322152 -304.245512) (xy 42.358185 -304.211372) (xy 42.399266 -304.183511)
			(xy 42.444314 -304.162664) (xy 42.492141 -304.14938) (xy 42.541488 -304.144008) (xy 42.591053 -304.14669)
			(xy 42.639531 -304.157356) (xy 42.685645 -304.175724) (xy 42.72818 -304.201311) (xy 42.766016 -304.233442)
			(xy 42.798154 -304.271271) (xy 42.823749 -304.313801) (xy 42.842126 -304.359911) (xy 42.852802 -304.408388)
			(xy 42.855048 -304.449734) (xy 43.193982 -304.449734) (xy 43.197942 -304.40068) (xy 43.209719 -304.352896)
			(xy 43.22901 -304.30762) (xy 43.255313 -304.266024) (xy 43.287948 -304.229187) (xy 43.326069 -304.198062)
			(xy 43.36869 -304.173455) (xy 43.414706 -304.156003) (xy 43.462925 -304.146159) (xy 43.5121 -304.144178)
			(xy 43.560955 -304.15011) (xy 43.608226 -304.163802) (xy 43.652688 -304.1849) (xy 43.693191 -304.212856)
			(xy 43.728684 -304.246948) (xy 43.758249 -304.286292) (xy 43.78112 -304.329869) (xy 43.796704 -304.37655)
			(xy 43.804599 -304.425127) (xy 43.805094 -304.449734) (xy 44.143942 -304.449734) (xy 44.147902 -304.40068)
			(xy 44.159679 -304.352896) (xy 44.17897 -304.30762) (xy 44.205273 -304.266024) (xy 44.237908 -304.229187)
			(xy 44.276029 -304.198062) (xy 44.31865 -304.173455) (xy 44.364666 -304.156003) (xy 44.412885 -304.146159)
			(xy 44.46206 -304.144178) (xy 44.510915 -304.15011) (xy 44.558186 -304.163802) (xy 44.602648 -304.1849)
			(xy 44.643151 -304.212856) (xy 44.678644 -304.246948) (xy 44.708209 -304.286292) (xy 44.73108 -304.329869)
			(xy 44.746664 -304.37655) (xy 44.754559 -304.425127) (xy 44.755054 -304.449734) (xy 45.094156 -304.449734)
			(xy 45.098116 -304.40068) (xy 45.109893 -304.352896) (xy 45.129184 -304.30762) (xy 45.155487 -304.266024)
			(xy 45.188122 -304.229187) (xy 45.226243 -304.198062) (xy 45.268864 -304.173455) (xy 45.31488 -304.156003)
			(xy 45.363099 -304.146159) (xy 45.412274 -304.144178) (xy 45.461129 -304.15011) (xy 45.5084 -304.163802)
			(xy 45.552862 -304.1849) (xy 45.593365 -304.212856) (xy 45.628858 -304.246948) (xy 45.658423 -304.286292)
			(xy 45.681294 -304.329869) (xy 45.696878 -304.37655) (xy 45.704773 -304.425127) (xy 45.7051 -304.441395)
			(xy 46.044216 -304.441395) (xy 46.049586 -304.39205) (xy 46.062869 -304.344225) (xy 46.083714 -304.299178)
			(xy 46.111572 -304.258097) (xy 46.145709 -304.222065) (xy 46.185226 -304.192029) (xy 46.229081 -304.168783)
			(xy 46.27612 -304.152937) (xy 46.325102 -304.14491) (xy 46.34992 -304.144426) (xy 46.364103 -304.144599)
			(xy 46.392343 -304.147274) (xy 46.406308 -304.14976) (xy 46.418754 -304.152046) (xy 46.442376 -304.14468)
			(xy 46.519846 -304.06721) (xy 46.527212 -304.043588) (xy 46.524926 -304.031142) (xy 46.522446 -304.017177)
			(xy 46.519776 -303.988937) (xy 46.519592 -303.974754) (xy 46.520114 -303.949499) (xy 46.528427 -303.899677)
			(xy 46.544828 -303.851903) (xy 46.568869 -303.80748) (xy 46.599893 -303.76762) (xy 46.637055 -303.73341)
			(xy 46.679341 -303.705784) (xy 46.725597 -303.685494) (xy 46.774562 -303.673094) (xy 46.8249 -303.668923)
			(xy 46.875238 -303.673094) (xy 46.924203 -303.685494) (xy 46.970459 -303.705784) (xy 47.012745 -303.73341)
			(xy 47.049907 -303.76762) (xy 47.080931 -303.80748) (xy 47.104972 -303.851903) (xy 47.121373 -303.899677)
			(xy 47.129686 -303.949499) (xy 47.130208 -303.974754) (xy 47.130025 -303.988937) (xy 47.127357 -304.017177)
			(xy 47.124874 -304.031142) (xy 47.122588 -304.043588) (xy 47.129954 -304.06721) (xy 47.207424 -304.14468)
			(xy 47.231046 -304.152046) (xy 47.243492 -304.14976) (xy 47.257459 -304.147289) (xy 47.285698 -304.144614)
			(xy 47.29988 -304.144426) (xy 47.314063 -304.144605) (xy 47.342303 -304.147275) (xy 47.356268 -304.14976)
			(xy 47.368714 -304.152046) (xy 47.392336 -304.14468) (xy 47.469806 -304.06721) (xy 47.477172 -304.043588)
			(xy 47.474886 -304.031142) (xy 47.472405 -304.017177) (xy 47.469736 -303.988937) (xy 47.469552 -303.974754)
			(xy 47.470127 -303.949937) (xy 47.478165 -303.900958) (xy 47.49402 -303.853925) (xy 47.517275 -303.810076)
			(xy 47.547319 -303.770567) (xy 47.583358 -303.736439) (xy 47.624443 -303.708591) (xy 47.669493 -303.687757)
			(xy 47.71732 -303.674485) (xy 47.766664 -303.669126) (xy 47.816224 -303.67182) (xy 47.864697 -303.682497)
			(xy 47.910803 -303.700875) (xy 47.953328 -303.72647) (xy 47.991153 -303.758608) (xy 48.02328 -303.796441)
			(xy 48.048863 -303.838974) (xy 48.067228 -303.885086) (xy 48.077891 -303.933561) (xy 48.080119 -303.974754)
			(xy 48.419016 -303.974754) (xy 48.422976 -303.9257) (xy 48.434753 -303.877916) (xy 48.454044 -303.83264)
			(xy 48.480347 -303.791044) (xy 48.512982 -303.754207) (xy 48.551103 -303.723082) (xy 48.593724 -303.698475)
			(xy 48.63974 -303.681023) (xy 48.687959 -303.671179) (xy 48.737134 -303.669198) (xy 48.785989 -303.67513)
			(xy 48.83326 -303.688822) (xy 48.877722 -303.70992) (xy 48.918225 -303.737876) (xy 48.953718 -303.771968)
			(xy 48.983283 -303.811312) (xy 49.006154 -303.854889) (xy 49.021738 -303.90157) (xy 49.029633 -303.950147)
			(xy 49.030128 -303.974754) (xy 49.029633 -303.999361) (xy 49.021738 -304.047938) (xy 49.006154 -304.094619)
			(xy 48.983283 -304.138196) (xy 48.953718 -304.17754) (xy 48.918225 -304.211632) (xy 48.877722 -304.239588)
			(xy 48.83326 -304.260686) (xy 48.785989 -304.274378) (xy 48.737134 -304.28031) (xy 48.687959 -304.278329)
			(xy 48.63974 -304.268485) (xy 48.593724 -304.251033) (xy 48.551103 -304.226426) (xy 48.512982 -304.195301)
			(xy 48.480347 -304.158464) (xy 48.454044 -304.116868) (xy 48.434753 -304.071592) (xy 48.422976 -304.023808)
			(xy 48.419016 -303.974754) (xy 48.080119 -303.974754) (xy 48.080572 -303.983122) (xy 48.075199 -304.032465)
			(xy 48.061914 -304.080288) (xy 48.041067 -304.125332) (xy 48.013207 -304.166409) (xy 47.979069 -304.202439)
			(xy 47.939552 -304.232471) (xy 47.895696 -304.255714) (xy 47.848658 -304.271556) (xy 47.799677 -304.27958)
			(xy 47.77486 -304.280062) (xy 47.760677 -304.279892) (xy 47.732437 -304.277215) (xy 47.718472 -304.274728)
			(xy 47.706026 -304.272442) (xy 47.682404 -304.279808) (xy 47.604934 -304.357278) (xy 47.597568 -304.3809)
			(xy 47.599854 -304.393346) (xy 47.602332 -304.407312) (xy 47.605003 -304.435551) (xy 47.605188 -304.449734)
			(xy 47.605016 -304.463917) (xy 47.602341 -304.492157) (xy 47.599854 -304.506122) (xy 47.597568 -304.518568)
			(xy 47.604934 -304.54219) (xy 47.682404 -304.61966) (xy 47.706026 -304.627026) (xy 47.718472 -304.62474)
			(xy 47.732437 -304.622258) (xy 47.760677 -304.61959) (xy 47.77486 -304.619406) (xy 47.799685 -304.619835)
			(xy 47.848681 -304.627861) (xy 47.895733 -304.643708) (xy 47.939601 -304.666959) (xy 47.97913 -304.697)
			(xy 48.013278 -304.733041) (xy 48.041145 -304.774132) (xy 48.061997 -304.81919) (xy 48.075285 -304.867028)
			(xy 48.080658 -304.916386) (xy 48.080207 -304.924714) (xy 48.419016 -304.924714) (xy 48.422976 -304.87566)
			(xy 48.434753 -304.827876) (xy 48.454044 -304.7826) (xy 48.480347 -304.741004) (xy 48.512982 -304.704167)
			(xy 48.551103 -304.673042) (xy 48.593724 -304.648435) (xy 48.63974 -304.630983) (xy 48.687959 -304.621139)
			(xy 48.737134 -304.619158) (xy 48.785989 -304.62509) (xy 48.83326 -304.638782) (xy 48.877722 -304.65988)
			(xy 48.918225 -304.687836) (xy 48.953718 -304.721928) (xy 48.983283 -304.761272) (xy 49.006154 -304.804849)
			(xy 49.021738 -304.85153) (xy 49.029633 -304.900107) (xy 49.030128 -304.924714) (xy 49.368976 -304.924714)
			(xy 49.372936 -304.87566) (xy 49.384713 -304.827876) (xy 49.404004 -304.7826) (xy 49.430307 -304.741004)
			(xy 49.462942 -304.704167) (xy 49.501063 -304.673042) (xy 49.543684 -304.648435) (xy 49.5897 -304.630983)
			(xy 49.637919 -304.621139) (xy 49.687094 -304.619158) (xy 49.735949 -304.62509) (xy 49.78322 -304.638782)
			(xy 49.827682 -304.65988) (xy 49.868185 -304.687836) (xy 49.903678 -304.721928) (xy 49.933243 -304.761272)
			(xy 49.956114 -304.804849) (xy 49.971698 -304.85153) (xy 49.979593 -304.900107) (xy 49.980088 -304.924714)
			(xy 50.31919 -304.924714) (xy 50.32315 -304.87566) (xy 50.334927 -304.827876) (xy 50.354218 -304.7826)
			(xy 50.380521 -304.741004) (xy 50.413156 -304.704167) (xy 50.451277 -304.673042) (xy 50.493898 -304.648435)
			(xy 50.539914 -304.630983) (xy 50.588133 -304.621139) (xy 50.637308 -304.619158) (xy 50.686163 -304.62509)
			(xy 50.733434 -304.638782) (xy 50.777896 -304.65988) (xy 50.818399 -304.687836) (xy 50.853892 -304.721928)
			(xy 50.883457 -304.761272) (xy 50.906328 -304.804849) (xy 50.921912 -304.85153) (xy 50.929807 -304.900107)
			(xy 50.930302 -304.924714) (xy 51.26915 -304.924714) (xy 51.27311 -304.87566) (xy 51.284887 -304.827876)
			(xy 51.304178 -304.7826) (xy 51.330481 -304.741004) (xy 51.363116 -304.704167) (xy 51.401237 -304.673042)
			(xy 51.443858 -304.648435) (xy 51.489874 -304.630983) (xy 51.538093 -304.621139) (xy 51.587268 -304.619158)
			(xy 51.636123 -304.62509) (xy 51.683394 -304.638782) (xy 51.727856 -304.65988) (xy 51.768359 -304.687836)
			(xy 51.803852 -304.721928) (xy 51.833417 -304.761272) (xy 51.856288 -304.804849) (xy 51.871872 -304.85153)
			(xy 51.879767 -304.900107) (xy 51.880262 -304.924714) (xy 52.21911 -304.924714) (xy 52.22307 -304.87566)
			(xy 52.234847 -304.827876) (xy 52.254138 -304.7826) (xy 52.280441 -304.741004) (xy 52.313076 -304.704167)
			(xy 52.351197 -304.673042) (xy 52.393818 -304.648435) (xy 52.439834 -304.630983) (xy 52.488053 -304.621139)
			(xy 52.537228 -304.619158) (xy 52.586083 -304.62509) (xy 52.633354 -304.638782) (xy 52.677816 -304.65988)
			(xy 52.718319 -304.687836) (xy 52.753812 -304.721928) (xy 52.783377 -304.761272) (xy 52.806248 -304.804849)
			(xy 52.821832 -304.85153) (xy 52.829727 -304.900107) (xy 52.830222 -304.924714) (xy 53.16907 -304.924714)
			(xy 53.17303 -304.87566) (xy 53.184807 -304.827876) (xy 53.204098 -304.7826) (xy 53.230401 -304.741004)
			(xy 53.263036 -304.704167) (xy 53.301157 -304.673042) (xy 53.343778 -304.648435) (xy 53.389794 -304.630983)
			(xy 53.438013 -304.621139) (xy 53.487188 -304.619158) (xy 53.536043 -304.62509) (xy 53.583314 -304.638782)
			(xy 53.627776 -304.65988) (xy 53.668279 -304.687836) (xy 53.703772 -304.721928) (xy 53.733337 -304.761272)
			(xy 53.756208 -304.804849) (xy 53.771792 -304.85153) (xy 53.779687 -304.900107) (xy 53.780182 -304.924714)
			(xy 54.11903 -304.924714) (xy 54.12299 -304.87566) (xy 54.134767 -304.827876) (xy 54.154058 -304.7826)
			(xy 54.180361 -304.741004) (xy 54.212996 -304.704167) (xy 54.251117 -304.673042) (xy 54.293738 -304.648435)
			(xy 54.339754 -304.630983) (xy 54.387973 -304.621139) (xy 54.437148 -304.619158) (xy 54.486003 -304.62509)
			(xy 54.533274 -304.638782) (xy 54.577736 -304.65988) (xy 54.618239 -304.687836) (xy 54.653732 -304.721928)
			(xy 54.683297 -304.761272) (xy 54.706168 -304.804849) (xy 54.721752 -304.85153) (xy 54.729647 -304.900107)
			(xy 54.730142 -304.924714) (xy 55.06899 -304.924714) (xy 55.07295 -304.87566) (xy 55.084727 -304.827876)
			(xy 55.104018 -304.7826) (xy 55.130321 -304.741004) (xy 55.162956 -304.704167) (xy 55.201077 -304.673042)
			(xy 55.243698 -304.648435) (xy 55.289714 -304.630983) (xy 55.337933 -304.621139) (xy 55.387108 -304.619158)
			(xy 55.435963 -304.62509) (xy 55.483234 -304.638782) (xy 55.527696 -304.65988) (xy 55.568199 -304.687836)
			(xy 55.603692 -304.721928) (xy 55.633257 -304.761272) (xy 55.656128 -304.804849) (xy 55.671712 -304.85153)
			(xy 55.679607 -304.900107) (xy 55.680102 -304.924714) (xy 56.01895 -304.924714) (xy 56.02291 -304.87566)
			(xy 56.034687 -304.827876) (xy 56.053978 -304.7826) (xy 56.080281 -304.741004) (xy 56.112916 -304.704167)
			(xy 56.151037 -304.673042) (xy 56.193658 -304.648435) (xy 56.239674 -304.630983) (xy 56.287893 -304.621139)
			(xy 56.337068 -304.619158) (xy 56.385923 -304.62509) (xy 56.433194 -304.638782) (xy 56.477656 -304.65988)
			(xy 56.518159 -304.687836) (xy 56.553652 -304.721928) (xy 56.583217 -304.761272) (xy 56.606088 -304.804849)
			(xy 56.621672 -304.85153) (xy 56.629567 -304.900107) (xy 56.630062 -304.924714) (xy 56.969164 -304.924714)
			(xy 56.973124 -304.87566) (xy 56.984901 -304.827876) (xy 57.004192 -304.7826) (xy 57.030495 -304.741004)
			(xy 57.06313 -304.704167) (xy 57.101251 -304.673042) (xy 57.143872 -304.648435) (xy 57.189888 -304.630983)
			(xy 57.238107 -304.621139) (xy 57.287282 -304.619158) (xy 57.336137 -304.62509) (xy 57.383408 -304.638782)
			(xy 57.42787 -304.65988) (xy 57.468373 -304.687836) (xy 57.503866 -304.721928) (xy 57.533431 -304.761272)
			(xy 57.556302 -304.804849) (xy 57.571886 -304.85153) (xy 57.579781 -304.900107) (xy 57.580276 -304.924714)
			(xy 57.919124 -304.924714) (xy 57.923084 -304.87566) (xy 57.934861 -304.827876) (xy 57.954152 -304.7826)
			(xy 57.980455 -304.741004) (xy 58.01309 -304.704167) (xy 58.051211 -304.673042) (xy 58.093832 -304.648435)
			(xy 58.139848 -304.630983) (xy 58.188067 -304.621139) (xy 58.237242 -304.619158) (xy 58.286097 -304.62509)
			(xy 58.333368 -304.638782) (xy 58.37783 -304.65988) (xy 58.418333 -304.687836) (xy 58.453826 -304.721928)
			(xy 58.483391 -304.761272) (xy 58.506262 -304.804849) (xy 58.521846 -304.85153) (xy 58.529741 -304.900107)
			(xy 58.530236 -304.924714) (xy 59.819044 -304.924714) (xy 59.823004 -304.87566) (xy 59.834781 -304.827876)
			(xy 59.854072 -304.7826) (xy 59.880375 -304.741004) (xy 59.91301 -304.704167) (xy 59.951131 -304.673042)
			(xy 59.993752 -304.648435) (xy 60.039768 -304.630983) (xy 60.087987 -304.621139) (xy 60.137162 -304.619158)
			(xy 60.186017 -304.62509) (xy 60.233288 -304.638782) (xy 60.27775 -304.65988) (xy 60.318253 -304.687836)
			(xy 60.353746 -304.721928) (xy 60.383311 -304.761272) (xy 60.406182 -304.804849) (xy 60.421766 -304.85153)
			(xy 60.429661 -304.900107) (xy 60.430156 -304.924714) (xy 60.769004 -304.924714) (xy 60.772964 -304.87566)
			(xy 60.784741 -304.827876) (xy 60.804032 -304.7826) (xy 60.830335 -304.741004) (xy 60.86297 -304.704167)
			(xy 60.901091 -304.673042) (xy 60.943712 -304.648435) (xy 60.989728 -304.630983) (xy 61.037947 -304.621139)
			(xy 61.087122 -304.619158) (xy 61.135977 -304.62509) (xy 61.183248 -304.638782) (xy 61.22771 -304.65988)
			(xy 61.268213 -304.687836) (xy 61.303706 -304.721928) (xy 61.333271 -304.761272) (xy 61.356142 -304.804849)
			(xy 61.371726 -304.85153) (xy 61.379621 -304.900107) (xy 61.380116 -304.924714) (xy 61.718964 -304.924714)
			(xy 61.722924 -304.87566) (xy 61.734701 -304.827876) (xy 61.753992 -304.7826) (xy 61.780295 -304.741004)
			(xy 61.81293 -304.704167) (xy 61.851051 -304.673042) (xy 61.893672 -304.648435) (xy 61.939688 -304.630983)
			(xy 61.987907 -304.621139) (xy 62.037082 -304.619158) (xy 62.085937 -304.62509) (xy 62.133208 -304.638782)
			(xy 62.17767 -304.65988) (xy 62.218173 -304.687836) (xy 62.253666 -304.721928) (xy 62.283231 -304.761272)
			(xy 62.306102 -304.804849) (xy 62.321686 -304.85153) (xy 62.329581 -304.900107) (xy 62.330076 -304.924714)
			(xy 62.669178 -304.924714) (xy 62.673138 -304.87566) (xy 62.684915 -304.827876) (xy 62.704206 -304.7826)
			(xy 62.730509 -304.741004) (xy 62.763144 -304.704167) (xy 62.801265 -304.673042) (xy 62.843886 -304.648435)
			(xy 62.889902 -304.630983) (xy 62.938121 -304.621139) (xy 62.987296 -304.619158) (xy 63.036151 -304.62509)
			(xy 63.083422 -304.638782) (xy 63.127884 -304.65988) (xy 63.168387 -304.687836) (xy 63.20388 -304.721928)
			(xy 63.233445 -304.761272) (xy 63.256316 -304.804849) (xy 63.2719 -304.85153) (xy 63.279795 -304.900107)
			(xy 63.28029 -304.924714) (xy 63.619138 -304.924714) (xy 63.623098 -304.87566) (xy 63.634875 -304.827876)
			(xy 63.654166 -304.7826) (xy 63.680469 -304.741004) (xy 63.713104 -304.704167) (xy 63.751225 -304.673042)
			(xy 63.793846 -304.648435) (xy 63.839862 -304.630983) (xy 63.888081 -304.621139) (xy 63.937256 -304.619158)
			(xy 63.986111 -304.62509) (xy 64.033382 -304.638782) (xy 64.077844 -304.65988) (xy 64.118347 -304.687836)
			(xy 64.15384 -304.721928) (xy 64.183405 -304.761272) (xy 64.206276 -304.804849) (xy 64.22186 -304.85153)
			(xy 64.229755 -304.900107) (xy 64.23025 -304.924714) (xy 64.569098 -304.924714) (xy 64.573058 -304.87566)
			(xy 64.584835 -304.827876) (xy 64.604126 -304.7826) (xy 64.630429 -304.741004) (xy 64.663064 -304.704167)
			(xy 64.701185 -304.673042) (xy 64.743806 -304.648435) (xy 64.789822 -304.630983) (xy 64.838041 -304.621139)
			(xy 64.887216 -304.619158) (xy 64.936071 -304.62509) (xy 64.983342 -304.638782) (xy 65.027804 -304.65988)
			(xy 65.068307 -304.687836) (xy 65.1038 -304.721928) (xy 65.133365 -304.761272) (xy 65.156236 -304.804849)
			(xy 65.17182 -304.85153) (xy 65.179715 -304.900107) (xy 65.18021 -304.924714) (xy 65.519058 -304.924714)
			(xy 65.523018 -304.87566) (xy 65.534795 -304.827876) (xy 65.554086 -304.7826) (xy 65.580389 -304.741004)
			(xy 65.613024 -304.704167) (xy 65.651145 -304.673042) (xy 65.693766 -304.648435) (xy 65.739782 -304.630983)
			(xy 65.788001 -304.621139) (xy 65.837176 -304.619158) (xy 65.886031 -304.62509) (xy 65.933302 -304.638782)
			(xy 65.977764 -304.65988) (xy 66.018267 -304.687836) (xy 66.05376 -304.721928) (xy 66.083325 -304.761272)
			(xy 66.106196 -304.804849) (xy 66.12178 -304.85153) (xy 66.129675 -304.900107) (xy 66.13017 -304.924714)
			(xy 66.469018 -304.924714) (xy 66.472978 -304.87566) (xy 66.484755 -304.827876) (xy 66.504046 -304.7826)
			(xy 66.530349 -304.741004) (xy 66.562984 -304.704167) (xy 66.601105 -304.673042) (xy 66.643726 -304.648435)
			(xy 66.689742 -304.630983) (xy 66.737961 -304.621139) (xy 66.787136 -304.619158) (xy 66.835991 -304.62509)
			(xy 66.883262 -304.638782) (xy 66.927724 -304.65988) (xy 66.968227 -304.687836) (xy 67.00372 -304.721928)
			(xy 67.033285 -304.761272) (xy 67.056156 -304.804849) (xy 67.07174 -304.85153) (xy 67.079635 -304.900107)
			(xy 67.08013 -304.924714) (xy 67.418978 -304.924714) (xy 67.422938 -304.87566) (xy 67.434715 -304.827876)
			(xy 67.454006 -304.7826) (xy 67.480309 -304.741004) (xy 67.512944 -304.704167) (xy 67.551065 -304.673042)
			(xy 67.593686 -304.648435) (xy 67.639702 -304.630983) (xy 67.687921 -304.621139) (xy 67.737096 -304.619158)
			(xy 67.785951 -304.62509) (xy 67.833222 -304.638782) (xy 67.877684 -304.65988) (xy 67.918187 -304.687836)
			(xy 67.95368 -304.721928) (xy 67.983245 -304.761272) (xy 68.006116 -304.804849) (xy 68.0217 -304.85153)
			(xy 68.029595 -304.900107) (xy 68.03009 -304.924714) (xy 68.368938 -304.924714) (xy 68.372898 -304.87566)
			(xy 68.384675 -304.827876) (xy 68.403966 -304.7826) (xy 68.430269 -304.741004) (xy 68.462904 -304.704167)
			(xy 68.501025 -304.673042) (xy 68.543646 -304.648435) (xy 68.589662 -304.630983) (xy 68.637881 -304.621139)
			(xy 68.687056 -304.619158) (xy 68.735911 -304.62509) (xy 68.783182 -304.638782) (xy 68.827644 -304.65988)
			(xy 68.868147 -304.687836) (xy 68.90364 -304.721928) (xy 68.933205 -304.761272) (xy 68.956076 -304.804849)
			(xy 68.97166 -304.85153) (xy 68.979555 -304.900107) (xy 68.98005 -304.924714) (xy 68.979555 -304.949321)
			(xy 68.97166 -304.997898) (xy 68.956076 -305.044579) (xy 68.933205 -305.088156) (xy 68.90364 -305.1275)
			(xy 68.868147 -305.161592) (xy 68.827644 -305.189548) (xy 68.783182 -305.210646) (xy 68.735911 -305.224338)
			(xy 68.687056 -305.23027) (xy 68.637881 -305.228289) (xy 68.589662 -305.218445) (xy 68.543646 -305.200993)
			(xy 68.501025 -305.176386) (xy 68.462904 -305.145261) (xy 68.430269 -305.108424) (xy 68.403966 -305.066828)
			(xy 68.384675 -305.021552) (xy 68.372898 -304.973768) (xy 68.368938 -304.924714) (xy 68.03009 -304.924714)
			(xy 68.029595 -304.949321) (xy 68.0217 -304.997898) (xy 68.006116 -305.044579) (xy 67.983245 -305.088156)
			(xy 67.95368 -305.1275) (xy 67.918187 -305.161592) (xy 67.877684 -305.189548) (xy 67.833222 -305.210646)
			(xy 67.785951 -305.224338) (xy 67.737096 -305.23027) (xy 67.687921 -305.228289) (xy 67.639702 -305.218445)
			(xy 67.593686 -305.200993) (xy 67.551065 -305.176386) (xy 67.512944 -305.145261) (xy 67.480309 -305.108424)
			(xy 67.454006 -305.066828) (xy 67.434715 -305.021552) (xy 67.422938 -304.973768) (xy 67.418978 -304.924714)
			(xy 67.08013 -304.924714) (xy 67.079635 -304.949321) (xy 67.07174 -304.997898) (xy 67.056156 -305.044579)
			(xy 67.033285 -305.088156) (xy 67.00372 -305.1275) (xy 66.968227 -305.161592) (xy 66.927724 -305.189548)
			(xy 66.883262 -305.210646) (xy 66.835991 -305.224338) (xy 66.787136 -305.23027) (xy 66.737961 -305.228289)
			(xy 66.689742 -305.218445) (xy 66.643726 -305.200993) (xy 66.601105 -305.176386) (xy 66.562984 -305.145261)
			(xy 66.530349 -305.108424) (xy 66.504046 -305.066828) (xy 66.484755 -305.021552) (xy 66.472978 -304.973768)
			(xy 66.469018 -304.924714) (xy 66.13017 -304.924714) (xy 66.129675 -304.949321) (xy 66.12178 -304.997898)
			(xy 66.106196 -305.044579) (xy 66.083325 -305.088156) (xy 66.05376 -305.1275) (xy 66.018267 -305.161592)
			(xy 65.977764 -305.189548) (xy 65.933302 -305.210646) (xy 65.886031 -305.224338) (xy 65.837176 -305.23027)
			(xy 65.788001 -305.228289) (xy 65.739782 -305.218445) (xy 65.693766 -305.200993) (xy 65.651145 -305.176386)
			(xy 65.613024 -305.145261) (xy 65.580389 -305.108424) (xy 65.554086 -305.066828) (xy 65.534795 -305.021552)
			(xy 65.523018 -304.973768) (xy 65.519058 -304.924714) (xy 65.18021 -304.924714) (xy 65.179715 -304.949321)
			(xy 65.17182 -304.997898) (xy 65.156236 -305.044579) (xy 65.133365 -305.088156) (xy 65.1038 -305.1275)
			(xy 65.068307 -305.161592) (xy 65.027804 -305.189548) (xy 64.983342 -305.210646) (xy 64.936071 -305.224338)
			(xy 64.887216 -305.23027) (xy 64.838041 -305.228289) (xy 64.789822 -305.218445) (xy 64.743806 -305.200993)
			(xy 64.701185 -305.176386) (xy 64.663064 -305.145261) (xy 64.630429 -305.108424) (xy 64.604126 -305.066828)
			(xy 64.584835 -305.021552) (xy 64.573058 -304.973768) (xy 64.569098 -304.924714) (xy 64.23025 -304.924714)
			(xy 64.229755 -304.949321) (xy 64.22186 -304.997898) (xy 64.206276 -305.044579) (xy 64.183405 -305.088156)
			(xy 64.15384 -305.1275) (xy 64.118347 -305.161592) (xy 64.077844 -305.189548) (xy 64.033382 -305.210646)
			(xy 63.986111 -305.224338) (xy 63.937256 -305.23027) (xy 63.888081 -305.228289) (xy 63.839862 -305.218445)
			(xy 63.793846 -305.200993) (xy 63.751225 -305.176386) (xy 63.713104 -305.145261) (xy 63.680469 -305.108424)
			(xy 63.654166 -305.066828) (xy 63.634875 -305.021552) (xy 63.623098 -304.973768) (xy 63.619138 -304.924714)
			(xy 63.28029 -304.924714) (xy 63.279795 -304.949321) (xy 63.2719 -304.997898) (xy 63.256316 -305.044579)
			(xy 63.233445 -305.088156) (xy 63.20388 -305.1275) (xy 63.168387 -305.161592) (xy 63.127884 -305.189548)
			(xy 63.083422 -305.210646) (xy 63.036151 -305.224338) (xy 62.987296 -305.23027) (xy 62.938121 -305.228289)
			(xy 62.889902 -305.218445) (xy 62.843886 -305.200993) (xy 62.801265 -305.176386) (xy 62.763144 -305.145261)
			(xy 62.730509 -305.108424) (xy 62.704206 -305.066828) (xy 62.684915 -305.021552) (xy 62.673138 -304.973768)
			(xy 62.669178 -304.924714) (xy 62.330076 -304.924714) (xy 62.329581 -304.949321) (xy 62.321686 -304.997898)
			(xy 62.306102 -305.044579) (xy 62.283231 -305.088156) (xy 62.253666 -305.1275) (xy 62.218173 -305.161592)
			(xy 62.17767 -305.189548) (xy 62.133208 -305.210646) (xy 62.085937 -305.224338) (xy 62.037082 -305.23027)
			(xy 61.987907 -305.228289) (xy 61.939688 -305.218445) (xy 61.893672 -305.200993) (xy 61.851051 -305.176386)
			(xy 61.81293 -305.145261) (xy 61.780295 -305.108424) (xy 61.753992 -305.066828) (xy 61.734701 -305.021552)
			(xy 61.722924 -304.973768) (xy 61.718964 -304.924714) (xy 61.380116 -304.924714) (xy 61.379621 -304.949321)
			(xy 61.371726 -304.997898) (xy 61.356142 -305.044579) (xy 61.333271 -305.088156) (xy 61.303706 -305.1275)
			(xy 61.268213 -305.161592) (xy 61.22771 -305.189548) (xy 61.183248 -305.210646) (xy 61.135977 -305.224338)
			(xy 61.087122 -305.23027) (xy 61.037947 -305.228289) (xy 60.989728 -305.218445) (xy 60.943712 -305.200993)
			(xy 60.901091 -305.176386) (xy 60.86297 -305.145261) (xy 60.830335 -305.108424) (xy 60.804032 -305.066828)
			(xy 60.784741 -305.021552) (xy 60.772964 -304.973768) (xy 60.769004 -304.924714) (xy 60.430156 -304.924714)
			(xy 60.429661 -304.949321) (xy 60.421766 -304.997898) (xy 60.406182 -305.044579) (xy 60.383311 -305.088156)
			(xy 60.353746 -305.1275) (xy 60.318253 -305.161592) (xy 60.27775 -305.189548) (xy 60.233288 -305.210646)
			(xy 60.186017 -305.224338) (xy 60.137162 -305.23027) (xy 60.087987 -305.228289) (xy 60.039768 -305.218445)
			(xy 59.993752 -305.200993) (xy 59.951131 -305.176386) (xy 59.91301 -305.145261) (xy 59.880375 -305.108424)
			(xy 59.854072 -305.066828) (xy 59.834781 -305.021552) (xy 59.823004 -304.973768) (xy 59.819044 -304.924714)
			(xy 58.530236 -304.924714) (xy 58.529741 -304.949321) (xy 58.521846 -304.997898) (xy 58.506262 -305.044579)
			(xy 58.483391 -305.088156) (xy 58.453826 -305.1275) (xy 58.418333 -305.161592) (xy 58.37783 -305.189548)
			(xy 58.333368 -305.210646) (xy 58.286097 -305.224338) (xy 58.237242 -305.23027) (xy 58.188067 -305.228289)
			(xy 58.139848 -305.218445) (xy 58.093832 -305.200993) (xy 58.051211 -305.176386) (xy 58.01309 -305.145261)
			(xy 57.980455 -305.108424) (xy 57.954152 -305.066828) (xy 57.934861 -305.021552) (xy 57.923084 -304.973768)
			(xy 57.919124 -304.924714) (xy 57.580276 -304.924714) (xy 57.579781 -304.949321) (xy 57.571886 -304.997898)
			(xy 57.556302 -305.044579) (xy 57.533431 -305.088156) (xy 57.503866 -305.1275) (xy 57.468373 -305.161592)
			(xy 57.42787 -305.189548) (xy 57.383408 -305.210646) (xy 57.336137 -305.224338) (xy 57.287282 -305.23027)
			(xy 57.238107 -305.228289) (xy 57.189888 -305.218445) (xy 57.143872 -305.200993) (xy 57.101251 -305.176386)
			(xy 57.06313 -305.145261) (xy 57.030495 -305.108424) (xy 57.004192 -305.066828) (xy 56.984901 -305.021552)
			(xy 56.973124 -304.973768) (xy 56.969164 -304.924714) (xy 56.630062 -304.924714) (xy 56.629567 -304.949321)
			(xy 56.621672 -304.997898) (xy 56.606088 -305.044579) (xy 56.583217 -305.088156) (xy 56.553652 -305.1275)
			(xy 56.518159 -305.161592) (xy 56.477656 -305.189548) (xy 56.433194 -305.210646) (xy 56.385923 -305.224338)
			(xy 56.337068 -305.23027) (xy 56.287893 -305.228289) (xy 56.239674 -305.218445) (xy 56.193658 -305.200993)
			(xy 56.151037 -305.176386) (xy 56.112916 -305.145261) (xy 56.080281 -305.108424) (xy 56.053978 -305.066828)
			(xy 56.034687 -305.021552) (xy 56.02291 -304.973768) (xy 56.01895 -304.924714) (xy 55.680102 -304.924714)
			(xy 55.679607 -304.949321) (xy 55.671712 -304.997898) (xy 55.656128 -305.044579) (xy 55.633257 -305.088156)
			(xy 55.603692 -305.1275) (xy 55.568199 -305.161592) (xy 55.527696 -305.189548) (xy 55.483234 -305.210646)
			(xy 55.435963 -305.224338) (xy 55.387108 -305.23027) (xy 55.337933 -305.228289) (xy 55.289714 -305.218445)
			(xy 55.243698 -305.200993) (xy 55.201077 -305.176386) (xy 55.162956 -305.145261) (xy 55.130321 -305.108424)
			(xy 55.104018 -305.066828) (xy 55.084727 -305.021552) (xy 55.07295 -304.973768) (xy 55.06899 -304.924714)
			(xy 54.730142 -304.924714) (xy 54.729647 -304.949321) (xy 54.721752 -304.997898) (xy 54.706168 -305.044579)
			(xy 54.683297 -305.088156) (xy 54.653732 -305.1275) (xy 54.618239 -305.161592) (xy 54.577736 -305.189548)
			(xy 54.533274 -305.210646) (xy 54.486003 -305.224338) (xy 54.437148 -305.23027) (xy 54.387973 -305.228289)
			(xy 54.339754 -305.218445) (xy 54.293738 -305.200993) (xy 54.251117 -305.176386) (xy 54.212996 -305.145261)
			(xy 54.180361 -305.108424) (xy 54.154058 -305.066828) (xy 54.134767 -305.021552) (xy 54.12299 -304.973768)
			(xy 54.11903 -304.924714) (xy 53.780182 -304.924714) (xy 53.779687 -304.949321) (xy 53.771792 -304.997898)
			(xy 53.756208 -305.044579) (xy 53.733337 -305.088156) (xy 53.703772 -305.1275) (xy 53.668279 -305.161592)
			(xy 53.627776 -305.189548) (xy 53.583314 -305.210646) (xy 53.536043 -305.224338) (xy 53.487188 -305.23027)
			(xy 53.438013 -305.228289) (xy 53.389794 -305.218445) (xy 53.343778 -305.200993) (xy 53.301157 -305.176386)
			(xy 53.263036 -305.145261) (xy 53.230401 -305.108424) (xy 53.204098 -305.066828) (xy 53.184807 -305.021552)
			(xy 53.17303 -304.973768) (xy 53.16907 -304.924714) (xy 52.830222 -304.924714) (xy 52.829727 -304.949321)
			(xy 52.821832 -304.997898) (xy 52.806248 -305.044579) (xy 52.783377 -305.088156) (xy 52.753812 -305.1275)
			(xy 52.718319 -305.161592) (xy 52.677816 -305.189548) (xy 52.633354 -305.210646) (xy 52.586083 -305.224338)
			(xy 52.537228 -305.23027) (xy 52.488053 -305.228289) (xy 52.439834 -305.218445) (xy 52.393818 -305.200993)
			(xy 52.351197 -305.176386) (xy 52.313076 -305.145261) (xy 52.280441 -305.108424) (xy 52.254138 -305.066828)
			(xy 52.234847 -305.021552) (xy 52.22307 -304.973768) (xy 52.21911 -304.924714) (xy 51.880262 -304.924714)
			(xy 51.879767 -304.949321) (xy 51.871872 -304.997898) (xy 51.856288 -305.044579) (xy 51.833417 -305.088156)
			(xy 51.803852 -305.1275) (xy 51.768359 -305.161592) (xy 51.727856 -305.189548) (xy 51.683394 -305.210646)
			(xy 51.636123 -305.224338) (xy 51.587268 -305.23027) (xy 51.538093 -305.228289) (xy 51.489874 -305.218445)
			(xy 51.443858 -305.200993) (xy 51.401237 -305.176386) (xy 51.363116 -305.145261) (xy 51.330481 -305.108424)
			(xy 51.304178 -305.066828) (xy 51.284887 -305.021552) (xy 51.27311 -304.973768) (xy 51.26915 -304.924714)
			(xy 50.930302 -304.924714) (xy 50.929807 -304.949321) (xy 50.921912 -304.997898) (xy 50.906328 -305.044579)
			(xy 50.883457 -305.088156) (xy 50.853892 -305.1275) (xy 50.818399 -305.161592) (xy 50.777896 -305.189548)
			(xy 50.733434 -305.210646) (xy 50.686163 -305.224338) (xy 50.637308 -305.23027) (xy 50.588133 -305.228289)
			(xy 50.539914 -305.218445) (xy 50.493898 -305.200993) (xy 50.451277 -305.176386) (xy 50.413156 -305.145261)
			(xy 50.380521 -305.108424) (xy 50.354218 -305.066828) (xy 50.334927 -305.021552) (xy 50.32315 -304.973768)
			(xy 50.31919 -304.924714) (xy 49.980088 -304.924714) (xy 49.979593 -304.949321) (xy 49.971698 -304.997898)
			(xy 49.956114 -305.044579) (xy 49.933243 -305.088156) (xy 49.903678 -305.1275) (xy 49.868185 -305.161592)
			(xy 49.827682 -305.189548) (xy 49.78322 -305.210646) (xy 49.735949 -305.224338) (xy 49.687094 -305.23027)
			(xy 49.637919 -305.228289) (xy 49.5897 -305.218445) (xy 49.543684 -305.200993) (xy 49.501063 -305.176386)
			(xy 49.462942 -305.145261) (xy 49.430307 -305.108424) (xy 49.404004 -305.066828) (xy 49.384713 -305.021552)
			(xy 49.372936 -304.973768) (xy 49.368976 -304.924714) (xy 49.030128 -304.924714) (xy 49.029633 -304.949321)
			(xy 49.021738 -304.997898) (xy 49.006154 -305.044579) (xy 48.983283 -305.088156) (xy 48.953718 -305.1275)
			(xy 48.918225 -305.161592) (xy 48.877722 -305.189548) (xy 48.83326 -305.210646) (xy 48.785989 -305.224338)
			(xy 48.737134 -305.23027) (xy 48.687959 -305.228289) (xy 48.63974 -305.218445) (xy 48.593724 -305.200993)
			(xy 48.551103 -305.176386) (xy 48.512982 -305.145261) (xy 48.480347 -305.108424) (xy 48.454044 -305.066828)
			(xy 48.434753 -305.021552) (xy 48.422976 -304.973768) (xy 48.419016 -304.924714) (xy 48.080207 -304.924714)
			(xy 48.077975 -304.965962) (xy 48.067307 -305.014452) (xy 48.048934 -305.060576) (xy 48.023341 -305.103121)
			(xy 47.991203 -305.140964) (xy 47.953365 -305.17311) (xy 47.910825 -305.19871) (xy 47.864703 -305.217091)
			(xy 47.816216 -305.227768) (xy 47.76664 -305.230459) (xy 47.717281 -305.225095) (xy 47.669441 -305.211816)
			(xy 47.624379 -305.190972) (xy 47.583284 -305.163112) (xy 47.547236 -305.12897) (xy 47.517188 -305.089447)
			(xy 47.493929 -305.045582) (xy 47.478074 -304.998533) (xy 47.470039 -304.949539) (xy 47.469552 -304.924714)
			(xy 47.469731 -304.910531) (xy 47.472402 -304.882291) (xy 47.474886 -304.868326) (xy 47.477172 -304.85588)
			(xy 47.469806 -304.832258) (xy 47.392336 -304.754788) (xy 47.368714 -304.747422) (xy 47.356268 -304.749708)
			(xy 47.342302 -304.752185) (xy 47.314063 -304.754856) (xy 47.29988 -304.755042) (xy 47.27589 -304.754556)
			(xy 47.228501 -304.747048) (xy 47.182869 -304.73222) (xy 47.140119 -304.710437) (xy 47.101302 -304.682235)
			(xy 47.067374 -304.648309) (xy 47.039171 -304.609493) (xy 47.017385 -304.566744) (xy 47.002555 -304.521113)
			(xy 46.995045 -304.473724) (xy 46.994572 -304.449734) (xy 46.994754 -304.435551) (xy 46.997422 -304.407311)
			(xy 46.999906 -304.393346) (xy 47.002192 -304.3809) (xy 46.994826 -304.357278) (xy 46.917356 -304.279808)
			(xy 46.893734 -304.272442) (xy 46.881288 -304.274728) (xy 46.867322 -304.277202) (xy 46.839082 -304.279876)
			(xy 46.8249 -304.280062) (xy 46.810717 -304.279886) (xy 46.782477 -304.277214) (xy 46.768512 -304.274728)
			(xy 46.756066 -304.272442) (xy 46.732444 -304.279808) (xy 46.654974 -304.357278) (xy 46.647608 -304.3809)
			(xy 46.649894 -304.393346) (xy 46.652373 -304.407312) (xy 46.655043 -304.435551) (xy 46.655228 -304.449734)
			(xy 46.654685 -304.474552) (xy 46.64665 -304.523533) (xy 46.630796 -304.570568) (xy 46.607542 -304.61442)
			(xy 46.577499 -304.653931) (xy 46.54146 -304.688062) (xy 46.500375 -304.715913) (xy 46.455324 -304.73675)
			(xy 46.407497 -304.750024) (xy 46.358151 -304.755386) (xy 46.308589 -304.752694) (xy 46.260114 -304.742019)
			(xy 46.214006 -304.723643) (xy 46.171477 -304.698049) (xy 46.13365 -304.665912) (xy 46.10152 -304.628079)
			(xy 46.075933 -304.585546) (xy 46.057565 -304.539434) (xy 46.046899 -304.490958) (xy 46.044216 -304.441395)
			(xy 45.7051 -304.441395) (xy 45.705268 -304.449734) (xy 45.704773 -304.474341) (xy 45.696878 -304.522918)
			(xy 45.681294 -304.569599) (xy 45.658423 -304.613176) (xy 45.628858 -304.65252) (xy 45.593365 -304.686612)
			(xy 45.552862 -304.714568) (xy 45.5084 -304.735666) (xy 45.461129 -304.749358) (xy 45.412274 -304.75529)
			(xy 45.363099 -304.753309) (xy 45.31488 -304.743465) (xy 45.268864 -304.726013) (xy 45.226243 -304.701406)
			(xy 45.188122 -304.670281) (xy 45.155487 -304.633444) (xy 45.129184 -304.591848) (xy 45.109893 -304.546572)
			(xy 45.098116 -304.498788) (xy 45.094156 -304.449734) (xy 44.755054 -304.449734) (xy 44.754559 -304.474341)
			(xy 44.746664 -304.522918) (xy 44.73108 -304.569599) (xy 44.708209 -304.613176) (xy 44.678644 -304.65252)
			(xy 44.643151 -304.686612) (xy 44.602648 -304.714568) (xy 44.558186 -304.735666) (xy 44.510915 -304.749358)
			(xy 44.46206 -304.75529) (xy 44.412885 -304.753309) (xy 44.364666 -304.743465) (xy 44.31865 -304.726013)
			(xy 44.276029 -304.701406) (xy 44.237908 -304.670281) (xy 44.205273 -304.633444) (xy 44.17897 -304.591848)
			(xy 44.159679 -304.546572) (xy 44.147902 -304.498788) (xy 44.143942 -304.449734) (xy 43.805094 -304.449734)
			(xy 43.804599 -304.474341) (xy 43.796704 -304.522918) (xy 43.78112 -304.569599) (xy 43.758249 -304.613176)
			(xy 43.728684 -304.65252) (xy 43.693191 -304.686612) (xy 43.652688 -304.714568) (xy 43.608226 -304.735666)
			(xy 43.560955 -304.749358) (xy 43.5121 -304.75529) (xy 43.462925 -304.753309) (xy 43.414706 -304.743465)
			(xy 43.36869 -304.726013) (xy 43.326069 -304.701406) (xy 43.287948 -304.670281) (xy 43.255313 -304.633444)
			(xy 43.22901 -304.591848) (xy 43.209719 -304.546572) (xy 43.197942 -304.498788) (xy 43.193982 -304.449734)
			(xy 42.855048 -304.449734) (xy 42.855494 -304.457952) (xy 42.850131 -304.5073) (xy 42.836856 -304.555129)
			(xy 42.816018 -304.600181) (xy 42.788166 -304.641268) (xy 42.754033 -304.677308) (xy 42.71452 -304.707351)
			(xy 42.670666 -304.730606) (xy 42.623628 -304.746459) (xy 42.574645 -304.754494) (xy 42.549826 -304.755042)
			(xy 42.549318 -304.755042) (xy 42.524146 -304.754505) (xy 42.474491 -304.746207) (xy 42.450512 -304.738532)
			(xy 42.442892 -304.7365) (xy 42.429684 -304.734214) (xy 42.419679 -304.734705) (xy 42.401196 -304.742368)
			(xy 42.387051 -304.756521) (xy 42.379399 -304.775009) (xy 42.378884 -304.785014) (xy 42.381678 -304.798984)
			(xy 42.383964 -304.807112) (xy 42.390822 -304.827178) (xy 42.390822 -304.827686) (xy 42.392346 -304.832258)
			(xy 42.392346 -304.832512) (xy 42.394632 -304.839878) (xy 42.395648 -304.84318) (xy 42.396156 -304.845466)
			(xy 42.397426 -304.851054) (xy 42.398188 -304.85461) (xy 42.398188 -304.854864) (xy 42.399204 -304.859944)
			(xy 42.403776 -304.89017) (xy 42.403776 -304.890424) (xy 42.40403 -304.891948) (xy 42.40403 -304.893472)
			(xy 42.404284 -304.896012) (xy 42.404284 -304.896266) (xy 42.404792 -304.902616) (xy 42.404792 -304.904902)
			(xy 42.405046 -304.908712) (xy 42.405046 -304.909728) (xy 42.4053 -304.911506) (xy 42.4053 -304.91938)
			(xy 42.4053 -304.923444) (xy 42.4053 -304.925222) (xy 42.405137 -304.9401) (xy 42.402466 -304.969736)
			(xy 42.399966 -304.984404) (xy 42.399966 -304.984912) (xy 42.39895 -304.991516) (xy 42.405808 -305.014122)
			(xy 42.470324 -305.081686) (xy 42.478962 -305.089758) (xy 42.5012 -305.097704) (xy 42.512996 -305.096926)
			(xy 42.51325 -305.096926) (xy 42.522357 -305.09587) (xy 42.540658 -305.094724) (xy 42.549826 -305.09464)
			(xy 42.574642 -305.095128) (xy 42.623619 -305.103161) (xy 42.670651 -305.119012) (xy 42.714499 -305.142262)
			(xy 42.754009 -305.1723) (xy 42.788139 -305.208333) (xy 42.81599 -305.249414) (xy 42.836828 -305.294458)
			(xy 42.850105 -305.342281) (xy 42.855471 -305.391621) (xy 42.85502 -305.399948) (xy 43.193982 -305.399948)
			(xy 43.197942 -305.350894) (xy 43.209719 -305.30311) (xy 43.22901 -305.257834) (xy 43.255313 -305.216238)
			(xy 43.287948 -305.179401) (xy 43.326069 -305.148276) (xy 43.36869 -305.123669) (xy 43.414706 -305.106217)
			(xy 43.462925 -305.096373) (xy 43.5121 -305.094392) (xy 43.560955 -305.100324) (xy 43.608226 -305.114016)
			(xy 43.652688 -305.135114) (xy 43.693191 -305.16307) (xy 43.728684 -305.197162) (xy 43.758249 -305.236506)
			(xy 43.78112 -305.280083) (xy 43.796704 -305.326764) (xy 43.804599 -305.375341) (xy 43.805094 -305.399948)
			(xy 44.143942 -305.399948) (xy 44.147902 -305.350894) (xy 44.159679 -305.30311) (xy 44.17897 -305.257834)
			(xy 44.205273 -305.216238) (xy 44.237908 -305.179401) (xy 44.276029 -305.148276) (xy 44.31865 -305.123669)
			(xy 44.364666 -305.106217) (xy 44.412885 -305.096373) (xy 44.46206 -305.094392) (xy 44.510915 -305.100324)
			(xy 44.558186 -305.114016) (xy 44.602648 -305.135114) (xy 44.643151 -305.16307) (xy 44.678644 -305.197162)
			(xy 44.708209 -305.236506) (xy 44.73108 -305.280083) (xy 44.746664 -305.326764) (xy 44.754559 -305.375341)
			(xy 44.755054 -305.399948) (xy 45.094156 -305.399948) (xy 45.098116 -305.350894) (xy 45.109893 -305.30311)
			(xy 45.129184 -305.257834) (xy 45.155487 -305.216238) (xy 45.188122 -305.179401) (xy 45.226243 -305.148276)
			(xy 45.268864 -305.123669) (xy 45.31488 -305.106217) (xy 45.363099 -305.096373) (xy 45.412274 -305.094392)
			(xy 45.461129 -305.100324) (xy 45.5084 -305.114016) (xy 45.552862 -305.135114) (xy 45.593365 -305.16307)
			(xy 45.628858 -305.197162) (xy 45.658423 -305.236506) (xy 45.681294 -305.280083) (xy 45.696878 -305.326764)
			(xy 45.704773 -305.375341) (xy 45.705268 -305.399948) (xy 46.044116 -305.399948) (xy 46.048076 -305.350894)
			(xy 46.059853 -305.30311) (xy 46.079144 -305.257834) (xy 46.105447 -305.216238) (xy 46.138082 -305.179401)
			(xy 46.176203 -305.148276) (xy 46.218824 -305.123669) (xy 46.26484 -305.106217) (xy 46.313059 -305.096373)
			(xy 46.362234 -305.094392) (xy 46.411089 -305.100324) (xy 46.45836 -305.114016) (xy 46.502822 -305.135114)
			(xy 46.543325 -305.16307) (xy 46.578818 -305.197162) (xy 46.608383 -305.236506) (xy 46.631254 -305.280083)
			(xy 46.646838 -305.326764) (xy 46.654733 -305.375341) (xy 46.655228 -305.399948) (xy 46.654733 -305.424555)
			(xy 46.646838 -305.473132) (xy 46.631254 -305.519813) (xy 46.608383 -305.56339) (xy 46.578818 -305.602734)
			(xy 46.543325 -305.636826) (xy 46.502822 -305.664782) (xy 46.45836 -305.68588) (xy 46.411089 -305.699572)
			(xy 46.362234 -305.705504) (xy 46.313059 -305.703523) (xy 46.26484 -305.693679) (xy 46.218824 -305.676227)
			(xy 46.176203 -305.65162) (xy 46.138082 -305.620495) (xy 46.105447 -305.583658) (xy 46.079144 -305.542062)
			(xy 46.059853 -305.496786) (xy 46.048076 -305.449002) (xy 46.044116 -305.399948) (xy 45.705268 -305.399948)
			(xy 45.704773 -305.424555) (xy 45.696878 -305.473132) (xy 45.681294 -305.519813) (xy 45.658423 -305.56339)
			(xy 45.628858 -305.602734) (xy 45.593365 -305.636826) (xy 45.552862 -305.664782) (xy 45.5084 -305.68588)
			(xy 45.461129 -305.699572) (xy 45.412274 -305.705504) (xy 45.363099 -305.703523) (xy 45.31488 -305.693679)
			(xy 45.268864 -305.676227) (xy 45.226243 -305.65162) (xy 45.188122 -305.620495) (xy 45.155487 -305.583658)
			(xy 45.129184 -305.542062) (xy 45.109893 -305.496786) (xy 45.098116 -305.449002) (xy 45.094156 -305.399948)
			(xy 44.755054 -305.399948) (xy 44.754559 -305.424555) (xy 44.746664 -305.473132) (xy 44.73108 -305.519813)
			(xy 44.708209 -305.56339) (xy 44.678644 -305.602734) (xy 44.643151 -305.636826) (xy 44.602648 -305.664782)
			(xy 44.558186 -305.68588) (xy 44.510915 -305.699572) (xy 44.46206 -305.705504) (xy 44.412885 -305.703523)
			(xy 44.364666 -305.693679) (xy 44.31865 -305.676227) (xy 44.276029 -305.65162) (xy 44.237908 -305.620495)
			(xy 44.205273 -305.583658) (xy 44.17897 -305.542062) (xy 44.159679 -305.496786) (xy 44.147902 -305.449002)
			(xy 44.143942 -305.399948) (xy 43.805094 -305.399948) (xy 43.804599 -305.424555) (xy 43.796704 -305.473132)
			(xy 43.78112 -305.519813) (xy 43.758249 -305.56339) (xy 43.728684 -305.602734) (xy 43.693191 -305.636826)
			(xy 43.652688 -305.664782) (xy 43.608226 -305.68588) (xy 43.560955 -305.699572) (xy 43.5121 -305.705504)
			(xy 43.462925 -305.703523) (xy 43.414706 -305.693679) (xy 43.36869 -305.676227) (xy 43.326069 -305.65162)
			(xy 43.287948 -305.620495) (xy 43.255313 -305.583658) (xy 43.22901 -305.542062) (xy 43.209719 -305.496786)
			(xy 43.197942 -305.449002) (xy 43.193982 -305.399948) (xy 42.85502 -305.399948) (xy 42.852784 -305.44118)
			(xy 42.842115 -305.489651) (xy 42.823745 -305.535758) (xy 42.798158 -305.578285) (xy 42.766029 -305.616113)
			(xy 42.728203 -305.648246) (xy 42.685677 -305.673835) (xy 42.639572 -305.692208) (xy 42.591102 -305.702881)
			(xy 42.541543 -305.705572) (xy 42.492203 -305.700209) (xy 42.444379 -305.686936) (xy 42.399333 -305.666101)
			(xy 42.35825 -305.638253) (xy 42.322214 -305.604125) (xy 42.292174 -305.564618) (xy 42.26892 -305.520771)
			(xy 42.253066 -305.47374) (xy 42.24503 -305.424764) (xy 42.244518 -305.399948) (xy 42.244612 -305.39078)
			(xy 42.245759 -305.37248) (xy 42.246804 -305.363372) (xy 42.248328 -305.351688) (xy 42.2402 -305.328828)
			(xy 42.163746 -305.256184) (xy 42.14114 -305.249072) (xy 42.132504 -305.250596) (xy 42.118207 -305.252965)
			(xy 42.089337 -305.255509) (xy 42.074846 -305.255676) (xy 42.004488 -305.255676) (xy 41.993794 -305.256236)
			(xy 41.974233 -305.264889) (xy 41.966642 -305.27244) (xy 41.916096 -305.328574) (xy 41.90931 -305.336794)
			(xy 41.902735 -305.357051) (xy 41.903396 -305.36769) (xy 41.903396 -305.367944) (xy 41.905174 -305.399948)
			(xy 41.9047 -305.423936) (xy 41.897187 -305.47132) (xy 41.882355 -305.516945) (xy 41.860569 -305.559689)
			(xy 41.832364 -305.598498) (xy 41.798435 -305.632417) (xy 41.759619 -305.660612) (xy 41.716869 -305.682387)
			(xy 41.67124 -305.697207) (xy 41.623854 -305.704706) (xy 41.599866 -305.705256) (xy 41.590635 -305.705171)
			(xy 41.572207 -305.704029) (xy 41.563036 -305.70297) (xy 41.562782 -305.70297) (xy 41.550976 -305.702144)
			(xy 41.528712 -305.710083) (xy 41.52011 -305.71821) (xy 41.455594 -305.785774) (xy 41.448482 -305.808634)
			(xy 41.450514 -305.820572) (xy 41.454484 -305.847607) (xy 41.454479 -305.902248) (xy 41.450514 -305.929284)
			(xy 41.448482 -305.941222) (xy 41.455594 -305.964082) (xy 41.52011 -306.031646) (xy 41.52875 -306.039713)
			(xy 41.550986 -306.047655) (xy 41.562782 -306.046886) (xy 41.563036 -306.046886) (xy 41.572207 -306.045825)
			(xy 41.590635 -306.044683) (xy 41.599866 -306.0446) (xy 41.623861 -306.045044) (xy 41.67126 -306.052546)
			(xy 41.716902 -306.067372) (xy 41.759662 -306.089156) (xy 41.798487 -306.117361) (xy 41.832422 -306.151293)
			(xy 41.860631 -306.190116) (xy 41.882418 -306.232874) (xy 41.897248 -306.278515) (xy 41.904754 -306.325913)
			(xy 41.905174 -306.349908) (xy 41.903396 -306.381658) (xy 41.903396 -306.382166) (xy 41.902877 -306.392788)
			(xy 41.909434 -306.412993) (xy 41.916096 -306.421282) (xy 41.966642 -306.477416) (xy 41.974159 -306.485075)
			(xy 41.993765 -306.49375) (xy 42.004488 -306.49418) (xy 42.074846 -306.49418) (xy 42.089274 -306.494342)
			(xy 42.118018 -306.496883) (xy 42.13225 -306.49926) (xy 42.132758 -306.49926) (xy 42.14114 -306.500784)
			(xy 42.163746 -306.493672) (xy 42.2402 -306.421028) (xy 42.248328 -306.398168) (xy 42.246804 -306.386484)
			(xy 42.24575 -306.377376) (xy 42.244607 -306.359076) (xy 42.244518 -306.349908) (xy 42.245003 -306.32509)
			(xy 42.253032 -306.276106) (xy 42.26888 -306.229067) (xy 42.292129 -306.185212) (xy 42.322166 -306.145695)
			(xy 42.358201 -306.111559) (xy 42.399284 -306.083702) (xy 42.444332 -306.062858) (xy 42.492159 -306.049576)
			(xy 42.541505 -306.044208) (xy 42.591069 -306.046892) (xy 42.639546 -306.057561) (xy 42.685659 -306.075931)
			(xy 42.728192 -306.101519) (xy 42.766025 -306.133651) (xy 42.798161 -306.171481) (xy 42.823754 -306.214011)
			(xy 42.842129 -306.260121) (xy 42.852803 -306.308597) (xy 42.855045 -306.349908) (xy 43.193982 -306.349908)
			(xy 43.197942 -306.300854) (xy 43.209719 -306.25307) (xy 43.22901 -306.207794) (xy 43.255313 -306.166198)
			(xy 43.287948 -306.129361) (xy 43.326069 -306.098236) (xy 43.36869 -306.073629) (xy 43.414706 -306.056177)
			(xy 43.462925 -306.046333) (xy 43.5121 -306.044352) (xy 43.560955 -306.050284) (xy 43.608226 -306.063976)
			(xy 43.652688 -306.085074) (xy 43.693191 -306.11303) (xy 43.728684 -306.147122) (xy 43.758249 -306.186466)
			(xy 43.78112 -306.230043) (xy 43.796704 -306.276724) (xy 43.804599 -306.325301) (xy 43.805094 -306.349908)
			(xy 44.143942 -306.349908) (xy 44.147902 -306.300854) (xy 44.159679 -306.25307) (xy 44.17897 -306.207794)
			(xy 44.205273 -306.166198) (xy 44.237908 -306.129361) (xy 44.276029 -306.098236) (xy 44.31865 -306.073629)
			(xy 44.364666 -306.056177) (xy 44.412885 -306.046333) (xy 44.46206 -306.044352) (xy 44.510915 -306.050284)
			(xy 44.558186 -306.063976) (xy 44.602648 -306.085074) (xy 44.643151 -306.11303) (xy 44.678644 -306.147122)
			(xy 44.708209 -306.186466) (xy 44.73108 -306.230043) (xy 44.746664 -306.276724) (xy 44.754559 -306.325301)
			(xy 44.755054 -306.349908) (xy 45.094156 -306.349908) (xy 45.098116 -306.300854) (xy 45.109893 -306.25307)
			(xy 45.129184 -306.207794) (xy 45.155487 -306.166198) (xy 45.188122 -306.129361) (xy 45.226243 -306.098236)
			(xy 45.268864 -306.073629) (xy 45.31488 -306.056177) (xy 45.363099 -306.046333) (xy 45.412274 -306.044352)
			(xy 45.461129 -306.050284) (xy 45.5084 -306.063976) (xy 45.552862 -306.085074) (xy 45.593365 -306.11303)
			(xy 45.628858 -306.147122) (xy 45.658423 -306.186466) (xy 45.681294 -306.230043) (xy 45.696878 -306.276724)
			(xy 45.704773 -306.325301) (xy 45.705268 -306.349908) (xy 46.044116 -306.349908) (xy 46.048076 -306.300854)
			(xy 46.059853 -306.25307) (xy 46.079144 -306.207794) (xy 46.105447 -306.166198) (xy 46.138082 -306.129361)
			(xy 46.176203 -306.098236) (xy 46.218824 -306.073629) (xy 46.26484 -306.056177) (xy 46.313059 -306.046333)
			(xy 46.362234 -306.044352) (xy 46.411089 -306.050284) (xy 46.45836 -306.063976) (xy 46.502822 -306.085074)
			(xy 46.543325 -306.11303) (xy 46.578818 -306.147122) (xy 46.608383 -306.186466) (xy 46.631254 -306.230043)
			(xy 46.646838 -306.276724) (xy 46.654733 -306.325301) (xy 46.655061 -306.341629) (xy 46.994189 -306.341629)
			(xy 46.999554 -306.292281) (xy 47.012832 -306.24445) (xy 47.033673 -306.199398) (xy 47.061528 -306.15831)
			(xy 47.095663 -306.122271) (xy 47.13518 -306.092228) (xy 47.179035 -306.068974) (xy 47.226075 -306.053121)
			(xy 47.27506 -306.045087) (xy 47.29988 -306.0446) (xy 47.314063 -306.044779) (xy 47.342303 -306.04745)
			(xy 47.356268 -306.049934) (xy 47.37024 -306.052045) (xy 47.398366 -306.049473) (xy 47.424709 -306.039292)
			(xy 47.447254 -306.022281) (xy 47.464274 -305.999743) (xy 47.474465 -305.973403) (xy 47.477047 -305.945279)
			(xy 47.474886 -305.931316) (xy 47.472402 -305.917351) (xy 47.469735 -305.889111) (xy 47.469552 -305.874928)
			(xy 47.470048 -305.850104) (xy 47.478076 -305.801108) (xy 47.493925 -305.754058) (xy 47.517178 -305.710191)
			(xy 47.547222 -305.670664) (xy 47.583264 -305.636519) (xy 47.624357 -305.608655) (xy 47.669416 -305.587806)
			(xy 47.717254 -305.574522) (xy 47.766612 -305.569153) (xy 47.816188 -305.57184) (xy 47.864676 -305.582513)
			(xy 47.910798 -305.60089) (xy 47.953339 -305.626487) (xy 47.991179 -305.658629) (xy 48.02332 -305.69647)
			(xy 48.048915 -305.739013) (xy 48.06729 -305.785136) (xy 48.077961 -305.833624) (xy 48.080198 -305.874928)
			(xy 48.419016 -305.874928) (xy 48.422976 -305.825874) (xy 48.434753 -305.77809) (xy 48.454044 -305.732814)
			(xy 48.480347 -305.691218) (xy 48.512982 -305.654381) (xy 48.551103 -305.623256) (xy 48.593724 -305.598649)
			(xy 48.63974 -305.581197) (xy 48.687959 -305.571353) (xy 48.737134 -305.569372) (xy 48.785989 -305.575304)
			(xy 48.83326 -305.588996) (xy 48.877722 -305.610094) (xy 48.918225 -305.63805) (xy 48.953718 -305.672142)
			(xy 48.983283 -305.711486) (xy 49.006154 -305.755063) (xy 49.021738 -305.801744) (xy 49.029633 -305.850321)
			(xy 49.030128 -305.874928) (xy 49.368976 -305.874928) (xy 49.372936 -305.825874) (xy 49.384713 -305.77809)
			(xy 49.404004 -305.732814) (xy 49.430307 -305.691218) (xy 49.462942 -305.654381) (xy 49.501063 -305.623256)
			(xy 49.543684 -305.598649) (xy 49.5897 -305.581197) (xy 49.637919 -305.571353) (xy 49.687094 -305.569372)
			(xy 49.735949 -305.575304) (xy 49.78322 -305.588996) (xy 49.827682 -305.610094) (xy 49.868185 -305.63805)
			(xy 49.903678 -305.672142) (xy 49.933243 -305.711486) (xy 49.956114 -305.755063) (xy 49.971698 -305.801744)
			(xy 49.979593 -305.850321) (xy 49.980088 -305.874928) (xy 50.31919 -305.874928) (xy 50.32315 -305.825874)
			(xy 50.334927 -305.77809) (xy 50.354218 -305.732814) (xy 50.380521 -305.691218) (xy 50.413156 -305.654381)
			(xy 50.451277 -305.623256) (xy 50.493898 -305.598649) (xy 50.539914 -305.581197) (xy 50.588133 -305.571353)
			(xy 50.637308 -305.569372) (xy 50.686163 -305.575304) (xy 50.733434 -305.588996) (xy 50.777896 -305.610094)
			(xy 50.818399 -305.63805) (xy 50.853892 -305.672142) (xy 50.883457 -305.711486) (xy 50.906328 -305.755063)
			(xy 50.921912 -305.801744) (xy 50.929807 -305.850321) (xy 50.930302 -305.874928) (xy 51.26915 -305.874928)
			(xy 51.27311 -305.825874) (xy 51.284887 -305.77809) (xy 51.304178 -305.732814) (xy 51.330481 -305.691218)
			(xy 51.363116 -305.654381) (xy 51.401237 -305.623256) (xy 51.443858 -305.598649) (xy 51.489874 -305.581197)
			(xy 51.538093 -305.571353) (xy 51.587268 -305.569372) (xy 51.636123 -305.575304) (xy 51.683394 -305.588996)
			(xy 51.727856 -305.610094) (xy 51.768359 -305.63805) (xy 51.803852 -305.672142) (xy 51.833417 -305.711486)
			(xy 51.856288 -305.755063) (xy 51.871872 -305.801744) (xy 51.879767 -305.850321) (xy 51.880262 -305.874928)
			(xy 52.21911 -305.874928) (xy 52.22307 -305.825874) (xy 52.234847 -305.77809) (xy 52.254138 -305.732814)
			(xy 52.280441 -305.691218) (xy 52.313076 -305.654381) (xy 52.351197 -305.623256) (xy 52.393818 -305.598649)
			(xy 52.439834 -305.581197) (xy 52.488053 -305.571353) (xy 52.537228 -305.569372) (xy 52.586083 -305.575304)
			(xy 52.633354 -305.588996) (xy 52.677816 -305.610094) (xy 52.718319 -305.63805) (xy 52.753812 -305.672142)
			(xy 52.783377 -305.711486) (xy 52.806248 -305.755063) (xy 52.821832 -305.801744) (xy 52.829727 -305.850321)
			(xy 52.830222 -305.874928) (xy 53.16907 -305.874928) (xy 53.17303 -305.825874) (xy 53.184807 -305.77809)
			(xy 53.204098 -305.732814) (xy 53.230401 -305.691218) (xy 53.263036 -305.654381) (xy 53.301157 -305.623256)
			(xy 53.343778 -305.598649) (xy 53.389794 -305.581197) (xy 53.438013 -305.571353) (xy 53.487188 -305.569372)
			(xy 53.536043 -305.575304) (xy 53.583314 -305.588996) (xy 53.627776 -305.610094) (xy 53.668279 -305.63805)
			(xy 53.703772 -305.672142) (xy 53.733337 -305.711486) (xy 53.756208 -305.755063) (xy 53.771792 -305.801744)
			(xy 53.779687 -305.850321) (xy 53.780182 -305.874928) (xy 54.11903 -305.874928) (xy 54.12299 -305.825874)
			(xy 54.134767 -305.77809) (xy 54.154058 -305.732814) (xy 54.180361 -305.691218) (xy 54.212996 -305.654381)
			(xy 54.251117 -305.623256) (xy 54.293738 -305.598649) (xy 54.339754 -305.581197) (xy 54.387973 -305.571353)
			(xy 54.437148 -305.569372) (xy 54.486003 -305.575304) (xy 54.533274 -305.588996) (xy 54.577736 -305.610094)
			(xy 54.618239 -305.63805) (xy 54.653732 -305.672142) (xy 54.683297 -305.711486) (xy 54.706168 -305.755063)
			(xy 54.721752 -305.801744) (xy 54.729647 -305.850321) (xy 54.730142 -305.874928) (xy 55.06899 -305.874928)
			(xy 55.07295 -305.825874) (xy 55.084727 -305.77809) (xy 55.104018 -305.732814) (xy 55.130321 -305.691218)
			(xy 55.162956 -305.654381) (xy 55.201077 -305.623256) (xy 55.243698 -305.598649) (xy 55.289714 -305.581197)
			(xy 55.337933 -305.571353) (xy 55.387108 -305.569372) (xy 55.435963 -305.575304) (xy 55.483234 -305.588996)
			(xy 55.527696 -305.610094) (xy 55.568199 -305.63805) (xy 55.603692 -305.672142) (xy 55.633257 -305.711486)
			(xy 55.656128 -305.755063) (xy 55.671712 -305.801744) (xy 55.679607 -305.850321) (xy 55.680102 -305.874928)
			(xy 56.01895 -305.874928) (xy 56.02291 -305.825874) (xy 56.034687 -305.77809) (xy 56.053978 -305.732814)
			(xy 56.080281 -305.691218) (xy 56.112916 -305.654381) (xy 56.151037 -305.623256) (xy 56.193658 -305.598649)
			(xy 56.239674 -305.581197) (xy 56.287893 -305.571353) (xy 56.337068 -305.569372) (xy 56.385923 -305.575304)
			(xy 56.433194 -305.588996) (xy 56.477656 -305.610094) (xy 56.518159 -305.63805) (xy 56.553652 -305.672142)
			(xy 56.583217 -305.711486) (xy 56.606088 -305.755063) (xy 56.621672 -305.801744) (xy 56.629567 -305.850321)
			(xy 56.630062 -305.874928) (xy 56.969164 -305.874928) (xy 56.973124 -305.825874) (xy 56.984901 -305.77809)
			(xy 57.004192 -305.732814) (xy 57.030495 -305.691218) (xy 57.06313 -305.654381) (xy 57.101251 -305.623256)
			(xy 57.143872 -305.598649) (xy 57.189888 -305.581197) (xy 57.238107 -305.571353) (xy 57.287282 -305.569372)
			(xy 57.336137 -305.575304) (xy 57.383408 -305.588996) (xy 57.42787 -305.610094) (xy 57.468373 -305.63805)
			(xy 57.503866 -305.672142) (xy 57.533431 -305.711486) (xy 57.556302 -305.755063) (xy 57.571886 -305.801744)
			(xy 57.579781 -305.850321) (xy 57.580276 -305.874928) (xy 57.919124 -305.874928) (xy 57.923084 -305.825874)
			(xy 57.934861 -305.77809) (xy 57.954152 -305.732814) (xy 57.980455 -305.691218) (xy 58.01309 -305.654381)
			(xy 58.051211 -305.623256) (xy 58.093832 -305.598649) (xy 58.139848 -305.581197) (xy 58.188067 -305.571353)
			(xy 58.237242 -305.569372) (xy 58.286097 -305.575304) (xy 58.333368 -305.588996) (xy 58.37783 -305.610094)
			(xy 58.418333 -305.63805) (xy 58.453826 -305.672142) (xy 58.483391 -305.711486) (xy 58.506262 -305.755063)
			(xy 58.521846 -305.801744) (xy 58.529741 -305.850321) (xy 58.530236 -305.874928) (xy 59.819044 -305.874928)
			(xy 59.823004 -305.825874) (xy 59.834781 -305.77809) (xy 59.854072 -305.732814) (xy 59.880375 -305.691218)
			(xy 59.91301 -305.654381) (xy 59.951131 -305.623256) (xy 59.993752 -305.598649) (xy 60.039768 -305.581197)
			(xy 60.087987 -305.571353) (xy 60.137162 -305.569372) (xy 60.186017 -305.575304) (xy 60.233288 -305.588996)
			(xy 60.27775 -305.610094) (xy 60.318253 -305.63805) (xy 60.353746 -305.672142) (xy 60.383311 -305.711486)
			(xy 60.406182 -305.755063) (xy 60.421766 -305.801744) (xy 60.429661 -305.850321) (xy 60.430156 -305.874928)
			(xy 60.769004 -305.874928) (xy 60.772964 -305.825874) (xy 60.784741 -305.77809) (xy 60.804032 -305.732814)
			(xy 60.830335 -305.691218) (xy 60.86297 -305.654381) (xy 60.901091 -305.623256) (xy 60.943712 -305.598649)
			(xy 60.989728 -305.581197) (xy 61.037947 -305.571353) (xy 61.087122 -305.569372) (xy 61.135977 -305.575304)
			(xy 61.183248 -305.588996) (xy 61.22771 -305.610094) (xy 61.268213 -305.63805) (xy 61.303706 -305.672142)
			(xy 61.333271 -305.711486) (xy 61.356142 -305.755063) (xy 61.371726 -305.801744) (xy 61.379621 -305.850321)
			(xy 61.380116 -305.874928) (xy 61.718964 -305.874928) (xy 61.722924 -305.825874) (xy 61.734701 -305.77809)
			(xy 61.753992 -305.732814) (xy 61.780295 -305.691218) (xy 61.81293 -305.654381) (xy 61.851051 -305.623256)
			(xy 61.893672 -305.598649) (xy 61.939688 -305.581197) (xy 61.987907 -305.571353) (xy 62.037082 -305.569372)
			(xy 62.085937 -305.575304) (xy 62.133208 -305.588996) (xy 62.17767 -305.610094) (xy 62.218173 -305.63805)
			(xy 62.253666 -305.672142) (xy 62.283231 -305.711486) (xy 62.306102 -305.755063) (xy 62.321686 -305.801744)
			(xy 62.329581 -305.850321) (xy 62.330076 -305.874928) (xy 62.669178 -305.874928) (xy 62.673138 -305.825874)
			(xy 62.684915 -305.77809) (xy 62.704206 -305.732814) (xy 62.730509 -305.691218) (xy 62.763144 -305.654381)
			(xy 62.801265 -305.623256) (xy 62.843886 -305.598649) (xy 62.889902 -305.581197) (xy 62.938121 -305.571353)
			(xy 62.987296 -305.569372) (xy 63.036151 -305.575304) (xy 63.083422 -305.588996) (xy 63.127884 -305.610094)
			(xy 63.168387 -305.63805) (xy 63.20388 -305.672142) (xy 63.233445 -305.711486) (xy 63.256316 -305.755063)
			(xy 63.2719 -305.801744) (xy 63.279795 -305.850321) (xy 63.28029 -305.874928) (xy 63.619138 -305.874928)
			(xy 63.623098 -305.825874) (xy 63.634875 -305.77809) (xy 63.654166 -305.732814) (xy 63.680469 -305.691218)
			(xy 63.713104 -305.654381) (xy 63.751225 -305.623256) (xy 63.793846 -305.598649) (xy 63.839862 -305.581197)
			(xy 63.888081 -305.571353) (xy 63.937256 -305.569372) (xy 63.986111 -305.575304) (xy 64.033382 -305.588996)
			(xy 64.077844 -305.610094) (xy 64.118347 -305.63805) (xy 64.15384 -305.672142) (xy 64.183405 -305.711486)
			(xy 64.206276 -305.755063) (xy 64.22186 -305.801744) (xy 64.229755 -305.850321) (xy 64.23025 -305.874928)
			(xy 64.569098 -305.874928) (xy 64.573058 -305.825874) (xy 64.584835 -305.77809) (xy 64.604126 -305.732814)
			(xy 64.630429 -305.691218) (xy 64.663064 -305.654381) (xy 64.701185 -305.623256) (xy 64.743806 -305.598649)
			(xy 64.789822 -305.581197) (xy 64.838041 -305.571353) (xy 64.887216 -305.569372) (xy 64.936071 -305.575304)
			(xy 64.983342 -305.588996) (xy 65.027804 -305.610094) (xy 65.068307 -305.63805) (xy 65.1038 -305.672142)
			(xy 65.133365 -305.711486) (xy 65.156236 -305.755063) (xy 65.17182 -305.801744) (xy 65.179715 -305.850321)
			(xy 65.18021 -305.874928) (xy 65.519058 -305.874928) (xy 65.523018 -305.825874) (xy 65.534795 -305.77809)
			(xy 65.554086 -305.732814) (xy 65.580389 -305.691218) (xy 65.613024 -305.654381) (xy 65.651145 -305.623256)
			(xy 65.693766 -305.598649) (xy 65.739782 -305.581197) (xy 65.788001 -305.571353) (xy 65.837176 -305.569372)
			(xy 65.886031 -305.575304) (xy 65.933302 -305.588996) (xy 65.977764 -305.610094) (xy 66.018267 -305.63805)
			(xy 66.05376 -305.672142) (xy 66.083325 -305.711486) (xy 66.106196 -305.755063) (xy 66.12178 -305.801744)
			(xy 66.129675 -305.850321) (xy 66.13017 -305.874928) (xy 66.469018 -305.874928) (xy 66.472978 -305.825874)
			(xy 66.484755 -305.77809) (xy 66.504046 -305.732814) (xy 66.530349 -305.691218) (xy 66.562984 -305.654381)
			(xy 66.601105 -305.623256) (xy 66.643726 -305.598649) (xy 66.689742 -305.581197) (xy 66.737961 -305.571353)
			(xy 66.787136 -305.569372) (xy 66.835991 -305.575304) (xy 66.883262 -305.588996) (xy 66.927724 -305.610094)
			(xy 66.968227 -305.63805) (xy 67.00372 -305.672142) (xy 67.033285 -305.711486) (xy 67.056156 -305.755063)
			(xy 67.07174 -305.801744) (xy 67.079635 -305.850321) (xy 67.08013 -305.874928) (xy 67.418978 -305.874928)
			(xy 67.422938 -305.825874) (xy 67.434715 -305.77809) (xy 67.454006 -305.732814) (xy 67.480309 -305.691218)
			(xy 67.512944 -305.654381) (xy 67.551065 -305.623256) (xy 67.593686 -305.598649) (xy 67.639702 -305.581197)
			(xy 67.687921 -305.571353) (xy 67.737096 -305.569372) (xy 67.785951 -305.575304) (xy 67.833222 -305.588996)
			(xy 67.877684 -305.610094) (xy 67.918187 -305.63805) (xy 67.95368 -305.672142) (xy 67.983245 -305.711486)
			(xy 68.006116 -305.755063) (xy 68.0217 -305.801744) (xy 68.029595 -305.850321) (xy 68.03009 -305.874928)
			(xy 68.368938 -305.874928) (xy 68.372898 -305.825874) (xy 68.384675 -305.77809) (xy 68.403966 -305.732814)
			(xy 68.430269 -305.691218) (xy 68.462904 -305.654381) (xy 68.501025 -305.623256) (xy 68.543646 -305.598649)
			(xy 68.589662 -305.581197) (xy 68.637881 -305.571353) (xy 68.687056 -305.569372) (xy 68.735911 -305.575304)
			(xy 68.783182 -305.588996) (xy 68.827644 -305.610094) (xy 68.868147 -305.63805) (xy 68.90364 -305.672142)
			(xy 68.933205 -305.711486) (xy 68.956076 -305.755063) (xy 68.97166 -305.801744) (xy 68.979555 -305.850321)
			(xy 68.98005 -305.874928) (xy 68.979555 -305.899535) (xy 68.97166 -305.948112) (xy 68.956076 -305.994793)
			(xy 68.933205 -306.03837) (xy 68.90364 -306.077714) (xy 68.868147 -306.111806) (xy 68.827644 -306.139762)
			(xy 68.783182 -306.16086) (xy 68.735911 -306.174552) (xy 68.687056 -306.180484) (xy 68.637881 -306.178503)
			(xy 68.589662 -306.168659) (xy 68.543646 -306.151207) (xy 68.501025 -306.1266) (xy 68.462904 -306.095475)
			(xy 68.430269 -306.058638) (xy 68.403966 -306.017042) (xy 68.384675 -305.971766) (xy 68.372898 -305.923982)
			(xy 68.368938 -305.874928) (xy 68.03009 -305.874928) (xy 68.029595 -305.899535) (xy 68.0217 -305.948112)
			(xy 68.006116 -305.994793) (xy 67.983245 -306.03837) (xy 67.95368 -306.077714) (xy 67.918187 -306.111806)
			(xy 67.877684 -306.139762) (xy 67.833222 -306.16086) (xy 67.785951 -306.174552) (xy 67.737096 -306.180484)
			(xy 67.687921 -306.178503) (xy 67.639702 -306.168659) (xy 67.593686 -306.151207) (xy 67.551065 -306.1266)
			(xy 67.512944 -306.095475) (xy 67.480309 -306.058638) (xy 67.454006 -306.017042) (xy 67.434715 -305.971766)
			(xy 67.422938 -305.923982) (xy 67.418978 -305.874928) (xy 67.08013 -305.874928) (xy 67.079635 -305.899535)
			(xy 67.07174 -305.948112) (xy 67.056156 -305.994793) (xy 67.033285 -306.03837) (xy 67.00372 -306.077714)
			(xy 66.968227 -306.111806) (xy 66.927724 -306.139762) (xy 66.883262 -306.16086) (xy 66.835991 -306.174552)
			(xy 66.787136 -306.180484) (xy 66.737961 -306.178503) (xy 66.689742 -306.168659) (xy 66.643726 -306.151207)
			(xy 66.601105 -306.1266) (xy 66.562984 -306.095475) (xy 66.530349 -306.058638) (xy 66.504046 -306.017042)
			(xy 66.484755 -305.971766) (xy 66.472978 -305.923982) (xy 66.469018 -305.874928) (xy 66.13017 -305.874928)
			(xy 66.129675 -305.899535) (xy 66.12178 -305.948112) (xy 66.106196 -305.994793) (xy 66.083325 -306.03837)
			(xy 66.05376 -306.077714) (xy 66.018267 -306.111806) (xy 65.977764 -306.139762) (xy 65.933302 -306.16086)
			(xy 65.886031 -306.174552) (xy 65.837176 -306.180484) (xy 65.788001 -306.178503) (xy 65.739782 -306.168659)
			(xy 65.693766 -306.151207) (xy 65.651145 -306.1266) (xy 65.613024 -306.095475) (xy 65.580389 -306.058638)
			(xy 65.554086 -306.017042) (xy 65.534795 -305.971766) (xy 65.523018 -305.923982) (xy 65.519058 -305.874928)
			(xy 65.18021 -305.874928) (xy 65.179715 -305.899535) (xy 65.17182 -305.948112) (xy 65.156236 -305.994793)
			(xy 65.133365 -306.03837) (xy 65.1038 -306.077714) (xy 65.068307 -306.111806) (xy 65.027804 -306.139762)
			(xy 64.983342 -306.16086) (xy 64.936071 -306.174552) (xy 64.887216 -306.180484) (xy 64.838041 -306.178503)
			(xy 64.789822 -306.168659) (xy 64.743806 -306.151207) (xy 64.701185 -306.1266) (xy 64.663064 -306.095475)
			(xy 64.630429 -306.058638) (xy 64.604126 -306.017042) (xy 64.584835 -305.971766) (xy 64.573058 -305.923982)
			(xy 64.569098 -305.874928) (xy 64.23025 -305.874928) (xy 64.229755 -305.899535) (xy 64.22186 -305.948112)
			(xy 64.206276 -305.994793) (xy 64.183405 -306.03837) (xy 64.15384 -306.077714) (xy 64.118347 -306.111806)
			(xy 64.077844 -306.139762) (xy 64.033382 -306.16086) (xy 63.986111 -306.174552) (xy 63.937256 -306.180484)
			(xy 63.888081 -306.178503) (xy 63.839862 -306.168659) (xy 63.793846 -306.151207) (xy 63.751225 -306.1266)
			(xy 63.713104 -306.095475) (xy 63.680469 -306.058638) (xy 63.654166 -306.017042) (xy 63.634875 -305.971766)
			(xy 63.623098 -305.923982) (xy 63.619138 -305.874928) (xy 63.28029 -305.874928) (xy 63.279795 -305.899535)
			(xy 63.2719 -305.948112) (xy 63.256316 -305.994793) (xy 63.233445 -306.03837) (xy 63.20388 -306.077714)
			(xy 63.168387 -306.111806) (xy 63.127884 -306.139762) (xy 63.083422 -306.16086) (xy 63.036151 -306.174552)
			(xy 62.987296 -306.180484) (xy 62.938121 -306.178503) (xy 62.889902 -306.168659) (xy 62.843886 -306.151207)
			(xy 62.801265 -306.1266) (xy 62.763144 -306.095475) (xy 62.730509 -306.058638) (xy 62.704206 -306.017042)
			(xy 62.684915 -305.971766) (xy 62.673138 -305.923982) (xy 62.669178 -305.874928) (xy 62.330076 -305.874928)
			(xy 62.329581 -305.899535) (xy 62.321686 -305.948112) (xy 62.306102 -305.994793) (xy 62.283231 -306.03837)
			(xy 62.253666 -306.077714) (xy 62.218173 -306.111806) (xy 62.17767 -306.139762) (xy 62.133208 -306.16086)
			(xy 62.085937 -306.174552) (xy 62.037082 -306.180484) (xy 61.987907 -306.178503) (xy 61.939688 -306.168659)
			(xy 61.893672 -306.151207) (xy 61.851051 -306.1266) (xy 61.81293 -306.095475) (xy 61.780295 -306.058638)
			(xy 61.753992 -306.017042) (xy 61.734701 -305.971766) (xy 61.722924 -305.923982) (xy 61.718964 -305.874928)
			(xy 61.380116 -305.874928) (xy 61.379621 -305.899535) (xy 61.371726 -305.948112) (xy 61.356142 -305.994793)
			(xy 61.333271 -306.03837) (xy 61.303706 -306.077714) (xy 61.268213 -306.111806) (xy 61.22771 -306.139762)
			(xy 61.183248 -306.16086) (xy 61.135977 -306.174552) (xy 61.087122 -306.180484) (xy 61.037947 -306.178503)
			(xy 60.989728 -306.168659) (xy 60.943712 -306.151207) (xy 60.901091 -306.1266) (xy 60.86297 -306.095475)
			(xy 60.830335 -306.058638) (xy 60.804032 -306.017042) (xy 60.784741 -305.971766) (xy 60.772964 -305.923982)
			(xy 60.769004 -305.874928) (xy 60.430156 -305.874928) (xy 60.429661 -305.899535) (xy 60.421766 -305.948112)
			(xy 60.406182 -305.994793) (xy 60.383311 -306.03837) (xy 60.353746 -306.077714) (xy 60.318253 -306.111806)
			(xy 60.27775 -306.139762) (xy 60.233288 -306.16086) (xy 60.186017 -306.174552) (xy 60.137162 -306.180484)
			(xy 60.087987 -306.178503) (xy 60.039768 -306.168659) (xy 59.993752 -306.151207) (xy 59.951131 -306.1266)
			(xy 59.91301 -306.095475) (xy 59.880375 -306.058638) (xy 59.854072 -306.017042) (xy 59.834781 -305.971766)
			(xy 59.823004 -305.923982) (xy 59.819044 -305.874928) (xy 58.530236 -305.874928) (xy 58.529741 -305.899535)
			(xy 58.521846 -305.948112) (xy 58.506262 -305.994793) (xy 58.483391 -306.03837) (xy 58.453826 -306.077714)
			(xy 58.418333 -306.111806) (xy 58.37783 -306.139762) (xy 58.333368 -306.16086) (xy 58.286097 -306.174552)
			(xy 58.237242 -306.180484) (xy 58.188067 -306.178503) (xy 58.139848 -306.168659) (xy 58.093832 -306.151207)
			(xy 58.051211 -306.1266) (xy 58.01309 -306.095475) (xy 57.980455 -306.058638) (xy 57.954152 -306.017042)
			(xy 57.934861 -305.971766) (xy 57.923084 -305.923982) (xy 57.919124 -305.874928) (xy 57.580276 -305.874928)
			(xy 57.579781 -305.899535) (xy 57.571886 -305.948112) (xy 57.556302 -305.994793) (xy 57.533431 -306.03837)
			(xy 57.503866 -306.077714) (xy 57.468373 -306.111806) (xy 57.42787 -306.139762) (xy 57.383408 -306.16086)
			(xy 57.336137 -306.174552) (xy 57.287282 -306.180484) (xy 57.238107 -306.178503) (xy 57.189888 -306.168659)
			(xy 57.143872 -306.151207) (xy 57.101251 -306.1266) (xy 57.06313 -306.095475) (xy 57.030495 -306.058638)
			(xy 57.004192 -306.017042) (xy 56.984901 -305.971766) (xy 56.973124 -305.923982) (xy 56.969164 -305.874928)
			(xy 56.630062 -305.874928) (xy 56.629567 -305.899535) (xy 56.621672 -305.948112) (xy 56.606088 -305.994793)
			(xy 56.583217 -306.03837) (xy 56.553652 -306.077714) (xy 56.518159 -306.111806) (xy 56.477656 -306.139762)
			(xy 56.433194 -306.16086) (xy 56.385923 -306.174552) (xy 56.337068 -306.180484) (xy 56.287893 -306.178503)
			(xy 56.239674 -306.168659) (xy 56.193658 -306.151207) (xy 56.151037 -306.1266) (xy 56.112916 -306.095475)
			(xy 56.080281 -306.058638) (xy 56.053978 -306.017042) (xy 56.034687 -305.971766) (xy 56.02291 -305.923982)
			(xy 56.01895 -305.874928) (xy 55.680102 -305.874928) (xy 55.679607 -305.899535) (xy 55.671712 -305.948112)
			(xy 55.656128 -305.994793) (xy 55.633257 -306.03837) (xy 55.603692 -306.077714) (xy 55.568199 -306.111806)
			(xy 55.527696 -306.139762) (xy 55.483234 -306.16086) (xy 55.435963 -306.174552) (xy 55.387108 -306.180484)
			(xy 55.337933 -306.178503) (xy 55.289714 -306.168659) (xy 55.243698 -306.151207) (xy 55.201077 -306.1266)
			(xy 55.162956 -306.095475) (xy 55.130321 -306.058638) (xy 55.104018 -306.017042) (xy 55.084727 -305.971766)
			(xy 55.07295 -305.923982) (xy 55.06899 -305.874928) (xy 54.730142 -305.874928) (xy 54.729647 -305.899535)
			(xy 54.721752 -305.948112) (xy 54.706168 -305.994793) (xy 54.683297 -306.03837) (xy 54.653732 -306.077714)
			(xy 54.618239 -306.111806) (xy 54.577736 -306.139762) (xy 54.533274 -306.16086) (xy 54.486003 -306.174552)
			(xy 54.437148 -306.180484) (xy 54.387973 -306.178503) (xy 54.339754 -306.168659) (xy 54.293738 -306.151207)
			(xy 54.251117 -306.1266) (xy 54.212996 -306.095475) (xy 54.180361 -306.058638) (xy 54.154058 -306.017042)
			(xy 54.134767 -305.971766) (xy 54.12299 -305.923982) (xy 54.11903 -305.874928) (xy 53.780182 -305.874928)
			(xy 53.779687 -305.899535) (xy 53.771792 -305.948112) (xy 53.756208 -305.994793) (xy 53.733337 -306.03837)
			(xy 53.703772 -306.077714) (xy 53.668279 -306.111806) (xy 53.627776 -306.139762) (xy 53.583314 -306.16086)
			(xy 53.536043 -306.174552) (xy 53.487188 -306.180484) (xy 53.438013 -306.178503) (xy 53.389794 -306.168659)
			(xy 53.343778 -306.151207) (xy 53.301157 -306.1266) (xy 53.263036 -306.095475) (xy 53.230401 -306.058638)
			(xy 53.204098 -306.017042) (xy 53.184807 -305.971766) (xy 53.17303 -305.923982) (xy 53.16907 -305.874928)
			(xy 52.830222 -305.874928) (xy 52.829727 -305.899535) (xy 52.821832 -305.948112) (xy 52.806248 -305.994793)
			(xy 52.783377 -306.03837) (xy 52.753812 -306.077714) (xy 52.718319 -306.111806) (xy 52.677816 -306.139762)
			(xy 52.633354 -306.16086) (xy 52.586083 -306.174552) (xy 52.537228 -306.180484) (xy 52.488053 -306.178503)
			(xy 52.439834 -306.168659) (xy 52.393818 -306.151207) (xy 52.351197 -306.1266) (xy 52.313076 -306.095475)
			(xy 52.280441 -306.058638) (xy 52.254138 -306.017042) (xy 52.234847 -305.971766) (xy 52.22307 -305.923982)
			(xy 52.21911 -305.874928) (xy 51.880262 -305.874928) (xy 51.879767 -305.899535) (xy 51.871872 -305.948112)
			(xy 51.856288 -305.994793) (xy 51.833417 -306.03837) (xy 51.803852 -306.077714) (xy 51.768359 -306.111806)
			(xy 51.727856 -306.139762) (xy 51.683394 -306.16086) (xy 51.636123 -306.174552) (xy 51.587268 -306.180484)
			(xy 51.538093 -306.178503) (xy 51.489874 -306.168659) (xy 51.443858 -306.151207) (xy 51.401237 -306.1266)
			(xy 51.363116 -306.095475) (xy 51.330481 -306.058638) (xy 51.304178 -306.017042) (xy 51.284887 -305.971766)
			(xy 51.27311 -305.923982) (xy 51.26915 -305.874928) (xy 50.930302 -305.874928) (xy 50.929807 -305.899535)
			(xy 50.921912 -305.948112) (xy 50.906328 -305.994793) (xy 50.883457 -306.03837) (xy 50.853892 -306.077714)
			(xy 50.818399 -306.111806) (xy 50.777896 -306.139762) (xy 50.733434 -306.16086) (xy 50.686163 -306.174552)
			(xy 50.637308 -306.180484) (xy 50.588133 -306.178503) (xy 50.539914 -306.168659) (xy 50.493898 -306.151207)
			(xy 50.451277 -306.1266) (xy 50.413156 -306.095475) (xy 50.380521 -306.058638) (xy 50.354218 -306.017042)
			(xy 50.334927 -305.971766) (xy 50.32315 -305.923982) (xy 50.31919 -305.874928) (xy 49.980088 -305.874928)
			(xy 49.979593 -305.899535) (xy 49.971698 -305.948112) (xy 49.956114 -305.994793) (xy 49.933243 -306.03837)
			(xy 49.903678 -306.077714) (xy 49.868185 -306.111806) (xy 49.827682 -306.139762) (xy 49.78322 -306.16086)
			(xy 49.735949 -306.174552) (xy 49.687094 -306.180484) (xy 49.637919 -306.178503) (xy 49.5897 -306.168659)
			(xy 49.543684 -306.151207) (xy 49.501063 -306.1266) (xy 49.462942 -306.095475) (xy 49.430307 -306.058638)
			(xy 49.404004 -306.017042) (xy 49.384713 -305.971766) (xy 49.372936 -305.923982) (xy 49.368976 -305.874928)
			(xy 49.030128 -305.874928) (xy 49.029633 -305.899535) (xy 49.021738 -305.948112) (xy 49.006154 -305.994793)
			(xy 48.983283 -306.03837) (xy 48.953718 -306.077714) (xy 48.918225 -306.111806) (xy 48.877722 -306.139762)
			(xy 48.83326 -306.16086) (xy 48.785989 -306.174552) (xy 48.737134 -306.180484) (xy 48.687959 -306.178503)
			(xy 48.63974 -306.168659) (xy 48.593724 -306.151207) (xy 48.551103 -306.1266) (xy 48.512982 -306.095475)
			(xy 48.480347 -306.058638) (xy 48.454044 -306.017042) (xy 48.434753 -305.971766) (xy 48.422976 -305.923982)
			(xy 48.419016 -305.874928) (xy 48.080198 -305.874928) (xy 48.080646 -305.8832) (xy 48.075275 -305.932557)
			(xy 48.06199 -305.980395) (xy 48.041139 -306.025454) (xy 48.013274 -306.066545) (xy 47.979127 -306.102586)
			(xy 47.939599 -306.132628) (xy 47.895731 -306.15588) (xy 47.84868 -306.171727) (xy 47.799684 -306.179753)
			(xy 47.77486 -306.180236) (xy 47.760677 -306.180064) (xy 47.732437 -306.177389) (xy 47.718472 -306.174902)
			(xy 47.704512 -306.172687) (xy 47.676374 -306.175273) (xy 47.650021 -306.18547) (xy 47.627472 -306.202499)
			(xy 47.610452 -306.225055) (xy 47.600264 -306.251412) (xy 47.597689 -306.279551) (xy 47.599854 -306.29352)
			(xy 47.602329 -306.307486) (xy 47.605002 -306.335726) (xy 47.605188 -306.349908) (xy 47.604714 -306.374728)
			(xy 47.596682 -306.423713) (xy 47.580831 -306.470754) (xy 47.557578 -306.51461) (xy 47.527537 -306.554128)
			(xy 47.491499 -306.588264) (xy 47.450413 -306.616121) (xy 47.405361 -306.636964) (xy 47.357531 -306.650244)
			(xy 47.308183 -306.655611) (xy 47.258616 -306.652924) (xy 47.210137 -306.642253) (xy 47.164023 -306.62388)
			(xy 47.121489 -306.598289) (xy 47.083655 -306.566154) (xy 47.051518 -306.528321) (xy 47.025925 -306.485788)
			(xy 47.00755 -306.439674) (xy 46.996878 -306.391196) (xy 46.994189 -306.341629) (xy 46.655061 -306.341629)
			(xy 46.655228 -306.349908) (xy 46.654733 -306.374515) (xy 46.646838 -306.423092) (xy 46.631254 -306.469773)
			(xy 46.608383 -306.51335) (xy 46.578818 -306.552694) (xy 46.543325 -306.586786) (xy 46.502822 -306.614742)
			(xy 46.45836 -306.63584) (xy 46.411089 -306.649532) (xy 46.362234 -306.655464) (xy 46.313059 -306.653483)
			(xy 46.26484 -306.643639) (xy 46.218824 -306.626187) (xy 46.176203 -306.60158) (xy 46.138082 -306.570455)
			(xy 46.105447 -306.533618) (xy 46.079144 -306.492022) (xy 46.059853 -306.446746) (xy 46.048076 -306.398962)
			(xy 46.044116 -306.349908) (xy 45.705268 -306.349908) (xy 45.704773 -306.374515) (xy 45.696878 -306.423092)
			(xy 45.681294 -306.469773) (xy 45.658423 -306.51335) (xy 45.628858 -306.552694) (xy 45.593365 -306.586786)
			(xy 45.552862 -306.614742) (xy 45.5084 -306.63584) (xy 45.461129 -306.649532) (xy 45.412274 -306.655464)
			(xy 45.363099 -306.653483) (xy 45.31488 -306.643639) (xy 45.268864 -306.626187) (xy 45.226243 -306.60158)
			(xy 45.188122 -306.570455) (xy 45.155487 -306.533618) (xy 45.129184 -306.492022) (xy 45.109893 -306.446746)
			(xy 45.098116 -306.398962) (xy 45.094156 -306.349908) (xy 44.755054 -306.349908) (xy 44.754559 -306.374515)
			(xy 44.746664 -306.423092) (xy 44.73108 -306.469773) (xy 44.708209 -306.51335) (xy 44.678644 -306.552694)
			(xy 44.643151 -306.586786) (xy 44.602648 -306.614742) (xy 44.558186 -306.63584) (xy 44.510915 -306.649532)
			(xy 44.46206 -306.655464) (xy 44.412885 -306.653483) (xy 44.364666 -306.643639) (xy 44.31865 -306.626187)
			(xy 44.276029 -306.60158) (xy 44.237908 -306.570455) (xy 44.205273 -306.533618) (xy 44.17897 -306.492022)
			(xy 44.159679 -306.446746) (xy 44.147902 -306.398962) (xy 44.143942 -306.349908) (xy 43.805094 -306.349908)
			(xy 43.804599 -306.374515) (xy 43.796704 -306.423092) (xy 43.78112 -306.469773) (xy 43.758249 -306.51335)
			(xy 43.728684 -306.552694) (xy 43.693191 -306.586786) (xy 43.652688 -306.614742) (xy 43.608226 -306.63584)
			(xy 43.560955 -306.649532) (xy 43.5121 -306.655464) (xy 43.462925 -306.653483) (xy 43.414706 -306.643639)
			(xy 43.36869 -306.626187) (xy 43.326069 -306.60158) (xy 43.287948 -306.570455) (xy 43.255313 -306.533618)
			(xy 43.22901 -306.492022) (xy 43.209719 -306.446746) (xy 43.197942 -306.398962) (xy 43.193982 -306.349908)
			(xy 42.855045 -306.349908) (xy 42.855493 -306.358161) (xy 42.85013 -306.407507) (xy 42.836854 -306.455336)
			(xy 42.816015 -306.500386) (xy 42.788163 -306.541472) (xy 42.75403 -306.577511) (xy 42.714517 -306.607553)
			(xy 42.670664 -306.630807) (xy 42.623627 -306.64666) (xy 42.574644 -306.654694) (xy 42.549826 -306.655216)
			(xy 42.540658 -306.655124) (xy 42.522358 -306.653982) (xy 42.51325 -306.65293) (xy 42.512996 -306.65293)
			(xy 42.501197 -306.652123) (xy 42.478957 -306.660084) (xy 42.470324 -306.66817) (xy 42.405808 -306.735734)
			(xy 42.39895 -306.75834) (xy 42.399966 -306.765198) (xy 42.402485 -306.779991) (xy 42.405155 -306.809883)
			(xy 42.4053 -306.824888) (xy 42.405145 -306.83983) (xy 42.402472 -306.869593) (xy 42.399966 -306.884324)
			(xy 42.399966 -306.884832) (xy 42.39895 -306.891436) (xy 42.405808 -306.914042) (xy 42.470324 -306.981606)
			(xy 42.478963 -306.989676) (xy 42.5012 -306.997618) (xy 42.512996 -306.996846) (xy 42.51325 -306.996846)
			(xy 42.522357 -306.99579) (xy 42.540658 -306.994644) (xy 42.549826 -306.99456) (xy 42.57465 -306.995048)
			(xy 42.623642 -307.003084) (xy 42.670689 -307.018941) (xy 42.714551 -307.0422) (xy 42.754072 -307.072248)
			(xy 42.788211 -307.108295) (xy 42.816068 -307.14939) (xy 42.836911 -307.19445) (xy 42.850188 -307.242289)
			(xy 42.855552 -307.291645) (xy 42.855105 -307.299868) (xy 43.193982 -307.299868) (xy 43.197942 -307.250814)
			(xy 43.209719 -307.20303) (xy 43.22901 -307.157754) (xy 43.255313 -307.116158) (xy 43.287948 -307.079321)
			(xy 43.326069 -307.048196) (xy 43.36869 -307.023589) (xy 43.414706 -307.006137) (xy 43.462925 -306.996293)
			(xy 43.5121 -306.994312) (xy 43.560955 -307.000244) (xy 43.608226 -307.013936) (xy 43.652688 -307.035034)
			(xy 43.693191 -307.06299) (xy 43.728684 -307.097082) (xy 43.758249 -307.136426) (xy 43.78112 -307.180003)
			(xy 43.796704 -307.226684) (xy 43.804599 -307.275261) (xy 43.805094 -307.299868) (xy 44.143942 -307.299868)
			(xy 44.147902 -307.250814) (xy 44.159679 -307.20303) (xy 44.17897 -307.157754) (xy 44.205273 -307.116158)
			(xy 44.237908 -307.079321) (xy 44.276029 -307.048196) (xy 44.31865 -307.023589) (xy 44.364666 -307.006137)
			(xy 44.412885 -306.996293) (xy 44.46206 -306.994312) (xy 44.510915 -307.000244) (xy 44.558186 -307.013936)
			(xy 44.602648 -307.035034) (xy 44.643151 -307.06299) (xy 44.678644 -307.097082) (xy 44.708209 -307.136426)
			(xy 44.73108 -307.180003) (xy 44.746664 -307.226684) (xy 44.754559 -307.275261) (xy 44.755054 -307.299868)
			(xy 45.094156 -307.299868) (xy 45.098116 -307.250814) (xy 45.109893 -307.20303) (xy 45.129184 -307.157754)
			(xy 45.155487 -307.116158) (xy 45.188122 -307.079321) (xy 45.226243 -307.048196) (xy 45.268864 -307.023589)
			(xy 45.31488 -307.006137) (xy 45.363099 -306.996293) (xy 45.412274 -306.994312) (xy 45.461129 -307.000244)
			(xy 45.5084 -307.013936) (xy 45.552862 -307.035034) (xy 45.593365 -307.06299) (xy 45.628858 -307.097082)
			(xy 45.658423 -307.136426) (xy 45.681294 -307.180003) (xy 45.696878 -307.226684) (xy 45.704773 -307.275261)
			(xy 45.705268 -307.299868) (xy 46.044116 -307.299868) (xy 46.048076 -307.250814) (xy 46.059853 -307.20303)
			(xy 46.079144 -307.157754) (xy 46.105447 -307.116158) (xy 46.138082 -307.079321) (xy 46.176203 -307.048196)
			(xy 46.218824 -307.023589) (xy 46.26484 -307.006137) (xy 46.313059 -306.996293) (xy 46.362234 -306.994312)
			(xy 46.411089 -307.000244) (xy 46.45836 -307.013936) (xy 46.502822 -307.035034) (xy 46.543325 -307.06299)
			(xy 46.578818 -307.097082) (xy 46.608383 -307.136426) (xy 46.631254 -307.180003) (xy 46.646838 -307.226684)
			(xy 46.654733 -307.275261) (xy 46.655228 -307.299868) (xy 46.994076 -307.299868) (xy 46.998036 -307.250814)
			(xy 47.009813 -307.20303) (xy 47.029104 -307.157754) (xy 47.055407 -307.116158) (xy 47.088042 -307.079321)
			(xy 47.126163 -307.048196) (xy 47.168784 -307.023589) (xy 47.2148 -307.006137) (xy 47.263019 -306.996293)
			(xy 47.312194 -306.994312) (xy 47.361049 -307.000244) (xy 47.40832 -307.013936) (xy 47.452782 -307.035034)
			(xy 47.493285 -307.06299) (xy 47.528778 -307.097082) (xy 47.558343 -307.136426) (xy 47.581214 -307.180003)
			(xy 47.596798 -307.226684) (xy 47.604693 -307.275261) (xy 47.605022 -307.291601) (xy 47.94405 -307.291601)
			(xy 47.949421 -307.242243) (xy 47.962706 -307.194404) (xy 47.983557 -307.149345) (xy 48.011423 -307.108253)
			(xy 48.04557 -307.072211) (xy 48.085098 -307.042168) (xy 48.128967 -307.018917) (xy 48.176019 -307.003069)
			(xy 48.225015 -306.995043) (xy 48.24984 -306.99456) (xy 48.264023 -306.994732) (xy 48.292263 -306.997407)
			(xy 48.306228 -306.999894) (xy 48.318674 -307.00218) (xy 48.342296 -306.994814) (xy 48.419766 -306.917344)
			(xy 48.427132 -306.893722) (xy 48.424846 -306.881276) (xy 48.422371 -306.86731) (xy 48.419698 -306.83907)
			(xy 48.419512 -306.824888) (xy 48.420034 -306.799633) (xy 48.428347 -306.749811) (xy 48.444748 -306.702037)
			(xy 48.468789 -306.657614) (xy 48.499813 -306.617754) (xy 48.536975 -306.583544) (xy 48.579261 -306.555918)
			(xy 48.625517 -306.535628) (xy 48.674482 -306.523228) (xy 48.72482 -306.519057) (xy 48.775158 -306.523228)
			(xy 48.824123 -306.535628) (xy 48.870379 -306.555918) (xy 48.912665 -306.583544) (xy 48.949827 -306.617754)
			(xy 48.980851 -306.657614) (xy 49.004892 -306.702037) (xy 49.021293 -306.749811) (xy 49.029606 -306.799633)
			(xy 49.030128 -306.824888) (xy 49.029949 -306.839071) (xy 49.027279 -306.867311) (xy 49.024794 -306.881276)
			(xy 49.022508 -306.893722) (xy 49.029874 -306.917344) (xy 49.107344 -306.994814) (xy 49.130966 -307.00218)
			(xy 49.143412 -306.999894) (xy 49.157378 -306.99742) (xy 49.185618 -306.994747) (xy 49.1998 -306.99456)
			(xy 49.213983 -306.994737) (xy 49.242223 -306.997409) (xy 49.256188 -306.999894) (xy 49.268634 -307.00218)
			(xy 49.292256 -306.994814) (xy 49.369726 -306.917344) (xy 49.377092 -306.893722) (xy 49.374806 -306.881276)
			(xy 49.37233 -306.86731) (xy 49.369658 -306.839071) (xy 49.369472 -306.824888) (xy 49.369994 -306.799633)
			(xy 49.378307 -306.749811) (xy 49.394708 -306.702037) (xy 49.418749 -306.657614) (xy 49.449773 -306.617754)
			(xy 49.486935 -306.583544) (xy 49.529221 -306.555918) (xy 49.575477 -306.535628) (xy 49.624442 -306.523228)
			(xy 49.67478 -306.519057) (xy 49.725118 -306.523228) (xy 49.774083 -306.535628) (xy 49.820339 -306.555918)
			(xy 49.862625 -306.583544) (xy 49.899787 -306.617754) (xy 49.930811 -306.657614) (xy 49.954852 -306.702037)
			(xy 49.971253 -306.749811) (xy 49.979566 -306.799633) (xy 49.980088 -306.824888) (xy 49.97991 -306.839071)
			(xy 49.977239 -306.867311) (xy 49.974754 -306.881276) (xy 49.972468 -306.893722) (xy 49.979834 -306.917344)
			(xy 50.057304 -306.994814) (xy 50.080926 -307.00218) (xy 50.093372 -306.999894) (xy 50.107337 -306.997412)
			(xy 50.135577 -306.994744) (xy 50.14976 -306.99456) (xy 50.164007 -306.99472) (xy 50.192375 -306.997394)
			(xy 50.206402 -306.999894) (xy 50.218848 -307.00218) (xy 50.24247 -306.994814) (xy 50.31105 -306.926488)
			(xy 50.319222 -306.917262) (xy 50.326524 -306.893763) (xy 50.32502 -306.88153) (xy 50.32502 -306.881022)
			(xy 50.322563 -306.867117) (xy 50.319888 -306.839006) (xy 50.319686 -306.824888) (xy 50.320191 -306.800068)
			(xy 50.328223 -306.751083) (xy 50.344075 -306.704042) (xy 50.367328 -306.660186) (xy 50.397371 -306.62067)
			(xy 50.43341 -306.586534) (xy 50.474497 -306.558678) (xy 50.519549 -306.537837) (xy 50.56738 -306.524558)
			(xy 50.616729 -306.519193) (xy 50.666295 -306.521882) (xy 50.714774 -306.532555) (xy 50.760887 -306.550929)
			(xy 50.803421 -306.576523) (xy 50.841253 -306.60866) (xy 50.873388 -306.646494) (xy 50.898979 -306.689029)
			(xy 50.917351 -306.735143) (xy 50.928021 -306.783623) (xy 50.930257 -306.824888) (xy 51.26915 -306.824888)
			(xy 51.27311 -306.775834) (xy 51.284887 -306.72805) (xy 51.304178 -306.682774) (xy 51.330481 -306.641178)
			(xy 51.363116 -306.604341) (xy 51.401237 -306.573216) (xy 51.443858 -306.548609) (xy 51.489874 -306.531157)
			(xy 51.538093 -306.521313) (xy 51.587268 -306.519332) (xy 51.636123 -306.525264) (xy 51.683394 -306.538956)
			(xy 51.727856 -306.560054) (xy 51.768359 -306.58801) (xy 51.803852 -306.622102) (xy 51.833417 -306.661446)
			(xy 51.856288 -306.705023) (xy 51.871872 -306.751704) (xy 51.879767 -306.800281) (xy 51.880262 -306.824888)
			(xy 52.21911 -306.824888) (xy 52.22307 -306.775834) (xy 52.234847 -306.72805) (xy 52.254138 -306.682774)
			(xy 52.280441 -306.641178) (xy 52.313076 -306.604341) (xy 52.351197 -306.573216) (xy 52.393818 -306.548609)
			(xy 52.439834 -306.531157) (xy 52.488053 -306.521313) (xy 52.537228 -306.519332) (xy 52.586083 -306.525264)
			(xy 52.633354 -306.538956) (xy 52.677816 -306.560054) (xy 52.718319 -306.58801) (xy 52.753812 -306.622102)
			(xy 52.783377 -306.661446) (xy 52.806248 -306.705023) (xy 52.821832 -306.751704) (xy 52.829727 -306.800281)
			(xy 52.830222 -306.824888) (xy 53.16907 -306.824888) (xy 53.17303 -306.775834) (xy 53.184807 -306.72805)
			(xy 53.204098 -306.682774) (xy 53.230401 -306.641178) (xy 53.263036 -306.604341) (xy 53.301157 -306.573216)
			(xy 53.343778 -306.548609) (xy 53.389794 -306.531157) (xy 53.438013 -306.521313) (xy 53.487188 -306.519332)
			(xy 53.536043 -306.525264) (xy 53.583314 -306.538956) (xy 53.627776 -306.560054) (xy 53.668279 -306.58801)
			(xy 53.703772 -306.622102) (xy 53.733337 -306.661446) (xy 53.756208 -306.705023) (xy 53.771792 -306.751704)
			(xy 53.779687 -306.800281) (xy 53.780182 -306.824888) (xy 54.11903 -306.824888) (xy 54.12299 -306.775834)
			(xy 54.134767 -306.72805) (xy 54.154058 -306.682774) (xy 54.180361 -306.641178) (xy 54.212996 -306.604341)
			(xy 54.251117 -306.573216) (xy 54.293738 -306.548609) (xy 54.339754 -306.531157) (xy 54.387973 -306.521313)
			(xy 54.437148 -306.519332) (xy 54.486003 -306.525264) (xy 54.533274 -306.538956) (xy 54.577736 -306.560054)
			(xy 54.618239 -306.58801) (xy 54.653732 -306.622102) (xy 54.683297 -306.661446) (xy 54.706168 -306.705023)
			(xy 54.721752 -306.751704) (xy 54.729647 -306.800281) (xy 54.730142 -306.824888) (xy 55.06899 -306.824888)
			(xy 55.07295 -306.775834) (xy 55.084727 -306.72805) (xy 55.104018 -306.682774) (xy 55.130321 -306.641178)
			(xy 55.162956 -306.604341) (xy 55.201077 -306.573216) (xy 55.243698 -306.548609) (xy 55.289714 -306.531157)
			(xy 55.337933 -306.521313) (xy 55.387108 -306.519332) (xy 55.435963 -306.525264) (xy 55.483234 -306.538956)
			(xy 55.527696 -306.560054) (xy 55.568199 -306.58801) (xy 55.603692 -306.622102) (xy 55.633257 -306.661446)
			(xy 55.656128 -306.705023) (xy 55.671712 -306.751704) (xy 55.679607 -306.800281) (xy 55.680102 -306.824888)
			(xy 56.01895 -306.824888) (xy 56.02291 -306.775834) (xy 56.034687 -306.72805) (xy 56.053978 -306.682774)
			(xy 56.080281 -306.641178) (xy 56.112916 -306.604341) (xy 56.151037 -306.573216) (xy 56.193658 -306.548609)
			(xy 56.239674 -306.531157) (xy 56.287893 -306.521313) (xy 56.337068 -306.519332) (xy 56.385923 -306.525264)
			(xy 56.433194 -306.538956) (xy 56.477656 -306.560054) (xy 56.518159 -306.58801) (xy 56.553652 -306.622102)
			(xy 56.583217 -306.661446) (xy 56.606088 -306.705023) (xy 56.621672 -306.751704) (xy 56.629567 -306.800281)
			(xy 56.630062 -306.824888) (xy 56.969164 -306.824888) (xy 56.973124 -306.775834) (xy 56.984901 -306.72805)
			(xy 57.004192 -306.682774) (xy 57.030495 -306.641178) (xy 57.06313 -306.604341) (xy 57.101251 -306.573216)
			(xy 57.143872 -306.548609) (xy 57.189888 -306.531157) (xy 57.238107 -306.521313) (xy 57.287282 -306.519332)
			(xy 57.336137 -306.525264) (xy 57.383408 -306.538956) (xy 57.42787 -306.560054) (xy 57.468373 -306.58801)
			(xy 57.503866 -306.622102) (xy 57.533431 -306.661446) (xy 57.556302 -306.705023) (xy 57.571886 -306.751704)
			(xy 57.579781 -306.800281) (xy 57.580276 -306.824888) (xy 57.919124 -306.824888) (xy 57.923084 -306.775834)
			(xy 57.934861 -306.72805) (xy 57.954152 -306.682774) (xy 57.980455 -306.641178) (xy 58.01309 -306.604341)
			(xy 58.051211 -306.573216) (xy 58.093832 -306.548609) (xy 58.139848 -306.531157) (xy 58.188067 -306.521313)
			(xy 58.237242 -306.519332) (xy 58.286097 -306.525264) (xy 58.333368 -306.538956) (xy 58.37783 -306.560054)
			(xy 58.418333 -306.58801) (xy 58.453826 -306.622102) (xy 58.483391 -306.661446) (xy 58.506262 -306.705023)
			(xy 58.521846 -306.751704) (xy 58.529741 -306.800281) (xy 58.530236 -306.824888) (xy 59.819044 -306.824888)
			(xy 59.823004 -306.775834) (xy 59.834781 -306.72805) (xy 59.854072 -306.682774) (xy 59.880375 -306.641178)
			(xy 59.91301 -306.604341) (xy 59.951131 -306.573216) (xy 59.993752 -306.548609) (xy 60.039768 -306.531157)
			(xy 60.087987 -306.521313) (xy 60.137162 -306.519332) (xy 60.186017 -306.525264) (xy 60.233288 -306.538956)
			(xy 60.27775 -306.560054) (xy 60.318253 -306.58801) (xy 60.353746 -306.622102) (xy 60.383311 -306.661446)
			(xy 60.406182 -306.705023) (xy 60.421766 -306.751704) (xy 60.429661 -306.800281) (xy 60.430156 -306.824888)
			(xy 60.769004 -306.824888) (xy 60.772964 -306.775834) (xy 60.784741 -306.72805) (xy 60.804032 -306.682774)
			(xy 60.830335 -306.641178) (xy 60.86297 -306.604341) (xy 60.901091 -306.573216) (xy 60.943712 -306.548609)
			(xy 60.989728 -306.531157) (xy 61.037947 -306.521313) (xy 61.087122 -306.519332) (xy 61.135977 -306.525264)
			(xy 61.183248 -306.538956) (xy 61.22771 -306.560054) (xy 61.268213 -306.58801) (xy 61.303706 -306.622102)
			(xy 61.333271 -306.661446) (xy 61.356142 -306.705023) (xy 61.371726 -306.751704) (xy 61.379621 -306.800281)
			(xy 61.380116 -306.824888) (xy 61.718964 -306.824888) (xy 61.722924 -306.775834) (xy 61.734701 -306.72805)
			(xy 61.753992 -306.682774) (xy 61.780295 -306.641178) (xy 61.81293 -306.604341) (xy 61.851051 -306.573216)
			(xy 61.893672 -306.548609) (xy 61.939688 -306.531157) (xy 61.987907 -306.521313) (xy 62.037082 -306.519332)
			(xy 62.085937 -306.525264) (xy 62.133208 -306.538956) (xy 62.17767 -306.560054) (xy 62.218173 -306.58801)
			(xy 62.253666 -306.622102) (xy 62.283231 -306.661446) (xy 62.306102 -306.705023) (xy 62.321686 -306.751704)
			(xy 62.329581 -306.800281) (xy 62.330076 -306.824888) (xy 62.329581 -306.849495) (xy 62.321686 -306.898072)
			(xy 62.306102 -306.944753) (xy 62.283231 -306.98833) (xy 62.253666 -307.027674) (xy 62.218173 -307.061766)
			(xy 62.17767 -307.089722) (xy 62.133208 -307.11082) (xy 62.085937 -307.124512) (xy 62.037082 -307.130444)
			(xy 61.987907 -307.128463) (xy 61.939688 -307.118619) (xy 61.893672 -307.101167) (xy 61.851051 -307.07656)
			(xy 61.81293 -307.045435) (xy 61.780295 -307.008598) (xy 61.753992 -306.967002) (xy 61.734701 -306.921726)
			(xy 61.722924 -306.873942) (xy 61.718964 -306.824888) (xy 61.380116 -306.824888) (xy 61.379621 -306.849495)
			(xy 61.371726 -306.898072) (xy 61.356142 -306.944753) (xy 61.333271 -306.98833) (xy 61.303706 -307.027674)
			(xy 61.268213 -307.061766) (xy 61.22771 -307.089722) (xy 61.183248 -307.11082) (xy 61.135977 -307.124512)
			(xy 61.087122 -307.130444) (xy 61.037947 -307.128463) (xy 60.989728 -307.118619) (xy 60.943712 -307.101167)
			(xy 60.901091 -307.07656) (xy 60.86297 -307.045435) (xy 60.830335 -307.008598) (xy 60.804032 -306.967002)
			(xy 60.784741 -306.921726) (xy 60.772964 -306.873942) (xy 60.769004 -306.824888) (xy 60.430156 -306.824888)
			(xy 60.429661 -306.849495) (xy 60.421766 -306.898072) (xy 60.406182 -306.944753) (xy 60.383311 -306.98833)
			(xy 60.353746 -307.027674) (xy 60.318253 -307.061766) (xy 60.27775 -307.089722) (xy 60.233288 -307.11082)
			(xy 60.186017 -307.124512) (xy 60.137162 -307.130444) (xy 60.087987 -307.128463) (xy 60.039768 -307.118619)
			(xy 59.993752 -307.101167) (xy 59.951131 -307.07656) (xy 59.91301 -307.045435) (xy 59.880375 -307.008598)
			(xy 59.854072 -306.967002) (xy 59.834781 -306.921726) (xy 59.823004 -306.873942) (xy 59.819044 -306.824888)
			(xy 58.530236 -306.824888) (xy 58.529741 -306.849495) (xy 58.521846 -306.898072) (xy 58.506262 -306.944753)
			(xy 58.483391 -306.98833) (xy 58.453826 -307.027674) (xy 58.418333 -307.061766) (xy 58.37783 -307.089722)
			(xy 58.333368 -307.11082) (xy 58.286097 -307.124512) (xy 58.237242 -307.130444) (xy 58.188067 -307.128463)
			(xy 58.139848 -307.118619) (xy 58.093832 -307.101167) (xy 58.051211 -307.07656) (xy 58.01309 -307.045435)
			(xy 57.980455 -307.008598) (xy 57.954152 -306.967002) (xy 57.934861 -306.921726) (xy 57.923084 -306.873942)
			(xy 57.919124 -306.824888) (xy 57.580276 -306.824888) (xy 57.579781 -306.849495) (xy 57.571886 -306.898072)
			(xy 57.556302 -306.944753) (xy 57.533431 -306.98833) (xy 57.503866 -307.027674) (xy 57.468373 -307.061766)
			(xy 57.42787 -307.089722) (xy 57.383408 -307.11082) (xy 57.336137 -307.124512) (xy 57.287282 -307.130444)
			(xy 57.238107 -307.128463) (xy 57.189888 -307.118619) (xy 57.143872 -307.101167) (xy 57.101251 -307.07656)
			(xy 57.06313 -307.045435) (xy 57.030495 -307.008598) (xy 57.004192 -306.967002) (xy 56.984901 -306.921726)
			(xy 56.973124 -306.873942) (xy 56.969164 -306.824888) (xy 56.630062 -306.824888) (xy 56.629567 -306.849495)
			(xy 56.621672 -306.898072) (xy 56.606088 -306.944753) (xy 56.583217 -306.98833) (xy 56.553652 -307.027674)
			(xy 56.518159 -307.061766) (xy 56.477656 -307.089722) (xy 56.433194 -307.11082) (xy 56.385923 -307.124512)
			(xy 56.337068 -307.130444) (xy 56.287893 -307.128463) (xy 56.239674 -307.118619) (xy 56.193658 -307.101167)
			(xy 56.151037 -307.07656) (xy 56.112916 -307.045435) (xy 56.080281 -307.008598) (xy 56.053978 -306.967002)
			(xy 56.034687 -306.921726) (xy 56.02291 -306.873942) (xy 56.01895 -306.824888) (xy 55.680102 -306.824888)
			(xy 55.679607 -306.849495) (xy 55.671712 -306.898072) (xy 55.656128 -306.944753) (xy 55.633257 -306.98833)
			(xy 55.603692 -307.027674) (xy 55.568199 -307.061766) (xy 55.527696 -307.089722) (xy 55.483234 -307.11082)
			(xy 55.435963 -307.124512) (xy 55.387108 -307.130444) (xy 55.337933 -307.128463) (xy 55.289714 -307.118619)
			(xy 55.243698 -307.101167) (xy 55.201077 -307.07656) (xy 55.162956 -307.045435) (xy 55.130321 -307.008598)
			(xy 55.104018 -306.967002) (xy 55.084727 -306.921726) (xy 55.07295 -306.873942) (xy 55.06899 -306.824888)
			(xy 54.730142 -306.824888) (xy 54.729647 -306.849495) (xy 54.721752 -306.898072) (xy 54.706168 -306.944753)
			(xy 54.683297 -306.98833) (xy 54.653732 -307.027674) (xy 54.618239 -307.061766) (xy 54.577736 -307.089722)
			(xy 54.533274 -307.11082) (xy 54.486003 -307.124512) (xy 54.437148 -307.130444) (xy 54.387973 -307.128463)
			(xy 54.339754 -307.118619) (xy 54.293738 -307.101167) (xy 54.251117 -307.07656) (xy 54.212996 -307.045435)
			(xy 54.180361 -307.008598) (xy 54.154058 -306.967002) (xy 54.134767 -306.921726) (xy 54.12299 -306.873942)
			(xy 54.11903 -306.824888) (xy 53.780182 -306.824888) (xy 53.779687 -306.849495) (xy 53.771792 -306.898072)
			(xy 53.756208 -306.944753) (xy 53.733337 -306.98833) (xy 53.703772 -307.027674) (xy 53.668279 -307.061766)
			(xy 53.627776 -307.089722) (xy 53.583314 -307.11082) (xy 53.536043 -307.124512) (xy 53.487188 -307.130444)
			(xy 53.438013 -307.128463) (xy 53.389794 -307.118619) (xy 53.343778 -307.101167) (xy 53.301157 -307.07656)
			(xy 53.263036 -307.045435) (xy 53.230401 -307.008598) (xy 53.204098 -306.967002) (xy 53.184807 -306.921726)
			(xy 53.17303 -306.873942) (xy 53.16907 -306.824888) (xy 52.830222 -306.824888) (xy 52.829727 -306.849495)
			(xy 52.821832 -306.898072) (xy 52.806248 -306.944753) (xy 52.783377 -306.98833) (xy 52.753812 -307.027674)
			(xy 52.718319 -307.061766) (xy 52.677816 -307.089722) (xy 52.633354 -307.11082) (xy 52.586083 -307.124512)
			(xy 52.537228 -307.130444) (xy 52.488053 -307.128463) (xy 52.439834 -307.118619) (xy 52.393818 -307.101167)
			(xy 52.351197 -307.07656) (xy 52.313076 -307.045435) (xy 52.280441 -307.008598) (xy 52.254138 -306.967002)
			(xy 52.234847 -306.921726) (xy 52.22307 -306.873942) (xy 52.21911 -306.824888) (xy 51.880262 -306.824888)
			(xy 51.879767 -306.849495) (xy 51.871872 -306.898072) (xy 51.856288 -306.944753) (xy 51.833417 -306.98833)
			(xy 51.803852 -307.027674) (xy 51.768359 -307.061766) (xy 51.727856 -307.089722) (xy 51.683394 -307.11082)
			(xy 51.636123 -307.124512) (xy 51.587268 -307.130444) (xy 51.538093 -307.128463) (xy 51.489874 -307.118619)
			(xy 51.443858 -307.101167) (xy 51.401237 -307.07656) (xy 51.363116 -307.045435) (xy 51.330481 -307.008598)
			(xy 51.304178 -306.967002) (xy 51.284887 -306.921726) (xy 51.27311 -306.873942) (xy 51.26915 -306.824888)
			(xy 50.930257 -306.824888) (xy 50.930707 -306.833189) (xy 50.925338 -306.882538) (xy 50.912057 -306.930368)
			(xy 50.891213 -306.975419) (xy 50.863355 -307.016504) (xy 50.829217 -307.052542) (xy 50.789699 -307.082581)
			(xy 50.745841 -307.105832) (xy 50.6988 -307.121681) (xy 50.649814 -307.129711) (xy 50.624994 -307.130196)
			(xy 50.610748 -307.130023) (xy 50.58238 -307.127354) (xy 50.568352 -307.124862) (xy 50.555906 -307.122576)
			(xy 50.532284 -307.129942) (xy 50.463704 -307.198268) (xy 50.455552 -307.207508) (xy 50.448241 -307.230996)
			(xy 50.449734 -307.243226) (xy 50.449734 -307.243734) (xy 50.452198 -307.257637) (xy 50.454869 -307.285749)
			(xy 50.455068 -307.299868) (xy 50.454546 -307.325123) (xy 50.446233 -307.374945) (xy 50.429832 -307.422719)
			(xy 50.405791 -307.467142) (xy 50.374767 -307.507002) (xy 50.337605 -307.541212) (xy 50.295319 -307.568838)
			(xy 50.249063 -307.589128) (xy 50.200098 -307.601528) (xy 50.14976 -307.605699) (xy 50.099422 -307.601528)
			(xy 50.050457 -307.589128) (xy 50.004201 -307.568838) (xy 49.961915 -307.541212) (xy 49.924753 -307.507002)
			(xy 49.893729 -307.467142) (xy 49.869688 -307.422719) (xy 49.853287 -307.374945) (xy 49.844974 -307.325123)
			(xy 49.844452 -307.299868) (xy 49.844625 -307.285685) (xy 49.8473 -307.257445) (xy 49.849786 -307.24348)
			(xy 49.852072 -307.231034) (xy 49.844706 -307.207412) (xy 49.767236 -307.129942) (xy 49.743614 -307.122576)
			(xy 49.731168 -307.124862) (xy 49.717202 -307.127339) (xy 49.688963 -307.13001) (xy 49.67478 -307.130196)
			(xy 49.660597 -307.130022) (xy 49.632357 -307.127348) (xy 49.618392 -307.124862) (xy 49.605946 -307.122576)
			(xy 49.582324 -307.129942) (xy 49.504854 -307.207412) (xy 49.497488 -307.231034) (xy 49.499774 -307.24348)
			(xy 49.502257 -307.257445) (xy 49.504925 -307.285685) (xy 49.505108 -307.299868) (xy 49.504586 -307.325123)
			(xy 49.496273 -307.374945) (xy 49.479872 -307.422719) (xy 49.455831 -307.467142) (xy 49.424807 -307.507002)
			(xy 49.387645 -307.541212) (xy 49.345359 -307.568838) (xy 49.299103 -307.589128) (xy 49.250138 -307.601528)
			(xy 49.1998 -307.605699) (xy 49.149462 -307.601528) (xy 49.100497 -307.589128) (xy 49.054241 -307.568838)
			(xy 49.011955 -307.541212) (xy 48.974793 -307.507002) (xy 48.943769 -307.467142) (xy 48.919728 -307.422719)
			(xy 48.903327 -307.374945) (xy 48.895014 -307.325123) (xy 48.894492 -307.299868) (xy 48.894664 -307.285685)
			(xy 48.897339 -307.257445) (xy 48.899826 -307.24348) (xy 48.902112 -307.231034) (xy 48.894746 -307.207412)
			(xy 48.817276 -307.129942) (xy 48.793654 -307.122576) (xy 48.781208 -307.124862) (xy 48.767241 -307.127333)
			(xy 48.739002 -307.130009) (xy 48.72482 -307.130196) (xy 48.710637 -307.130017) (xy 48.682397 -307.127346)
			(xy 48.668432 -307.124862) (xy 48.655986 -307.122576) (xy 48.632364 -307.129942) (xy 48.554894 -307.207412)
			(xy 48.547528 -307.231034) (xy 48.549814 -307.24348) (xy 48.552298 -307.257445) (xy 48.554965 -307.285685)
			(xy 48.555148 -307.299868) (xy 48.554657 -307.324693) (xy 48.546629 -307.373689) (xy 48.53078 -307.420741)
			(xy 48.507527 -307.464608) (xy 48.477484 -307.504136) (xy 48.441441 -307.538282) (xy 48.400348 -307.566147)
			(xy 48.355288 -307.586996) (xy 48.307449 -307.600281) (xy 48.258091 -307.605651) (xy 48.208514 -307.602964)
			(xy 48.160026 -307.592291) (xy 48.113902 -307.573915) (xy 48.07136 -307.548318) (xy 48.033519 -307.516175)
			(xy 48.001378 -307.478334) (xy 47.975782 -307.43579) (xy 47.957406 -307.389667) (xy 47.946735 -307.341178)
			(xy 47.94405 -307.291601) (xy 47.605022 -307.291601) (xy 47.605188 -307.299868) (xy 47.604693 -307.324475)
			(xy 47.596798 -307.373052) (xy 47.581214 -307.419733) (xy 47.558343 -307.46331) (xy 47.528778 -307.502654)
			(xy 47.493285 -307.536746) (xy 47.452782 -307.564702) (xy 47.40832 -307.5858) (xy 47.361049 -307.599492)
			(xy 47.312194 -307.605424) (xy 47.263019 -307.603443) (xy 47.2148 -307.593599) (xy 47.168784 -307.576147)
			(xy 47.126163 -307.55154) (xy 47.088042 -307.520415) (xy 47.055407 -307.483578) (xy 47.029104 -307.441982)
			(xy 47.009813 -307.396706) (xy 46.998036 -307.348922) (xy 46.994076 -307.299868) (xy 46.655228 -307.299868)
			(xy 46.654733 -307.324475) (xy 46.646838 -307.373052) (xy 46.631254 -307.419733) (xy 46.608383 -307.46331)
			(xy 46.578818 -307.502654) (xy 46.543325 -307.536746) (xy 46.502822 -307.564702) (xy 46.45836 -307.5858)
			(xy 46.411089 -307.599492) (xy 46.362234 -307.605424) (xy 46.313059 -307.603443) (xy 46.26484 -307.593599)
			(xy 46.218824 -307.576147) (xy 46.176203 -307.55154) (xy 46.138082 -307.520415) (xy 46.105447 -307.483578)
			(xy 46.079144 -307.441982) (xy 46.059853 -307.396706) (xy 46.048076 -307.348922) (xy 46.044116 -307.299868)
			(xy 45.705268 -307.299868) (xy 45.704773 -307.324475) (xy 45.696878 -307.373052) (xy 45.681294 -307.419733)
			(xy 45.658423 -307.46331) (xy 45.628858 -307.502654) (xy 45.593365 -307.536746) (xy 45.552862 -307.564702)
			(xy 45.5084 -307.5858) (xy 45.461129 -307.599492) (xy 45.412274 -307.605424) (xy 45.363099 -307.603443)
			(xy 45.31488 -307.593599) (xy 45.268864 -307.576147) (xy 45.226243 -307.55154) (xy 45.188122 -307.520415)
			(xy 45.155487 -307.483578) (xy 45.129184 -307.441982) (xy 45.109893 -307.396706) (xy 45.098116 -307.348922)
			(xy 45.094156 -307.299868) (xy 44.755054 -307.299868) (xy 44.754559 -307.324475) (xy 44.746664 -307.373052)
			(xy 44.73108 -307.419733) (xy 44.708209 -307.46331) (xy 44.678644 -307.502654) (xy 44.643151 -307.536746)
			(xy 44.602648 -307.564702) (xy 44.558186 -307.5858) (xy 44.510915 -307.599492) (xy 44.46206 -307.605424)
			(xy 44.412885 -307.603443) (xy 44.364666 -307.593599) (xy 44.31865 -307.576147) (xy 44.276029 -307.55154)
			(xy 44.237908 -307.520415) (xy 44.205273 -307.483578) (xy 44.17897 -307.441982) (xy 44.159679 -307.396706)
			(xy 44.147902 -307.348922) (xy 44.143942 -307.299868) (xy 43.805094 -307.299868) (xy 43.804599 -307.324475)
			(xy 43.796704 -307.373052) (xy 43.78112 -307.419733) (xy 43.758249 -307.46331) (xy 43.728684 -307.502654)
			(xy 43.693191 -307.536746) (xy 43.652688 -307.564702) (xy 43.608226 -307.5858) (xy 43.560955 -307.599492)
			(xy 43.5121 -307.605424) (xy 43.462925 -307.603443) (xy 43.414706 -307.593599) (xy 43.36869 -307.576147)
			(xy 43.326069 -307.55154) (xy 43.287948 -307.520415) (xy 43.255313 -307.483578) (xy 43.22901 -307.441982)
			(xy 43.209719 -307.396706) (xy 43.197942 -307.348922) (xy 43.193982 -307.299868) (xy 42.855105 -307.299868)
			(xy 42.852859 -307.341219) (xy 42.842182 -307.389705) (xy 42.823801 -307.435824) (xy 42.798202 -307.478362)
			(xy 42.766057 -307.516198) (xy 42.728215 -307.548336) (xy 42.685672 -307.573927) (xy 42.639549 -307.592299)
			(xy 42.591062 -307.602967) (xy 42.541487 -307.60565) (xy 42.492132 -307.600277) (xy 42.444296 -307.586991)
			(xy 42.399239 -307.56614) (xy 42.35815 -307.538274) (xy 42.32211 -307.504128) (xy 42.292068 -307.464602)
			(xy 42.268818 -307.420735) (xy 42.25297 -307.373686) (xy 42.244943 -307.324692) (xy 42.244518 -307.299868)
			(xy 42.244611 -307.2907) (xy 42.245757 -307.2724) (xy 42.246804 -307.263292) (xy 42.248328 -307.251608)
			(xy 42.2402 -307.228748) (xy 42.163746 -307.156104) (xy 42.14114 -307.148992) (xy 42.132504 -307.150516)
			(xy 42.118207 -307.152885) (xy 42.089337 -307.155429) (xy 42.074846 -307.155596) (xy 42.004488 -307.155596)
			(xy 41.993795 -307.156157) (xy 41.974236 -307.164813) (xy 41.966642 -307.17236) (xy 41.916096 -307.228494)
			(xy 41.909313 -307.236715) (xy 41.902747 -307.256971) (xy 41.903396 -307.26761) (xy 41.903396 -307.267864)
			(xy 41.905174 -307.299868) (xy 41.90473 -307.323862) (xy 41.897227 -307.371259) (xy 41.882401 -307.416899)
			(xy 41.860617 -307.459657) (xy 41.832411 -307.49848) (xy 41.798479 -307.532413) (xy 41.759655 -307.560618)
			(xy 41.716897 -307.582402) (xy 41.671257 -307.597228) (xy 41.62386 -307.60473) (xy 41.599866 -307.605176)
			(xy 41.590635 -307.605091) (xy 41.572207 -307.603949) (xy 41.563036 -307.60289) (xy 41.562782 -307.60289)
			(xy 41.550974 -307.602063) (xy 41.528703 -307.609993) (xy 41.52011 -307.61813) (xy 41.455594 -307.685694)
			(xy 41.448482 -307.708554) (xy 41.450514 -307.720492) (xy 41.454482 -307.747527) (xy 41.454475 -307.802167)
			(xy 41.450514 -307.829204) (xy 41.448482 -307.841142) (xy 41.455594 -307.864002) (xy 41.52011 -307.931566)
			(xy 41.528751 -307.939631) (xy 41.550987 -307.94757) (xy 41.562782 -307.946806) (xy 41.563036 -307.946806)
			(xy 41.572207 -307.945746) (xy 41.590635 -307.944604) (xy 41.599866 -307.94452) (xy 41.62386 -307.944964)
			(xy 41.671258 -307.952466) (xy 41.716898 -307.967292) (xy 41.759657 -307.989076) (xy 41.798481 -308.017282)
			(xy 41.832414 -308.051214) (xy 41.860621 -308.090038) (xy 41.882405 -308.132796) (xy 41.897232 -308.178436)
			(xy 41.904736 -308.225834) (xy 41.905174 -308.249828) (xy 41.903396 -308.281578) (xy 41.903396 -308.282086)
			(xy 41.902881 -308.292706) (xy 41.909444 -308.312906) (xy 41.916096 -308.321202) (xy 41.966642 -308.377336)
			(xy 41.97416 -308.384992) (xy 41.993766 -308.393664) (xy 42.004488 -308.3941) (xy 42.074846 -308.3941)
			(xy 42.089274 -308.394262) (xy 42.118018 -308.396804) (xy 42.13225 -308.39918) (xy 42.132758 -308.39918)
			(xy 42.14114 -308.400704) (xy 42.163746 -308.393592) (xy 42.2402 -308.320948) (xy 42.248328 -308.298088)
			(xy 42.246804 -308.286404) (xy 42.24575 -308.277296) (xy 42.244606 -308.258996) (xy 42.244518 -308.249828)
			(xy 42.245002 -308.225009) (xy 42.253028 -308.176025) (xy 42.268873 -308.128984) (xy 42.292119 -308.085127)
			(xy 42.322155 -308.045608) (xy 42.358189 -308.011469) (xy 42.39927 -307.983609) (xy 42.444318 -307.962763)
			(xy 42.492146 -307.949479) (xy 42.541492 -307.944108) (xy 42.591057 -307.946791) (xy 42.639535 -307.957457)
			(xy 42.685648 -307.975826) (xy 42.728183 -308.001413) (xy 42.766018 -308.033544) (xy 42.798156 -308.071373)
			(xy 42.82375 -308.113903) (xy 42.842127 -308.160014) (xy 42.852802 -308.20849) (xy 42.855047 -308.249828)
			(xy 43.193982 -308.249828) (xy 43.197942 -308.200774) (xy 43.209719 -308.15299) (xy 43.22901 -308.107714)
			(xy 43.255313 -308.066118) (xy 43.287948 -308.029281) (xy 43.326069 -307.998156) (xy 43.36869 -307.973549)
			(xy 43.414706 -307.956097) (xy 43.462925 -307.946253) (xy 43.5121 -307.944272) (xy 43.560955 -307.950204)
			(xy 43.608226 -307.963896) (xy 43.652688 -307.984994) (xy 43.693191 -308.01295) (xy 43.728684 -308.047042)
			(xy 43.758249 -308.086386) (xy 43.78112 -308.129963) (xy 43.796704 -308.176644) (xy 43.804599 -308.225221)
			(xy 43.805094 -308.249828) (xy 44.143942 -308.249828) (xy 44.147902 -308.200774) (xy 44.159679 -308.15299)
			(xy 44.17897 -308.107714) (xy 44.205273 -308.066118) (xy 44.237908 -308.029281) (xy 44.276029 -307.998156)
			(xy 44.31865 -307.973549) (xy 44.364666 -307.956097) (xy 44.412885 -307.946253) (xy 44.46206 -307.944272)
			(xy 44.510915 -307.950204) (xy 44.558186 -307.963896) (xy 44.602648 -307.984994) (xy 44.643151 -308.01295)
			(xy 44.678644 -308.047042) (xy 44.708209 -308.086386) (xy 44.73108 -308.129963) (xy 44.746664 -308.176644)
			(xy 44.754559 -308.225221) (xy 44.755054 -308.249828) (xy 45.094156 -308.249828) (xy 45.098116 -308.200774)
			(xy 45.109893 -308.15299) (xy 45.129184 -308.107714) (xy 45.155487 -308.066118) (xy 45.188122 -308.029281)
			(xy 45.226243 -307.998156) (xy 45.268864 -307.973549) (xy 45.31488 -307.956097) (xy 45.363099 -307.946253)
			(xy 45.412274 -307.944272) (xy 45.461129 -307.950204) (xy 45.5084 -307.963896) (xy 45.552862 -307.984994)
			(xy 45.593365 -308.01295) (xy 45.628858 -308.047042) (xy 45.658423 -308.086386) (xy 45.681294 -308.129963)
			(xy 45.696878 -308.176644) (xy 45.704773 -308.225221) (xy 45.705268 -308.249828) (xy 46.044116 -308.249828)
			(xy 46.048076 -308.200774) (xy 46.059853 -308.15299) (xy 46.079144 -308.107714) (xy 46.105447 -308.066118)
			(xy 46.138082 -308.029281) (xy 46.176203 -307.998156) (xy 46.218824 -307.973549) (xy 46.26484 -307.956097)
			(xy 46.313059 -307.946253) (xy 46.362234 -307.944272) (xy 46.411089 -307.950204) (xy 46.45836 -307.963896)
			(xy 46.502822 -307.984994) (xy 46.543325 -308.01295) (xy 46.578818 -308.047042) (xy 46.608383 -308.086386)
			(xy 46.631254 -308.129963) (xy 46.646838 -308.176644) (xy 46.654733 -308.225221) (xy 46.655228 -308.249828)
			(xy 46.994076 -308.249828) (xy 46.998036 -308.200774) (xy 47.009813 -308.15299) (xy 47.029104 -308.107714)
			(xy 47.055407 -308.066118) (xy 47.088042 -308.029281) (xy 47.126163 -307.998156) (xy 47.168784 -307.973549)
			(xy 47.2148 -307.956097) (xy 47.263019 -307.946253) (xy 47.312194 -307.944272) (xy 47.361049 -307.950204)
			(xy 47.40832 -307.963896) (xy 47.452782 -307.984994) (xy 47.493285 -308.01295) (xy 47.528778 -308.047042)
			(xy 47.558343 -308.086386) (xy 47.581214 -308.129963) (xy 47.596798 -308.176644) (xy 47.604693 -308.225221)
			(xy 47.605188 -308.249828) (xy 47.944036 -308.249828) (xy 47.947996 -308.200774) (xy 47.959773 -308.15299)
			(xy 47.979064 -308.107714) (xy 48.005367 -308.066118) (xy 48.038002 -308.029281) (xy 48.076123 -307.998156)
			(xy 48.118744 -307.973549) (xy 48.16476 -307.956097) (xy 48.212979 -307.946253) (xy 48.262154 -307.944272)
			(xy 48.311009 -307.950204) (xy 48.35828 -307.963896) (xy 48.402742 -307.984994) (xy 48.443245 -308.01295)
			(xy 48.478738 -308.047042) (xy 48.508303 -308.086386) (xy 48.531174 -308.129963) (xy 48.546758 -308.176644)
			(xy 48.554653 -308.225221) (xy 48.555148 -308.249828) (xy 48.554982 -308.258073) (xy 48.894081 -308.258073)
			(xy 48.89677 -308.208503) (xy 48.907443 -308.160021) (xy 48.92582 -308.113905) (xy 48.951415 -308.071369)
			(xy 48.983555 -308.033535) (xy 49.021392 -308.001399) (xy 49.06393 -307.975807) (xy 49.110048 -307.957435)
			(xy 49.158531 -307.946766) (xy 49.208101 -307.944082) (xy 49.257452 -307.949452) (xy 49.305284 -307.962736)
			(xy 49.350337 -307.983584) (xy 49.391424 -308.011445) (xy 49.427462 -308.045587) (xy 49.457501 -308.08511)
			(xy 49.48075 -308.128972) (xy 49.496597 -308.176017) (xy 49.504624 -308.225007) (xy 49.505108 -308.249828)
			(xy 49.504935 -308.264011) (xy 49.502261 -308.292251) (xy 49.499774 -308.306216) (xy 49.497488 -308.318662)
			(xy 49.504854 -308.342284) (xy 49.582324 -308.419754) (xy 49.605946 -308.42712) (xy 49.618392 -308.424834)
			(xy 49.632359 -308.422363) (xy 49.660598 -308.419687) (xy 49.67478 -308.4195) (xy 49.698773 -308.419957)
			(xy 49.746169 -308.427461) (xy 49.791807 -308.442287) (xy 49.834563 -308.464071) (xy 49.873386 -308.492275)
			(xy 49.907317 -308.526205) (xy 49.935523 -308.565027) (xy 49.957308 -308.607782) (xy 49.972137 -308.65342)
			(xy 49.979642 -308.700815) (xy 49.980088 -308.724808) (xy 49.979913 -308.738991) (xy 49.97724 -308.767231)
			(xy 49.974754 -308.781196) (xy 49.972468 -308.793642) (xy 49.979834 -308.817264) (xy 50.057304 -308.894734)
			(xy 50.080926 -308.9021) (xy 50.093372 -308.899814) (xy 50.107337 -308.897332) (xy 50.135577 -308.894664)
			(xy 50.14976 -308.89448) (xy 50.174585 -308.894935) (xy 50.223582 -308.902961) (xy 50.270635 -308.918809)
			(xy 50.314504 -308.94206) (xy 50.354033 -308.972103) (xy 50.388181 -309.008145) (xy 50.416048 -309.049237)
			(xy 50.436899 -309.094297) (xy 50.450186 -309.142136) (xy 50.455558 -309.191494) (xy 50.455556 -309.191539)
			(xy 50.794269 -309.191539) (xy 50.799632 -309.142187) (xy 50.81291 -309.094352) (xy 50.833751 -309.049296)
			(xy 50.861607 -309.008205) (xy 50.895744 -308.972161) (xy 50.935262 -308.942115) (xy 50.979121 -308.918858)
			(xy 51.026164 -308.903003) (xy 51.075152 -308.894968) (xy 51.099974 -308.89448) (xy 51.114157 -308.89466)
			(xy 51.142397 -308.89733) (xy 51.156362 -308.899814) (xy 51.168808 -308.9021) (xy 51.19243 -308.894734)
			(xy 51.2699 -308.817264) (xy 51.277266 -308.793642) (xy 51.27498 -308.781196) (xy 51.272507 -308.76723)
			(xy 51.269833 -308.73899) (xy 51.269646 -308.724808) (xy 51.269825 -308.710625) (xy 51.272495 -308.682385)
			(xy 51.27498 -308.66842) (xy 51.277266 -308.655974) (xy 51.2699 -308.632352) (xy 51.19243 -308.554882)
			(xy 51.168808 -308.547516) (xy 51.156362 -308.549802) (xy 51.142396 -308.55228) (xy 51.114157 -308.554951)
			(xy 51.099974 -308.555136) (xy 51.075155 -308.554594) (xy 51.026172 -308.546559) (xy 50.979134 -308.530706)
			(xy 50.935281 -308.507452) (xy 50.895768 -308.477409) (xy 50.861635 -308.441369) (xy 50.833783 -308.400282)
			(xy 50.812944 -308.355231) (xy 50.799669 -308.307401) (xy 50.794306 -308.258054) (xy 50.796998 -308.20849)
			(xy 50.807673 -308.160014) (xy 50.82605 -308.113903) (xy 50.851644 -308.071373) (xy 50.883782 -308.033544)
			(xy 50.921617 -308.001413) (xy 50.964152 -307.975826) (xy 51.010265 -307.957457) (xy 51.058743 -307.946791)
			(xy 51.108308 -307.944108) (xy 51.157654 -307.949479) (xy 51.205482 -307.962763) (xy 51.25053 -307.983609)
			(xy 51.291611 -308.011469) (xy 51.327645 -308.045608) (xy 51.357681 -308.085127) (xy 51.380927 -308.128984)
			(xy 51.396772 -308.176025) (xy 51.404798 -308.225009) (xy 51.405282 -308.249828) (xy 51.40511 -308.264011)
			(xy 51.402435 -308.292251) (xy 51.399948 -308.306216) (xy 51.397662 -308.318662) (xy 51.405028 -308.342284)
			(xy 51.482498 -308.419754) (xy 51.50612 -308.42712) (xy 51.518566 -308.424834) (xy 51.532531 -308.422353)
			(xy 51.560771 -308.419684) (xy 51.574954 -308.4195) (xy 51.589137 -308.419683) (xy 51.617377 -308.422351)
			(xy 51.631342 -308.424834) (xy 51.643788 -308.42712) (xy 51.66741 -308.419754) (xy 51.74488 -308.342284)
			(xy 51.752246 -308.318662) (xy 51.74996 -308.306216) (xy 51.747477 -308.292251) (xy 51.744809 -308.264011)
			(xy 51.744626 -308.249828) (xy 51.745048 -308.225005) (xy 51.753075 -308.176012) (xy 51.768923 -308.128963)
			(xy 51.792173 -308.085098) (xy 51.822214 -308.045573) (xy 51.858254 -308.011428) (xy 51.899342 -307.983563)
			(xy 51.944398 -307.962713) (xy 51.992233 -307.949426) (xy 52.041588 -307.944054) (xy 52.091161 -307.946737)
			(xy 52.139647 -307.957404) (xy 52.185769 -307.975776) (xy 52.228311 -308.001367) (xy 52.266153 -308.033503)
			(xy 52.298297 -308.071338) (xy 52.323897 -308.113875) (xy 52.342277 -308.159993) (xy 52.352955 -308.208477)
			(xy 52.3552 -308.2498) (xy 52.694097 -308.2498) (xy 52.698268 -308.199467) (xy 52.710666 -308.150507)
			(xy 52.730953 -308.104256) (xy 52.758577 -308.061974) (xy 52.792783 -308.024816) (xy 52.832638 -307.993794)
			(xy 52.877056 -307.969756) (xy 52.924825 -307.953356) (xy 52.974641 -307.945042) (xy 52.999894 -307.94452)
			(xy 53.014077 -307.944697) (xy 53.042317 -307.947369) (xy 53.056282 -307.949854) (xy 53.068728 -307.95214)
			(xy 53.09235 -307.944774) (xy 53.16982 -307.867304) (xy 53.177186 -307.843682) (xy 53.1749 -307.831236)
			(xy 53.172419 -307.817271) (xy 53.16975 -307.789031) (xy 53.169566 -307.774848) (xy 53.170026 -307.750022)
			(xy 53.178051 -307.701023) (xy 53.193899 -307.653967) (xy 53.21715 -307.610096) (xy 53.247194 -307.570565)
			(xy 53.283237 -307.536415) (xy 53.32433 -307.508546) (xy 53.369391 -307.487693) (xy 53.417233 -307.474406)
			(xy 53.466593 -307.469033) (xy 53.516173 -307.471718) (xy 53.564665 -307.482388) (xy 53.610791 -307.500764)
			(xy 53.653337 -307.52636) (xy 53.691182 -307.558503) (xy 53.723327 -307.596345) (xy 53.748926 -307.638889)
			(xy 53.767305 -307.685014) (xy 53.777979 -307.733505) (xy 53.78022 -307.774848) (xy 54.11903 -307.774848)
			(xy 54.12299 -307.725794) (xy 54.134767 -307.67801) (xy 54.154058 -307.632734) (xy 54.180361 -307.591138)
			(xy 54.212996 -307.554301) (xy 54.251117 -307.523176) (xy 54.293738 -307.498569) (xy 54.339754 -307.481117)
			(xy 54.387973 -307.471273) (xy 54.437148 -307.469292) (xy 54.486003 -307.475224) (xy 54.533274 -307.488916)
			(xy 54.577736 -307.510014) (xy 54.618239 -307.53797) (xy 54.653732 -307.572062) (xy 54.683297 -307.611406)
			(xy 54.706168 -307.654983) (xy 54.721752 -307.701664) (xy 54.729647 -307.750241) (xy 54.730142 -307.774848)
			(xy 55.06899 -307.774848) (xy 55.07295 -307.725794) (xy 55.084727 -307.67801) (xy 55.104018 -307.632734)
			(xy 55.130321 -307.591138) (xy 55.162956 -307.554301) (xy 55.201077 -307.523176) (xy 55.243698 -307.498569)
			(xy 55.289714 -307.481117) (xy 55.337933 -307.471273) (xy 55.387108 -307.469292) (xy 55.435963 -307.475224)
			(xy 55.483234 -307.488916) (xy 55.527696 -307.510014) (xy 55.568199 -307.53797) (xy 55.603692 -307.572062)
			(xy 55.633257 -307.611406) (xy 55.656128 -307.654983) (xy 55.671712 -307.701664) (xy 55.679607 -307.750241)
			(xy 55.680102 -307.774848) (xy 56.019204 -307.774848) (xy 56.023164 -307.725794) (xy 56.034941 -307.67801)
			(xy 56.054232 -307.632734) (xy 56.080535 -307.591138) (xy 56.11317 -307.554301) (xy 56.151291 -307.523176)
			(xy 56.193912 -307.498569) (xy 56.239928 -307.481117) (xy 56.288147 -307.471273) (xy 56.337322 -307.469292)
			(xy 56.386177 -307.475224) (xy 56.433448 -307.488916) (xy 56.47791 -307.510014) (xy 56.518413 -307.53797)
			(xy 56.553906 -307.572062) (xy 56.583471 -307.611406) (xy 56.606342 -307.654983) (xy 56.621926 -307.701664)
			(xy 56.629821 -307.750241) (xy 56.630316 -307.774848) (xy 56.969164 -307.774848) (xy 56.973124 -307.725794)
			(xy 56.984901 -307.67801) (xy 57.004192 -307.632734) (xy 57.030495 -307.591138) (xy 57.06313 -307.554301)
			(xy 57.101251 -307.523176) (xy 57.143872 -307.498569) (xy 57.189888 -307.481117) (xy 57.238107 -307.471273)
			(xy 57.287282 -307.469292) (xy 57.336137 -307.475224) (xy 57.383408 -307.488916) (xy 57.42787 -307.510014)
			(xy 57.468373 -307.53797) (xy 57.503866 -307.572062) (xy 57.533431 -307.611406) (xy 57.556302 -307.654983)
			(xy 57.571886 -307.701664) (xy 57.579781 -307.750241) (xy 57.580276 -307.774848) (xy 57.919124 -307.774848)
			(xy 57.923084 -307.725794) (xy 57.934861 -307.67801) (xy 57.954152 -307.632734) (xy 57.980455 -307.591138)
			(xy 58.01309 -307.554301) (xy 58.051211 -307.523176) (xy 58.093832 -307.498569) (xy 58.139848 -307.481117)
			(xy 58.188067 -307.471273) (xy 58.237242 -307.469292) (xy 58.286097 -307.475224) (xy 58.333368 -307.488916)
			(xy 58.37783 -307.510014) (xy 58.418333 -307.53797) (xy 58.453826 -307.572062) (xy 58.483391 -307.611406)
			(xy 58.506262 -307.654983) (xy 58.521846 -307.701664) (xy 58.529741 -307.750241) (xy 58.530236 -307.774848)
			(xy 59.819044 -307.774848) (xy 59.823004 -307.725794) (xy 59.834781 -307.67801) (xy 59.854072 -307.632734)
			(xy 59.880375 -307.591138) (xy 59.91301 -307.554301) (xy 59.951131 -307.523176) (xy 59.993752 -307.498569)
			(xy 60.039768 -307.481117) (xy 60.087987 -307.471273) (xy 60.137162 -307.469292) (xy 60.186017 -307.475224)
			(xy 60.233288 -307.488916) (xy 60.27775 -307.510014) (xy 60.318253 -307.53797) (xy 60.353746 -307.572062)
			(xy 60.383311 -307.611406) (xy 60.406182 -307.654983) (xy 60.421766 -307.701664) (xy 60.429661 -307.750241)
			(xy 60.430156 -307.774848) (xy 60.769004 -307.774848) (xy 60.772964 -307.725794) (xy 60.784741 -307.67801)
			(xy 60.804032 -307.632734) (xy 60.830335 -307.591138) (xy 60.86297 -307.554301) (xy 60.901091 -307.523176)
			(xy 60.943712 -307.498569) (xy 60.989728 -307.481117) (xy 61.037947 -307.471273) (xy 61.087122 -307.469292)
			(xy 61.135977 -307.475224) (xy 61.183248 -307.488916) (xy 61.22771 -307.510014) (xy 61.268213 -307.53797)
			(xy 61.303706 -307.572062) (xy 61.333271 -307.611406) (xy 61.356142 -307.654983) (xy 61.371726 -307.701664)
			(xy 61.379621 -307.750241) (xy 61.380116 -307.774848) (xy 61.379621 -307.799455) (xy 61.371726 -307.848032)
			(xy 61.356142 -307.894713) (xy 61.333271 -307.93829) (xy 61.303706 -307.977634) (xy 61.268213 -308.011726)
			(xy 61.22771 -308.039682) (xy 61.183248 -308.06078) (xy 61.135977 -308.074472) (xy 61.087122 -308.080404)
			(xy 61.037947 -308.078423) (xy 60.989728 -308.068579) (xy 60.943712 -308.051127) (xy 60.901091 -308.02652)
			(xy 60.86297 -307.995395) (xy 60.830335 -307.958558) (xy 60.804032 -307.916962) (xy 60.784741 -307.871686)
			(xy 60.772964 -307.823902) (xy 60.769004 -307.774848) (xy 60.430156 -307.774848) (xy 60.429661 -307.799455)
			(xy 60.421766 -307.848032) (xy 60.406182 -307.894713) (xy 60.383311 -307.93829) (xy 60.353746 -307.977634)
			(xy 60.318253 -308.011726) (xy 60.27775 -308.039682) (xy 60.233288 -308.06078) (xy 60.186017 -308.074472)
			(xy 60.137162 -308.080404) (xy 60.087987 -308.078423) (xy 60.039768 -308.068579) (xy 59.993752 -308.051127)
			(xy 59.951131 -308.02652) (xy 59.91301 -307.995395) (xy 59.880375 -307.958558) (xy 59.854072 -307.916962)
			(xy 59.834781 -307.871686) (xy 59.823004 -307.823902) (xy 59.819044 -307.774848) (xy 58.530236 -307.774848)
			(xy 58.529741 -307.799455) (xy 58.521846 -307.848032) (xy 58.506262 -307.894713) (xy 58.483391 -307.93829)
			(xy 58.453826 -307.977634) (xy 58.418333 -308.011726) (xy 58.37783 -308.039682) (xy 58.333368 -308.06078)
			(xy 58.286097 -308.074472) (xy 58.237242 -308.080404) (xy 58.188067 -308.078423) (xy 58.139848 -308.068579)
			(xy 58.093832 -308.051127) (xy 58.051211 -308.02652) (xy 58.01309 -307.995395) (xy 57.980455 -307.958558)
			(xy 57.954152 -307.916962) (xy 57.934861 -307.871686) (xy 57.923084 -307.823902) (xy 57.919124 -307.774848)
			(xy 57.580276 -307.774848) (xy 57.579781 -307.799455) (xy 57.571886 -307.848032) (xy 57.556302 -307.894713)
			(xy 57.533431 -307.93829) (xy 57.503866 -307.977634) (xy 57.468373 -308.011726) (xy 57.42787 -308.039682)
			(xy 57.383408 -308.06078) (xy 57.336137 -308.074472) (xy 57.287282 -308.080404) (xy 57.238107 -308.078423)
			(xy 57.189888 -308.068579) (xy 57.143872 -308.051127) (xy 57.101251 -308.02652) (xy 57.06313 -307.995395)
			(xy 57.030495 -307.958558) (xy 57.004192 -307.916962) (xy 56.984901 -307.871686) (xy 56.973124 -307.823902)
			(xy 56.969164 -307.774848) (xy 56.630316 -307.774848) (xy 56.629821 -307.799455) (xy 56.621926 -307.848032)
			(xy 56.606342 -307.894713) (xy 56.583471 -307.93829) (xy 56.553906 -307.977634) (xy 56.518413 -308.011726)
			(xy 56.47791 -308.039682) (xy 56.433448 -308.06078) (xy 56.386177 -308.074472) (xy 56.337322 -308.080404)
			(xy 56.288147 -308.078423) (xy 56.239928 -308.068579) (xy 56.193912 -308.051127) (xy 56.151291 -308.02652)
			(xy 56.11317 -307.995395) (xy 56.080535 -307.958558) (xy 56.054232 -307.916962) (xy 56.034941 -307.871686)
			(xy 56.023164 -307.823902) (xy 56.019204 -307.774848) (xy 55.680102 -307.774848) (xy 55.679607 -307.799455)
			(xy 55.671712 -307.848032) (xy 55.656128 -307.894713) (xy 55.633257 -307.93829) (xy 55.603692 -307.977634)
			(xy 55.568199 -308.011726) (xy 55.527696 -308.039682) (xy 55.483234 -308.06078) (xy 55.435963 -308.074472)
			(xy 55.387108 -308.080404) (xy 55.337933 -308.078423) (xy 55.289714 -308.068579) (xy 55.243698 -308.051127)
			(xy 55.201077 -308.02652) (xy 55.162956 -307.995395) (xy 55.130321 -307.958558) (xy 55.104018 -307.916962)
			(xy 55.084727 -307.871686) (xy 55.07295 -307.823902) (xy 55.06899 -307.774848) (xy 54.730142 -307.774848)
			(xy 54.729647 -307.799455) (xy 54.721752 -307.848032) (xy 54.706168 -307.894713) (xy 54.683297 -307.93829)
			(xy 54.653732 -307.977634) (xy 54.618239 -308.011726) (xy 54.577736 -308.039682) (xy 54.533274 -308.06078)
			(xy 54.486003 -308.074472) (xy 54.437148 -308.080404) (xy 54.387973 -308.078423) (xy 54.339754 -308.068579)
			(xy 54.293738 -308.051127) (xy 54.251117 -308.02652) (xy 54.212996 -307.995395) (xy 54.180361 -307.958558)
			(xy 54.154058 -307.916962) (xy 54.134767 -307.871686) (xy 54.12299 -307.823902) (xy 54.11903 -307.774848)
			(xy 53.78022 -307.774848) (xy 53.780667 -307.783085) (xy 53.775298 -307.832446) (xy 53.762014 -307.880288)
			(xy 53.741165 -307.92535) (xy 53.713299 -307.966446) (xy 53.679152 -308.002492) (xy 53.639622 -308.032538)
			(xy 53.595753 -308.055793) (xy 53.548699 -308.071643) (xy 53.4997 -308.079672) (xy 53.474874 -308.080156)
			(xy 53.460691 -308.079984) (xy 53.432451 -308.077309) (xy 53.418486 -308.074822) (xy 53.40604 -308.072536)
			(xy 53.382418 -308.079902) (xy 53.304948 -308.157372) (xy 53.297582 -308.180994) (xy 53.299868 -308.19344)
			(xy 53.302346 -308.207406) (xy 53.305017 -308.235645) (xy 53.305202 -308.249828) (xy 53.305029 -308.264011)
			(xy 53.302355 -308.292251) (xy 53.299868 -308.306216) (xy 53.297582 -308.318662) (xy 53.304948 -308.342284)
			(xy 53.382418 -308.419754) (xy 53.40604 -308.42712) (xy 53.418486 -308.424834) (xy 53.432453 -308.422364)
			(xy 53.460692 -308.419688) (xy 53.474874 -308.4195) (xy 53.500134 -308.419975) (xy 53.549965 -308.428286)
			(xy 53.597748 -308.444687) (xy 53.64218 -308.468729) (xy 53.682049 -308.499756) (xy 53.716266 -308.536923)
			(xy 53.743899 -308.579216) (xy 53.764193 -308.62548) (xy 53.776596 -308.674453) (xy 53.780768 -308.7248)
			(xy 53.780767 -308.724808) (xy 54.11903 -308.724808) (xy 54.12299 -308.675754) (xy 54.134767 -308.62797)
			(xy 54.154058 -308.582694) (xy 54.180361 -308.541098) (xy 54.212996 -308.504261) (xy 54.251117 -308.473136)
			(xy 54.293738 -308.448529) (xy 54.339754 -308.431077) (xy 54.387973 -308.421233) (xy 54.437148 -308.419252)
			(xy 54.486003 -308.425184) (xy 54.533274 -308.438876) (xy 54.577736 -308.459974) (xy 54.618239 -308.48793)
			(xy 54.653732 -308.522022) (xy 54.683297 -308.561366) (xy 54.706168 -308.604943) (xy 54.721752 -308.651624)
			(xy 54.729647 -308.700201) (xy 54.730142 -308.724808) (xy 54.729976 -308.733075) (xy 55.069087 -308.733075)
			(xy 55.071776 -308.683507) (xy 55.082448 -308.635027) (xy 55.100823 -308.588912) (xy 55.126416 -308.546378)
			(xy 55.158554 -308.508544) (xy 55.196389 -308.476408) (xy 55.238925 -308.450817) (xy 55.28504 -308.432444)
			(xy 55.333521 -308.421774) (xy 55.383089 -308.419087) (xy 55.432439 -308.424456) (xy 55.48027 -308.437737)
			(xy 55.525322 -308.458582) (xy 55.566408 -308.486441) (xy 55.602447 -308.52058) (xy 55.632487 -308.560099)
			(xy 55.655738 -308.603958) (xy 55.671587 -308.651001) (xy 55.679617 -308.699988) (xy 55.680102 -308.724808)
			(xy 55.679927 -308.738991) (xy 55.677254 -308.767231) (xy 55.674768 -308.781196) (xy 55.672482 -308.793642)
			(xy 55.679848 -308.817264) (xy 55.757318 -308.894734) (xy 55.78094 -308.9021) (xy 55.793386 -308.899814)
			(xy 55.807353 -308.897343) (xy 55.835592 -308.894668) (xy 55.849774 -308.89448) (xy 55.864021 -308.894637)
			(xy 55.892389 -308.897313) (xy 55.906416 -308.899814) (xy 55.918862 -308.9021) (xy 55.942484 -308.894734)
			(xy 56.011064 -308.826408) (xy 56.019226 -308.817175) (xy 56.026533 -308.793682) (xy 56.025034 -308.78145)
			(xy 56.025034 -308.780942) (xy 56.022566 -308.767039) (xy 56.019898 -308.738927) (xy 56.0197 -308.724808)
			(xy 56.020169 -308.699986) (xy 56.028199 -308.650997) (xy 56.044049 -308.603952) (xy 56.067301 -308.560092)
			(xy 56.097343 -308.52057) (xy 56.133383 -308.48643) (xy 56.174471 -308.45857) (xy 56.219525 -308.437724)
			(xy 56.267358 -308.424442) (xy 56.31671 -308.419073) (xy 56.36628 -308.42176) (xy 56.414763 -308.43243)
			(xy 56.460881 -308.450804) (xy 56.503418 -308.476396) (xy 56.541255 -308.508534) (xy 56.573394 -308.546369)
			(xy 56.598989 -308.588905) (xy 56.617365 -308.635022) (xy 56.628038 -308.683504) (xy 56.630279 -308.724808)
			(xy 57.919124 -308.724808) (xy 57.923084 -308.675754) (xy 57.934861 -308.62797) (xy 57.954152 -308.582694)
			(xy 57.980455 -308.541098) (xy 58.01309 -308.504261) (xy 58.051211 -308.473136) (xy 58.093832 -308.448529)
			(xy 58.139848 -308.431077) (xy 58.188067 -308.421233) (xy 58.237242 -308.419252) (xy 58.286097 -308.425184)
			(xy 58.333368 -308.438876) (xy 58.37783 -308.459974) (xy 58.418333 -308.48793) (xy 58.453826 -308.522022)
			(xy 58.483391 -308.561366) (xy 58.506262 -308.604943) (xy 58.521846 -308.651624) (xy 58.529741 -308.700201)
			(xy 58.530236 -308.724808) (xy 58.530069 -308.733113) (xy 59.819033 -308.733113) (xy 59.821717 -308.683534)
			(xy 59.832386 -308.635042) (xy 59.85076 -308.588916) (xy 59.876355 -308.546369) (xy 59.908496 -308.508525)
			(xy 59.946337 -308.476379) (xy 59.98888 -308.450778) (xy 60.035004 -308.432398) (xy 60.083494 -308.421722)
			(xy 60.133073 -308.419032) (xy 60.182433 -308.424399) (xy 60.230275 -308.437681) (xy 60.275338 -308.458528)
			(xy 60.316435 -308.486392) (xy 60.352481 -308.520537) (xy 60.382529 -308.560064) (xy 60.405786 -308.603932)
			(xy 60.421639 -308.650985) (xy 60.429671 -308.699982) (xy 60.430156 -308.724808) (xy 60.429981 -308.738991)
			(xy 60.427308 -308.767231) (xy 60.424822 -308.781196) (xy 60.422536 -308.793642) (xy 60.429902 -308.817264)
			(xy 60.507372 -308.894734) (xy 60.530994 -308.9021) (xy 60.54344 -308.899814) (xy 60.557406 -308.897336)
			(xy 60.585645 -308.894665) (xy 60.599828 -308.89448) (xy 60.614011 -308.894653) (xy 60.642251 -308.897328)
			(xy 60.656216 -308.899814) (xy 60.668662 -308.9021) (xy 60.692284 -308.894734) (xy 60.769754 -308.817264)
			(xy 60.77712 -308.793642) (xy 60.774834 -308.781196) (xy 60.772361 -308.76723) (xy 60.769687 -308.73899)
			(xy 60.7695 -308.724808) (xy 60.770022 -308.699553) (xy 60.778335 -308.649731) (xy 60.794736 -308.601957)
			(xy 60.818777 -308.557534) (xy 60.849801 -308.517674) (xy 60.886963 -308.483464) (xy 60.929249 -308.455838)
			(xy 60.975505 -308.435548) (xy 61.02447 -308.423148) (xy 61.074808 -308.418977) (xy 61.125146 -308.423148)
			(xy 61.174111 -308.435548) (xy 61.220367 -308.455838) (xy 61.262653 -308.483464) (xy 61.299815 -308.517674)
			(xy 61.330839 -308.557534) (xy 61.35488 -308.601957) (xy 61.371281 -308.649731) (xy 61.379594 -308.699553)
			(xy 61.380116 -308.724808) (xy 61.37994 -308.738991) (xy 61.377268 -308.767231) (xy 61.374782 -308.781196)
			(xy 61.372496 -308.793642) (xy 61.379862 -308.817264) (xy 61.457332 -308.894734) (xy 61.480954 -308.9021)
			(xy 61.4934 -308.899814) (xy 61.507367 -308.897342) (xy 61.535606 -308.894667) (xy 61.549788 -308.89448)
			(xy 61.563971 -308.894659) (xy 61.592211 -308.897329) (xy 61.606176 -308.899814) (xy 61.618622 -308.9021)
			(xy 61.642244 -308.894734) (xy 61.719714 -308.817264) (xy 61.72708 -308.793642) (xy 61.724794 -308.781196)
			(xy 61.722321 -308.76723) (xy 61.719647 -308.73899) (xy 61.71946 -308.724808) (xy 61.719969 -308.699986)
			(xy 61.728 -308.650995) (xy 61.743851 -308.603949) (xy 61.767104 -308.560088) (xy 61.797147 -308.520566)
			(xy 61.833188 -308.486425) (xy 61.874279 -308.458565) (xy 61.919335 -308.437721) (xy 61.96717 -308.42444)
			(xy 62.016523 -308.419073) (xy 62.066095 -308.421762) (xy 62.114578 -308.432435) (xy 62.160696 -308.450811)
			(xy 62.203233 -308.476407) (xy 62.241069 -308.508548) (xy 62.273207 -308.546386) (xy 62.298799 -308.588925)
			(xy 62.317172 -308.635045) (xy 62.327842 -308.683529) (xy 62.330526 -308.733101) (xy 62.325156 -308.782454)
			(xy 62.311871 -308.830288) (xy 62.291023 -308.875342) (xy 62.26316 -308.91643) (xy 62.229016 -308.952469)
			(xy 62.189492 -308.982509) (xy 62.145629 -309.005759) (xy 62.098581 -309.021606) (xy 62.04959 -309.029633)
			(xy 62.024768 -309.030116) (xy 62.010585 -309.029944) (xy 61.982345 -309.027269) (xy 61.96838 -309.024782)
			(xy 61.955934 -309.022496) (xy 61.932312 -309.029862) (xy 61.854842 -309.107332) (xy 61.847476 -309.130954)
			(xy 61.849762 -309.1434) (xy 61.852234 -309.157367) (xy 61.854909 -309.185606) (xy 61.855096 -309.199788)
			(xy 61.854574 -309.225043) (xy 61.846261 -309.274865) (xy 61.82986 -309.322639) (xy 61.805819 -309.367062)
			(xy 61.774795 -309.406922) (xy 61.737633 -309.441132) (xy 61.695347 -309.468758) (xy 61.649091 -309.489048)
			(xy 61.600126 -309.501448) (xy 61.549788 -309.505619) (xy 61.49945 -309.501448) (xy 61.450485 -309.489048)
			(xy 61.404229 -309.468758) (xy 61.361943 -309.441132) (xy 61.324781 -309.406922) (xy 61.293757 -309.367062)
			(xy 61.269716 -309.322639) (xy 61.253315 -309.274865) (xy 61.245002 -309.225043) (xy 61.24448 -309.199788)
			(xy 61.244655 -309.185605) (xy 61.247328 -309.157365) (xy 61.249814 -309.1434) (xy 61.2521 -309.130954)
			(xy 61.244734 -309.107332) (xy 61.167264 -309.029862) (xy 61.143642 -309.022496) (xy 61.131196 -309.024782)
			(xy 61.11723 -309.027255) (xy 61.08899 -309.029929) (xy 61.074808 -309.030116) (xy 61.060625 -309.029938)
			(xy 61.032385 -309.027267) (xy 61.01842 -309.024782) (xy 61.005974 -309.022496) (xy 60.982352 -309.029862)
			(xy 60.904882 -309.107332) (xy 60.897516 -309.130954) (xy 60.899802 -309.1434) (xy 60.902275 -309.157367)
			(xy 60.904949 -309.185606) (xy 60.905136 -309.199788) (xy 60.904614 -309.225043) (xy 60.896301 -309.274865)
			(xy 60.8799 -309.322639) (xy 60.855859 -309.367062) (xy 60.824835 -309.406922) (xy 60.787673 -309.441132)
			(xy 60.745387 -309.468758) (xy 60.699131 -309.489048) (xy 60.650166 -309.501448) (xy 60.599828 -309.505619)
			(xy 60.54949 -309.501448) (xy 60.500525 -309.489048) (xy 60.454269 -309.468758) (xy 60.411983 -309.441132)
			(xy 60.374821 -309.406922) (xy 60.343797 -309.367062) (xy 60.319756 -309.322639) (xy 60.303355 -309.274865)
			(xy 60.295042 -309.225043) (xy 60.29452 -309.199788) (xy 60.294695 -309.185605) (xy 60.297368 -309.157365)
			(xy 60.299854 -309.1434) (xy 60.30214 -309.130954) (xy 60.294774 -309.107332) (xy 60.217304 -309.029862)
			(xy 60.193682 -309.022496) (xy 60.181236 -309.024782) (xy 60.167271 -309.027263) (xy 60.139031 -309.029932)
			(xy 60.124848 -309.030116) (xy 60.100022 -309.029674) (xy 60.051024 -309.021649) (xy 60.003969 -309.005802)
			(xy 59.960098 -308.982551) (xy 59.920567 -308.952508) (xy 59.886417 -308.916466) (xy 59.858548 -308.875373)
			(xy 59.837695 -308.830313) (xy 59.824407 -308.782473) (xy 59.819033 -308.733113) (xy 58.530069 -308.733113)
			(xy 58.529741 -308.749415) (xy 58.521846 -308.797992) (xy 58.506262 -308.844673) (xy 58.483391 -308.88825)
			(xy 58.453826 -308.927594) (xy 58.418333 -308.961686) (xy 58.37783 -308.989642) (xy 58.333368 -309.01074)
			(xy 58.286097 -309.024432) (xy 58.237242 -309.030364) (xy 58.188067 -309.028383) (xy 58.139848 -309.018539)
			(xy 58.093832 -309.001087) (xy 58.051211 -308.97648) (xy 58.01309 -308.945355) (xy 57.980455 -308.908518)
			(xy 57.954152 -308.866922) (xy 57.934861 -308.821646) (xy 57.923084 -308.773862) (xy 57.919124 -308.724808)
			(xy 56.630279 -308.724808) (xy 56.630727 -308.733074) (xy 56.625361 -308.782426) (xy 56.612081 -308.83026)
			(xy 56.591238 -308.875315) (xy 56.56338 -308.916405) (xy 56.529242 -308.952446) (xy 56.489722 -308.98249)
			(xy 56.445862 -309.005744) (xy 56.398818 -309.021597) (xy 56.349829 -309.029629) (xy 56.325008 -309.030116)
			(xy 56.310762 -309.029941) (xy 56.282394 -309.027274) (xy 56.268366 -309.024782) (xy 56.25592 -309.022496)
			(xy 56.232298 -309.029862) (xy 56.163718 -309.098188) (xy 56.155556 -309.107421) (xy 56.14825 -309.130914)
			(xy 56.149748 -309.143146) (xy 56.149748 -309.143654) (xy 56.152215 -309.157557) (xy 56.154884 -309.185669)
			(xy 56.155082 -309.199788) (xy 56.15456 -309.225043) (xy 56.146247 -309.274865) (xy 56.129846 -309.322639)
			(xy 56.105805 -309.367062) (xy 56.074781 -309.406922) (xy 56.037619 -309.441132) (xy 55.995333 -309.468758)
			(xy 55.949077 -309.489048) (xy 55.900112 -309.501448) (xy 55.849774 -309.505619) (xy 55.799436 -309.501448)
			(xy 55.750471 -309.489048) (xy 55.704215 -309.468758) (xy 55.661929 -309.441132) (xy 55.624767 -309.406922)
			(xy 55.593743 -309.367062) (xy 55.569702 -309.322639) (xy 55.553301 -309.274865) (xy 55.544988 -309.225043)
			(xy 55.544466 -309.199788) (xy 55.544641 -309.185605) (xy 55.547314 -309.157365) (xy 55.5498 -309.1434)
			(xy 55.552086 -309.130954) (xy 55.54472 -309.107332) (xy 55.46725 -309.029862) (xy 55.443628 -309.022496)
			(xy 55.431182 -309.024782) (xy 55.417216 -309.027257) (xy 55.388976 -309.02993) (xy 55.374794 -309.030116)
			(xy 55.349974 -309.029616) (xy 55.300987 -309.021584) (xy 55.253945 -309.005732) (xy 55.210087 -308.982479)
			(xy 55.170569 -308.952437) (xy 55.136432 -308.916397) (xy 55.108575 -308.87531) (xy 55.087732 -308.830256)
			(xy 55.074453 -308.782425) (xy 55.069087 -308.733075) (xy 54.729976 -308.733075) (xy 54.729647 -308.749415)
			(xy 54.721752 -308.797992) (xy 54.706168 -308.844673) (xy 54.683297 -308.88825) (xy 54.653732 -308.927594)
			(xy 54.618239 -308.961686) (xy 54.577736 -308.989642) (xy 54.533274 -309.01074) (xy 54.486003 -309.024432)
			(xy 54.437148 -309.030364) (xy 54.387973 -309.028383) (xy 54.339754 -309.018539) (xy 54.293738 -309.001087)
			(xy 54.251117 -308.97648) (xy 54.212996 -308.945355) (xy 54.180361 -308.908518) (xy 54.154058 -308.866922)
			(xy 54.134767 -308.821646) (xy 54.12299 -308.773862) (xy 54.11903 -308.724808) (xy 53.780767 -308.724808)
			(xy 53.776596 -308.775147) (xy 53.764193 -308.82412) (xy 53.743899 -308.870384) (xy 53.716266 -308.912677)
			(xy 53.682049 -308.949844) (xy 53.64218 -308.980871) (xy 53.597748 -309.004913) (xy 53.549965 -309.021314)
			(xy 53.500134 -309.029625) (xy 53.474874 -309.030116) (xy 53.460691 -309.029943) (xy 53.432451 -309.027268)
			(xy 53.418486 -309.024782) (xy 53.40604 -309.022496) (xy 53.382418 -309.029862) (xy 53.304948 -309.107332)
			(xy 53.297582 -309.130954) (xy 53.299868 -309.1434) (xy 53.30234 -309.157367) (xy 53.305015 -309.185606)
			(xy 53.305202 -309.199788) (xy 53.304735 -309.22461) (xy 53.296705 -309.2736) (xy 53.280856 -309.320646)
			(xy 53.257604 -309.364508) (xy 53.227562 -309.40403) (xy 53.191522 -309.438171) (xy 53.150433 -309.466032)
			(xy 53.105379 -309.486879) (xy 53.057545 -309.500161) (xy 53.008192 -309.505531) (xy 52.958621 -309.502845)
			(xy 52.910137 -309.492174) (xy 52.864019 -309.4738) (xy 52.82148 -309.448208) (xy 52.783643 -309.41607)
			(xy 52.751503 -309.378234) (xy 52.725908 -309.335697) (xy 52.707531 -309.28958) (xy 52.696858 -309.241097)
			(xy 52.694169 -309.191526) (xy 52.699535 -309.142173) (xy 52.712815 -309.094338) (xy 52.733659 -309.049282)
			(xy 52.761517 -309.008192) (xy 52.795657 -308.97215) (xy 52.835177 -308.942106) (xy 52.879038 -308.918851)
			(xy 52.926082 -308.902999) (xy 52.975072 -308.894966) (xy 52.999894 -308.89448) (xy 53.014077 -308.894658)
			(xy 53.042317 -308.897329) (xy 53.056282 -308.899814) (xy 53.068728 -308.9021) (xy 53.09235 -308.894734)
			(xy 53.16982 -308.817264) (xy 53.177186 -308.793642) (xy 53.1749 -308.781196) (xy 53.172427 -308.76723)
			(xy 53.169753 -308.73899) (xy 53.169566 -308.724808) (xy 53.169744 -308.710625) (xy 53.172415 -308.682385)
			(xy 53.1749 -308.66842) (xy 53.177186 -308.655974) (xy 53.16982 -308.632352) (xy 53.09235 -308.554882)
			(xy 53.068728 -308.547516) (xy 53.056282 -308.549802) (xy 53.042316 -308.552277) (xy 53.014076 -308.55495)
			(xy 52.999894 -308.555136) (xy 52.974641 -308.554558) (xy 52.924825 -308.546244) (xy 52.877056 -308.529844)
			(xy 52.832638 -308.505806) (xy 52.792783 -308.474784) (xy 52.758577 -308.437626) (xy 52.730953 -308.395344)
			(xy 52.710666 -308.349093) (xy 52.698268 -308.300133) (xy 52.694097 -308.2498) (xy 52.3552 -308.2498)
			(xy 52.355648 -308.25805) (xy 52.350285 -308.307406) (xy 52.337009 -308.355244) (xy 52.316168 -308.400304)
			(xy 52.288311 -308.441398) (xy 52.254174 -308.477445) (xy 52.214654 -308.507493) (xy 52.170794 -308.530753)
			(xy 52.123748 -308.54661) (xy 52.074757 -308.554647) (xy 52.049934 -308.555136) (xy 52.035751 -308.554954)
			(xy 52.007511 -308.552285) (xy 51.993546 -308.549802) (xy 51.9811 -308.547516) (xy 51.957478 -308.554882)
			(xy 51.880008 -308.632352) (xy 51.872642 -308.655974) (xy 51.874928 -308.66842) (xy 51.877404 -308.682386)
			(xy 51.880076 -308.710626) (xy 51.880262 -308.724808) (xy 51.879869 -308.748804) (xy 51.87236 -308.796204)
			(xy 51.857527 -308.841846) (xy 51.835737 -308.884605) (xy 51.807525 -308.923428) (xy 51.773587 -308.95736)
			(xy 51.734759 -308.985565) (xy 51.691996 -309.007348) (xy 51.646351 -309.022172) (xy 51.59895 -309.029673)
			(xy 51.574954 -309.030116) (xy 51.560771 -309.029932) (xy 51.532531 -309.027265) (xy 51.518566 -309.024782)
			(xy 51.50612 -309.022496) (xy 51.482498 -309.029862) (xy 51.405028 -309.107332) (xy 51.397662 -309.130954)
			(xy 51.399948 -309.1434) (xy 51.40242 -309.157367) (xy 51.405095 -309.185606) (xy 51.405282 -309.199788)
			(xy 51.404835 -309.22461) (xy 51.396806 -309.273599) (xy 51.380957 -309.320644) (xy 51.357705 -309.364506)
			(xy 51.327664 -309.404028) (xy 51.291625 -309.438169) (xy 51.250537 -309.46603) (xy 51.205484 -309.486877)
			(xy 51.157651 -309.50016) (xy 51.108299 -309.50553) (xy 51.058728 -309.502845) (xy 51.010245 -309.492176)
			(xy 50.964127 -309.473804) (xy 50.921588 -309.448213) (xy 50.88375 -309.416077) (xy 50.851609 -309.378243)
			(xy 50.826013 -309.335708) (xy 50.807635 -309.289591) (xy 50.79696 -309.24111) (xy 50.794269 -309.191539)
			(xy 50.455556 -309.191539) (xy 50.452874 -309.241072) (xy 50.442204 -309.289561) (xy 50.423829 -309.335686)
			(xy 50.398234 -309.378231) (xy 50.366093 -309.416074) (xy 50.328253 -309.448218) (xy 50.285711 -309.473817)
			(xy 50.239588 -309.492196) (xy 50.191099 -309.50287) (xy 50.141522 -309.505559) (xy 50.092163 -309.500192)
			(xy 50.044323 -309.486909) (xy 49.999262 -309.466062) (xy 49.958167 -309.438199) (xy 49.922122 -309.404054)
			(xy 49.892075 -309.364527) (xy 49.86882 -309.320661) (xy 49.852968 -309.273609) (xy 49.844937 -309.224613)
			(xy 49.844452 -309.199788) (xy 49.844628 -309.185605) (xy 49.8473 -309.157365) (xy 49.849786 -309.1434)
			(xy 49.852072 -309.130954) (xy 49.844706 -309.107332) (xy 49.767236 -309.029862) (xy 49.743614 -309.022496)
			(xy 49.731168 -309.024782) (xy 49.717202 -309.027259) (xy 49.688963 -309.02993) (xy 49.67478 -309.030116)
			(xy 49.650789 -309.029656) (xy 49.603397 -309.022147) (xy 49.557763 -309.007317) (xy 49.515011 -308.985532)
			(xy 49.476193 -308.957327) (xy 49.442265 -308.923398) (xy 49.414062 -308.884579) (xy 49.392278 -308.841826)
			(xy 49.37745 -308.796191) (xy 49.369943 -308.748799) (xy 49.369472 -308.724808) (xy 49.36965 -308.710625)
			(xy 49.372321 -308.682385) (xy 49.374806 -308.66842) (xy 49.377092 -308.655974) (xy 49.369726 -308.632352)
			(xy 49.292256 -308.554882) (xy 49.268634 -308.547516) (xy 49.256188 -308.549802) (xy 49.242222 -308.552276)
			(xy 49.213982 -308.554949) (xy 49.1998 -308.555136) (xy 49.174979 -308.554622) (xy 49.12599 -308.546591)
			(xy 49.078946 -308.530739) (xy 49.035086 -308.507486) (xy 48.995567 -308.477443) (xy 48.961428 -308.441402)
			(xy 48.93357 -308.400313) (xy 48.912726 -308.355258) (xy 48.899447 -308.307424) (xy 48.894081 -308.258073)
			(xy 48.554982 -308.258073) (xy 48.554653 -308.274435) (xy 48.546758 -308.323012) (xy 48.531174 -308.369693)
			(xy 48.508303 -308.41327) (xy 48.478738 -308.452614) (xy 48.443245 -308.486706) (xy 48.402742 -308.514662)
			(xy 48.35828 -308.53576) (xy 48.311009 -308.549452) (xy 48.262154 -308.555384) (xy 48.212979 -308.553403)
			(xy 48.16476 -308.543559) (xy 48.118744 -308.526107) (xy 48.076123 -308.5015) (xy 48.038002 -308.470375)
			(xy 48.005367 -308.433538) (xy 47.979064 -308.391942) (xy 47.959773 -308.346666) (xy 47.947996 -308.298882)
			(xy 47.944036 -308.249828) (xy 47.605188 -308.249828) (xy 47.604693 -308.274435) (xy 47.596798 -308.323012)
			(xy 47.581214 -308.369693) (xy 47.558343 -308.41327) (xy 47.528778 -308.452614) (xy 47.493285 -308.486706)
			(xy 47.452782 -308.514662) (xy 47.40832 -308.53576) (xy 47.361049 -308.549452) (xy 47.312194 -308.555384)
			(xy 47.263019 -308.553403) (xy 47.2148 -308.543559) (xy 47.168784 -308.526107) (xy 47.126163 -308.5015)
			(xy 47.088042 -308.470375) (xy 47.055407 -308.433538) (xy 47.029104 -308.391942) (xy 47.009813 -308.346666)
			(xy 46.998036 -308.298882) (xy 46.994076 -308.249828) (xy 46.655228 -308.249828) (xy 46.654733 -308.274435)
			(xy 46.646838 -308.323012) (xy 46.631254 -308.369693) (xy 46.608383 -308.41327) (xy 46.578818 -308.452614)
			(xy 46.543325 -308.486706) (xy 46.502822 -308.514662) (xy 46.45836 -308.53576) (xy 46.411089 -308.549452)
			(xy 46.362234 -308.555384) (xy 46.313059 -308.553403) (xy 46.26484 -308.543559) (xy 46.218824 -308.526107)
			(xy 46.176203 -308.5015) (xy 46.138082 -308.470375) (xy 46.105447 -308.433538) (xy 46.079144 -308.391942)
			(xy 46.059853 -308.346666) (xy 46.048076 -308.298882) (xy 46.044116 -308.249828) (xy 45.705268 -308.249828)
			(xy 45.704773 -308.274435) (xy 45.696878 -308.323012) (xy 45.681294 -308.369693) (xy 45.658423 -308.41327)
			(xy 45.628858 -308.452614) (xy 45.593365 -308.486706) (xy 45.552862 -308.514662) (xy 45.5084 -308.53576)
			(xy 45.461129 -308.549452) (xy 45.412274 -308.555384) (xy 45.363099 -308.553403) (xy 45.31488 -308.543559)
			(xy 45.268864 -308.526107) (xy 45.226243 -308.5015) (xy 45.188122 -308.470375) (xy 45.155487 -308.433538)
			(xy 45.129184 -308.391942) (xy 45.109893 -308.346666) (xy 45.098116 -308.298882) (xy 45.094156 -308.249828)
			(xy 44.755054 -308.249828) (xy 44.754559 -308.274435) (xy 44.746664 -308.323012) (xy 44.73108 -308.369693)
			(xy 44.708209 -308.41327) (xy 44.678644 -308.452614) (xy 44.643151 -308.486706) (xy 44.602648 -308.514662)
			(xy 44.558186 -308.53576) (xy 44.510915 -308.549452) (xy 44.46206 -308.555384) (xy 44.412885 -308.553403)
			(xy 44.364666 -308.543559) (xy 44.31865 -308.526107) (xy 44.276029 -308.5015) (xy 44.237908 -308.470375)
			(xy 44.205273 -308.433538) (xy 44.17897 -308.391942) (xy 44.159679 -308.346666) (xy 44.147902 -308.298882)
			(xy 44.143942 -308.249828) (xy 43.805094 -308.249828) (xy 43.804599 -308.274435) (xy 43.796704 -308.323012)
			(xy 43.78112 -308.369693) (xy 43.758249 -308.41327) (xy 43.728684 -308.452614) (xy 43.693191 -308.486706)
			(xy 43.652688 -308.514662) (xy 43.608226 -308.53576) (xy 43.560955 -308.549452) (xy 43.5121 -308.555384)
			(xy 43.462925 -308.553403) (xy 43.414706 -308.543559) (xy 43.36869 -308.526107) (xy 43.326069 -308.5015)
			(xy 43.287948 -308.470375) (xy 43.255313 -308.433538) (xy 43.22901 -308.391942) (xy 43.209719 -308.346666)
			(xy 43.197942 -308.298882) (xy 43.193982 -308.249828) (xy 42.855047 -308.249828) (xy 42.855494 -308.258054)
			(xy 42.850131 -308.307401) (xy 42.836856 -308.355231) (xy 42.816017 -308.400282) (xy 42.788165 -308.441369)
			(xy 42.754032 -308.477409) (xy 42.714519 -308.507452) (xy 42.670666 -308.530706) (xy 42.623628 -308.546559)
			(xy 42.574645 -308.554594) (xy 42.549826 -308.555136) (xy 42.540658 -308.555044) (xy 42.522358 -308.553902)
			(xy 42.51325 -308.55285) (xy 42.512996 -308.55285) (xy 42.501197 -308.552043) (xy 42.47896 -308.560006)
			(xy 42.470324 -308.56809) (xy 42.405808 -308.635654) (xy 42.39895 -308.65826) (xy 42.399966 -308.665118)
			(xy 42.402484 -308.679911) (xy 42.405152 -308.709803) (xy 42.4053 -308.724808) (xy 42.405144 -308.73975)
			(xy 42.40247 -308.769513) (xy 42.399966 -308.784244) (xy 42.399966 -308.784752) (xy 42.39895 -308.791356)
			(xy 42.405808 -308.813962) (xy 42.470324 -308.881526) (xy 42.478964 -308.889593) (xy 42.5012 -308.897532)
			(xy 42.512996 -308.896766) (xy 42.51325 -308.896766) (xy 42.522357 -308.89571) (xy 42.540658 -308.894564)
			(xy 42.549826 -308.89448) (xy 42.574648 -308.894968) (xy 42.623636 -308.903003) (xy 42.670679 -308.918858)
			(xy 42.714538 -308.942115) (xy 42.754056 -308.972161) (xy 42.788193 -309.008205) (xy 42.816049 -309.049296)
			(xy 42.83689 -309.094352) (xy 42.850168 -309.142187) (xy 42.855531 -309.191539) (xy 42.855083 -309.199788)
			(xy 43.193982 -309.199788) (xy 43.197942 -309.150734) (xy 43.209719 -309.10295) (xy 43.22901 -309.057674)
			(xy 43.255313 -309.016078) (xy 43.287948 -308.979241) (xy 43.326069 -308.948116) (xy 43.36869 -308.923509)
			(xy 43.414706 -308.906057) (xy 43.462925 -308.896213) (xy 43.5121 -308.894232) (xy 43.560955 -308.900164)
			(xy 43.608226 -308.913856) (xy 43.652688 -308.934954) (xy 43.693191 -308.96291) (xy 43.728684 -308.997002)
			(xy 43.758249 -309.036346) (xy 43.78112 -309.079923) (xy 43.796704 -309.126604) (xy 43.804599 -309.175181)
			(xy 43.805094 -309.199788) (xy 44.143942 -309.199788) (xy 44.147902 -309.150734) (xy 44.159679 -309.10295)
			(xy 44.17897 -309.057674) (xy 44.205273 -309.016078) (xy 44.237908 -308.979241) (xy 44.276029 -308.948116)
			(xy 44.31865 -308.923509) (xy 44.364666 -308.906057) (xy 44.412885 -308.896213) (xy 44.46206 -308.894232)
			(xy 44.510915 -308.900164) (xy 44.558186 -308.913856) (xy 44.602648 -308.934954) (xy 44.643151 -308.96291)
			(xy 44.678644 -308.997002) (xy 44.708209 -309.036346) (xy 44.73108 -309.079923) (xy 44.746664 -309.126604)
			(xy 44.754559 -309.175181) (xy 44.755054 -309.199788) (xy 45.094156 -309.199788) (xy 45.098116 -309.150734)
			(xy 45.109893 -309.10295) (xy 45.129184 -309.057674) (xy 45.155487 -309.016078) (xy 45.188122 -308.979241)
			(xy 45.226243 -308.948116) (xy 45.268864 -308.923509) (xy 45.31488 -308.906057) (xy 45.363099 -308.896213)
			(xy 45.412274 -308.894232) (xy 45.461129 -308.900164) (xy 45.5084 -308.913856) (xy 45.552862 -308.934954)
			(xy 45.593365 -308.96291) (xy 45.628858 -308.997002) (xy 45.658423 -309.036346) (xy 45.681294 -309.079923)
			(xy 45.696878 -309.126604) (xy 45.704773 -309.175181) (xy 45.705268 -309.199788) (xy 46.044116 -309.199788)
			(xy 46.048076 -309.150734) (xy 46.059853 -309.10295) (xy 46.079144 -309.057674) (xy 46.105447 -309.016078)
			(xy 46.138082 -308.979241) (xy 46.176203 -308.948116) (xy 46.218824 -308.923509) (xy 46.26484 -308.906057)
			(xy 46.313059 -308.896213) (xy 46.362234 -308.894232) (xy 46.411089 -308.900164) (xy 46.45836 -308.913856)
			(xy 46.502822 -308.934954) (xy 46.543325 -308.96291) (xy 46.578818 -308.997002) (xy 46.608383 -309.036346)
			(xy 46.631254 -309.079923) (xy 46.646838 -309.126604) (xy 46.654733 -309.175181) (xy 46.655228 -309.199788)
			(xy 46.994076 -309.199788) (xy 46.998036 -309.150734) (xy 47.009813 -309.10295) (xy 47.029104 -309.057674)
			(xy 47.055407 -309.016078) (xy 47.088042 -308.979241) (xy 47.126163 -308.948116) (xy 47.168784 -308.923509)
			(xy 47.2148 -308.906057) (xy 47.263019 -308.896213) (xy 47.312194 -308.894232) (xy 47.361049 -308.900164)
			(xy 47.40832 -308.913856) (xy 47.452782 -308.934954) (xy 47.493285 -308.96291) (xy 47.528778 -308.997002)
			(xy 47.558343 -309.036346) (xy 47.581214 -309.079923) (xy 47.596798 -309.126604) (xy 47.604693 -309.175181)
			(xy 47.605188 -309.199788) (xy 47.605021 -309.208114) (xy 47.944042 -309.208114) (xy 47.946725 -309.158537)
			(xy 47.957393 -309.110048) (xy 47.975766 -309.063923) (xy 48.001359 -309.021378) (xy 48.033498 -308.983535)
			(xy 48.071336 -308.95139) (xy 48.113876 -308.925789) (xy 48.159998 -308.907409) (xy 48.208485 -308.896732)
			(xy 48.258062 -308.894041) (xy 48.30742 -308.899405) (xy 48.35526 -308.912685) (xy 48.400322 -308.933529)
			(xy 48.441418 -308.961389) (xy 48.477465 -308.995531) (xy 48.507513 -309.035055) (xy 48.530771 -309.078919)
			(xy 48.546627 -309.125969) (xy 48.554661 -309.174963) (xy 48.555148 -309.199788) (xy 48.554969 -309.213971)
			(xy 48.552298 -309.242211) (xy 48.549814 -309.256176) (xy 48.547528 -309.268622) (xy 48.554894 -309.292244)
			(xy 48.632364 -309.369714) (xy 48.655986 -309.37708) (xy 48.668432 -309.374794) (xy 48.682398 -309.372317)
			(xy 48.710637 -309.369646) (xy 48.72482 -309.36946) (xy 48.74881 -309.369944) (xy 48.796199 -309.377452)
			(xy 48.841831 -309.39228) (xy 48.884582 -309.414064) (xy 48.923399 -309.442266) (xy 48.957327 -309.476192)
			(xy 48.98553 -309.515008) (xy 49.007315 -309.557758) (xy 49.022145 -309.603389) (xy 49.029655 -309.650778)
			(xy 49.030128 -309.674768) (xy 49.029947 -309.688951) (xy 49.027278 -309.717191) (xy 49.024794 -309.731156)
			(xy 49.022508 -309.743602) (xy 49.029874 -309.767224) (xy 49.107344 -309.844694) (xy 49.130966 -309.85206)
			(xy 49.143412 -309.849774) (xy 49.157378 -309.8473) (xy 49.185618 -309.844626) (xy 49.1998 -309.84444)
			(xy 49.22462 -309.844878) (xy 49.273606 -309.852908) (xy 49.320648 -309.868758) (xy 49.364506 -309.892009)
			(xy 49.404025 -309.922049) (xy 49.438163 -309.958087) (xy 49.466022 -309.999172) (xy 49.486867 -310.044224)
			(xy 49.500149 -310.092054) (xy 49.505518 -310.141403) (xy 49.505066 -310.149748) (xy 49.843956 -310.149748)
			(xy 49.847916 -310.100694) (xy 49.859693 -310.05291) (xy 49.878984 -310.007634) (xy 49.905287 -309.966038)
			(xy 49.937922 -309.929201) (xy 49.976043 -309.898076) (xy 50.018664 -309.873469) (xy 50.06468 -309.856017)
			(xy 50.112899 -309.846173) (xy 50.162074 -309.844192) (xy 50.210929 -309.850124) (xy 50.2582 -309.863816)
			(xy 50.302662 -309.884914) (xy 50.343165 -309.91287) (xy 50.378658 -309.946962) (xy 50.408223 -309.986306)
			(xy 50.431094 -310.029883) (xy 50.446678 -310.076564) (xy 50.454573 -310.125141) (xy 50.455068 -310.149748)
			(xy 50.79417 -310.149748) (xy 50.79813 -310.100694) (xy 50.809907 -310.05291) (xy 50.829198 -310.007634)
			(xy 50.855501 -309.966038) (xy 50.888136 -309.929201) (xy 50.926257 -309.898076) (xy 50.968878 -309.873469)
			(xy 51.014894 -309.856017) (xy 51.063113 -309.846173) (xy 51.112288 -309.844192) (xy 51.161143 -309.850124)
			(xy 51.208414 -309.863816) (xy 51.252876 -309.884914) (xy 51.293379 -309.91287) (xy 51.328872 -309.946962)
			(xy 51.358437 -309.986306) (xy 51.381308 -310.029883) (xy 51.396892 -310.076564) (xy 51.404787 -310.125141)
			(xy 51.405282 -310.149748) (xy 51.74413 -310.149748) (xy 51.74809 -310.100694) (xy 51.759867 -310.05291)
			(xy 51.779158 -310.007634) (xy 51.805461 -309.966038) (xy 51.838096 -309.929201) (xy 51.876217 -309.898076)
			(xy 51.918838 -309.873469) (xy 51.964854 -309.856017) (xy 52.013073 -309.846173) (xy 52.062248 -309.844192)
			(xy 52.111103 -309.850124) (xy 52.158374 -309.863816) (xy 52.202836 -309.884914) (xy 52.243339 -309.91287)
			(xy 52.278832 -309.946962) (xy 52.308397 -309.986306) (xy 52.331268 -310.029883) (xy 52.346852 -310.076564)
			(xy 52.354747 -310.125141) (xy 52.355242 -310.149748) (xy 52.69409 -310.149748) (xy 52.69805 -310.100694)
			(xy 52.709827 -310.05291) (xy 52.729118 -310.007634) (xy 52.755421 -309.966038) (xy 52.788056 -309.929201)
			(xy 52.826177 -309.898076) (xy 52.868798 -309.873469) (xy 52.914814 -309.856017) (xy 52.963033 -309.846173)
			(xy 53.012208 -309.844192) (xy 53.061063 -309.850124) (xy 53.108334 -309.863816) (xy 53.152796 -309.884914)
			(xy 53.193299 -309.91287) (xy 53.228792 -309.946962) (xy 53.258357 -309.986306) (xy 53.281228 -310.029883)
			(xy 53.296812 -310.076564) (xy 53.304707 -310.125141) (xy 53.305202 -310.149748) (xy 53.64405 -310.149748)
			(xy 53.64801 -310.100694) (xy 53.659787 -310.05291) (xy 53.679078 -310.007634) (xy 53.705381 -309.966038)
			(xy 53.738016 -309.929201) (xy 53.776137 -309.898076) (xy 53.818758 -309.873469) (xy 53.864774 -309.856017)
			(xy 53.912993 -309.846173) (xy 53.962168 -309.844192) (xy 54.011023 -309.850124) (xy 54.058294 -309.863816)
			(xy 54.102756 -309.884914) (xy 54.143259 -309.91287) (xy 54.178752 -309.946962) (xy 54.208317 -309.986306)
			(xy 54.231188 -310.029883) (xy 54.246772 -310.076564) (xy 54.254667 -310.125141) (xy 54.255162 -310.149748)
			(xy 54.59401 -310.149748) (xy 54.59797 -310.100694) (xy 54.609747 -310.05291) (xy 54.629038 -310.007634)
			(xy 54.655341 -309.966038) (xy 54.687976 -309.929201) (xy 54.726097 -309.898076) (xy 54.768718 -309.873469)
			(xy 54.814734 -309.856017) (xy 54.862953 -309.846173) (xy 54.912128 -309.844192) (xy 54.960983 -309.850124)
			(xy 55.008254 -309.863816) (xy 55.052716 -309.884914) (xy 55.093219 -309.91287) (xy 55.128712 -309.946962)
			(xy 55.158277 -309.986306) (xy 55.181148 -310.029883) (xy 55.196732 -310.076564) (xy 55.204627 -310.125141)
			(xy 55.205122 -310.149748) (xy 55.54397 -310.149748) (xy 55.54793 -310.100694) (xy 55.559707 -310.05291)
			(xy 55.578998 -310.007634) (xy 55.605301 -309.966038) (xy 55.637936 -309.929201) (xy 55.676057 -309.898076)
			(xy 55.718678 -309.873469) (xy 55.764694 -309.856017) (xy 55.812913 -309.846173) (xy 55.862088 -309.844192)
			(xy 55.910943 -309.850124) (xy 55.958214 -309.863816) (xy 56.002676 -309.884914) (xy 56.043179 -309.91287)
			(xy 56.078672 -309.946962) (xy 56.108237 -309.986306) (xy 56.131108 -310.029883) (xy 56.146692 -310.076564)
			(xy 56.154587 -310.125141) (xy 56.155082 -310.149748) (xy 56.494184 -310.149748) (xy 56.498144 -310.100694)
			(xy 56.509921 -310.05291) (xy 56.529212 -310.007634) (xy 56.555515 -309.966038) (xy 56.58815 -309.929201)
			(xy 56.626271 -309.898076) (xy 56.668892 -309.873469) (xy 56.714908 -309.856017) (xy 56.763127 -309.846173)
			(xy 56.812302 -309.844192) (xy 56.861157 -309.850124) (xy 56.908428 -309.863816) (xy 56.95289 -309.884914)
			(xy 56.993393 -309.91287) (xy 57.028886 -309.946962) (xy 57.058451 -309.986306) (xy 57.081322 -310.029883)
			(xy 57.096906 -310.076564) (xy 57.104801 -310.125141) (xy 57.105296 -310.149748) (xy 57.444144 -310.149748)
			(xy 57.448104 -310.100694) (xy 57.459881 -310.05291) (xy 57.479172 -310.007634) (xy 57.505475 -309.966038)
			(xy 57.53811 -309.929201) (xy 57.576231 -309.898076) (xy 57.618852 -309.873469) (xy 57.664868 -309.856017)
			(xy 57.713087 -309.846173) (xy 57.762262 -309.844192) (xy 57.811117 -309.850124) (xy 57.858388 -309.863816)
			(xy 57.90285 -309.884914) (xy 57.943353 -309.91287) (xy 57.978846 -309.946962) (xy 58.008411 -309.986306)
			(xy 58.031282 -310.029883) (xy 58.046866 -310.076564) (xy 58.054761 -310.125141) (xy 58.055256 -310.149748)
			(xy 58.394104 -310.149748) (xy 58.398064 -310.100694) (xy 58.409841 -310.05291) (xy 58.429132 -310.007634)
			(xy 58.455435 -309.966038) (xy 58.48807 -309.929201) (xy 58.526191 -309.898076) (xy 58.568812 -309.873469)
			(xy 58.614828 -309.856017) (xy 58.663047 -309.846173) (xy 58.712222 -309.844192) (xy 58.761077 -309.850124)
			(xy 58.808348 -309.863816) (xy 58.85281 -309.884914) (xy 58.893313 -309.91287) (xy 58.928806 -309.946962)
			(xy 58.958371 -309.986306) (xy 58.981242 -310.029883) (xy 58.996826 -310.076564) (xy 59.004721 -310.125141)
			(xy 59.005216 -310.149748) (xy 59.344064 -310.149748) (xy 59.348024 -310.100694) (xy 59.359801 -310.05291)
			(xy 59.379092 -310.007634) (xy 59.405395 -309.966038) (xy 59.43803 -309.929201) (xy 59.476151 -309.898076)
			(xy 59.518772 -309.873469) (xy 59.564788 -309.856017) (xy 59.613007 -309.846173) (xy 59.662182 -309.844192)
			(xy 59.711037 -309.850124) (xy 59.758308 -309.863816) (xy 59.80277 -309.884914) (xy 59.843273 -309.91287)
			(xy 59.878766 -309.946962) (xy 59.908331 -309.986306) (xy 59.931202 -310.029883) (xy 59.946786 -310.076564)
			(xy 59.954681 -310.125141) (xy 59.955176 -310.149748) (xy 60.294024 -310.149748) (xy 60.297984 -310.100694)
			(xy 60.309761 -310.05291) (xy 60.329052 -310.007634) (xy 60.355355 -309.966038) (xy 60.38799 -309.929201)
			(xy 60.426111 -309.898076) (xy 60.468732 -309.873469) (xy 60.514748 -309.856017) (xy 60.562967 -309.846173)
			(xy 60.612142 -309.844192) (xy 60.660997 -309.850124) (xy 60.708268 -309.863816) (xy 60.75273 -309.884914)
			(xy 60.793233 -309.91287) (xy 60.828726 -309.946962) (xy 60.858291 -309.986306) (xy 60.881162 -310.029883)
			(xy 60.896746 -310.076564) (xy 60.904641 -310.125141) (xy 60.905136 -310.149748) (xy 61.243984 -310.149748)
			(xy 61.247944 -310.100694) (xy 61.259721 -310.05291) (xy 61.279012 -310.007634) (xy 61.305315 -309.966038)
			(xy 61.33795 -309.929201) (xy 61.376071 -309.898076) (xy 61.418692 -309.873469) (xy 61.464708 -309.856017)
			(xy 61.512927 -309.846173) (xy 61.562102 -309.844192) (xy 61.610957 -309.850124) (xy 61.658228 -309.863816)
			(xy 61.70269 -309.884914) (xy 61.743193 -309.91287) (xy 61.778686 -309.946962) (xy 61.808251 -309.986306)
			(xy 61.831122 -310.029883) (xy 61.846706 -310.076564) (xy 61.854601 -310.125141) (xy 61.855096 -310.149748)
			(xy 61.854601 -310.174355) (xy 61.846706 -310.222932) (xy 61.831122 -310.269613) (xy 61.808251 -310.31319)
			(xy 61.778686 -310.352534) (xy 61.743193 -310.386626) (xy 61.70269 -310.414582) (xy 61.658228 -310.43568)
			(xy 61.610957 -310.449372) (xy 61.562102 -310.455304) (xy 61.512927 -310.453323) (xy 61.464708 -310.443479)
			(xy 61.418692 -310.426027) (xy 61.376071 -310.40142) (xy 61.33795 -310.370295) (xy 61.305315 -310.333458)
			(xy 61.279012 -310.291862) (xy 61.259721 -310.246586) (xy 61.247944 -310.198802) (xy 61.243984 -310.149748)
			(xy 60.905136 -310.149748) (xy 60.904641 -310.174355) (xy 60.896746 -310.222932) (xy 60.881162 -310.269613)
			(xy 60.858291 -310.31319) (xy 60.828726 -310.352534) (xy 60.793233 -310.386626) (xy 60.75273 -310.414582)
			(xy 60.708268 -310.43568) (xy 60.660997 -310.449372) (xy 60.612142 -310.455304) (xy 60.562967 -310.453323)
			(xy 60.514748 -310.443479) (xy 60.468732 -310.426027) (xy 60.426111 -310.40142) (xy 60.38799 -310.370295)
			(xy 60.355355 -310.333458) (xy 60.329052 -310.291862) (xy 60.309761 -310.246586) (xy 60.297984 -310.198802)
			(xy 60.294024 -310.149748) (xy 59.955176 -310.149748) (xy 59.954681 -310.174355) (xy 59.946786 -310.222932)
			(xy 59.931202 -310.269613) (xy 59.908331 -310.31319) (xy 59.878766 -310.352534) (xy 59.843273 -310.386626)
			(xy 59.80277 -310.414582) (xy 59.758308 -310.43568) (xy 59.711037 -310.449372) (xy 59.662182 -310.455304)
			(xy 59.613007 -310.453323) (xy 59.564788 -310.443479) (xy 59.518772 -310.426027) (xy 59.476151 -310.40142)
			(xy 59.43803 -310.370295) (xy 59.405395 -310.333458) (xy 59.379092 -310.291862) (xy 59.359801 -310.246586)
			(xy 59.348024 -310.198802) (xy 59.344064 -310.149748) (xy 59.005216 -310.149748) (xy 59.004721 -310.174355)
			(xy 58.996826 -310.222932) (xy 58.981242 -310.269613) (xy 58.958371 -310.31319) (xy 58.928806 -310.352534)
			(xy 58.893313 -310.386626) (xy 58.85281 -310.414582) (xy 58.808348 -310.43568) (xy 58.761077 -310.449372)
			(xy 58.712222 -310.455304) (xy 58.663047 -310.453323) (xy 58.614828 -310.443479) (xy 58.568812 -310.426027)
			(xy 58.526191 -310.40142) (xy 58.48807 -310.370295) (xy 58.455435 -310.333458) (xy 58.429132 -310.291862)
			(xy 58.409841 -310.246586) (xy 58.398064 -310.198802) (xy 58.394104 -310.149748) (xy 58.055256 -310.149748)
			(xy 58.054761 -310.174355) (xy 58.046866 -310.222932) (xy 58.031282 -310.269613) (xy 58.008411 -310.31319)
			(xy 57.978846 -310.352534) (xy 57.943353 -310.386626) (xy 57.90285 -310.414582) (xy 57.858388 -310.43568)
			(xy 57.811117 -310.449372) (xy 57.762262 -310.455304) (xy 57.713087 -310.453323) (xy 57.664868 -310.443479)
			(xy 57.618852 -310.426027) (xy 57.576231 -310.40142) (xy 57.53811 -310.370295) (xy 57.505475 -310.333458)
			(xy 57.479172 -310.291862) (xy 57.459881 -310.246586) (xy 57.448104 -310.198802) (xy 57.444144 -310.149748)
			(xy 57.105296 -310.149748) (xy 57.104801 -310.174355) (xy 57.096906 -310.222932) (xy 57.081322 -310.269613)
			(xy 57.058451 -310.31319) (xy 57.028886 -310.352534) (xy 56.993393 -310.386626) (xy 56.95289 -310.414582)
			(xy 56.908428 -310.43568) (xy 56.861157 -310.449372) (xy 56.812302 -310.455304) (xy 56.763127 -310.453323)
			(xy 56.714908 -310.443479) (xy 56.668892 -310.426027) (xy 56.626271 -310.40142) (xy 56.58815 -310.370295)
			(xy 56.555515 -310.333458) (xy 56.529212 -310.291862) (xy 56.509921 -310.246586) (xy 56.498144 -310.198802)
			(xy 56.494184 -310.149748) (xy 56.155082 -310.149748) (xy 56.154587 -310.174355) (xy 56.146692 -310.222932)
			(xy 56.131108 -310.269613) (xy 56.108237 -310.31319) (xy 56.078672 -310.352534) (xy 56.043179 -310.386626)
			(xy 56.002676 -310.414582) (xy 55.958214 -310.43568) (xy 55.910943 -310.449372) (xy 55.862088 -310.455304)
			(xy 55.812913 -310.453323) (xy 55.764694 -310.443479) (xy 55.718678 -310.426027) (xy 55.676057 -310.40142)
			(xy 55.637936 -310.370295) (xy 55.605301 -310.333458) (xy 55.578998 -310.291862) (xy 55.559707 -310.246586)
			(xy 55.54793 -310.198802) (xy 55.54397 -310.149748) (xy 55.205122 -310.149748) (xy 55.204627 -310.174355)
			(xy 55.196732 -310.222932) (xy 55.181148 -310.269613) (xy 55.158277 -310.31319) (xy 55.128712 -310.352534)
			(xy 55.093219 -310.386626) (xy 55.052716 -310.414582) (xy 55.008254 -310.43568) (xy 54.960983 -310.449372)
			(xy 54.912128 -310.455304) (xy 54.862953 -310.453323) (xy 54.814734 -310.443479) (xy 54.768718 -310.426027)
			(xy 54.726097 -310.40142) (xy 54.687976 -310.370295) (xy 54.655341 -310.333458) (xy 54.629038 -310.291862)
			(xy 54.609747 -310.246586) (xy 54.59797 -310.198802) (xy 54.59401 -310.149748) (xy 54.255162 -310.149748)
			(xy 54.254667 -310.174355) (xy 54.246772 -310.222932) (xy 54.231188 -310.269613) (xy 54.208317 -310.31319)
			(xy 54.178752 -310.352534) (xy 54.143259 -310.386626) (xy 54.102756 -310.414582) (xy 54.058294 -310.43568)
			(xy 54.011023 -310.449372) (xy 53.962168 -310.455304) (xy 53.912993 -310.453323) (xy 53.864774 -310.443479)
			(xy 53.818758 -310.426027) (xy 53.776137 -310.40142) (xy 53.738016 -310.370295) (xy 53.705381 -310.333458)
			(xy 53.679078 -310.291862) (xy 53.659787 -310.246586) (xy 53.64801 -310.198802) (xy 53.64405 -310.149748)
			(xy 53.305202 -310.149748) (xy 53.304707 -310.174355) (xy 53.296812 -310.222932) (xy 53.281228 -310.269613)
			(xy 53.258357 -310.31319) (xy 53.228792 -310.352534) (xy 53.193299 -310.386626) (xy 53.152796 -310.414582)
			(xy 53.108334 -310.43568) (xy 53.061063 -310.449372) (xy 53.012208 -310.455304) (xy 52.963033 -310.453323)
			(xy 52.914814 -310.443479) (xy 52.868798 -310.426027) (xy 52.826177 -310.40142) (xy 52.788056 -310.370295)
			(xy 52.755421 -310.333458) (xy 52.729118 -310.291862) (xy 52.709827 -310.246586) (xy 52.69805 -310.198802)
			(xy 52.69409 -310.149748) (xy 52.355242 -310.149748) (xy 52.354747 -310.174355) (xy 52.346852 -310.222932)
			(xy 52.331268 -310.269613) (xy 52.308397 -310.31319) (xy 52.278832 -310.352534) (xy 52.243339 -310.386626)
			(xy 52.202836 -310.414582) (xy 52.158374 -310.43568) (xy 52.111103 -310.449372) (xy 52.062248 -310.455304)
			(xy 52.013073 -310.453323) (xy 51.964854 -310.443479) (xy 51.918838 -310.426027) (xy 51.876217 -310.40142)
			(xy 51.838096 -310.370295) (xy 51.805461 -310.333458) (xy 51.779158 -310.291862) (xy 51.759867 -310.246586)
			(xy 51.74809 -310.198802) (xy 51.74413 -310.149748) (xy 51.405282 -310.149748) (xy 51.404787 -310.174355)
			(xy 51.396892 -310.222932) (xy 51.381308 -310.269613) (xy 51.358437 -310.31319) (xy 51.328872 -310.352534)
			(xy 51.293379 -310.386626) (xy 51.252876 -310.414582) (xy 51.208414 -310.43568) (xy 51.161143 -310.449372)
			(xy 51.112288 -310.455304) (xy 51.063113 -310.453323) (xy 51.014894 -310.443479) (xy 50.968878 -310.426027)
			(xy 50.926257 -310.40142) (xy 50.888136 -310.370295) (xy 50.855501 -310.333458) (xy 50.829198 -310.291862)
			(xy 50.809907 -310.246586) (xy 50.79813 -310.198802) (xy 50.79417 -310.149748) (xy 50.455068 -310.149748)
			(xy 50.454573 -310.174355) (xy 50.446678 -310.222932) (xy 50.431094 -310.269613) (xy 50.408223 -310.31319)
			(xy 50.378658 -310.352534) (xy 50.343165 -310.386626) (xy 50.302662 -310.414582) (xy 50.2582 -310.43568)
			(xy 50.210929 -310.449372) (xy 50.162074 -310.455304) (xy 50.112899 -310.453323) (xy 50.06468 -310.443479)
			(xy 50.018664 -310.426027) (xy 49.976043 -310.40142) (xy 49.937922 -310.370295) (xy 49.905287 -310.333458)
			(xy 49.878984 -310.291862) (xy 49.859693 -310.246586) (xy 49.847916 -310.198802) (xy 49.843956 -310.149748)
			(xy 49.505066 -310.149748) (xy 49.502834 -310.19097) (xy 49.492165 -310.23945) (xy 49.473795 -310.285566)
			(xy 49.448206 -310.328102) (xy 49.416072 -310.365938) (xy 49.378241 -310.398078) (xy 49.335709 -310.423673)
			(xy 49.289596 -310.442051) (xy 49.241118 -310.452727) (xy 49.191551 -310.45542) (xy 49.142201 -310.450058)
			(xy 49.094369 -310.436783) (xy 49.049314 -310.415945) (xy 49.008224 -310.388093) (xy 48.972181 -310.35396)
			(xy 48.942135 -310.314446) (xy 48.918877 -310.270592) (xy 48.90302 -310.223553) (xy 48.894982 -310.174568)
			(xy 48.894492 -310.149748) (xy 48.894675 -310.135565) (xy 48.897343 -310.107325) (xy 48.899826 -310.09336)
			(xy 48.902112 -310.080914) (xy 48.894746 -310.057292) (xy 48.817276 -309.979822) (xy 48.793654 -309.972456)
			(xy 48.781208 -309.974742) (xy 48.767241 -309.977213) (xy 48.739002 -309.979889) (xy 48.72482 -309.980076)
			(xy 48.710637 -309.979897) (xy 48.682397 -309.977227) (xy 48.668432 -309.974742) (xy 48.655986 -309.972456)
			(xy 48.632364 -309.979822) (xy 48.554894 -310.057292) (xy 48.547528 -310.080914) (xy 48.549814 -310.09336)
			(xy 48.552295 -310.107325) (xy 48.554964 -310.135565) (xy 48.555148 -310.149748) (xy 48.55457 -310.174565)
			(xy 48.546533 -310.223543) (xy 48.530677 -310.270576) (xy 48.507422 -310.314425) (xy 48.477379 -310.353933)
			(xy 48.44134 -310.388061) (xy 48.400254 -310.415908) (xy 48.355205 -310.436742) (xy 48.307378 -310.450013)
			(xy 48.258035 -310.455372) (xy 48.208475 -310.452678) (xy 48.160003 -310.442001) (xy 48.113897 -310.423623)
			(xy 48.071372 -310.398028) (xy 48.033548 -310.36589) (xy 48.001421 -310.328057) (xy 47.975838 -310.285524)
			(xy 47.957473 -310.239413) (xy 47.94681 -310.190938) (xy 47.94413 -310.141377) (xy 47.949503 -310.092035)
			(xy 47.962789 -310.044212) (xy 47.983635 -309.999169) (xy 48.011495 -309.958091) (xy 48.045633 -309.922062)
			(xy 48.08515 -309.892031) (xy 48.129005 -309.868788) (xy 48.176042 -309.852946) (xy 48.225023 -309.844922)
			(xy 48.24984 -309.84444) (xy 48.264023 -309.84461) (xy 48.292263 -309.847287) (xy 48.306228 -309.849774)
			(xy 48.318674 -309.85206) (xy 48.342296 -309.844694) (xy 48.419766 -309.767224) (xy 48.427132 -309.743602)
			(xy 48.424846 -309.731156) (xy 48.422368 -309.71719) (xy 48.419697 -309.688951) (xy 48.419512 -309.674768)
			(xy 48.419684 -309.660585) (xy 48.422359 -309.632345) (xy 48.424846 -309.61838) (xy 48.427132 -309.605934)
			(xy 48.419766 -309.582312) (xy 48.342296 -309.504842) (xy 48.318674 -309.497476) (xy 48.306228 -309.499762)
			(xy 48.292263 -309.502244) (xy 48.264023 -309.504912) (xy 48.24984 -309.505096) (xy 48.225015 -309.504665)
			(xy 48.176019 -309.496639) (xy 48.128967 -309.480792) (xy 48.085099 -309.457541) (xy 48.04557 -309.427499)
			(xy 48.011422 -309.391458) (xy 47.983555 -309.350367) (xy 47.962703 -309.305309) (xy 47.949415 -309.257471)
			(xy 47.944042 -309.208114) (xy 47.605021 -309.208114) (xy 47.604693 -309.224395) (xy 47.596798 -309.272972)
			(xy 47.581214 -309.319653) (xy 47.558343 -309.36323) (xy 47.528778 -309.402574) (xy 47.493285 -309.436666)
			(xy 47.452782 -309.464622) (xy 47.40832 -309.48572) (xy 47.361049 -309.499412) (xy 47.312194 -309.505344)
			(xy 47.263019 -309.503363) (xy 47.2148 -309.493519) (xy 47.168784 -309.476067) (xy 47.126163 -309.45146)
			(xy 47.088042 -309.420335) (xy 47.055407 -309.383498) (xy 47.029104 -309.341902) (xy 47.009813 -309.296626)
			(xy 46.998036 -309.248842) (xy 46.994076 -309.199788) (xy 46.655228 -309.199788) (xy 46.654733 -309.224395)
			(xy 46.646838 -309.272972) (xy 46.631254 -309.319653) (xy 46.608383 -309.36323) (xy 46.578818 -309.402574)
			(xy 46.543325 -309.436666) (xy 46.502822 -309.464622) (xy 46.45836 -309.48572) (xy 46.411089 -309.499412)
			(xy 46.362234 -309.505344) (xy 46.313059 -309.503363) (xy 46.26484 -309.493519) (xy 46.218824 -309.476067)
			(xy 46.176203 -309.45146) (xy 46.138082 -309.420335) (xy 46.105447 -309.383498) (xy 46.079144 -309.341902)
			(xy 46.059853 -309.296626) (xy 46.048076 -309.248842) (xy 46.044116 -309.199788) (xy 45.705268 -309.199788)
			(xy 45.704773 -309.224395) (xy 45.696878 -309.272972) (xy 45.681294 -309.319653) (xy 45.658423 -309.36323)
			(xy 45.628858 -309.402574) (xy 45.593365 -309.436666) (xy 45.552862 -309.464622) (xy 45.5084 -309.48572)
			(xy 45.461129 -309.499412) (xy 45.412274 -309.505344) (xy 45.363099 -309.503363) (xy 45.31488 -309.493519)
			(xy 45.268864 -309.476067) (xy 45.226243 -309.45146) (xy 45.188122 -309.420335) (xy 45.155487 -309.383498)
			(xy 45.129184 -309.341902) (xy 45.109893 -309.296626) (xy 45.098116 -309.248842) (xy 45.094156 -309.199788)
			(xy 44.755054 -309.199788) (xy 44.754559 -309.224395) (xy 44.746664 -309.272972) (xy 44.73108 -309.319653)
			(xy 44.708209 -309.36323) (xy 44.678644 -309.402574) (xy 44.643151 -309.436666) (xy 44.602648 -309.464622)
			(xy 44.558186 -309.48572) (xy 44.510915 -309.499412) (xy 44.46206 -309.505344) (xy 44.412885 -309.503363)
			(xy 44.364666 -309.493519) (xy 44.31865 -309.476067) (xy 44.276029 -309.45146) (xy 44.237908 -309.420335)
			(xy 44.205273 -309.383498) (xy 44.17897 -309.341902) (xy 44.159679 -309.296626) (xy 44.147902 -309.248842)
			(xy 44.143942 -309.199788) (xy 43.805094 -309.199788) (xy 43.804599 -309.224395) (xy 43.796704 -309.272972)
			(xy 43.78112 -309.319653) (xy 43.758249 -309.36323) (xy 43.728684 -309.402574) (xy 43.693191 -309.436666)
			(xy 43.652688 -309.464622) (xy 43.608226 -309.48572) (xy 43.560955 -309.499412) (xy 43.5121 -309.505344)
			(xy 43.462925 -309.503363) (xy 43.414706 -309.493519) (xy 43.36869 -309.476067) (xy 43.326069 -309.45146)
			(xy 43.287948 -309.420335) (xy 43.255313 -309.383498) (xy 43.22901 -309.341902) (xy 43.209719 -309.296626)
			(xy 43.197942 -309.248842) (xy 43.193982 -309.199788) (xy 42.855083 -309.199788) (xy 42.85284 -309.24111)
			(xy 42.842165 -309.289591) (xy 42.823787 -309.335708) (xy 42.798191 -309.378243) (xy 42.76605 -309.416077)
			(xy 42.728212 -309.448213) (xy 42.685673 -309.473804) (xy 42.639555 -309.492176) (xy 42.591072 -309.502845)
			(xy 42.541501 -309.50553) (xy 42.492149 -309.50016) (xy 42.444316 -309.486877) (xy 42.399263 -309.46603)
			(xy 42.358175 -309.438169) (xy 42.322136 -309.404028) (xy 42.292095 -309.364506) (xy 42.268843 -309.320644)
			(xy 42.252994 -309.273599) (xy 42.244965 -309.22461) (xy 42.244518 -309.199788) (xy 42.244611 -309.19062)
			(xy 42.245755 -309.17232) (xy 42.246804 -309.163212) (xy 42.248328 -309.151528) (xy 42.2402 -309.128668)
			(xy 42.163746 -309.056024) (xy 42.14114 -309.048912) (xy 42.132504 -309.050436) (xy 42.118207 -309.052805)
			(xy 42.089337 -309.055348) (xy 42.074846 -309.055516) (xy 42.004488 -309.055516) (xy 41.993796 -309.056078)
			(xy 41.974239 -309.064735) (xy 41.966642 -309.07228) (xy 41.916096 -309.128414) (xy 41.909299 -309.136631)
			(xy 41.902701 -309.15689) (xy 41.903396 -309.16753) (xy 41.903396 -309.167784) (xy 41.905174 -309.199788)
			(xy 41.904729 -309.223781) (xy 41.897223 -309.271176) (xy 41.882395 -309.316813) (xy 41.86061 -309.359568)
			(xy 41.832404 -309.398389) (xy 41.798472 -309.432318) (xy 41.759649 -309.460522) (xy 41.716892 -309.482304)
			(xy 41.671254 -309.497128) (xy 41.623859 -309.50463) (xy 41.599866 -309.505096) (xy 41.590635 -309.505011)
			(xy 41.572207 -309.503869) (xy 41.563036 -309.50281) (xy 41.562782 -309.50281) (xy 41.550975 -309.501983)
			(xy 41.528706 -309.509916) (xy 41.52011 -309.51805) (xy 41.455594 -309.585614) (xy 41.448482 -309.608474)
			(xy 41.450514 -309.620412) (xy 41.454489 -309.647448) (xy 41.454494 -309.702089) (xy 41.450514 -309.729124)
			(xy 41.448482 -309.741062) (xy 41.455594 -309.763922) (xy 41.52011 -309.831486) (xy 41.528747 -309.839561)
			(xy 41.550985 -309.847513) (xy 41.562782 -309.846726) (xy 41.563036 -309.846726) (xy 41.572207 -309.845665)
			(xy 41.590635 -309.844523) (xy 41.599866 -309.84444) (xy 41.625122 -309.84493) (xy 41.674945 -309.853239)
			(xy 41.72272 -309.869635) (xy 41.767145 -309.893673) (xy 41.807008 -309.924695) (xy 41.84122 -309.961855)
			(xy 41.868849 -310.00414) (xy 41.88914 -310.050396) (xy 41.901541 -310.099361) (xy 41.905712 -310.1497)
			(xy 41.905708 -310.149748) (xy 42.244022 -310.149748) (xy 42.247982 -310.100694) (xy 42.259759 -310.05291)
			(xy 42.27905 -310.007634) (xy 42.305353 -309.966038) (xy 42.337988 -309.929201) (xy 42.376109 -309.898076)
			(xy 42.41873 -309.873469) (xy 42.464746 -309.856017) (xy 42.512965 -309.846173) (xy 42.56214 -309.844192)
			(xy 42.610995 -309.850124) (xy 42.658266 -309.863816) (xy 42.702728 -309.884914) (xy 42.743231 -309.91287)
			(xy 42.778724 -309.946962) (xy 42.808289 -309.986306) (xy 42.83116 -310.029883) (xy 42.846744 -310.076564)
			(xy 42.854639 -310.125141) (xy 42.855134 -310.149748) (xy 43.193982 -310.149748) (xy 43.197942 -310.100694)
			(xy 43.209719 -310.05291) (xy 43.22901 -310.007634) (xy 43.255313 -309.966038) (xy 43.287948 -309.929201)
			(xy 43.326069 -309.898076) (xy 43.36869 -309.873469) (xy 43.414706 -309.856017) (xy 43.462925 -309.846173)
			(xy 43.5121 -309.844192) (xy 43.560955 -309.850124) (xy 43.608226 -309.863816) (xy 43.652688 -309.884914)
			(xy 43.693191 -309.91287) (xy 43.728684 -309.946962) (xy 43.758249 -309.986306) (xy 43.78112 -310.029883)
			(xy 43.796704 -310.076564) (xy 43.804599 -310.125141) (xy 43.805094 -310.149748) (xy 44.143942 -310.149748)
			(xy 44.147902 -310.100694) (xy 44.159679 -310.05291) (xy 44.17897 -310.007634) (xy 44.205273 -309.966038)
			(xy 44.237908 -309.929201) (xy 44.276029 -309.898076) (xy 44.31865 -309.873469) (xy 44.364666 -309.856017)
			(xy 44.412885 -309.846173) (xy 44.46206 -309.844192) (xy 44.510915 -309.850124) (xy 44.558186 -309.863816)
			(xy 44.602648 -309.884914) (xy 44.643151 -309.91287) (xy 44.678644 -309.946962) (xy 44.708209 -309.986306)
			(xy 44.73108 -310.029883) (xy 44.746664 -310.076564) (xy 44.754559 -310.125141) (xy 44.755054 -310.149748)
			(xy 45.094156 -310.149748) (xy 45.098116 -310.100694) (xy 45.109893 -310.05291) (xy 45.129184 -310.007634)
			(xy 45.155487 -309.966038) (xy 45.188122 -309.929201) (xy 45.226243 -309.898076) (xy 45.268864 -309.873469)
			(xy 45.31488 -309.856017) (xy 45.363099 -309.846173) (xy 45.412274 -309.844192) (xy 45.461129 -309.850124)
			(xy 45.5084 -309.863816) (xy 45.552862 -309.884914) (xy 45.593365 -309.91287) (xy 45.628858 -309.946962)
			(xy 45.658423 -309.986306) (xy 45.681294 -310.029883) (xy 45.696878 -310.076564) (xy 45.704773 -310.125141)
			(xy 45.705268 -310.149748) (xy 46.044116 -310.149748) (xy 46.048076 -310.100694) (xy 46.059853 -310.05291)
			(xy 46.079144 -310.007634) (xy 46.105447 -309.966038) (xy 46.138082 -309.929201) (xy 46.176203 -309.898076)
			(xy 46.218824 -309.873469) (xy 46.26484 -309.856017) (xy 46.313059 -309.846173) (xy 46.362234 -309.844192)
			(xy 46.411089 -309.850124) (xy 46.45836 -309.863816) (xy 46.502822 -309.884914) (xy 46.543325 -309.91287)
			(xy 46.578818 -309.946962) (xy 46.608383 -309.986306) (xy 46.631254 -310.029883) (xy 46.646838 -310.076564)
			(xy 46.654733 -310.125141) (xy 46.655228 -310.149748) (xy 46.994076 -310.149748) (xy 46.998036 -310.100694)
			(xy 47.009813 -310.05291) (xy 47.029104 -310.007634) (xy 47.055407 -309.966038) (xy 47.088042 -309.929201)
			(xy 47.126163 -309.898076) (xy 47.168784 -309.873469) (xy 47.2148 -309.856017) (xy 47.263019 -309.846173)
			(xy 47.312194 -309.844192) (xy 47.361049 -309.850124) (xy 47.40832 -309.863816) (xy 47.452782 -309.884914)
			(xy 47.493285 -309.91287) (xy 47.528778 -309.946962) (xy 47.558343 -309.986306) (xy 47.581214 -310.029883)
			(xy 47.596798 -310.076564) (xy 47.604693 -310.125141) (xy 47.605188 -310.149748) (xy 47.604693 -310.174355)
			(xy 47.596798 -310.222932) (xy 47.581214 -310.269613) (xy 47.558343 -310.31319) (xy 47.528778 -310.352534)
			(xy 47.493285 -310.386626) (xy 47.452782 -310.414582) (xy 47.40832 -310.43568) (xy 47.361049 -310.449372)
			(xy 47.312194 -310.455304) (xy 47.263019 -310.453323) (xy 47.2148 -310.443479) (xy 47.168784 -310.426027)
			(xy 47.126163 -310.40142) (xy 47.088042 -310.370295) (xy 47.055407 -310.333458) (xy 47.029104 -310.291862)
			(xy 47.009813 -310.246586) (xy 46.998036 -310.198802) (xy 46.994076 -310.149748) (xy 46.655228 -310.149748)
			(xy 46.654733 -310.174355) (xy 46.646838 -310.222932) (xy 46.631254 -310.269613) (xy 46.608383 -310.31319)
			(xy 46.578818 -310.352534) (xy 46.543325 -310.386626) (xy 46.502822 -310.414582) (xy 46.45836 -310.43568)
			(xy 46.411089 -310.449372) (xy 46.362234 -310.455304) (xy 46.313059 -310.453323) (xy 46.26484 -310.443479)
			(xy 46.218824 -310.426027) (xy 46.176203 -310.40142) (xy 46.138082 -310.370295) (xy 46.105447 -310.333458)
			(xy 46.079144 -310.291862) (xy 46.059853 -310.246586) (xy 46.048076 -310.198802) (xy 46.044116 -310.149748)
			(xy 45.705268 -310.149748) (xy 45.704773 -310.174355) (xy 45.696878 -310.222932) (xy 45.681294 -310.269613)
			(xy 45.658423 -310.31319) (xy 45.628858 -310.352534) (xy 45.593365 -310.386626) (xy 45.552862 -310.414582)
			(xy 45.5084 -310.43568) (xy 45.461129 -310.449372) (xy 45.412274 -310.455304) (xy 45.363099 -310.453323)
			(xy 45.31488 -310.443479) (xy 45.268864 -310.426027) (xy 45.226243 -310.40142) (xy 45.188122 -310.370295)
			(xy 45.155487 -310.333458) (xy 45.129184 -310.291862) (xy 45.109893 -310.246586) (xy 45.098116 -310.198802)
			(xy 45.094156 -310.149748) (xy 44.755054 -310.149748) (xy 44.754559 -310.174355) (xy 44.746664 -310.222932)
			(xy 44.73108 -310.269613) (xy 44.708209 -310.31319) (xy 44.678644 -310.352534) (xy 44.643151 -310.386626)
			(xy 44.602648 -310.414582) (xy 44.558186 -310.43568) (xy 44.510915 -310.449372) (xy 44.46206 -310.455304)
			(xy 44.412885 -310.453323) (xy 44.364666 -310.443479) (xy 44.31865 -310.426027) (xy 44.276029 -310.40142)
			(xy 44.237908 -310.370295) (xy 44.205273 -310.333458) (xy 44.17897 -310.291862) (xy 44.159679 -310.246586)
			(xy 44.147902 -310.198802) (xy 44.143942 -310.149748) (xy 43.805094 -310.149748) (xy 43.804599 -310.174355)
			(xy 43.796704 -310.222932) (xy 43.78112 -310.269613) (xy 43.758249 -310.31319) (xy 43.728684 -310.352534)
			(xy 43.693191 -310.386626) (xy 43.652688 -310.414582) (xy 43.608226 -310.43568) (xy 43.560955 -310.449372)
			(xy 43.5121 -310.455304) (xy 43.462925 -310.453323) (xy 43.414706 -310.443479) (xy 43.36869 -310.426027)
			(xy 43.326069 -310.40142) (xy 43.287948 -310.370295) (xy 43.255313 -310.333458) (xy 43.22901 -310.291862)
			(xy 43.209719 -310.246586) (xy 43.197942 -310.198802) (xy 43.193982 -310.149748) (xy 42.855134 -310.149748)
			(xy 42.854639 -310.174355) (xy 42.846744 -310.222932) (xy 42.83116 -310.269613) (xy 42.808289 -310.31319)
			(xy 42.778724 -310.352534) (xy 42.743231 -310.386626) (xy 42.702728 -310.414582) (xy 42.658266 -310.43568)
			(xy 42.610995 -310.449372) (xy 42.56214 -310.455304) (xy 42.512965 -310.453323) (xy 42.464746 -310.443479)
			(xy 42.41873 -310.426027) (xy 42.376109 -310.40142) (xy 42.337988 -310.370295) (xy 42.305353 -310.333458)
			(xy 42.27905 -310.291862) (xy 42.259759 -310.246586) (xy 42.247982 -310.198802) (xy 42.244022 -310.149748)
			(xy 41.905708 -310.149748) (xy 41.901541 -310.200039) (xy 41.88914 -310.249004) (xy 41.868849 -310.29526)
			(xy 41.84122 -310.337545) (xy 41.807008 -310.374705) (xy 41.767145 -310.405727) (xy 41.72272 -310.429765)
			(xy 41.674945 -310.446161) (xy 41.625122 -310.45447) (xy 41.599866 -310.455056) (xy 41.573546 -310.454485)
			(xy 41.521692 -310.445421) (xy 41.496742 -310.437022) (xy 41.487622 -310.434156) (xy 41.468527 -310.434696)
			(xy 41.450955 -310.442186) (xy 41.437341 -310.455586) (xy 41.429575 -310.473039) (xy 41.428734 -310.492123)
			(xy 41.431464 -310.501284) (xy 41.440862 -310.528208) (xy 41.444418 -310.540654) (xy 41.445688 -310.545988)
			(xy 41.450152 -310.565303) (xy 41.454985 -310.604653) (xy 41.45534 -310.624474) (xy 41.45534 -310.69534)
			(xy 41.455908 -310.706029) (xy 41.464576 -310.725575) (xy 41.472104 -310.733186) (xy 41.53662 -310.790844)
			(xy 41.55694 -310.797448) (xy 41.567608 -310.796432) (xy 41.599866 -310.794654) (xy 41.625129 -310.795144)
			(xy 41.674966 -310.803455) (xy 41.722755 -310.819857) (xy 41.767192 -310.843901) (xy 41.807066 -310.874931)
			(xy 41.841288 -310.912102) (xy 41.868924 -310.954399) (xy 41.889221 -311.000668) (xy 41.901625 -311.049647)
			(xy 41.905795 -311.099962) (xy 42.244022 -311.099962) (xy 42.247982 -311.050908) (xy 42.259759 -311.003124)
			(xy 42.27905 -310.957848) (xy 42.305353 -310.916252) (xy 42.337988 -310.879415) (xy 42.376109 -310.84829)
			(xy 42.41873 -310.823683) (xy 42.464746 -310.806231) (xy 42.512965 -310.796387) (xy 42.56214 -310.794406)
			(xy 42.610995 -310.800338) (xy 42.658266 -310.81403) (xy 42.702728 -310.835128) (xy 42.743231 -310.863084)
			(xy 42.778724 -310.897176) (xy 42.808289 -310.93652) (xy 42.83116 -310.980097) (xy 42.846744 -311.026778)
			(xy 42.854639 -311.075355) (xy 42.855134 -311.099962) (xy 43.193982 -311.099962) (xy 43.197942 -311.050908)
			(xy 43.209719 -311.003124) (xy 43.22901 -310.957848) (xy 43.255313 -310.916252) (xy 43.287948 -310.879415)
			(xy 43.326069 -310.84829) (xy 43.36869 -310.823683) (xy 43.414706 -310.806231) (xy 43.462925 -310.796387)
			(xy 43.5121 -310.794406) (xy 43.560955 -310.800338) (xy 43.608226 -310.81403) (xy 43.652688 -310.835128)
			(xy 43.693191 -310.863084) (xy 43.728684 -310.897176) (xy 43.758249 -310.93652) (xy 43.78112 -310.980097)
			(xy 43.796704 -311.026778) (xy 43.804599 -311.075355) (xy 43.805094 -311.099962) (xy 44.143942 -311.099962)
			(xy 44.147902 -311.050908) (xy 44.159679 -311.003124) (xy 44.17897 -310.957848) (xy 44.205273 -310.916252)
			(xy 44.237908 -310.879415) (xy 44.276029 -310.84829) (xy 44.31865 -310.823683) (xy 44.364666 -310.806231)
			(xy 44.412885 -310.796387) (xy 44.46206 -310.794406) (xy 44.510915 -310.800338) (xy 44.558186 -310.81403)
			(xy 44.602648 -310.835128) (xy 44.643151 -310.863084) (xy 44.678644 -310.897176) (xy 44.708209 -310.93652)
			(xy 44.73108 -310.980097) (xy 44.746664 -311.026778) (xy 44.754559 -311.075355) (xy 44.755054 -311.099962)
			(xy 45.094156 -311.099962) (xy 45.098116 -311.050908) (xy 45.109893 -311.003124) (xy 45.129184 -310.957848)
			(xy 45.155487 -310.916252) (xy 45.188122 -310.879415) (xy 45.226243 -310.84829) (xy 45.268864 -310.823683)
			(xy 45.31488 -310.806231) (xy 45.363099 -310.796387) (xy 45.412274 -310.794406) (xy 45.461129 -310.800338)
			(xy 45.5084 -310.81403) (xy 45.552862 -310.835128) (xy 45.593365 -310.863084) (xy 45.628858 -310.897176)
			(xy 45.658423 -310.93652) (xy 45.681294 -310.980097) (xy 45.696878 -311.026778) (xy 45.704773 -311.075355)
			(xy 45.705268 -311.099962) (xy 46.044116 -311.099962) (xy 46.048076 -311.050908) (xy 46.059853 -311.003124)
			(xy 46.079144 -310.957848) (xy 46.105447 -310.916252) (xy 46.138082 -310.879415) (xy 46.176203 -310.84829)
			(xy 46.218824 -310.823683) (xy 46.26484 -310.806231) (xy 46.313059 -310.796387) (xy 46.362234 -310.794406)
			(xy 46.411089 -310.800338) (xy 46.45836 -310.81403) (xy 46.502822 -310.835128) (xy 46.543325 -310.863084)
			(xy 46.578818 -310.897176) (xy 46.608383 -310.93652) (xy 46.631254 -310.980097) (xy 46.646838 -311.026778)
			(xy 46.654733 -311.075355) (xy 46.655228 -311.099962) (xy 46.994076 -311.099962) (xy 46.998036 -311.050908)
			(xy 47.009813 -311.003124) (xy 47.029104 -310.957848) (xy 47.055407 -310.916252) (xy 47.088042 -310.879415)
			(xy 47.126163 -310.84829) (xy 47.168784 -310.823683) (xy 47.2148 -310.806231) (xy 47.263019 -310.796387)
			(xy 47.312194 -310.794406) (xy 47.361049 -310.800338) (xy 47.40832 -310.81403) (xy 47.452782 -310.835128)
			(xy 47.493285 -310.863084) (xy 47.528778 -310.897176) (xy 47.558343 -310.93652) (xy 47.581214 -310.980097)
			(xy 47.596798 -311.026778) (xy 47.604693 -311.075355) (xy 47.605188 -311.099962) (xy 47.944036 -311.099962)
			(xy 47.947996 -311.050908) (xy 47.959773 -311.003124) (xy 47.979064 -310.957848) (xy 48.005367 -310.916252)
			(xy 48.038002 -310.879415) (xy 48.076123 -310.84829) (xy 48.118744 -310.823683) (xy 48.16476 -310.806231)
			(xy 48.212979 -310.796387) (xy 48.262154 -310.794406) (xy 48.311009 -310.800338) (xy 48.35828 -310.81403)
			(xy 48.402742 -310.835128) (xy 48.443245 -310.863084) (xy 48.478738 -310.897176) (xy 48.508303 -310.93652)
			(xy 48.531174 -310.980097) (xy 48.546758 -311.026778) (xy 48.554653 -311.075355) (xy 48.555148 -311.099962)
			(xy 48.893996 -311.099962) (xy 48.897956 -311.050908) (xy 48.909733 -311.003124) (xy 48.929024 -310.957848)
			(xy 48.955327 -310.916252) (xy 48.987962 -310.879415) (xy 49.026083 -310.84829) (xy 49.068704 -310.823683)
			(xy 49.11472 -310.806231) (xy 49.162939 -310.796387) (xy 49.212114 -310.794406) (xy 49.260969 -310.800338)
			(xy 49.30824 -310.81403) (xy 49.352702 -310.835128) (xy 49.393205 -310.863084) (xy 49.428698 -310.897176)
			(xy 49.458263 -310.93652) (xy 49.481134 -310.980097) (xy 49.496718 -311.026778) (xy 49.504613 -311.075355)
			(xy 49.505108 -311.099962) (xy 49.843956 -311.099962) (xy 49.847916 -311.050908) (xy 49.859693 -311.003124)
			(xy 49.878984 -310.957848) (xy 49.905287 -310.916252) (xy 49.937922 -310.879415) (xy 49.976043 -310.84829)
			(xy 50.018664 -310.823683) (xy 50.06468 -310.806231) (xy 50.112899 -310.796387) (xy 50.162074 -310.794406)
			(xy 50.210929 -310.800338) (xy 50.2582 -310.81403) (xy 50.302662 -310.835128) (xy 50.343165 -310.863084)
			(xy 50.378658 -310.897176) (xy 50.408223 -310.93652) (xy 50.431094 -310.980097) (xy 50.446678 -311.026778)
			(xy 50.454573 -311.075355) (xy 50.455068 -311.099962) (xy 50.79417 -311.099962) (xy 50.79813 -311.050908)
			(xy 50.809907 -311.003124) (xy 50.829198 -310.957848) (xy 50.855501 -310.916252) (xy 50.888136 -310.879415)
			(xy 50.926257 -310.84829) (xy 50.968878 -310.823683) (xy 51.014894 -310.806231) (xy 51.063113 -310.796387)
			(xy 51.112288 -310.794406) (xy 51.161143 -310.800338) (xy 51.208414 -310.81403) (xy 51.252876 -310.835128)
			(xy 51.293379 -310.863084) (xy 51.328872 -310.897176) (xy 51.358437 -310.93652) (xy 51.381308 -310.980097)
			(xy 51.396892 -311.026778) (xy 51.404787 -311.075355) (xy 51.405282 -311.099962) (xy 51.74413 -311.099962)
			(xy 51.74809 -311.050908) (xy 51.759867 -311.003124) (xy 51.779158 -310.957848) (xy 51.805461 -310.916252)
			(xy 51.838096 -310.879415) (xy 51.876217 -310.84829) (xy 51.918838 -310.823683) (xy 51.964854 -310.806231)
			(xy 52.013073 -310.796387) (xy 52.062248 -310.794406) (xy 52.111103 -310.800338) (xy 52.158374 -310.81403)
			(xy 52.202836 -310.835128) (xy 52.243339 -310.863084) (xy 52.278832 -310.897176) (xy 52.308397 -310.93652)
			(xy 52.331268 -310.980097) (xy 52.346852 -311.026778) (xy 52.354747 -311.075355) (xy 52.355242 -311.099962)
			(xy 52.69409 -311.099962) (xy 52.69805 -311.050908) (xy 52.709827 -311.003124) (xy 52.729118 -310.957848)
			(xy 52.755421 -310.916252) (xy 52.788056 -310.879415) (xy 52.826177 -310.84829) (xy 52.868798 -310.823683)
			(xy 52.914814 -310.806231) (xy 52.963033 -310.796387) (xy 53.012208 -310.794406) (xy 53.061063 -310.800338)
			(xy 53.108334 -310.81403) (xy 53.152796 -310.835128) (xy 53.193299 -310.863084) (xy 53.228792 -310.897176)
			(xy 53.258357 -310.93652) (xy 53.281228 -310.980097) (xy 53.296812 -311.026778) (xy 53.304707 -311.075355)
			(xy 53.305202 -311.099962) (xy 53.64405 -311.099962) (xy 53.64801 -311.050908) (xy 53.659787 -311.003124)
			(xy 53.679078 -310.957848) (xy 53.705381 -310.916252) (xy 53.738016 -310.879415) (xy 53.776137 -310.84829)
			(xy 53.818758 -310.823683) (xy 53.864774 -310.806231) (xy 53.912993 -310.796387) (xy 53.962168 -310.794406)
			(xy 54.011023 -310.800338) (xy 54.058294 -310.81403) (xy 54.102756 -310.835128) (xy 54.143259 -310.863084)
			(xy 54.178752 -310.897176) (xy 54.208317 -310.93652) (xy 54.231188 -310.980097) (xy 54.246772 -311.026778)
			(xy 54.254667 -311.075355) (xy 54.255162 -311.099962) (xy 54.59401 -311.099962) (xy 54.59797 -311.050908)
			(xy 54.609747 -311.003124) (xy 54.629038 -310.957848) (xy 54.655341 -310.916252) (xy 54.687976 -310.879415)
			(xy 54.726097 -310.84829) (xy 54.768718 -310.823683) (xy 54.814734 -310.806231) (xy 54.862953 -310.796387)
			(xy 54.912128 -310.794406) (xy 54.960983 -310.800338) (xy 55.008254 -310.81403) (xy 55.052716 -310.835128)
			(xy 55.093219 -310.863084) (xy 55.128712 -310.897176) (xy 55.158277 -310.93652) (xy 55.181148 -310.980097)
			(xy 55.196732 -311.026778) (xy 55.204627 -311.075355) (xy 55.205122 -311.099962) (xy 55.54397 -311.099962)
			(xy 55.54793 -311.050908) (xy 55.559707 -311.003124) (xy 55.578998 -310.957848) (xy 55.605301 -310.916252)
			(xy 55.637936 -310.879415) (xy 55.676057 -310.84829) (xy 55.718678 -310.823683) (xy 55.764694 -310.806231)
			(xy 55.812913 -310.796387) (xy 55.862088 -310.794406) (xy 55.910943 -310.800338) (xy 55.958214 -310.81403)
			(xy 56.002676 -310.835128) (xy 56.043179 -310.863084) (xy 56.078672 -310.897176) (xy 56.108237 -310.93652)
			(xy 56.131108 -310.980097) (xy 56.146692 -311.026778) (xy 56.154587 -311.075355) (xy 56.155082 -311.099962)
			(xy 56.494184 -311.099962) (xy 56.498144 -311.050908) (xy 56.509921 -311.003124) (xy 56.529212 -310.957848)
			(xy 56.555515 -310.916252) (xy 56.58815 -310.879415) (xy 56.626271 -310.84829) (xy 56.668892 -310.823683)
			(xy 56.714908 -310.806231) (xy 56.763127 -310.796387) (xy 56.812302 -310.794406) (xy 56.861157 -310.800338)
			(xy 56.908428 -310.81403) (xy 56.95289 -310.835128) (xy 56.993393 -310.863084) (xy 57.028886 -310.897176)
			(xy 57.058451 -310.93652) (xy 57.081322 -310.980097) (xy 57.096906 -311.026778) (xy 57.104801 -311.075355)
			(xy 57.105296 -311.099962) (xy 57.444144 -311.099962) (xy 57.448104 -311.050908) (xy 57.459881 -311.003124)
			(xy 57.479172 -310.957848) (xy 57.505475 -310.916252) (xy 57.53811 -310.879415) (xy 57.576231 -310.84829)
			(xy 57.618852 -310.823683) (xy 57.664868 -310.806231) (xy 57.713087 -310.796387) (xy 57.762262 -310.794406)
			(xy 57.811117 -310.800338) (xy 57.858388 -310.81403) (xy 57.90285 -310.835128) (xy 57.943353 -310.863084)
			(xy 57.978846 -310.897176) (xy 58.008411 -310.93652) (xy 58.031282 -310.980097) (xy 58.046866 -311.026778)
			(xy 58.054761 -311.075355) (xy 58.055256 -311.099962) (xy 58.394104 -311.099962) (xy 58.398064 -311.050908)
			(xy 58.409841 -311.003124) (xy 58.429132 -310.957848) (xy 58.455435 -310.916252) (xy 58.48807 -310.879415)
			(xy 58.526191 -310.84829) (xy 58.568812 -310.823683) (xy 58.614828 -310.806231) (xy 58.663047 -310.796387)
			(xy 58.712222 -310.794406) (xy 58.761077 -310.800338) (xy 58.808348 -310.81403) (xy 58.85281 -310.835128)
			(xy 58.893313 -310.863084) (xy 58.928806 -310.897176) (xy 58.958371 -310.93652) (xy 58.981242 -310.980097)
			(xy 58.996826 -311.026778) (xy 59.004721 -311.075355) (xy 59.005216 -311.099962) (xy 59.344064 -311.099962)
			(xy 59.348024 -311.050908) (xy 59.359801 -311.003124) (xy 59.379092 -310.957848) (xy 59.405395 -310.916252)
			(xy 59.43803 -310.879415) (xy 59.476151 -310.84829) (xy 59.518772 -310.823683) (xy 59.564788 -310.806231)
			(xy 59.613007 -310.796387) (xy 59.662182 -310.794406) (xy 59.711037 -310.800338) (xy 59.758308 -310.81403)
			(xy 59.80277 -310.835128) (xy 59.843273 -310.863084) (xy 59.878766 -310.897176) (xy 59.908331 -310.93652)
			(xy 59.931202 -310.980097) (xy 59.946786 -311.026778) (xy 59.954681 -311.075355) (xy 59.955176 -311.099962)
			(xy 60.294024 -311.099962) (xy 60.297984 -311.050908) (xy 60.309761 -311.003124) (xy 60.329052 -310.957848)
			(xy 60.355355 -310.916252) (xy 60.38799 -310.879415) (xy 60.426111 -310.84829) (xy 60.468732 -310.823683)
			(xy 60.514748 -310.806231) (xy 60.562967 -310.796387) (xy 60.612142 -310.794406) (xy 60.660997 -310.800338)
			(xy 60.708268 -310.81403) (xy 60.75273 -310.835128) (xy 60.793233 -310.863084) (xy 60.828726 -310.897176)
			(xy 60.858291 -310.93652) (xy 60.881162 -310.980097) (xy 60.896746 -311.026778) (xy 60.904641 -311.075355)
			(xy 60.905136 -311.099962) (xy 61.243984 -311.099962) (xy 61.247944 -311.050908) (xy 61.259721 -311.003124)
			(xy 61.279012 -310.957848) (xy 61.305315 -310.916252) (xy 61.33795 -310.879415) (xy 61.376071 -310.84829)
			(xy 61.418692 -310.823683) (xy 61.464708 -310.806231) (xy 61.512927 -310.796387) (xy 61.562102 -310.794406)
			(xy 61.610957 -310.800338) (xy 61.658228 -310.81403) (xy 61.70269 -310.835128) (xy 61.743193 -310.863084)
			(xy 61.778686 -310.897176) (xy 61.808251 -310.93652) (xy 61.831122 -310.980097) (xy 61.846706 -311.026778)
			(xy 61.854601 -311.075355) (xy 61.855096 -311.099962) (xy 61.854601 -311.124569) (xy 61.846706 -311.173146)
			(xy 61.831122 -311.219827) (xy 61.808251 -311.263404) (xy 61.778686 -311.302748) (xy 61.743193 -311.33684)
			(xy 61.70269 -311.364796) (xy 61.658228 -311.385894) (xy 61.610957 -311.399586) (xy 61.562102 -311.405518)
			(xy 61.512927 -311.403537) (xy 61.464708 -311.393693) (xy 61.418692 -311.376241) (xy 61.376071 -311.351634)
			(xy 61.33795 -311.320509) (xy 61.305315 -311.283672) (xy 61.279012 -311.242076) (xy 61.259721 -311.1968)
			(xy 61.247944 -311.149016) (xy 61.243984 -311.099962) (xy 60.905136 -311.099962) (xy 60.904641 -311.124569)
			(xy 60.896746 -311.173146) (xy 60.881162 -311.219827) (xy 60.858291 -311.263404) (xy 60.828726 -311.302748)
			(xy 60.793233 -311.33684) (xy 60.75273 -311.364796) (xy 60.708268 -311.385894) (xy 60.660997 -311.399586)
			(xy 60.612142 -311.405518) (xy 60.562967 -311.403537) (xy 60.514748 -311.393693) (xy 60.468732 -311.376241)
			(xy 60.426111 -311.351634) (xy 60.38799 -311.320509) (xy 60.355355 -311.283672) (xy 60.329052 -311.242076)
			(xy 60.309761 -311.1968) (xy 60.297984 -311.149016) (xy 60.294024 -311.099962) (xy 59.955176 -311.099962)
			(xy 59.954681 -311.124569) (xy 59.946786 -311.173146) (xy 59.931202 -311.219827) (xy 59.908331 -311.263404)
			(xy 59.878766 -311.302748) (xy 59.843273 -311.33684) (xy 59.80277 -311.364796) (xy 59.758308 -311.385894)
			(xy 59.711037 -311.399586) (xy 59.662182 -311.405518) (xy 59.613007 -311.403537) (xy 59.564788 -311.393693)
			(xy 59.518772 -311.376241) (xy 59.476151 -311.351634) (xy 59.43803 -311.320509) (xy 59.405395 -311.283672)
			(xy 59.379092 -311.242076) (xy 59.359801 -311.1968) (xy 59.348024 -311.149016) (xy 59.344064 -311.099962)
			(xy 59.005216 -311.099962) (xy 59.004721 -311.124569) (xy 58.996826 -311.173146) (xy 58.981242 -311.219827)
			(xy 58.958371 -311.263404) (xy 58.928806 -311.302748) (xy 58.893313 -311.33684) (xy 58.85281 -311.364796)
			(xy 58.808348 -311.385894) (xy 58.761077 -311.399586) (xy 58.712222 -311.405518) (xy 58.663047 -311.403537)
			(xy 58.614828 -311.393693) (xy 58.568812 -311.376241) (xy 58.526191 -311.351634) (xy 58.48807 -311.320509)
			(xy 58.455435 -311.283672) (xy 58.429132 -311.242076) (xy 58.409841 -311.1968) (xy 58.398064 -311.149016)
			(xy 58.394104 -311.099962) (xy 58.055256 -311.099962) (xy 58.054761 -311.124569) (xy 58.046866 -311.173146)
			(xy 58.031282 -311.219827) (xy 58.008411 -311.263404) (xy 57.978846 -311.302748) (xy 57.943353 -311.33684)
			(xy 57.90285 -311.364796) (xy 57.858388 -311.385894) (xy 57.811117 -311.399586) (xy 57.762262 -311.405518)
			(xy 57.713087 -311.403537) (xy 57.664868 -311.393693) (xy 57.618852 -311.376241) (xy 57.576231 -311.351634)
			(xy 57.53811 -311.320509) (xy 57.505475 -311.283672) (xy 57.479172 -311.242076) (xy 57.459881 -311.1968)
			(xy 57.448104 -311.149016) (xy 57.444144 -311.099962) (xy 57.105296 -311.099962) (xy 57.104801 -311.124569)
			(xy 57.096906 -311.173146) (xy 57.081322 -311.219827) (xy 57.058451 -311.263404) (xy 57.028886 -311.302748)
			(xy 56.993393 -311.33684) (xy 56.95289 -311.364796) (xy 56.908428 -311.385894) (xy 56.861157 -311.399586)
			(xy 56.812302 -311.405518) (xy 56.763127 -311.403537) (xy 56.714908 -311.393693) (xy 56.668892 -311.376241)
			(xy 56.626271 -311.351634) (xy 56.58815 -311.320509) (xy 56.555515 -311.283672) (xy 56.529212 -311.242076)
			(xy 56.509921 -311.1968) (xy 56.498144 -311.149016) (xy 56.494184 -311.099962) (xy 56.155082 -311.099962)
			(xy 56.154587 -311.124569) (xy 56.146692 -311.173146) (xy 56.131108 -311.219827) (xy 56.108237 -311.263404)
			(xy 56.078672 -311.302748) (xy 56.043179 -311.33684) (xy 56.002676 -311.364796) (xy 55.958214 -311.385894)
			(xy 55.910943 -311.399586) (xy 55.862088 -311.405518) (xy 55.812913 -311.403537) (xy 55.764694 -311.393693)
			(xy 55.718678 -311.376241) (xy 55.676057 -311.351634) (xy 55.637936 -311.320509) (xy 55.605301 -311.283672)
			(xy 55.578998 -311.242076) (xy 55.559707 -311.1968) (xy 55.54793 -311.149016) (xy 55.54397 -311.099962)
			(xy 55.205122 -311.099962) (xy 55.204627 -311.124569) (xy 55.196732 -311.173146) (xy 55.181148 -311.219827)
			(xy 55.158277 -311.263404) (xy 55.128712 -311.302748) (xy 55.093219 -311.33684) (xy 55.052716 -311.364796)
			(xy 55.008254 -311.385894) (xy 54.960983 -311.399586) (xy 54.912128 -311.405518) (xy 54.862953 -311.403537)
			(xy 54.814734 -311.393693) (xy 54.768718 -311.376241) (xy 54.726097 -311.351634) (xy 54.687976 -311.320509)
			(xy 54.655341 -311.283672) (xy 54.629038 -311.242076) (xy 54.609747 -311.1968) (xy 54.59797 -311.149016)
			(xy 54.59401 -311.099962) (xy 54.255162 -311.099962) (xy 54.254667 -311.124569) (xy 54.246772 -311.173146)
			(xy 54.231188 -311.219827) (xy 54.208317 -311.263404) (xy 54.178752 -311.302748) (xy 54.143259 -311.33684)
			(xy 54.102756 -311.364796) (xy 54.058294 -311.385894) (xy 54.011023 -311.399586) (xy 53.962168 -311.405518)
			(xy 53.912993 -311.403537) (xy 53.864774 -311.393693) (xy 53.818758 -311.376241) (xy 53.776137 -311.351634)
			(xy 53.738016 -311.320509) (xy 53.705381 -311.283672) (xy 53.679078 -311.242076) (xy 53.659787 -311.1968)
			(xy 53.64801 -311.149016) (xy 53.64405 -311.099962) (xy 53.305202 -311.099962) (xy 53.304707 -311.124569)
			(xy 53.296812 -311.173146) (xy 53.281228 -311.219827) (xy 53.258357 -311.263404) (xy 53.228792 -311.302748)
			(xy 53.193299 -311.33684) (xy 53.152796 -311.364796) (xy 53.108334 -311.385894) (xy 53.061063 -311.399586)
			(xy 53.012208 -311.405518) (xy 52.963033 -311.403537) (xy 52.914814 -311.393693) (xy 52.868798 -311.376241)
			(xy 52.826177 -311.351634) (xy 52.788056 -311.320509) (xy 52.755421 -311.283672) (xy 52.729118 -311.242076)
			(xy 52.709827 -311.1968) (xy 52.69805 -311.149016) (xy 52.69409 -311.099962) (xy 52.355242 -311.099962)
			(xy 52.354747 -311.124569) (xy 52.346852 -311.173146) (xy 52.331268 -311.219827) (xy 52.308397 -311.263404)
			(xy 52.278832 -311.302748) (xy 52.243339 -311.33684) (xy 52.202836 -311.364796) (xy 52.158374 -311.385894)
			(xy 52.111103 -311.399586) (xy 52.062248 -311.405518) (xy 52.013073 -311.403537) (xy 51.964854 -311.393693)
			(xy 51.918838 -311.376241) (xy 51.876217 -311.351634) (xy 51.838096 -311.320509) (xy 51.805461 -311.283672)
			(xy 51.779158 -311.242076) (xy 51.759867 -311.1968) (xy 51.74809 -311.149016) (xy 51.74413 -311.099962)
			(xy 51.405282 -311.099962) (xy 51.404787 -311.124569) (xy 51.396892 -311.173146) (xy 51.381308 -311.219827)
			(xy 51.358437 -311.263404) (xy 51.328872 -311.302748) (xy 51.293379 -311.33684) (xy 51.252876 -311.364796)
			(xy 51.208414 -311.385894) (xy 51.161143 -311.399586) (xy 51.112288 -311.405518) (xy 51.063113 -311.403537)
			(xy 51.014894 -311.393693) (xy 50.968878 -311.376241) (xy 50.926257 -311.351634) (xy 50.888136 -311.320509)
			(xy 50.855501 -311.283672) (xy 50.829198 -311.242076) (xy 50.809907 -311.1968) (xy 50.79813 -311.149016)
			(xy 50.79417 -311.099962) (xy 50.455068 -311.099962) (xy 50.454573 -311.124569) (xy 50.446678 -311.173146)
			(xy 50.431094 -311.219827) (xy 50.408223 -311.263404) (xy 50.378658 -311.302748) (xy 50.343165 -311.33684)
			(xy 50.302662 -311.364796) (xy 50.2582 -311.385894) (xy 50.210929 -311.399586) (xy 50.162074 -311.405518)
			(xy 50.112899 -311.403537) (xy 50.06468 -311.393693) (xy 50.018664 -311.376241) (xy 49.976043 -311.351634)
			(xy 49.937922 -311.320509) (xy 49.905287 -311.283672) (xy 49.878984 -311.242076) (xy 49.859693 -311.1968)
			(xy 49.847916 -311.149016) (xy 49.843956 -311.099962) (xy 49.505108 -311.099962) (xy 49.504613 -311.124569)
			(xy 49.496718 -311.173146) (xy 49.481134 -311.219827) (xy 49.458263 -311.263404) (xy 49.428698 -311.302748)
			(xy 49.393205 -311.33684) (xy 49.352702 -311.364796) (xy 49.30824 -311.385894) (xy 49.260969 -311.399586)
			(xy 49.212114 -311.405518) (xy 49.162939 -311.403537) (xy 49.11472 -311.393693) (xy 49.068704 -311.376241)
			(xy 49.026083 -311.351634) (xy 48.987962 -311.320509) (xy 48.955327 -311.283672) (xy 48.929024 -311.242076)
			(xy 48.909733 -311.1968) (xy 48.897956 -311.149016) (xy 48.893996 -311.099962) (xy 48.555148 -311.099962)
			(xy 48.554653 -311.124569) (xy 48.546758 -311.173146) (xy 48.531174 -311.219827) (xy 48.508303 -311.263404)
			(xy 48.478738 -311.302748) (xy 48.443245 -311.33684) (xy 48.402742 -311.364796) (xy 48.35828 -311.385894)
			(xy 48.311009 -311.399586) (xy 48.262154 -311.405518) (xy 48.212979 -311.403537) (xy 48.16476 -311.393693)
			(xy 48.118744 -311.376241) (xy 48.076123 -311.351634) (xy 48.038002 -311.320509) (xy 48.005367 -311.283672)
			(xy 47.979064 -311.242076) (xy 47.959773 -311.1968) (xy 47.947996 -311.149016) (xy 47.944036 -311.099962)
			(xy 47.605188 -311.099962) (xy 47.604693 -311.124569) (xy 47.596798 -311.173146) (xy 47.581214 -311.219827)
			(xy 47.558343 -311.263404) (xy 47.528778 -311.302748) (xy 47.493285 -311.33684) (xy 47.452782 -311.364796)
			(xy 47.40832 -311.385894) (xy 47.361049 -311.399586) (xy 47.312194 -311.405518) (xy 47.263019 -311.403537)
			(xy 47.2148 -311.393693) (xy 47.168784 -311.376241) (xy 47.126163 -311.351634) (xy 47.088042 -311.320509)
			(xy 47.055407 -311.283672) (xy 47.029104 -311.242076) (xy 47.009813 -311.1968) (xy 46.998036 -311.149016)
			(xy 46.994076 -311.099962) (xy 46.655228 -311.099962) (xy 46.654733 -311.124569) (xy 46.646838 -311.173146)
			(xy 46.631254 -311.219827) (xy 46.608383 -311.263404) (xy 46.578818 -311.302748) (xy 46.543325 -311.33684)
			(xy 46.502822 -311.364796) (xy 46.45836 -311.385894) (xy 46.411089 -311.399586) (xy 46.362234 -311.405518)
			(xy 46.313059 -311.403537) (xy 46.26484 -311.393693) (xy 46.218824 -311.376241) (xy 46.176203 -311.351634)
			(xy 46.138082 -311.320509) (xy 46.105447 -311.283672) (xy 46.079144 -311.242076) (xy 46.059853 -311.1968)
			(xy 46.048076 -311.149016) (xy 46.044116 -311.099962) (xy 45.705268 -311.099962) (xy 45.704773 -311.124569)
			(xy 45.696878 -311.173146) (xy 45.681294 -311.219827) (xy 45.658423 -311.263404) (xy 45.628858 -311.302748)
			(xy 45.593365 -311.33684) (xy 45.552862 -311.364796) (xy 45.5084 -311.385894) (xy 45.461129 -311.399586)
			(xy 45.412274 -311.405518) (xy 45.363099 -311.403537) (xy 45.31488 -311.393693) (xy 45.268864 -311.376241)
			(xy 45.226243 -311.351634) (xy 45.188122 -311.320509) (xy 45.155487 -311.283672) (xy 45.129184 -311.242076)
			(xy 45.109893 -311.1968) (xy 45.098116 -311.149016) (xy 45.094156 -311.099962) (xy 44.755054 -311.099962)
			(xy 44.754559 -311.124569) (xy 44.746664 -311.173146) (xy 44.73108 -311.219827) (xy 44.708209 -311.263404)
			(xy 44.678644 -311.302748) (xy 44.643151 -311.33684) (xy 44.602648 -311.364796) (xy 44.558186 -311.385894)
			(xy 44.510915 -311.399586) (xy 44.46206 -311.405518) (xy 44.412885 -311.403537) (xy 44.364666 -311.393693)
			(xy 44.31865 -311.376241) (xy 44.276029 -311.351634) (xy 44.237908 -311.320509) (xy 44.205273 -311.283672)
			(xy 44.17897 -311.242076) (xy 44.159679 -311.1968) (xy 44.147902 -311.149016) (xy 44.143942 -311.099962)
			(xy 43.805094 -311.099962) (xy 43.804599 -311.124569) (xy 43.796704 -311.173146) (xy 43.78112 -311.219827)
			(xy 43.758249 -311.263404) (xy 43.728684 -311.302748) (xy 43.693191 -311.33684) (xy 43.652688 -311.364796)
			(xy 43.608226 -311.385894) (xy 43.560955 -311.399586) (xy 43.5121 -311.405518) (xy 43.462925 -311.403537)
			(xy 43.414706 -311.393693) (xy 43.36869 -311.376241) (xy 43.326069 -311.351634) (xy 43.287948 -311.320509)
			(xy 43.255313 -311.283672) (xy 43.22901 -311.242076) (xy 43.209719 -311.1968) (xy 43.197942 -311.149016)
			(xy 43.193982 -311.099962) (xy 42.855134 -311.099962) (xy 42.854639 -311.124569) (xy 42.846744 -311.173146)
			(xy 42.83116 -311.219827) (xy 42.808289 -311.263404) (xy 42.778724 -311.302748) (xy 42.743231 -311.33684)
			(xy 42.702728 -311.364796) (xy 42.658266 -311.385894) (xy 42.610995 -311.399586) (xy 42.56214 -311.405518)
			(xy 42.512965 -311.403537) (xy 42.464746 -311.393693) (xy 42.41873 -311.376241) (xy 42.376109 -311.351634)
			(xy 42.337988 -311.320509) (xy 42.305353 -311.283672) (xy 42.27905 -311.242076) (xy 42.259759 -311.1968)
			(xy 42.247982 -311.149016) (xy 42.244022 -311.099962) (xy 41.905795 -311.099962) (xy 41.905798 -311.1)
			(xy 41.901625 -311.150353) (xy 41.889221 -311.199332) (xy 41.868924 -311.245601) (xy 41.841288 -311.287898)
			(xy 41.807066 -311.325069) (xy 41.767192 -311.356099) (xy 41.722755 -311.380143) (xy 41.674966 -311.396545)
			(xy 41.625129 -311.404856) (xy 41.599866 -311.40527) (xy 41.567862 -311.403492) (xy 41.567354 -311.403492)
			(xy 41.55694 -311.402476) (xy 41.53662 -311.40908) (xy 41.472104 -311.466738) (xy 41.464455 -311.474259)
			(xy 41.455792 -311.493864) (xy 41.45534 -311.504584) (xy 41.45534 -311.574942) (xy 41.455178 -311.58937)
			(xy 41.452635 -311.618114) (xy 41.45026 -311.632346) (xy 41.45026 -311.632854) (xy 41.448736 -311.641236)
			(xy 41.455848 -311.663842) (xy 41.520364 -311.731406) (xy 41.529004 -311.739621) (xy 41.551397 -311.747709)
			(xy 41.56329 -311.7469) (xy 41.572398 -311.745845) (xy 41.590698 -311.744701) (xy 41.599866 -311.744614)
			(xy 41.625124 -311.745104) (xy 41.674951 -311.753414) (xy 41.722731 -311.769812) (xy 41.76716 -311.793851)
			(xy 41.807025 -311.824876) (xy 41.84124 -311.862039) (xy 41.868871 -311.904328) (xy 41.889165 -311.950588)
			(xy 41.901566 -311.999557) (xy 41.905738 -312.0499) (xy 41.905736 -312.049922) (xy 42.244022 -312.049922)
			(xy 42.247982 -312.000868) (xy 42.259759 -311.953084) (xy 42.27905 -311.907808) (xy 42.305353 -311.866212)
			(xy 42.337988 -311.829375) (xy 42.376109 -311.79825) (xy 42.41873 -311.773643) (xy 42.464746 -311.756191)
			(xy 42.512965 -311.746347) (xy 42.56214 -311.744366) (xy 42.610995 -311.750298) (xy 42.658266 -311.76399)
			(xy 42.702728 -311.785088) (xy 42.743231 -311.813044) (xy 42.778724 -311.847136) (xy 42.808289 -311.88648)
			(xy 42.83116 -311.930057) (xy 42.846744 -311.976738) (xy 42.854639 -312.025315) (xy 42.855134 -312.049922)
			(xy 43.193982 -312.049922) (xy 43.197942 -312.000868) (xy 43.209719 -311.953084) (xy 43.22901 -311.907808)
			(xy 43.255313 -311.866212) (xy 43.287948 -311.829375) (xy 43.326069 -311.79825) (xy 43.36869 -311.773643)
			(xy 43.414706 -311.756191) (xy 43.462925 -311.746347) (xy 43.5121 -311.744366) (xy 43.560955 -311.750298)
			(xy 43.608226 -311.76399) (xy 43.652688 -311.785088) (xy 43.693191 -311.813044) (xy 43.728684 -311.847136)
			(xy 43.758249 -311.88648) (xy 43.78112 -311.930057) (xy 43.796704 -311.976738) (xy 43.804599 -312.025315)
			(xy 43.805094 -312.049922) (xy 44.143942 -312.049922) (xy 44.147902 -312.000868) (xy 44.159679 -311.953084)
			(xy 44.17897 -311.907808) (xy 44.205273 -311.866212) (xy 44.237908 -311.829375) (xy 44.276029 -311.79825)
			(xy 44.31865 -311.773643) (xy 44.364666 -311.756191) (xy 44.412885 -311.746347) (xy 44.46206 -311.744366)
			(xy 44.510915 -311.750298) (xy 44.558186 -311.76399) (xy 44.602648 -311.785088) (xy 44.643151 -311.813044)
			(xy 44.678644 -311.847136) (xy 44.708209 -311.88648) (xy 44.73108 -311.930057) (xy 44.746664 -311.976738)
			(xy 44.754559 -312.025315) (xy 44.755054 -312.049922) (xy 45.094156 -312.049922) (xy 45.098116 -312.000868)
			(xy 45.109893 -311.953084) (xy 45.129184 -311.907808) (xy 45.155487 -311.866212) (xy 45.188122 -311.829375)
			(xy 45.226243 -311.79825) (xy 45.268864 -311.773643) (xy 45.31488 -311.756191) (xy 45.363099 -311.746347)
			(xy 45.412274 -311.744366) (xy 45.461129 -311.750298) (xy 45.5084 -311.76399) (xy 45.552862 -311.785088)
			(xy 45.593365 -311.813044) (xy 45.628858 -311.847136) (xy 45.658423 -311.88648) (xy 45.681294 -311.930057)
			(xy 45.696878 -311.976738) (xy 45.704773 -312.025315) (xy 45.705268 -312.049922) (xy 46.044116 -312.049922)
			(xy 46.048076 -312.000868) (xy 46.059853 -311.953084) (xy 46.079144 -311.907808) (xy 46.105447 -311.866212)
			(xy 46.138082 -311.829375) (xy 46.176203 -311.79825) (xy 46.218824 -311.773643) (xy 46.26484 -311.756191)
			(xy 46.313059 -311.746347) (xy 46.362234 -311.744366) (xy 46.411089 -311.750298) (xy 46.45836 -311.76399)
			(xy 46.502822 -311.785088) (xy 46.543325 -311.813044) (xy 46.578818 -311.847136) (xy 46.608383 -311.88648)
			(xy 46.631254 -311.930057) (xy 46.646838 -311.976738) (xy 46.654733 -312.025315) (xy 46.655228 -312.049922)
			(xy 46.994076 -312.049922) (xy 46.998036 -312.000868) (xy 47.009813 -311.953084) (xy 47.029104 -311.907808)
			(xy 47.055407 -311.866212) (xy 47.088042 -311.829375) (xy 47.126163 -311.79825) (xy 47.168784 -311.773643)
			(xy 47.2148 -311.756191) (xy 47.263019 -311.746347) (xy 47.312194 -311.744366) (xy 47.361049 -311.750298)
			(xy 47.40832 -311.76399) (xy 47.452782 -311.785088) (xy 47.493285 -311.813044) (xy 47.528778 -311.847136)
			(xy 47.558343 -311.88648) (xy 47.581214 -311.930057) (xy 47.596798 -311.976738) (xy 47.604693 -312.025315)
			(xy 47.605188 -312.049922) (xy 47.944036 -312.049922) (xy 47.947996 -312.000868) (xy 47.959773 -311.953084)
			(xy 47.979064 -311.907808) (xy 48.005367 -311.866212) (xy 48.038002 -311.829375) (xy 48.076123 -311.79825)
			(xy 48.118744 -311.773643) (xy 48.16476 -311.756191) (xy 48.212979 -311.746347) (xy 48.262154 -311.744366)
			(xy 48.311009 -311.750298) (xy 48.35828 -311.76399) (xy 48.402742 -311.785088) (xy 48.443245 -311.813044)
			(xy 48.478738 -311.847136) (xy 48.508303 -311.88648) (xy 48.531174 -311.930057) (xy 48.546758 -311.976738)
			(xy 48.554653 -312.025315) (xy 48.555148 -312.049922) (xy 48.893996 -312.049922) (xy 48.897956 -312.000868)
			(xy 48.909733 -311.953084) (xy 48.929024 -311.907808) (xy 48.955327 -311.866212) (xy 48.987962 -311.829375)
			(xy 49.026083 -311.79825) (xy 49.068704 -311.773643) (xy 49.11472 -311.756191) (xy 49.162939 -311.746347)
			(xy 49.212114 -311.744366) (xy 49.260969 -311.750298) (xy 49.30824 -311.76399) (xy 49.352702 -311.785088)
			(xy 49.393205 -311.813044) (xy 49.428698 -311.847136) (xy 49.458263 -311.88648) (xy 49.481134 -311.930057)
			(xy 49.496718 -311.976738) (xy 49.504613 -312.025315) (xy 49.505108 -312.049922) (xy 49.843956 -312.049922)
			(xy 49.847916 -312.000868) (xy 49.859693 -311.953084) (xy 49.878984 -311.907808) (xy 49.905287 -311.866212)
			(xy 49.937922 -311.829375) (xy 49.976043 -311.79825) (xy 50.018664 -311.773643) (xy 50.06468 -311.756191)
			(xy 50.112899 -311.746347) (xy 50.162074 -311.744366) (xy 50.210929 -311.750298) (xy 50.2582 -311.76399)
			(xy 50.302662 -311.785088) (xy 50.343165 -311.813044) (xy 50.378658 -311.847136) (xy 50.408223 -311.88648)
			(xy 50.431094 -311.930057) (xy 50.446678 -311.976738) (xy 50.454573 -312.025315) (xy 50.455068 -312.049922)
			(xy 50.79417 -312.049922) (xy 50.79813 -312.000868) (xy 50.809907 -311.953084) (xy 50.829198 -311.907808)
			(xy 50.855501 -311.866212) (xy 50.888136 -311.829375) (xy 50.926257 -311.79825) (xy 50.968878 -311.773643)
			(xy 51.014894 -311.756191) (xy 51.063113 -311.746347) (xy 51.112288 -311.744366) (xy 51.161143 -311.750298)
			(xy 51.208414 -311.76399) (xy 51.252876 -311.785088) (xy 51.293379 -311.813044) (xy 51.328872 -311.847136)
			(xy 51.358437 -311.88648) (xy 51.381308 -311.930057) (xy 51.396892 -311.976738) (xy 51.404787 -312.025315)
			(xy 51.405282 -312.049922) (xy 51.74413 -312.049922) (xy 51.74809 -312.000868) (xy 51.759867 -311.953084)
			(xy 51.779158 -311.907808) (xy 51.805461 -311.866212) (xy 51.838096 -311.829375) (xy 51.876217 -311.79825)
			(xy 51.918838 -311.773643) (xy 51.964854 -311.756191) (xy 52.013073 -311.746347) (xy 52.062248 -311.744366)
			(xy 52.111103 -311.750298) (xy 52.158374 -311.76399) (xy 52.202836 -311.785088) (xy 52.243339 -311.813044)
			(xy 52.278832 -311.847136) (xy 52.308397 -311.88648) (xy 52.331268 -311.930057) (xy 52.346852 -311.976738)
			(xy 52.354747 -312.025315) (xy 52.355242 -312.049922) (xy 52.69409 -312.049922) (xy 52.69805 -312.000868)
			(xy 52.709827 -311.953084) (xy 52.729118 -311.907808) (xy 52.755421 -311.866212) (xy 52.788056 -311.829375)
			(xy 52.826177 -311.79825) (xy 52.868798 -311.773643) (xy 52.914814 -311.756191) (xy 52.963033 -311.746347)
			(xy 53.012208 -311.744366) (xy 53.061063 -311.750298) (xy 53.108334 -311.76399) (xy 53.152796 -311.785088)
			(xy 53.193299 -311.813044) (xy 53.228792 -311.847136) (xy 53.258357 -311.88648) (xy 53.281228 -311.930057)
			(xy 53.296812 -311.976738) (xy 53.304707 -312.025315) (xy 53.305202 -312.049922) (xy 53.64405 -312.049922)
			(xy 53.64801 -312.000868) (xy 53.659787 -311.953084) (xy 53.679078 -311.907808) (xy 53.705381 -311.866212)
			(xy 53.738016 -311.829375) (xy 53.776137 -311.79825) (xy 53.818758 -311.773643) (xy 53.864774 -311.756191)
			(xy 53.912993 -311.746347) (xy 53.962168 -311.744366) (xy 54.011023 -311.750298) (xy 54.058294 -311.76399)
			(xy 54.102756 -311.785088) (xy 54.143259 -311.813044) (xy 54.178752 -311.847136) (xy 54.208317 -311.88648)
			(xy 54.231188 -311.930057) (xy 54.246772 -311.976738) (xy 54.254667 -312.025315) (xy 54.255162 -312.049922)
			(xy 54.59401 -312.049922) (xy 54.59797 -312.000868) (xy 54.609747 -311.953084) (xy 54.629038 -311.907808)
			(xy 54.655341 -311.866212) (xy 54.687976 -311.829375) (xy 54.726097 -311.79825) (xy 54.768718 -311.773643)
			(xy 54.814734 -311.756191) (xy 54.862953 -311.746347) (xy 54.912128 -311.744366) (xy 54.960983 -311.750298)
			(xy 55.008254 -311.76399) (xy 55.052716 -311.785088) (xy 55.093219 -311.813044) (xy 55.128712 -311.847136)
			(xy 55.158277 -311.88648) (xy 55.181148 -311.930057) (xy 55.196732 -311.976738) (xy 55.204627 -312.025315)
			(xy 55.205122 -312.049922) (xy 55.54397 -312.049922) (xy 55.54793 -312.000868) (xy 55.559707 -311.953084)
			(xy 55.578998 -311.907808) (xy 55.605301 -311.866212) (xy 55.637936 -311.829375) (xy 55.676057 -311.79825)
			(xy 55.718678 -311.773643) (xy 55.764694 -311.756191) (xy 55.812913 -311.746347) (xy 55.862088 -311.744366)
			(xy 55.910943 -311.750298) (xy 55.958214 -311.76399) (xy 56.002676 -311.785088) (xy 56.043179 -311.813044)
			(xy 56.078672 -311.847136) (xy 56.108237 -311.88648) (xy 56.131108 -311.930057) (xy 56.146692 -311.976738)
			(xy 56.154587 -312.025315) (xy 56.155082 -312.049922) (xy 56.494184 -312.049922) (xy 56.498144 -312.000868)
			(xy 56.509921 -311.953084) (xy 56.529212 -311.907808) (xy 56.555515 -311.866212) (xy 56.58815 -311.829375)
			(xy 56.626271 -311.79825) (xy 56.668892 -311.773643) (xy 56.714908 -311.756191) (xy 56.763127 -311.746347)
			(xy 56.812302 -311.744366) (xy 56.861157 -311.750298) (xy 56.908428 -311.76399) (xy 56.95289 -311.785088)
			(xy 56.993393 -311.813044) (xy 57.028886 -311.847136) (xy 57.058451 -311.88648) (xy 57.081322 -311.930057)
			(xy 57.096906 -311.976738) (xy 57.104801 -312.025315) (xy 57.105296 -312.049922) (xy 57.444144 -312.049922)
			(xy 57.448104 -312.000868) (xy 57.459881 -311.953084) (xy 57.479172 -311.907808) (xy 57.505475 -311.866212)
			(xy 57.53811 -311.829375) (xy 57.576231 -311.79825) (xy 57.618852 -311.773643) (xy 57.664868 -311.756191)
			(xy 57.713087 -311.746347) (xy 57.762262 -311.744366) (xy 57.811117 -311.750298) (xy 57.858388 -311.76399)
			(xy 57.90285 -311.785088) (xy 57.943353 -311.813044) (xy 57.978846 -311.847136) (xy 58.008411 -311.88648)
			(xy 58.031282 -311.930057) (xy 58.046866 -311.976738) (xy 58.054761 -312.025315) (xy 58.055256 -312.049922)
			(xy 58.394104 -312.049922) (xy 58.398064 -312.000868) (xy 58.409841 -311.953084) (xy 58.429132 -311.907808)
			(xy 58.455435 -311.866212) (xy 58.48807 -311.829375) (xy 58.526191 -311.79825) (xy 58.568812 -311.773643)
			(xy 58.614828 -311.756191) (xy 58.663047 -311.746347) (xy 58.712222 -311.744366) (xy 58.761077 -311.750298)
			(xy 58.808348 -311.76399) (xy 58.85281 -311.785088) (xy 58.893313 -311.813044) (xy 58.928806 -311.847136)
			(xy 58.958371 -311.88648) (xy 58.981242 -311.930057) (xy 58.996826 -311.976738) (xy 59.004721 -312.025315)
			(xy 59.005216 -312.049922) (xy 59.344064 -312.049922) (xy 59.348024 -312.000868) (xy 59.359801 -311.953084)
			(xy 59.379092 -311.907808) (xy 59.405395 -311.866212) (xy 59.43803 -311.829375) (xy 59.476151 -311.79825)
			(xy 59.518772 -311.773643) (xy 59.564788 -311.756191) (xy 59.613007 -311.746347) (xy 59.662182 -311.744366)
			(xy 59.711037 -311.750298) (xy 59.758308 -311.76399) (xy 59.80277 -311.785088) (xy 59.843273 -311.813044)
			(xy 59.878766 -311.847136) (xy 59.908331 -311.88648) (xy 59.931202 -311.930057) (xy 59.946786 -311.976738)
			(xy 59.954681 -312.025315) (xy 59.955176 -312.049922) (xy 60.294024 -312.049922) (xy 60.297984 -312.000868)
			(xy 60.309761 -311.953084) (xy 60.329052 -311.907808) (xy 60.355355 -311.866212) (xy 60.38799 -311.829375)
			(xy 60.426111 -311.79825) (xy 60.468732 -311.773643) (xy 60.514748 -311.756191) (xy 60.562967 -311.746347)
			(xy 60.612142 -311.744366) (xy 60.660997 -311.750298) (xy 60.708268 -311.76399) (xy 60.75273 -311.785088)
			(xy 60.793233 -311.813044) (xy 60.828726 -311.847136) (xy 60.858291 -311.88648) (xy 60.881162 -311.930057)
			(xy 60.896746 -311.976738) (xy 60.904641 -312.025315) (xy 60.905136 -312.049922) (xy 61.243984 -312.049922)
			(xy 61.247944 -312.000868) (xy 61.259721 -311.953084) (xy 61.279012 -311.907808) (xy 61.305315 -311.866212)
			(xy 61.33795 -311.829375) (xy 61.376071 -311.79825) (xy 61.418692 -311.773643) (xy 61.464708 -311.756191)
			(xy 61.512927 -311.746347) (xy 61.562102 -311.744366) (xy 61.610957 -311.750298) (xy 61.658228 -311.76399)
			(xy 61.70269 -311.785088) (xy 61.743193 -311.813044) (xy 61.778686 -311.847136) (xy 61.808251 -311.88648)
			(xy 61.831122 -311.930057) (xy 61.846706 -311.976738) (xy 61.854601 -312.025315) (xy 61.855096 -312.049922)
			(xy 61.854601 -312.074529) (xy 61.846706 -312.123106) (xy 61.831122 -312.169787) (xy 61.808251 -312.213364)
			(xy 61.778686 -312.252708) (xy 61.743193 -312.2868) (xy 61.70269 -312.314756) (xy 61.658228 -312.335854)
			(xy 61.610957 -312.349546) (xy 61.562102 -312.355478) (xy 61.512927 -312.353497) (xy 61.464708 -312.343653)
			(xy 61.418692 -312.326201) (xy 61.376071 -312.301594) (xy 61.33795 -312.270469) (xy 61.305315 -312.233632)
			(xy 61.279012 -312.192036) (xy 61.259721 -312.14676) (xy 61.247944 -312.098976) (xy 61.243984 -312.049922)
			(xy 60.905136 -312.049922) (xy 60.904641 -312.074529) (xy 60.896746 -312.123106) (xy 60.881162 -312.169787)
			(xy 60.858291 -312.213364) (xy 60.828726 -312.252708) (xy 60.793233 -312.2868) (xy 60.75273 -312.314756)
			(xy 60.708268 -312.335854) (xy 60.660997 -312.349546) (xy 60.612142 -312.355478) (xy 60.562967 -312.353497)
			(xy 60.514748 -312.343653) (xy 60.468732 -312.326201) (xy 60.426111 -312.301594) (xy 60.38799 -312.270469)
			(xy 60.355355 -312.233632) (xy 60.329052 -312.192036) (xy 60.309761 -312.14676) (xy 60.297984 -312.098976)
			(xy 60.294024 -312.049922) (xy 59.955176 -312.049922) (xy 59.954681 -312.074529) (xy 59.946786 -312.123106)
			(xy 59.931202 -312.169787) (xy 59.908331 -312.213364) (xy 59.878766 -312.252708) (xy 59.843273 -312.2868)
			(xy 59.80277 -312.314756) (xy 59.758308 -312.335854) (xy 59.711037 -312.349546) (xy 59.662182 -312.355478)
			(xy 59.613007 -312.353497) (xy 59.564788 -312.343653) (xy 59.518772 -312.326201) (xy 59.476151 -312.301594)
			(xy 59.43803 -312.270469) (xy 59.405395 -312.233632) (xy 59.379092 -312.192036) (xy 59.359801 -312.14676)
			(xy 59.348024 -312.098976) (xy 59.344064 -312.049922) (xy 59.005216 -312.049922) (xy 59.004721 -312.074529)
			(xy 58.996826 -312.123106) (xy 58.981242 -312.169787) (xy 58.958371 -312.213364) (xy 58.928806 -312.252708)
			(xy 58.893313 -312.2868) (xy 58.85281 -312.314756) (xy 58.808348 -312.335854) (xy 58.761077 -312.349546)
			(xy 58.712222 -312.355478) (xy 58.663047 -312.353497) (xy 58.614828 -312.343653) (xy 58.568812 -312.326201)
			(xy 58.526191 -312.301594) (xy 58.48807 -312.270469) (xy 58.455435 -312.233632) (xy 58.429132 -312.192036)
			(xy 58.409841 -312.14676) (xy 58.398064 -312.098976) (xy 58.394104 -312.049922) (xy 58.055256 -312.049922)
			(xy 58.054761 -312.074529) (xy 58.046866 -312.123106) (xy 58.031282 -312.169787) (xy 58.008411 -312.213364)
			(xy 57.978846 -312.252708) (xy 57.943353 -312.2868) (xy 57.90285 -312.314756) (xy 57.858388 -312.335854)
			(xy 57.811117 -312.349546) (xy 57.762262 -312.355478) (xy 57.713087 -312.353497) (xy 57.664868 -312.343653)
			(xy 57.618852 -312.326201) (xy 57.576231 -312.301594) (xy 57.53811 -312.270469) (xy 57.505475 -312.233632)
			(xy 57.479172 -312.192036) (xy 57.459881 -312.14676) (xy 57.448104 -312.098976) (xy 57.444144 -312.049922)
			(xy 57.105296 -312.049922) (xy 57.104801 -312.074529) (xy 57.096906 -312.123106) (xy 57.081322 -312.169787)
			(xy 57.058451 -312.213364) (xy 57.028886 -312.252708) (xy 56.993393 -312.2868) (xy 56.95289 -312.314756)
			(xy 56.908428 -312.335854) (xy 56.861157 -312.349546) (xy 56.812302 -312.355478) (xy 56.763127 -312.353497)
			(xy 56.714908 -312.343653) (xy 56.668892 -312.326201) (xy 56.626271 -312.301594) (xy 56.58815 -312.270469)
			(xy 56.555515 -312.233632) (xy 56.529212 -312.192036) (xy 56.509921 -312.14676) (xy 56.498144 -312.098976)
			(xy 56.494184 -312.049922) (xy 56.155082 -312.049922) (xy 56.154587 -312.074529) (xy 56.146692 -312.123106)
			(xy 56.131108 -312.169787) (xy 56.108237 -312.213364) (xy 56.078672 -312.252708) (xy 56.043179 -312.2868)
			(xy 56.002676 -312.314756) (xy 55.958214 -312.335854) (xy 55.910943 -312.349546) (xy 55.862088 -312.355478)
			(xy 55.812913 -312.353497) (xy 55.764694 -312.343653) (xy 55.718678 -312.326201) (xy 55.676057 -312.301594)
			(xy 55.637936 -312.270469) (xy 55.605301 -312.233632) (xy 55.578998 -312.192036) (xy 55.559707 -312.14676)
			(xy 55.54793 -312.098976) (xy 55.54397 -312.049922) (xy 55.205122 -312.049922) (xy 55.204627 -312.074529)
			(xy 55.196732 -312.123106) (xy 55.181148 -312.169787) (xy 55.158277 -312.213364) (xy 55.128712 -312.252708)
			(xy 55.093219 -312.2868) (xy 55.052716 -312.314756) (xy 55.008254 -312.335854) (xy 54.960983 -312.349546)
			(xy 54.912128 -312.355478) (xy 54.862953 -312.353497) (xy 54.814734 -312.343653) (xy 54.768718 -312.326201)
			(xy 54.726097 -312.301594) (xy 54.687976 -312.270469) (xy 54.655341 -312.233632) (xy 54.629038 -312.192036)
			(xy 54.609747 -312.14676) (xy 54.59797 -312.098976) (xy 54.59401 -312.049922) (xy 54.255162 -312.049922)
			(xy 54.254667 -312.074529) (xy 54.246772 -312.123106) (xy 54.231188 -312.169787) (xy 54.208317 -312.213364)
			(xy 54.178752 -312.252708) (xy 54.143259 -312.2868) (xy 54.102756 -312.314756) (xy 54.058294 -312.335854)
			(xy 54.011023 -312.349546) (xy 53.962168 -312.355478) (xy 53.912993 -312.353497) (xy 53.864774 -312.343653)
			(xy 53.818758 -312.326201) (xy 53.776137 -312.301594) (xy 53.738016 -312.270469) (xy 53.705381 -312.233632)
			(xy 53.679078 -312.192036) (xy 53.659787 -312.14676) (xy 53.64801 -312.098976) (xy 53.64405 -312.049922)
			(xy 53.305202 -312.049922) (xy 53.304707 -312.074529) (xy 53.296812 -312.123106) (xy 53.281228 -312.169787)
			(xy 53.258357 -312.213364) (xy 53.228792 -312.252708) (xy 53.193299 -312.2868) (xy 53.152796 -312.314756)
			(xy 53.108334 -312.335854) (xy 53.061063 -312.349546) (xy 53.012208 -312.355478) (xy 52.963033 -312.353497)
			(xy 52.914814 -312.343653) (xy 52.868798 -312.326201) (xy 52.826177 -312.301594) (xy 52.788056 -312.270469)
			(xy 52.755421 -312.233632) (xy 52.729118 -312.192036) (xy 52.709827 -312.14676) (xy 52.69805 -312.098976)
			(xy 52.69409 -312.049922) (xy 52.355242 -312.049922) (xy 52.354747 -312.074529) (xy 52.346852 -312.123106)
			(xy 52.331268 -312.169787) (xy 52.308397 -312.213364) (xy 52.278832 -312.252708) (xy 52.243339 -312.2868)
			(xy 52.202836 -312.314756) (xy 52.158374 -312.335854) (xy 52.111103 -312.349546) (xy 52.062248 -312.355478)
			(xy 52.013073 -312.353497) (xy 51.964854 -312.343653) (xy 51.918838 -312.326201) (xy 51.876217 -312.301594)
			(xy 51.838096 -312.270469) (xy 51.805461 -312.233632) (xy 51.779158 -312.192036) (xy 51.759867 -312.14676)
			(xy 51.74809 -312.098976) (xy 51.74413 -312.049922) (xy 51.405282 -312.049922) (xy 51.404787 -312.074529)
			(xy 51.396892 -312.123106) (xy 51.381308 -312.169787) (xy 51.358437 -312.213364) (xy 51.328872 -312.252708)
			(xy 51.293379 -312.2868) (xy 51.252876 -312.314756) (xy 51.208414 -312.335854) (xy 51.161143 -312.349546)
			(xy 51.112288 -312.355478) (xy 51.063113 -312.353497) (xy 51.014894 -312.343653) (xy 50.968878 -312.326201)
			(xy 50.926257 -312.301594) (xy 50.888136 -312.270469) (xy 50.855501 -312.233632) (xy 50.829198 -312.192036)
			(xy 50.809907 -312.14676) (xy 50.79813 -312.098976) (xy 50.79417 -312.049922) (xy 50.455068 -312.049922)
			(xy 50.454573 -312.074529) (xy 50.446678 -312.123106) (xy 50.431094 -312.169787) (xy 50.408223 -312.213364)
			(xy 50.378658 -312.252708) (xy 50.343165 -312.2868) (xy 50.302662 -312.314756) (xy 50.2582 -312.335854)
			(xy 50.210929 -312.349546) (xy 50.162074 -312.355478) (xy 50.112899 -312.353497) (xy 50.06468 -312.343653)
			(xy 50.018664 -312.326201) (xy 49.976043 -312.301594) (xy 49.937922 -312.270469) (xy 49.905287 -312.233632)
			(xy 49.878984 -312.192036) (xy 49.859693 -312.14676) (xy 49.847916 -312.098976) (xy 49.843956 -312.049922)
			(xy 49.505108 -312.049922) (xy 49.504613 -312.074529) (xy 49.496718 -312.123106) (xy 49.481134 -312.169787)
			(xy 49.458263 -312.213364) (xy 49.428698 -312.252708) (xy 49.393205 -312.2868) (xy 49.352702 -312.314756)
			(xy 49.30824 -312.335854) (xy 49.260969 -312.349546) (xy 49.212114 -312.355478) (xy 49.162939 -312.353497)
			(xy 49.11472 -312.343653) (xy 49.068704 -312.326201) (xy 49.026083 -312.301594) (xy 48.987962 -312.270469)
			(xy 48.955327 -312.233632) (xy 48.929024 -312.192036) (xy 48.909733 -312.14676) (xy 48.897956 -312.098976)
			(xy 48.893996 -312.049922) (xy 48.555148 -312.049922) (xy 48.554653 -312.074529) (xy 48.546758 -312.123106)
			(xy 48.531174 -312.169787) (xy 48.508303 -312.213364) (xy 48.478738 -312.252708) (xy 48.443245 -312.2868)
			(xy 48.402742 -312.314756) (xy 48.35828 -312.335854) (xy 48.311009 -312.349546) (xy 48.262154 -312.355478)
			(xy 48.212979 -312.353497) (xy 48.16476 -312.343653) (xy 48.118744 -312.326201) (xy 48.076123 -312.301594)
			(xy 48.038002 -312.270469) (xy 48.005367 -312.233632) (xy 47.979064 -312.192036) (xy 47.959773 -312.14676)
			(xy 47.947996 -312.098976) (xy 47.944036 -312.049922) (xy 47.605188 -312.049922) (xy 47.604693 -312.074529)
			(xy 47.596798 -312.123106) (xy 47.581214 -312.169787) (xy 47.558343 -312.213364) (xy 47.528778 -312.252708)
			(xy 47.493285 -312.2868) (xy 47.452782 -312.314756) (xy 47.40832 -312.335854) (xy 47.361049 -312.349546)
			(xy 47.312194 -312.355478) (xy 47.263019 -312.353497) (xy 47.2148 -312.343653) (xy 47.168784 -312.326201)
			(xy 47.126163 -312.301594) (xy 47.088042 -312.270469) (xy 47.055407 -312.233632) (xy 47.029104 -312.192036)
			(xy 47.009813 -312.14676) (xy 46.998036 -312.098976) (xy 46.994076 -312.049922) (xy 46.655228 -312.049922)
			(xy 46.654733 -312.074529) (xy 46.646838 -312.123106) (xy 46.631254 -312.169787) (xy 46.608383 -312.213364)
			(xy 46.578818 -312.252708) (xy 46.543325 -312.2868) (xy 46.502822 -312.314756) (xy 46.45836 -312.335854)
			(xy 46.411089 -312.349546) (xy 46.362234 -312.355478) (xy 46.313059 -312.353497) (xy 46.26484 -312.343653)
			(xy 46.218824 -312.326201) (xy 46.176203 -312.301594) (xy 46.138082 -312.270469) (xy 46.105447 -312.233632)
			(xy 46.079144 -312.192036) (xy 46.059853 -312.14676) (xy 46.048076 -312.098976) (xy 46.044116 -312.049922)
			(xy 45.705268 -312.049922) (xy 45.704773 -312.074529) (xy 45.696878 -312.123106) (xy 45.681294 -312.169787)
			(xy 45.658423 -312.213364) (xy 45.628858 -312.252708) (xy 45.593365 -312.2868) (xy 45.552862 -312.314756)
			(xy 45.5084 -312.335854) (xy 45.461129 -312.349546) (xy 45.412274 -312.355478) (xy 45.363099 -312.353497)
			(xy 45.31488 -312.343653) (xy 45.268864 -312.326201) (xy 45.226243 -312.301594) (xy 45.188122 -312.270469)
			(xy 45.155487 -312.233632) (xy 45.129184 -312.192036) (xy 45.109893 -312.14676) (xy 45.098116 -312.098976)
			(xy 45.094156 -312.049922) (xy 44.755054 -312.049922) (xy 44.754559 -312.074529) (xy 44.746664 -312.123106)
			(xy 44.73108 -312.169787) (xy 44.708209 -312.213364) (xy 44.678644 -312.252708) (xy 44.643151 -312.2868)
			(xy 44.602648 -312.314756) (xy 44.558186 -312.335854) (xy 44.510915 -312.349546) (xy 44.46206 -312.355478)
			(xy 44.412885 -312.353497) (xy 44.364666 -312.343653) (xy 44.31865 -312.326201) (xy 44.276029 -312.301594)
			(xy 44.237908 -312.270469) (xy 44.205273 -312.233632) (xy 44.17897 -312.192036) (xy 44.159679 -312.14676)
			(xy 44.147902 -312.098976) (xy 44.143942 -312.049922) (xy 43.805094 -312.049922) (xy 43.804599 -312.074529)
			(xy 43.796704 -312.123106) (xy 43.78112 -312.169787) (xy 43.758249 -312.213364) (xy 43.728684 -312.252708)
			(xy 43.693191 -312.2868) (xy 43.652688 -312.314756) (xy 43.608226 -312.335854) (xy 43.560955 -312.349546)
			(xy 43.5121 -312.355478) (xy 43.462925 -312.353497) (xy 43.414706 -312.343653) (xy 43.36869 -312.326201)
			(xy 43.326069 -312.301594) (xy 43.287948 -312.270469) (xy 43.255313 -312.233632) (xy 43.22901 -312.192036)
			(xy 43.209719 -312.14676) (xy 43.197942 -312.098976) (xy 43.193982 -312.049922) (xy 42.855134 -312.049922)
			(xy 42.854639 -312.074529) (xy 42.846744 -312.123106) (xy 42.83116 -312.169787) (xy 42.808289 -312.213364)
			(xy 42.778724 -312.252708) (xy 42.743231 -312.2868) (xy 42.702728 -312.314756) (xy 42.658266 -312.335854)
			(xy 42.610995 -312.349546) (xy 42.56214 -312.355478) (xy 42.512965 -312.353497) (xy 42.464746 -312.343653)
			(xy 42.41873 -312.326201) (xy 42.376109 -312.301594) (xy 42.337988 -312.270469) (xy 42.305353 -312.233632)
			(xy 42.27905 -312.192036) (xy 42.259759 -312.14676) (xy 42.247982 -312.098976) (xy 42.244022 -312.049922)
			(xy 41.905736 -312.049922) (xy 41.901566 -312.100243) (xy 41.889165 -312.149212) (xy 41.868871 -312.195472)
			(xy 41.84124 -312.237761) (xy 41.807025 -312.274924) (xy 41.76716 -312.305949) (xy 41.722731 -312.329988)
			(xy 41.674951 -312.346386) (xy 41.625124 -312.354696) (xy 41.599866 -312.35523) (xy 41.58562 -312.355053)
			(xy 41.557253 -312.352381) (xy 41.543224 -312.349896) (xy 41.530778 -312.34761) (xy 41.507156 -312.354976)
			(xy 41.429686 -312.432192) (xy 41.42232 -312.455814) (xy 41.42359 -312.462926) (xy 41.427467 -312.483376)
			(xy 41.430298 -312.524902) (xy 41.427466 -312.566428) (xy 41.42359 -312.586878) (xy 41.42359 -312.587894)
			(xy 41.42232 -312.593736) (xy 41.42994 -312.617866) (xy 41.498266 -312.685938) (xy 41.507506 -312.694089)
			(xy 41.530995 -312.701398) (xy 41.543224 -312.699908) (xy 41.543478 -312.699908) (xy 41.557443 -312.697421)
			(xy 41.585683 -312.694746) (xy 41.599866 -312.694574) (xy 41.623861 -312.695018) (xy 41.671262 -312.70252)
			(xy 41.716905 -312.717345) (xy 41.759668 -312.739129) (xy 41.798495 -312.767333) (xy 41.832433 -312.801265)
			(xy 41.860644 -312.840088) (xy 41.882435 -312.882846) (xy 41.897268 -312.928487) (xy 41.904778 -312.975887)
			(xy 41.905174 -312.999882) (xy 41.905127 -313.008919) (xy 41.90411 -313.026965) (xy 41.903142 -313.03595)
			(xy 41.903142 -313.036204) (xy 41.902335 -313.048003) (xy 41.910297 -313.070241) (xy 41.918382 -313.078876)
			(xy 41.985692 -313.143138) (xy 42.008552 -313.15025) (xy 42.02049 -313.148218) (xy 42.033857 -313.14617)
			(xy 42.060815 -313.144005) (xy 42.074338 -313.1439) (xy 42.074592 -313.1439) (xy 42.08902 -313.144064)
			(xy 42.117763 -313.146612) (xy 42.131996 -313.14898) (xy 42.132504 -313.14898) (xy 42.14114 -313.150504)
			(xy 42.163746 -313.143392) (xy 42.23131 -313.078622) (xy 42.23939 -313.070131) (xy 42.247476 -313.048159)
			(xy 42.246804 -313.036458) (xy 42.246804 -313.036204) (xy 42.245756 -313.02716) (xy 42.244613 -313.008986)
			(xy 42.244518 -312.999882) (xy 42.245005 -312.975064) (xy 42.253038 -312.926082) (xy 42.268889 -312.879045)
			(xy 42.292141 -312.835193) (xy 42.322181 -312.795679) (xy 42.358218 -312.761545) (xy 42.399302 -312.733692)
			(xy 42.444351 -312.712851) (xy 42.492177 -312.699573) (xy 42.541523 -312.694207) (xy 42.591086 -312.696895)
			(xy 42.639561 -312.707565) (xy 42.685672 -312.725937) (xy 42.728203 -312.751527) (xy 42.766034 -312.78366)
			(xy 42.798168 -312.821491) (xy 42.823759 -312.864021) (xy 42.842132 -312.910131) (xy 42.852804 -312.958606)
			(xy 42.855493 -313.008169) (xy 42.850129 -313.057515) (xy 42.836852 -313.105342) (xy 42.816012 -313.150391)
			(xy 42.78816 -313.191476) (xy 42.754027 -313.227514) (xy 42.714514 -313.257555) (xy 42.670662 -313.280808)
			(xy 42.623625 -313.29666) (xy 42.574644 -313.304694) (xy 42.549826 -313.30519) (xy 42.540658 -313.305098)
			(xy 42.522358 -313.303956) (xy 42.51325 -313.302904) (xy 42.512996 -313.302904) (xy 42.501196 -313.302097)
			(xy 42.478954 -313.310054) (xy 42.470324 -313.318144) (xy 42.405808 -313.385708) (xy 42.398696 -313.408314)
			(xy 42.399712 -313.414918) (xy 42.402296 -313.42977) (xy 42.405094 -313.459788) (xy 42.4053 -313.474862)
			(xy 42.4053 -313.54522) (xy 42.405863 -313.555912) (xy 42.414521 -313.575468) (xy 42.422064 -313.583066)
			(xy 42.48658 -313.640724) (xy 42.5069 -313.647328) (xy 42.517568 -313.646312) (xy 42.549826 -313.644534)
			(xy 42.573817 -313.644982) (xy 42.621206 -313.652492) (xy 42.666838 -313.667324) (xy 42.709587 -313.689111)
			(xy 42.748402 -313.717318) (xy 42.782326 -313.75125) (xy 42.810524 -313.790071) (xy 42.832302 -313.832825)
			(xy 42.847124 -313.87846) (xy 42.854623 -313.925851) (xy 42.855134 -313.949842) (xy 42.85495 -313.964025)
			(xy 42.852282 -313.992265) (xy 42.8498 -314.00623) (xy 42.847514 -314.018676) (xy 42.85488 -314.042298)
			(xy 42.931842 -314.119514) (xy 42.955972 -314.12688) (xy 42.968418 -314.124594) (xy 42.990324 -314.120965)
			(xy 43.034694 -314.119314) (xy 43.05681 -314.121292) (xy 43.057318 -314.121292) (xy 43.084242 -314.125356)
			(xy 43.08475 -314.125356) (xy 43.09364 -314.127134) (xy 43.117262 -314.119768) (xy 43.185842 -314.051442)
			(xy 43.193994 -314.042203) (xy 43.201306 -314.018713) (xy 43.199812 -314.006484) (xy 43.199812 -314.00623)
			(xy 43.197325 -313.992265) (xy 43.194649 -313.964025) (xy 43.194478 -313.949842) (xy 43.194921 -313.925846)
			(xy 43.202422 -313.878445) (xy 43.217247 -313.832801) (xy 43.23903 -313.790038) (xy 43.267235 -313.751209)
			(xy 43.301167 -313.717271) (xy 43.33999 -313.689059) (xy 43.382749 -313.667269) (xy 43.42839 -313.652436)
			(xy 43.47579 -313.644925) (xy 43.499786 -313.644534) (xy 43.531282 -313.646312) (xy 43.53179 -313.646312)
			(xy 43.54241 -313.646827) (xy 43.56261 -313.640263) (xy 43.570906 -313.633612) (xy 43.62704 -313.583066)
			(xy 43.634697 -313.575548) (xy 43.643371 -313.555943) (xy 43.643804 -313.54522) (xy 43.643804 -313.474862)
			(xy 43.644001 -313.459851) (xy 43.646797 -313.429958) (xy 43.649392 -313.415172) (xy 43.649392 -313.414156)
			(xy 43.650408 -313.408568) (xy 43.643296 -313.385962) (xy 43.570398 -313.309762) (xy 43.548046 -313.301634)
			(xy 43.536108 -313.303158) (xy 43.527061 -313.304146) (xy 43.508887 -313.30516) (xy 43.499786 -313.30519)
			(xy 43.474967 -313.304703) (xy 43.425984 -313.296671) (xy 43.378945 -313.280819) (xy 43.33509 -313.257567)
			(xy 43.295575 -313.227526) (xy 43.26144 -313.191489) (xy 43.233585 -313.150403) (xy 43.212744 -313.105353)
			(xy 43.199465 -313.057524) (xy 43.194099 -313.008178) (xy 43.196787 -312.958613) (xy 43.207458 -312.910136)
			(xy 43.225831 -312.864024) (xy 43.251422 -312.821491) (xy 43.283556 -312.783659) (xy 43.321388 -312.751524)
			(xy 43.36392 -312.725932) (xy 43.410032 -312.707559) (xy 43.458509 -312.696887) (xy 43.508074 -312.694199)
			(xy 43.557421 -312.699564) (xy 43.605249 -312.712842) (xy 43.6503 -312.733683) (xy 43.691386 -312.761538)
			(xy 43.727424 -312.795672) (xy 43.757465 -312.835187) (xy 43.780718 -312.879041) (xy 43.79657 -312.92608)
			(xy 43.804603 -312.975063) (xy 43.805094 -312.999882) (xy 43.80499 -313.008923) (xy 43.803846 -313.026969)
			(xy 43.802808 -313.03595) (xy 43.802808 -313.036712) (xy 43.8021 -313.048385) (xy 43.81004 -313.070354)
			(xy 43.818048 -313.078876) (xy 43.885612 -313.143646) (xy 43.908218 -313.150758) (xy 43.913044 -313.149996)
			(xy 43.928264 -313.147266) (xy 43.95905 -313.144336) (xy 43.974512 -313.144154) (xy 43.974766 -313.144154)
			(xy 43.989194 -313.144317) (xy 44.017938 -313.14686) (xy 44.03217 -313.149234) (xy 44.032678 -313.149234)
			(xy 44.04106 -313.150758) (xy 44.063666 -313.143646) (xy 44.14012 -313.071002) (xy 44.148248 -313.048142)
			(xy 44.146724 -313.036458) (xy 44.145671 -313.02735) (xy 44.14453 -313.00905) (xy 44.144438 -312.999882)
			(xy 44.144925 -312.975066) (xy 44.152957 -312.926088) (xy 44.168807 -312.879055) (xy 44.192057 -312.835205)
			(xy 44.222094 -312.795695) (xy 44.258127 -312.761563) (xy 44.299208 -312.733711) (xy 44.344253 -312.712872)
			(xy 44.392076 -312.699594) (xy 44.441417 -312.694227) (xy 44.490976 -312.696914) (xy 44.539448 -312.707582)
			(xy 44.585555 -312.725951) (xy 44.628084 -312.751538) (xy 44.665913 -312.783667) (xy 44.698046 -312.821494)
			(xy 44.723636 -312.86402) (xy 44.74201 -312.910125) (xy 44.752683 -312.958596) (xy 44.755374 -313.008155)
			(xy 44.750012 -313.057497) (xy 44.736738 -313.105321) (xy 44.715903 -313.150368) (xy 44.688054 -313.191451)
			(xy 44.653926 -313.227487) (xy 44.614418 -313.257528) (xy 44.570571 -313.280782) (xy 44.523539 -313.296636)
			(xy 44.474562 -313.304673) (xy 44.449746 -313.30519) (xy 44.440578 -313.305099) (xy 44.422278 -313.303958)
			(xy 44.41317 -313.302904) (xy 44.412916 -313.302904) (xy 44.401114 -313.302092) (xy 44.378866 -313.310044)
			(xy 44.370244 -313.318144) (xy 44.305728 -313.385708) (xy 44.29887 -313.408314) (xy 44.299886 -313.415172)
			(xy 44.302406 -313.429965) (xy 44.305078 -313.459856) (xy 44.30522 -313.474862) (xy 44.30522 -313.54522)
			(xy 44.305783 -313.555912) (xy 44.314444 -313.575466) (xy 44.321984 -313.583066) (xy 44.3865 -313.640724)
			(xy 44.40682 -313.647328) (xy 44.417488 -313.646312) (xy 44.449746 -313.644534) (xy 44.473734 -313.645008)
			(xy 44.521117 -313.65252) (xy 44.566743 -313.667352) (xy 44.609486 -313.689139) (xy 44.648295 -313.717344)
			(xy 44.682213 -313.751272) (xy 44.710407 -313.790089) (xy 44.732182 -313.832839) (xy 44.747 -313.878468)
			(xy 44.754499 -313.925854) (xy 44.755054 -313.949842) (xy 44.75487 -313.964025) (xy 44.752202 -313.992265)
			(xy 44.74972 -314.00623) (xy 44.747434 -314.018676) (xy 44.7548 -314.042298) (xy 44.83227 -314.119768)
			(xy 44.855892 -314.127134) (xy 44.862496 -314.125864) (xy 44.87788 -314.122878) (xy 44.909056 -314.119695)
			(xy 44.924726 -314.119514) (xy 44.939748 -314.11968) (xy 44.969648 -314.122605) (xy 44.984416 -314.125356)
			(xy 44.984924 -314.125356) (xy 44.993814 -314.127134) (xy 45.017436 -314.119768) (xy 45.086016 -314.051442)
			(xy 45.094171 -314.042204) (xy 45.101488 -314.018713) (xy 45.099986 -314.006484) (xy 45.099986 -314.00623)
			(xy 45.097499 -313.992265) (xy 45.094823 -313.964025) (xy 45.094652 -313.949842) (xy 45.095095 -313.925846)
			(xy 45.102596 -313.878443) (xy 45.117421 -313.832797) (xy 45.139203 -313.790032) (xy 45.167407 -313.751201)
			(xy 45.201339 -313.717261) (xy 45.240162 -313.689046) (xy 45.282921 -313.667252) (xy 45.328563 -313.652415)
			(xy 45.375964 -313.644901) (xy 45.39996 -313.644534) (xy 45.43171 -313.646058) (xy 45.442124 -313.647328)
			(xy 45.462952 -313.640724) (xy 45.52696 -313.583066) (xy 45.534615 -313.575547) (xy 45.543285 -313.555942)
			(xy 45.543724 -313.54522) (xy 45.543724 -313.474862) (xy 45.543921 -313.459851) (xy 45.546718 -313.429958)
			(xy 45.549312 -313.415172) (xy 45.549312 -313.414156) (xy 45.550328 -313.408568) (xy 45.543216 -313.385962)
			(xy 45.470318 -313.309762) (xy 45.447966 -313.301634) (xy 45.436028 -313.303158) (xy 45.427044 -313.304141)
			(xy 45.408998 -313.305158) (xy 45.39996 -313.30519) (xy 45.375142 -313.304701) (xy 45.32616 -313.296665)
			(xy 45.279123 -313.28081) (xy 45.235271 -313.257555) (xy 45.195759 -313.227512) (xy 45.161627 -313.191472)
			(xy 45.133775 -313.150386) (xy 45.112937 -313.105335) (xy 45.099662 -313.057506) (xy 45.094299 -313.00816)
			(xy 45.096989 -312.958596) (xy 45.107662 -312.910121) (xy 45.126037 -312.86401) (xy 45.15163 -312.82148)
			(xy 45.183765 -312.78365) (xy 45.221598 -312.751517) (xy 45.26413 -312.725927) (xy 45.310242 -312.707556)
			(xy 45.358718 -312.696886) (xy 45.408282 -312.694199) (xy 45.457628 -312.699566) (xy 45.505456 -312.712845)
			(xy 45.550505 -312.733686) (xy 45.591589 -312.761541) (xy 45.627626 -312.795675) (xy 45.657667 -312.83519)
			(xy 45.680919 -312.879043) (xy 45.69677 -312.926081) (xy 45.704803 -312.975064) (xy 45.705268 -312.999882)
			(xy 45.705164 -313.008923) (xy 45.70402 -313.026969) (xy 45.702982 -313.03595) (xy 45.702982 -313.036458)
			(xy 45.701712 -313.048142) (xy 45.70984 -313.070494) (xy 45.785786 -313.143392) (xy 45.808646 -313.150504)
			(xy 45.820584 -313.148472) (xy 45.833951 -313.146425) (xy 45.860909 -313.144265) (xy 45.874432 -313.144154)
			(xy 45.88886 -313.144315) (xy 45.917604 -313.146855) (xy 45.931836 -313.149234) (xy 45.932598 -313.149234)
			(xy 45.941234 -313.150758) (xy 45.96384 -313.143646) (xy 46.040294 -313.071002) (xy 46.048422 -313.048142)
			(xy 46.046898 -313.036458) (xy 46.045845 -313.02735) (xy 46.044704 -313.00905) (xy 46.044612 -312.999882)
			(xy 46.045099 -312.975063) (xy 46.053132 -312.926081) (xy 46.068984 -312.879043) (xy 46.092236 -312.835189)
			(xy 46.122277 -312.795674) (xy 46.158315 -312.76154) (xy 46.1994 -312.733686) (xy 46.24445 -312.712845)
			(xy 46.292278 -312.699567) (xy 46.341624 -312.694201) (xy 46.391189 -312.696889) (xy 46.439665 -312.70756)
			(xy 46.485777 -312.725933) (xy 46.528309 -312.751524) (xy 46.56614 -312.783658) (xy 46.598275 -312.82149)
			(xy 46.623866 -312.864021) (xy 46.642239 -312.910133) (xy 46.652911 -312.958609) (xy 46.655599 -313.008174)
			(xy 46.650234 -313.05752) (xy 46.636956 -313.105348) (xy 46.616115 -313.150398) (xy 46.588261 -313.191484)
			(xy 46.554127 -313.227522) (xy 46.514613 -313.257563) (xy 46.470759 -313.280815) (xy 46.423721 -313.296667)
			(xy 46.374739 -313.304701) (xy 46.34992 -313.30519) (xy 46.340689 -313.305104) (xy 46.322261 -313.303959)
			(xy 46.31309 -313.302904) (xy 46.301152 -313.30138) (xy 46.2788 -313.309508) (xy 46.205648 -313.385708)
			(xy 46.19879 -313.408314) (xy 46.199806 -313.415172) (xy 46.202326 -313.429965) (xy 46.204998 -313.459856)
			(xy 46.20514 -313.474862) (xy 46.20514 -313.54522) (xy 46.205704 -313.555911) (xy 46.214367 -313.575463)
			(xy 46.221904 -313.583066) (xy 46.28642 -313.640724) (xy 46.30674 -313.647328) (xy 46.317408 -313.646312)
			(xy 46.34992 -313.644534) (xy 46.373911 -313.644982) (xy 46.421302 -313.652491) (xy 46.466934 -313.667322)
			(xy 46.509684 -313.689109) (xy 46.5485 -313.717316) (xy 46.582425 -313.751248) (xy 46.610623 -313.790069)
			(xy 46.632402 -313.832824) (xy 46.647223 -313.878459) (xy 46.654723 -313.925851) (xy 46.655228 -313.949842)
			(xy 46.655044 -313.964025) (xy 46.652376 -313.992265) (xy 46.649894 -314.00623) (xy 46.647608 -314.018676)
			(xy 46.654974 -314.042298) (xy 46.731936 -314.119514) (xy 46.756066 -314.12688) (xy 46.768512 -314.124594)
			(xy 46.782421 -314.122195) (xy 46.810532 -314.119649) (xy 46.824646 -314.119514) (xy 46.839667 -314.119681)
			(xy 46.869567 -314.122608) (xy 46.884336 -314.125356) (xy 46.884844 -314.125356) (xy 46.893734 -314.127134)
			(xy 46.917356 -314.119768) (xy 46.985936 -314.051442) (xy 46.994089 -314.042203) (xy 47.001402 -314.018713)
			(xy 46.999906 -314.006484) (xy 46.999906 -314.00623) (xy 46.997419 -313.992265) (xy 46.994743 -313.964025)
			(xy 46.994572 -313.949842) (xy 46.995015 -313.925846) (xy 47.002516 -313.878444) (xy 47.017341 -313.8328)
			(xy 47.039124 -313.790036) (xy 47.067328 -313.751207) (xy 47.10126 -313.717269) (xy 47.140083 -313.689056)
			(xy 47.182842 -313.667265) (xy 47.228484 -313.652431) (xy 47.275884 -313.64492) (xy 47.29988 -313.644534)
			(xy 47.33163 -313.646058) (xy 47.342044 -313.647328) (xy 47.362872 -313.640724) (xy 47.42688 -313.583066)
			(xy 47.434532 -313.575546) (xy 47.443199 -313.555941) (xy 47.443644 -313.54522) (xy 47.443644 -313.474862)
			(xy 47.44384 -313.459851) (xy 47.446637 -313.429958) (xy 47.449232 -313.415172) (xy 47.449232 -313.414156)
			(xy 47.450248 -313.408568) (xy 47.443136 -313.385962) (xy 47.370238 -313.309762) (xy 47.347886 -313.301634)
			(xy 47.335948 -313.303158) (xy 47.326964 -313.304141) (xy 47.308918 -313.305159) (xy 47.29988 -313.30519)
			(xy 47.275061 -313.304703) (xy 47.226078 -313.296669) (xy 47.17904 -313.280817) (xy 47.135186 -313.257564)
			(xy 47.095671 -313.227523) (xy 47.061537 -313.191485) (xy 47.033683 -313.150399) (xy 47.012842 -313.105349)
			(xy 46.999564 -313.05752) (xy 46.994199 -313.008174) (xy 46.996887 -312.958609) (xy 47.007559 -312.910132)
			(xy 47.025932 -312.86402) (xy 47.051523 -312.821488) (xy 47.083658 -312.783657) (xy 47.12149 -312.751522)
			(xy 47.164022 -312.725931) (xy 47.210134 -312.707558) (xy 47.258611 -312.696887) (xy 47.308176 -312.694199)
			(xy 47.357522 -312.699565) (xy 47.405351 -312.712843) (xy 47.450401 -312.733684) (xy 47.491486 -312.761538)
			(xy 47.527524 -312.795673) (xy 47.557565 -312.835188) (xy 47.580818 -312.879042) (xy 47.59667 -312.92608)
			(xy 47.604703 -312.975063) (xy 47.605188 -312.999882) (xy 47.605084 -313.008923) (xy 47.60394 -313.026969)
			(xy 47.602902 -313.03595) (xy 47.602902 -313.036458) (xy 47.601632 -313.048142) (xy 47.60976 -313.070494)
			(xy 47.685706 -313.143392) (xy 47.708566 -313.150504) (xy 47.720504 -313.148472) (xy 47.733871 -313.146426)
			(xy 47.760829 -313.144267) (xy 47.774352 -313.144154) (xy 47.78878 -313.144316) (xy 47.817524 -313.146858)
			(xy 47.831756 -313.149234) (xy 47.832518 -313.149234) (xy 47.841154 -313.150758) (xy 47.86376 -313.143646)
			(xy 47.940214 -313.071002) (xy 47.948342 -313.048142) (xy 47.946818 -313.036458) (xy 47.945765 -313.02735)
			(xy 47.944624 -313.00905) (xy 47.944532 -312.999882) (xy 47.945019 -312.975065) (xy 47.953051 -312.926086)
			(xy 47.968902 -312.879052) (xy 47.992152 -312.835201) (xy 48.02219 -312.79569) (xy 48.058224 -312.761558)
			(xy 48.099306 -312.733705) (xy 48.144352 -312.712865) (xy 48.192176 -312.699587) (xy 48.241518 -312.694221)
			(xy 48.291079 -312.696908) (xy 48.339552 -312.707577) (xy 48.38566 -312.725947) (xy 48.428189 -312.751535)
			(xy 48.466019 -312.783665) (xy 48.498152 -312.821493) (xy 48.523743 -312.86402) (xy 48.542117 -312.910127)
			(xy 48.552789 -312.958599) (xy 48.555479 -313.00816) (xy 48.550117 -313.057502) (xy 48.536842 -313.105327)
			(xy 48.516006 -313.150375) (xy 48.488156 -313.191458) (xy 48.454027 -313.227495) (xy 48.414517 -313.257536)
			(xy 48.370668 -313.28079) (xy 48.323635 -313.296643) (xy 48.274657 -313.304679) (xy 48.24984 -313.30519)
			(xy 48.240609 -313.305104) (xy 48.222181 -313.303961) (xy 48.21301 -313.302904) (xy 48.201072 -313.30138)
			(xy 48.17872 -313.309508) (xy 48.105568 -313.385708) (xy 48.09871 -313.408314) (xy 48.099726 -313.415172)
			(xy 48.102247 -313.429965) (xy 48.104919 -313.459856) (xy 48.10506 -313.474862) (xy 48.10506 -313.54522)
			(xy 48.105624 -313.555911) (xy 48.11429 -313.57546) (xy 48.121824 -313.583066) (xy 48.18634 -313.640724)
			(xy 48.20666 -313.647328) (xy 48.217328 -313.646312) (xy 48.24984 -313.644534) (xy 48.27383 -313.644983)
			(xy 48.321218 -313.652495) (xy 48.366848 -313.667328) (xy 48.409595 -313.689116) (xy 48.448408 -313.717323)
			(xy 48.48233 -313.751254) (xy 48.510527 -313.790075) (xy 48.532304 -313.832828) (xy 48.547124 -313.878462)
			(xy 48.554623 -313.925852) (xy 48.555148 -313.949842) (xy 48.554964 -313.964025) (xy 48.552296 -313.992265)
			(xy 48.549814 -314.00623) (xy 48.547528 -314.018676) (xy 48.554894 -314.042298) (xy 48.631856 -314.119514)
			(xy 48.655986 -314.12688) (xy 48.668432 -314.124594) (xy 48.690337 -314.120959) (xy 48.734709 -314.119296)
			(xy 48.756824 -314.121292) (xy 48.757332 -314.121292) (xy 48.784256 -314.125356) (xy 48.784764 -314.125356)
			(xy 48.793654 -314.127134) (xy 48.817276 -314.119768) (xy 48.885856 -314.051442) (xy 48.894006 -314.042202)
			(xy 48.901316 -314.018713) (xy 48.899826 -314.006484) (xy 48.899826 -314.00623) (xy 48.897339 -313.992265)
			(xy 48.894663 -313.964025) (xy 48.894492 -313.949842) (xy 48.894935 -313.925847) (xy 48.902437 -313.878446)
			(xy 48.917261 -313.832803) (xy 48.939045 -313.790041) (xy 48.967249 -313.751213) (xy 49.001181 -313.717277)
			(xy 49.040005 -313.689066) (xy 49.082764 -313.667278) (xy 49.128405 -313.652446) (xy 49.175805 -313.644938)
			(xy 49.1998 -313.644534) (xy 49.23155 -313.646058) (xy 49.241964 -313.647328) (xy 49.262792 -313.640724)
			(xy 49.3268 -313.583066) (xy 49.33445 -313.575545) (xy 49.343113 -313.55594) (xy 49.343564 -313.54522)
			(xy 49.343564 -313.474862) (xy 49.343754 -313.459788) (xy 49.346557 -313.429769) (xy 49.349152 -313.414918)
			(xy 49.349152 -313.413902) (xy 49.350168 -313.408568) (xy 49.343056 -313.385962) (xy 49.270158 -313.309762)
			(xy 49.247806 -313.301634) (xy 49.235868 -313.303158) (xy 49.226884 -313.304142) (xy 49.208838 -313.305161)
			(xy 49.1998 -313.30519) (xy 49.174981 -313.304704) (xy 49.125997 -313.296674) (xy 49.078957 -313.280824)
			(xy 49.035101 -313.257574) (xy 48.995584 -313.227534) (xy 48.961447 -313.191498) (xy 48.933591 -313.150413)
			(xy 48.912747 -313.105363) (xy 48.899467 -313.057534) (xy 48.894099 -313.008187) (xy 48.896786 -312.958622)
			(xy 48.907455 -312.910144) (xy 48.925827 -312.864031) (xy 48.951417 -312.821497) (xy 48.983551 -312.783664)
			(xy 49.021383 -312.751528) (xy 49.063915 -312.725935) (xy 49.110027 -312.707561) (xy 49.158504 -312.696888)
			(xy 49.208069 -312.694199) (xy 49.257417 -312.699564) (xy 49.305246 -312.712841) (xy 49.350297 -312.733682)
			(xy 49.391384 -312.761536) (xy 49.427422 -312.79567) (xy 49.457464 -312.835186) (xy 49.480717 -312.87904)
			(xy 49.496569 -312.926079) (xy 49.504603 -312.975063) (xy 49.505108 -312.999882) (xy 49.505069 -313.008983)
			(xy 49.504054 -313.027156) (xy 49.503076 -313.036204) (xy 49.501552 -313.048142) (xy 49.50968 -313.070494)
			(xy 49.585626 -313.143392) (xy 49.608232 -313.150504) (xy 49.612804 -313.149742) (xy 49.628088 -313.147006)
			(xy 49.659 -313.144078) (xy 49.674526 -313.1439) (xy 49.675288 -313.1439) (xy 49.689652 -313.14407)
			(xy 49.718269 -313.146613) (xy 49.732438 -313.14898) (xy 49.732946 -313.14898) (xy 49.741074 -313.15025)
			(xy 49.76368 -313.143392) (xy 49.831244 -313.078622) (xy 49.839332 -313.070135) (xy 49.847429 -313.04816)
			(xy 49.846738 -313.036458) (xy 49.846738 -313.036204) (xy 49.84569 -313.02716) (xy 49.844548 -313.008986)
			(xy 49.844452 -312.999882) (xy 49.84494 -312.975058) (xy 49.852975 -312.926063) (xy 49.868831 -312.879014)
			(xy 49.89209 -312.83515) (xy 49.922139 -312.795627) (xy 49.958186 -312.761486) (xy 49.999282 -312.733627)
			(xy 50.044344 -312.712783) (xy 50.092184 -312.699504) (xy 50.141542 -312.69414) (xy 50.191118 -312.696833)
			(xy 50.239606 -312.70751) (xy 50.285727 -312.725891) (xy 50.328266 -312.751491) (xy 50.366104 -312.783637)
			(xy 50.398242 -312.821481) (xy 50.423835 -312.864025) (xy 50.442207 -312.91015) (xy 50.452875 -312.958639)
			(xy 50.455107 -312.999882) (xy 50.79417 -312.999882) (xy 50.79813 -312.950828) (xy 50.809907 -312.903044)
			(xy 50.829198 -312.857768) (xy 50.855501 -312.816172) (xy 50.888136 -312.779335) (xy 50.926257 -312.74821)
			(xy 50.968878 -312.723603) (xy 51.014894 -312.706151) (xy 51.063113 -312.696307) (xy 51.112288 -312.694326)
			(xy 51.161143 -312.700258) (xy 51.208414 -312.71395) (xy 51.252876 -312.735048) (xy 51.293379 -312.763004)
			(xy 51.328872 -312.797096) (xy 51.358437 -312.83644) (xy 51.381308 -312.880017) (xy 51.396892 -312.926698)
			(xy 51.404787 -312.975275) (xy 51.405282 -312.999882) (xy 51.74413 -312.999882) (xy 51.74809 -312.950828)
			(xy 51.759867 -312.903044) (xy 51.779158 -312.857768) (xy 51.805461 -312.816172) (xy 51.838096 -312.779335)
			(xy 51.876217 -312.74821) (xy 51.918838 -312.723603) (xy 51.964854 -312.706151) (xy 52.013073 -312.696307)
			(xy 52.062248 -312.694326) (xy 52.111103 -312.700258) (xy 52.158374 -312.71395) (xy 52.202836 -312.735048)
			(xy 52.243339 -312.763004) (xy 52.278832 -312.797096) (xy 52.308397 -312.83644) (xy 52.331268 -312.880017)
			(xy 52.346852 -312.926698) (xy 52.354747 -312.975275) (xy 52.355242 -312.999882) (xy 52.69409 -312.999882)
			(xy 52.69805 -312.950828) (xy 52.709827 -312.903044) (xy 52.729118 -312.857768) (xy 52.755421 -312.816172)
			(xy 52.788056 -312.779335) (xy 52.826177 -312.74821) (xy 52.868798 -312.723603) (xy 52.914814 -312.706151)
			(xy 52.963033 -312.696307) (xy 53.012208 -312.694326) (xy 53.061063 -312.700258) (xy 53.108334 -312.71395)
			(xy 53.152796 -312.735048) (xy 53.193299 -312.763004) (xy 53.228792 -312.797096) (xy 53.258357 -312.83644)
			(xy 53.281228 -312.880017) (xy 53.296812 -312.926698) (xy 53.304707 -312.975275) (xy 53.305202 -312.999882)
			(xy 53.64405 -312.999882) (xy 53.64801 -312.950828) (xy 53.659787 -312.903044) (xy 53.679078 -312.857768)
			(xy 53.705381 -312.816172) (xy 53.738016 -312.779335) (xy 53.776137 -312.74821) (xy 53.818758 -312.723603)
			(xy 53.864774 -312.706151) (xy 53.912993 -312.696307) (xy 53.962168 -312.694326) (xy 54.011023 -312.700258)
			(xy 54.058294 -312.71395) (xy 54.102756 -312.735048) (xy 54.143259 -312.763004) (xy 54.178752 -312.797096)
			(xy 54.208317 -312.83644) (xy 54.231188 -312.880017) (xy 54.246772 -312.926698) (xy 54.254667 -312.975275)
			(xy 54.255162 -312.999882) (xy 54.59401 -312.999882) (xy 54.59797 -312.950828) (xy 54.609747 -312.903044)
			(xy 54.629038 -312.857768) (xy 54.655341 -312.816172) (xy 54.687976 -312.779335) (xy 54.726097 -312.74821)
			(xy 54.768718 -312.723603) (xy 54.814734 -312.706151) (xy 54.862953 -312.696307) (xy 54.912128 -312.694326)
			(xy 54.960983 -312.700258) (xy 55.008254 -312.71395) (xy 55.052716 -312.735048) (xy 55.093219 -312.763004)
			(xy 55.128712 -312.797096) (xy 55.158277 -312.83644) (xy 55.181148 -312.880017) (xy 55.196732 -312.926698)
			(xy 55.204627 -312.975275) (xy 55.205122 -312.999882) (xy 55.54397 -312.999882) (xy 55.54793 -312.950828)
			(xy 55.559707 -312.903044) (xy 55.578998 -312.857768) (xy 55.605301 -312.816172) (xy 55.637936 -312.779335)
			(xy 55.676057 -312.74821) (xy 55.718678 -312.723603) (xy 55.764694 -312.706151) (xy 55.812913 -312.696307)
			(xy 55.862088 -312.694326) (xy 55.910943 -312.700258) (xy 55.958214 -312.71395) (xy 56.002676 -312.735048)
			(xy 56.043179 -312.763004) (xy 56.078672 -312.797096) (xy 56.108237 -312.83644) (xy 56.131108 -312.880017)
			(xy 56.146692 -312.926698) (xy 56.154587 -312.975275) (xy 56.155082 -312.999882) (xy 56.154587 -313.024489)
			(xy 56.146692 -313.073066) (xy 56.131108 -313.119747) (xy 56.108237 -313.163324) (xy 56.078672 -313.202668)
			(xy 56.043179 -313.23676) (xy 56.002676 -313.264716) (xy 55.958214 -313.285814) (xy 55.910943 -313.299506)
			(xy 55.862088 -313.305438) (xy 55.812913 -313.303457) (xy 55.764694 -313.293613) (xy 55.718678 -313.276161)
			(xy 55.676057 -313.251554) (xy 55.637936 -313.220429) (xy 55.605301 -313.183592) (xy 55.578998 -313.141996)
			(xy 55.559707 -313.09672) (xy 55.54793 -313.048936) (xy 55.54397 -312.999882) (xy 55.205122 -312.999882)
			(xy 55.204627 -313.024489) (xy 55.196732 -313.073066) (xy 55.181148 -313.119747) (xy 55.158277 -313.163324)
			(xy 55.128712 -313.202668) (xy 55.093219 -313.23676) (xy 55.052716 -313.264716) (xy 55.008254 -313.285814)
			(xy 54.960983 -313.299506) (xy 54.912128 -313.305438) (xy 54.862953 -313.303457) (xy 54.814734 -313.293613)
			(xy 54.768718 -313.276161) (xy 54.726097 -313.251554) (xy 54.687976 -313.220429) (xy 54.655341 -313.183592)
			(xy 54.629038 -313.141996) (xy 54.609747 -313.09672) (xy 54.59797 -313.048936) (xy 54.59401 -312.999882)
			(xy 54.255162 -312.999882) (xy 54.254667 -313.024489) (xy 54.246772 -313.073066) (xy 54.231188 -313.119747)
			(xy 54.208317 -313.163324) (xy 54.178752 -313.202668) (xy 54.143259 -313.23676) (xy 54.102756 -313.264716)
			(xy 54.058294 -313.285814) (xy 54.011023 -313.299506) (xy 53.962168 -313.305438) (xy 53.912993 -313.303457)
			(xy 53.864774 -313.293613) (xy 53.818758 -313.276161) (xy 53.776137 -313.251554) (xy 53.738016 -313.220429)
			(xy 53.705381 -313.183592) (xy 53.679078 -313.141996) (xy 53.659787 -313.09672) (xy 53.64801 -313.048936)
			(xy 53.64405 -312.999882) (xy 53.305202 -312.999882) (xy 53.304707 -313.024489) (xy 53.296812 -313.073066)
			(xy 53.281228 -313.119747) (xy 53.258357 -313.163324) (xy 53.228792 -313.202668) (xy 53.193299 -313.23676)
			(xy 53.152796 -313.264716) (xy 53.108334 -313.285814) (xy 53.061063 -313.299506) (xy 53.012208 -313.305438)
			(xy 52.963033 -313.303457) (xy 52.914814 -313.293613) (xy 52.868798 -313.276161) (xy 52.826177 -313.251554)
			(xy 52.788056 -313.220429) (xy 52.755421 -313.183592) (xy 52.729118 -313.141996) (xy 52.709827 -313.09672)
			(xy 52.69805 -313.048936) (xy 52.69409 -312.999882) (xy 52.355242 -312.999882) (xy 52.354747 -313.024489)
			(xy 52.346852 -313.073066) (xy 52.331268 -313.119747) (xy 52.308397 -313.163324) (xy 52.278832 -313.202668)
			(xy 52.243339 -313.23676) (xy 52.202836 -313.264716) (xy 52.158374 -313.285814) (xy 52.111103 -313.299506)
			(xy 52.062248 -313.305438) (xy 52.013073 -313.303457) (xy 51.964854 -313.293613) (xy 51.918838 -313.276161)
			(xy 51.876217 -313.251554) (xy 51.838096 -313.220429) (xy 51.805461 -313.183592) (xy 51.779158 -313.141996)
			(xy 51.759867 -313.09672) (xy 51.74809 -313.048936) (xy 51.74413 -312.999882) (xy 51.405282 -312.999882)
			(xy 51.404787 -313.024489) (xy 51.396892 -313.073066) (xy 51.381308 -313.119747) (xy 51.358437 -313.163324)
			(xy 51.328872 -313.202668) (xy 51.293379 -313.23676) (xy 51.252876 -313.264716) (xy 51.208414 -313.285814)
			(xy 51.161143 -313.299506) (xy 51.112288 -313.305438) (xy 51.063113 -313.303457) (xy 51.014894 -313.293613)
			(xy 50.968878 -313.276161) (xy 50.926257 -313.251554) (xy 50.888136 -313.220429) (xy 50.855501 -313.183592)
			(xy 50.829198 -313.141996) (xy 50.809907 -313.09672) (xy 50.79813 -313.048936) (xy 50.79417 -312.999882)
			(xy 50.455107 -312.999882) (xy 50.455558 -313.008216) (xy 50.450185 -313.057573) (xy 50.436897 -313.105411)
			(xy 50.416045 -313.150469) (xy 50.388177 -313.191559) (xy 50.35403 -313.2276) (xy 50.314501 -313.257642)
			(xy 50.270632 -313.280892) (xy 50.22358 -313.296739) (xy 50.174585 -313.304765) (xy 50.14976 -313.30519)
			(xy 50.140656 -313.305092) (xy 50.122483 -313.303949) (xy 50.113438 -313.302904) (xy 50.113184 -313.302904)
			(xy 50.101376 -313.302076) (xy 50.079106 -313.310008) (xy 50.070512 -313.318144) (xy 50.005996 -313.385708)
			(xy 49.998884 -313.408314) (xy 49.9999 -313.414918) (xy 50.002483 -313.42977) (xy 50.005281 -313.459788)
			(xy 50.005488 -313.474862) (xy 50.005488 -313.54522) (xy 50.00605 -313.555912) (xy 50.014707 -313.57547)
			(xy 50.022252 -313.583066) (xy 50.078386 -313.633612) (xy 50.086607 -313.640395) (xy 50.106863 -313.646964)
			(xy 50.117502 -313.646312) (xy 50.117756 -313.646312) (xy 50.14976 -313.644534) (xy 50.175016 -313.645023)
			(xy 50.224841 -313.653332) (xy 50.272619 -313.669728) (xy 50.317045 -313.693766) (xy 50.356909 -313.724788)
			(xy 50.391123 -313.761949) (xy 50.418753 -313.804236) (xy 50.439045 -313.850493) (xy 50.451446 -313.89946)
			(xy 50.455618 -313.9498) (xy 50.455615 -313.949842) (xy 50.79417 -313.949842) (xy 50.79813 -313.900788)
			(xy 50.809907 -313.853004) (xy 50.829198 -313.807728) (xy 50.855501 -313.766132) (xy 50.888136 -313.729295)
			(xy 50.926257 -313.69817) (xy 50.968878 -313.673563) (xy 51.014894 -313.656111) (xy 51.063113 -313.646267)
			(xy 51.112288 -313.644286) (xy 51.161143 -313.650218) (xy 51.208414 -313.66391) (xy 51.252876 -313.685008)
			(xy 51.293379 -313.712964) (xy 51.328872 -313.747056) (xy 51.358437 -313.7864) (xy 51.381308 -313.829977)
			(xy 51.396892 -313.876658) (xy 51.404787 -313.925235) (xy 51.405282 -313.949842) (xy 51.74413 -313.949842)
			(xy 51.74809 -313.900788) (xy 51.759867 -313.853004) (xy 51.779158 -313.807728) (xy 51.805461 -313.766132)
			(xy 51.838096 -313.729295) (xy 51.876217 -313.69817) (xy 51.918838 -313.673563) (xy 51.964854 -313.656111)
			(xy 52.013073 -313.646267) (xy 52.062248 -313.644286) (xy 52.111103 -313.650218) (xy 52.158374 -313.66391)
			(xy 52.202836 -313.685008) (xy 52.243339 -313.712964) (xy 52.278832 -313.747056) (xy 52.308397 -313.7864)
			(xy 52.331268 -313.829977) (xy 52.346852 -313.876658) (xy 52.354747 -313.925235) (xy 52.355242 -313.949842)
			(xy 52.69409 -313.949842) (xy 52.69805 -313.900788) (xy 52.709827 -313.853004) (xy 52.729118 -313.807728)
			(xy 52.755421 -313.766132) (xy 52.788056 -313.729295) (xy 52.826177 -313.69817) (xy 52.868798 -313.673563)
			(xy 52.914814 -313.656111) (xy 52.963033 -313.646267) (xy 53.012208 -313.644286) (xy 53.061063 -313.650218)
			(xy 53.108334 -313.66391) (xy 53.152796 -313.685008) (xy 53.193299 -313.712964) (xy 53.228792 -313.747056)
			(xy 53.258357 -313.7864) (xy 53.281228 -313.829977) (xy 53.296812 -313.876658) (xy 53.304707 -313.925235)
			(xy 53.305202 -313.949842) (xy 53.64405 -313.949842) (xy 53.64801 -313.900788) (xy 53.659787 -313.853004)
			(xy 53.679078 -313.807728) (xy 53.705381 -313.766132) (xy 53.738016 -313.729295) (xy 53.776137 -313.69817)
			(xy 53.818758 -313.673563) (xy 53.864774 -313.656111) (xy 53.912993 -313.646267) (xy 53.962168 -313.644286)
			(xy 54.011023 -313.650218) (xy 54.058294 -313.66391) (xy 54.102756 -313.685008) (xy 54.143259 -313.712964)
			(xy 54.178752 -313.747056) (xy 54.208317 -313.7864) (xy 54.231188 -313.829977) (xy 54.246772 -313.876658)
			(xy 54.254667 -313.925235) (xy 54.255162 -313.949842) (xy 54.59401 -313.949842) (xy 54.59797 -313.900788)
			(xy 54.609747 -313.853004) (xy 54.629038 -313.807728) (xy 54.655341 -313.766132) (xy 54.687976 -313.729295)
			(xy 54.726097 -313.69817) (xy 54.768718 -313.673563) (xy 54.814734 -313.656111) (xy 54.862953 -313.646267)
			(xy 54.912128 -313.644286) (xy 54.960983 -313.650218) (xy 55.008254 -313.66391) (xy 55.052716 -313.685008)
			(xy 55.093219 -313.712964) (xy 55.128712 -313.747056) (xy 55.158277 -313.7864) (xy 55.181148 -313.829977)
			(xy 55.196732 -313.876658) (xy 55.204627 -313.925235) (xy 55.205122 -313.949842) (xy 55.54397 -313.949842)
			(xy 55.54793 -313.900788) (xy 55.559707 -313.853004) (xy 55.578998 -313.807728) (xy 55.605301 -313.766132)
			(xy 55.637936 -313.729295) (xy 55.676057 -313.69817) (xy 55.718678 -313.673563) (xy 55.764694 -313.656111)
			(xy 55.812913 -313.646267) (xy 55.862088 -313.644286) (xy 55.910943 -313.650218) (xy 55.958214 -313.66391)
			(xy 56.002676 -313.685008) (xy 56.043179 -313.712964) (xy 56.078672 -313.747056) (xy 56.108237 -313.7864)
			(xy 56.131108 -313.829977) (xy 56.146692 -313.876658) (xy 56.154587 -313.925235) (xy 56.155082 -313.949842)
			(xy 56.154587 -313.974449) (xy 56.146692 -314.023026) (xy 56.131108 -314.069707) (xy 56.108237 -314.113284)
			(xy 56.078672 -314.152628) (xy 56.043179 -314.18672) (xy 56.002676 -314.214676) (xy 55.958214 -314.235774)
			(xy 55.910943 -314.249466) (xy 55.862088 -314.255398) (xy 55.812913 -314.253417) (xy 55.764694 -314.243573)
			(xy 55.718678 -314.226121) (xy 55.676057 -314.201514) (xy 55.637936 -314.170389) (xy 55.605301 -314.133552)
			(xy 55.578998 -314.091956) (xy 55.559707 -314.04668) (xy 55.54793 -313.998896) (xy 55.54397 -313.949842)
			(xy 55.205122 -313.949842) (xy 55.204627 -313.974449) (xy 55.196732 -314.023026) (xy 55.181148 -314.069707)
			(xy 55.158277 -314.113284) (xy 55.128712 -314.152628) (xy 55.093219 -314.18672) (xy 55.052716 -314.214676)
			(xy 55.008254 -314.235774) (xy 54.960983 -314.249466) (xy 54.912128 -314.255398) (xy 54.862953 -314.253417)
			(xy 54.814734 -314.243573) (xy 54.768718 -314.226121) (xy 54.726097 -314.201514) (xy 54.687976 -314.170389)
			(xy 54.655341 -314.133552) (xy 54.629038 -314.091956) (xy 54.609747 -314.04668) (xy 54.59797 -313.998896)
			(xy 54.59401 -313.949842) (xy 54.255162 -313.949842) (xy 54.254667 -313.974449) (xy 54.246772 -314.023026)
			(xy 54.231188 -314.069707) (xy 54.208317 -314.113284) (xy 54.178752 -314.152628) (xy 54.143259 -314.18672)
			(xy 54.102756 -314.214676) (xy 54.058294 -314.235774) (xy 54.011023 -314.249466) (xy 53.962168 -314.255398)
			(xy 53.912993 -314.253417) (xy 53.864774 -314.243573) (xy 53.818758 -314.226121) (xy 53.776137 -314.201514)
			(xy 53.738016 -314.170389) (xy 53.705381 -314.133552) (xy 53.679078 -314.091956) (xy 53.659787 -314.04668)
			(xy 53.64801 -313.998896) (xy 53.64405 -313.949842) (xy 53.305202 -313.949842) (xy 53.304707 -313.974449)
			(xy 53.296812 -314.023026) (xy 53.281228 -314.069707) (xy 53.258357 -314.113284) (xy 53.228792 -314.152628)
			(xy 53.193299 -314.18672) (xy 53.152796 -314.214676) (xy 53.108334 -314.235774) (xy 53.061063 -314.249466)
			(xy 53.012208 -314.255398) (xy 52.963033 -314.253417) (xy 52.914814 -314.243573) (xy 52.868798 -314.226121)
			(xy 52.826177 -314.201514) (xy 52.788056 -314.170389) (xy 52.755421 -314.133552) (xy 52.729118 -314.091956)
			(xy 52.709827 -314.04668) (xy 52.69805 -313.998896) (xy 52.69409 -313.949842) (xy 52.355242 -313.949842)
			(xy 52.354747 -313.974449) (xy 52.346852 -314.023026) (xy 52.331268 -314.069707) (xy 52.308397 -314.113284)
			(xy 52.278832 -314.152628) (xy 52.243339 -314.18672) (xy 52.202836 -314.214676) (xy 52.158374 -314.235774)
			(xy 52.111103 -314.249466) (xy 52.062248 -314.255398) (xy 52.013073 -314.253417) (xy 51.964854 -314.243573)
			(xy 51.918838 -314.226121) (xy 51.876217 -314.201514) (xy 51.838096 -314.170389) (xy 51.805461 -314.133552)
			(xy 51.779158 -314.091956) (xy 51.759867 -314.04668) (xy 51.74809 -313.998896) (xy 51.74413 -313.949842)
			(xy 51.405282 -313.949842) (xy 51.404787 -313.974449) (xy 51.396892 -314.023026) (xy 51.381308 -314.069707)
			(xy 51.358437 -314.113284) (xy 51.328872 -314.152628) (xy 51.293379 -314.18672) (xy 51.252876 -314.214676)
			(xy 51.208414 -314.235774) (xy 51.161143 -314.249466) (xy 51.112288 -314.255398) (xy 51.063113 -314.253417)
			(xy 51.014894 -314.243573) (xy 50.968878 -314.226121) (xy 50.926257 -314.201514) (xy 50.888136 -314.170389)
			(xy 50.855501 -314.133552) (xy 50.829198 -314.091956) (xy 50.809907 -314.04668) (xy 50.79813 -313.998896)
			(xy 50.79417 -313.949842) (xy 50.455615 -313.949842) (xy 50.451446 -314.00014) (xy 50.439045 -314.049107)
			(xy 50.418753 -314.095364) (xy 50.391123 -314.137651) (xy 50.356909 -314.174812) (xy 50.317045 -314.205834)
			(xy 50.272619 -314.229872) (xy 50.224841 -314.246268) (xy 50.175016 -314.254577) (xy 50.14976 -314.25515)
			(xy 50.11801 -314.253372) (xy 50.117502 -314.253372) (xy 50.106882 -314.252859) (xy 50.086684 -314.259423)
			(xy 50.078386 -314.266072) (xy 50.022252 -314.316618) (xy 50.014593 -314.324135) (xy 50.005915 -314.34374)
			(xy 50.005488 -314.354464) (xy 50.005488 -314.424822) (xy 50.005269 -314.439706) (xy 50.002471 -314.469343)
			(xy 49.9999 -314.484004) (xy 49.9999 -314.485528) (xy 49.998884 -314.49137) (xy 50.005996 -314.513976)
			(xy 50.070512 -314.58154) (xy 50.079152 -314.589608) (xy 50.101388 -314.59755) (xy 50.113184 -314.59678)
			(xy 50.113438 -314.59678) (xy 50.122482 -314.59573) (xy 50.140656 -314.594584) (xy 50.14976 -314.594494)
			(xy 50.173755 -314.594937) (xy 50.221155 -314.602439) (xy 50.266798 -314.617264) (xy 50.30956 -314.639047)
			(xy 50.348387 -314.667252) (xy 50.382323 -314.701184) (xy 50.410533 -314.740008) (xy 50.432321 -314.782767)
			(xy 50.447152 -314.828408) (xy 50.45466 -314.875807) (xy 50.455068 -314.899802) (xy 50.454306 -314.920884)
			(xy 50.454019 -314.931396) (xy 50.460965 -314.95122) (xy 50.467768 -314.959238) (xy 50.518568 -315.01334)
			(xy 50.526039 -315.020677) (xy 50.545194 -315.029081) (xy 50.555652 -315.029596) (xy 50.694082 -315.029596)
			(xy 50.704525 -315.029025) (xy 50.723656 -315.020622) (xy 50.731166 -315.01334) (xy 50.781966 -314.959238)
			(xy 50.788699 -314.951182) (xy 50.795627 -314.931384) (xy 50.795428 -314.920884) (xy 50.794666 -314.899802)
			(xy 50.795188 -314.874547) (xy 50.803501 -314.824725) (xy 50.819902 -314.776951) (xy 50.843943 -314.732528)
			(xy 50.874967 -314.692668) (xy 50.912129 -314.658458) (xy 50.954415 -314.630832) (xy 51.000671 -314.610542)
			(xy 51.049636 -314.598142) (xy 51.099974 -314.593971) (xy 51.150312 -314.598142) (xy 51.199277 -314.610542)
			(xy 51.245533 -314.630832) (xy 51.287819 -314.658458) (xy 51.324981 -314.692668) (xy 51.356005 -314.732528)
			(xy 51.380046 -314.776951) (xy 51.396447 -314.824725) (xy 51.40476 -314.874547) (xy 51.405282 -314.899802)
			(xy 51.405282 -314.900056) (xy 51.405017 -314.91768) (xy 51.400944 -314.952692) (xy 51.397154 -314.969906)
			(xy 51.395884 -314.981336) (xy 51.396341 -314.992774) (xy 51.406153 -315.01343) (xy 51.423984 -315.027749)
			(xy 51.435 -315.030866) (xy 51.438556 -315.031882) (xy 51.444391 -315.033893) (xy 51.454924 -315.040316)
			(xy 51.459384 -315.044582) (xy 51.475132 -315.06033) (xy 51.48072 -315.065156) (xy 51.484168 -315.067599)
			(xy 51.491702 -315.071426) (xy 51.495706 -315.072776) (xy 51.507136 -315.076332) (xy 51.519582 -315.074046)
			(xy 51.542365 -315.070354) (xy 51.588499 -315.069071) (xy 51.634301 -315.074753) (xy 51.678723 -315.08727)
			(xy 51.699922 -315.096398) (xy 51.709574 -315.10097) (xy 51.719233 -315.10444) (xy 51.739738 -315.104201)
			(xy 51.758515 -315.095959) (xy 51.772571 -315.081027) (xy 51.779664 -315.061787) (xy 51.778664 -315.041305)
			(xy 51.774598 -315.031882) (xy 51.765163 -315.011199) (xy 51.751827 -314.967739) (xy 51.745066 -314.922785)
			(xy 51.744626 -314.900056) (xy 51.744626 -314.899802) (xy 51.745148 -314.874547) (xy 51.753461 -314.824725)
			(xy 51.769862 -314.776951) (xy 51.793903 -314.732528) (xy 51.824927 -314.692668) (xy 51.862089 -314.658458)
			(xy 51.904375 -314.630832) (xy 51.950631 -314.610542) (xy 51.999596 -314.598142) (xy 52.049934 -314.593971)
			(xy 52.100272 -314.598142) (xy 52.149237 -314.610542) (xy 52.195493 -314.630832) (xy 52.237779 -314.658458)
			(xy 52.274941 -314.692668) (xy 52.305965 -314.732528) (xy 52.330006 -314.776951) (xy 52.346407 -314.824725)
			(xy 52.35472 -314.874547) (xy 52.355242 -314.899802) (xy 52.354837 -314.922345) (xy 52.348203 -314.96694)
			(xy 52.335079 -315.010073) (xy 52.325778 -315.030612) (xy 52.321984 -315.039842) (xy 52.321035 -315.059755)
			(xy 52.32773 -315.078532) (xy 52.341064 -315.093352) (xy 52.359032 -315.101987) (xy 52.368958 -315.103002)
			(xy 52.375166 -315.103148) (xy 52.387364 -315.100838) (xy 52.393088 -315.09843) (xy 52.412138 -315.090302)
			(xy 52.427638 -315.084544) (xy 52.459585 -315.076015) (xy 52.475892 -315.073284) (xy 52.476146 -315.073284)
			(xy 52.479956 -315.072776) (xy 52.491005 -315.071244) (xy 52.513252 -315.06959) (xy 52.524406 -315.069474)
			(xy 52.53101 -315.069474) (xy 52.548999 -315.070108) (xy 52.584653 -315.075069) (xy 52.60213 -315.07938)
			(xy 52.616181 -315.08324) (xy 52.643532 -315.093292) (xy 52.65674 -315.099446) (xy 52.665429 -315.103234)
			(xy 52.684313 -315.104722) (xy 52.702434 -315.099204) (xy 52.71008 -315.093604) (xy 52.718804 -315.08605)
			(xy 52.728917 -315.065331) (xy 52.72901 -315.042277) (xy 52.724558 -315.031628) (xy 52.715121 -315.010945)
			(xy 52.70178 -314.967486) (xy 52.695013 -314.922532) (xy 52.694586 -314.899802) (xy 52.695108 -314.874547)
			(xy 52.703421 -314.824725) (xy 52.719822 -314.776951) (xy 52.743863 -314.732528) (xy 52.774887 -314.692668)
			(xy 52.812049 -314.658458) (xy 52.854335 -314.630832) (xy 52.900591 -314.610542) (xy 52.949556 -314.598142)
			(xy 52.999894 -314.593971) (xy 53.050232 -314.598142) (xy 53.099197 -314.610542) (xy 53.145453 -314.630832)
			(xy 53.187739 -314.658458) (xy 53.224901 -314.692668) (xy 53.255925 -314.732528) (xy 53.279966 -314.776951)
			(xy 53.296367 -314.824725) (xy 53.30468 -314.874547) (xy 53.305202 -314.899802) (xy 53.305202 -314.900056)
			(xy 53.304813 -314.921855) (xy 53.298569 -314.965003) (xy 53.286244 -315.006823) (xy 53.277516 -315.026802)
			(xy 53.274214 -315.036454) (xy 53.270404 -315.053218) (xy 53.270895 -315.063223) (xy 53.278558 -315.081708)
			(xy 53.292711 -315.095854) (xy 53.311199 -315.103509) (xy 53.321204 -315.104018) (xy 53.342794 -315.099192)
			(xy 53.34889 -315.096398) (xy 53.372703 -315.086254) (xy 53.422795 -315.073234) (xy 53.474366 -315.068853)
			(xy 53.525937 -315.073234) (xy 53.576029 -315.086254) (xy 53.599842 -315.096398) (xy 53.609494 -315.10097)
			(xy 53.619151 -315.104436) (xy 53.639648 -315.104191) (xy 53.658417 -315.095949) (xy 53.672466 -315.081021)
			(xy 53.679556 -315.061788) (xy 53.678558 -315.041313) (xy 53.674518 -315.031882) (xy 53.665083 -315.011199)
			(xy 53.651746 -314.96774) (xy 53.644984 -314.922786) (xy 53.644546 -314.900056) (xy 53.644546 -314.899802)
			(xy 53.645068 -314.874547) (xy 53.653381 -314.824725) (xy 53.669782 -314.776951) (xy 53.693823 -314.732528)
			(xy 53.724847 -314.692668) (xy 53.762009 -314.658458) (xy 53.804295 -314.630832) (xy 53.850551 -314.610542)
			(xy 53.899516 -314.598142) (xy 53.949854 -314.593971) (xy 54.000192 -314.598142) (xy 54.049157 -314.610542)
			(xy 54.095413 -314.630832) (xy 54.137699 -314.658458) (xy 54.174861 -314.692668) (xy 54.205885 -314.732528)
			(xy 54.229926 -314.776951) (xy 54.246327 -314.824725) (xy 54.25464 -314.874547) (xy 54.255162 -314.899802)
			(xy 54.254757 -314.922345) (xy 54.248123 -314.96694) (xy 54.235 -315.010074) (xy 54.225698 -315.030612)
			(xy 54.221903 -315.039841) (xy 54.220953 -315.059752) (xy 54.227649 -315.078528) (xy 54.240984 -315.093344)
			(xy 54.258954 -315.101974) (xy 54.268878 -315.103002) (xy 54.275086 -315.103146) (xy 54.287281 -315.100831)
			(xy 54.293008 -315.09843) (xy 54.312058 -315.090302) (xy 54.327558 -315.084545) (xy 54.359505 -315.076018)
			(xy 54.375812 -315.073284) (xy 54.376066 -315.073284) (xy 54.379876 -315.072776) (xy 54.390925 -315.071244)
			(xy 54.413172 -315.069592) (xy 54.424326 -315.069474) (xy 54.43093 -315.069474) (xy 54.448919 -315.070109)
			(xy 54.484573 -315.075072) (xy 54.50205 -315.07938) (xy 54.516102 -315.083237) (xy 54.543456 -315.093282)
			(xy 54.55666 -315.099446) (xy 54.565349 -315.103231) (xy 54.584229 -315.104711) (xy 54.602344 -315.099189)
			(xy 54.61 -315.093604) (xy 54.618722 -315.086049) (xy 54.62883 -315.065331) (xy 54.628924 -315.042278)
			(xy 54.624478 -315.031628) (xy 54.615041 -315.010945) (xy 54.601699 -314.967486) (xy 54.594931 -314.922532)
			(xy 54.594506 -314.899802) (xy 54.595028 -314.874547) (xy 54.603341 -314.824725) (xy 54.619742 -314.776951)
			(xy 54.643783 -314.732528) (xy 54.674807 -314.692668) (xy 54.711969 -314.658458) (xy 54.754255 -314.630832)
			(xy 54.800511 -314.610542) (xy 54.849476 -314.598142) (xy 54.899814 -314.593971) (xy 54.950152 -314.598142)
			(xy 54.999117 -314.610542) (xy 55.045373 -314.630832) (xy 55.087659 -314.658458) (xy 55.124821 -314.692668)
			(xy 55.155845 -314.732528) (xy 55.179886 -314.776951) (xy 55.196287 -314.824725) (xy 55.2046 -314.874547)
			(xy 55.205122 -314.899802) (xy 55.204689 -314.922491) (xy 55.197925 -314.967362) (xy 55.184578 -315.010732)
			(xy 55.17515 -315.031374) (xy 55.171042 -315.041059) (xy 55.170231 -315.062059) (xy 55.177894 -315.081627)
			(xy 55.19275 -315.096491) (xy 55.212314 -315.104165) (xy 55.233314 -315.103365) (xy 55.242968 -315.099192)
			(xy 55.243222 -315.099192) (xy 55.249064 -315.096398) (xy 55.272877 -315.086254) (xy 55.322969 -315.073234)
			(xy 55.37454 -315.068853) (xy 55.426111 -315.073234) (xy 55.476203 -315.086254) (xy 55.500016 -315.096398)
			(xy 55.50662 -315.099446) (xy 55.516299 -315.103544) (xy 55.53728 -315.104342) (xy 55.556828 -315.096677)
			(xy 55.571675 -315.081831) (xy 55.579341 -315.062284) (xy 55.578545 -315.041303) (xy 55.574438 -315.031628)
			(xy 55.565002 -315.010945) (xy 55.551662 -314.967486) (xy 55.544895 -314.922532) (xy 55.544466 -314.899802)
			(xy 55.544988 -314.874547) (xy 55.553301 -314.824725) (xy 55.569702 -314.776951) (xy 55.593743 -314.732528)
			(xy 55.624767 -314.692668) (xy 55.661929 -314.658458) (xy 55.704215 -314.630832) (xy 55.750471 -314.610542)
			(xy 55.799436 -314.598142) (xy 55.849774 -314.593971) (xy 55.900112 -314.598142) (xy 55.949077 -314.610542)
			(xy 55.995333 -314.630832) (xy 56.037619 -314.658458) (xy 56.074781 -314.692668) (xy 56.105805 -314.732528)
			(xy 56.129846 -314.776951) (xy 56.146247 -314.824725) (xy 56.15456 -314.874547) (xy 56.155082 -314.899802)
			(xy 56.154874 -314.913857) (xy 56.152201 -314.941841) (xy 56.149748 -314.955682) (xy 56.149748 -314.95619)
			(xy 56.148259 -314.968419) (xy 56.155576 -314.9919) (xy 56.163718 -315.001148) (xy 56.231536 -315.069474)
			(xy 56.255158 -315.07684) (xy 56.261508 -315.075824) (xy 56.278018 -315.07303) (xy 56.281574 -315.072522)
			(xy 56.292249 -315.071103) (xy 56.313732 -315.069579) (xy 56.3245 -315.069474) (xy 56.324754 -315.069474)
			(xy 56.340105 -315.069719) (xy 56.370641 -315.072905) (xy 56.385714 -315.075824) (xy 56.386984 -315.075824)
			(xy 56.393842 -315.077094) (xy 56.417464 -315.069728) (xy 56.486044 -315.001402) (xy 56.494188 -314.992161)
			(xy 56.501482 -314.968674) (xy 56.500014 -314.956444) (xy 56.500014 -314.95619) (xy 56.497529 -314.942225)
			(xy 56.494857 -314.913985) (xy 56.49468 -314.899802) (xy 56.49515 -314.87581) (xy 56.502656 -314.828418)
			(xy 56.517483 -314.782783) (xy 56.539267 -314.740029) (xy 56.56747 -314.701209) (xy 56.601398 -314.667279)
			(xy 56.640217 -314.639074) (xy 56.68297 -314.617289) (xy 56.728604 -314.60246) (xy 56.775996 -314.594952)
			(xy 56.799988 -314.594494) (xy 56.809025 -314.594541) (xy 56.827071 -314.595559) (xy 56.836056 -314.596526)
			(xy 56.847994 -314.59805) (xy 56.870346 -314.589922) (xy 56.943244 -314.513722) (xy 56.950356 -314.491116)
			(xy 56.94934 -314.485274) (xy 56.946734 -314.470297) (xy 56.943937 -314.440023) (xy 56.943752 -314.424822)
			(xy 56.943752 -314.354464) (xy 56.943185 -314.343775) (xy 56.934517 -314.324228) (xy 56.926988 -314.316618)
			(xy 56.86298 -314.25896) (xy 56.842152 -314.252356) (xy 56.831738 -314.253626) (xy 56.799988 -314.25515)
			(xy 56.77473 -314.254627) (xy 56.724903 -314.246311) (xy 56.677124 -314.229907) (xy 56.632697 -314.205862)
			(xy 56.592833 -314.174834) (xy 56.55862 -314.137667) (xy 56.530991 -314.095376) (xy 56.510699 -314.049114)
			(xy 56.498299 -314.000144) (xy 56.494127 -313.9498) (xy 56.498299 -313.899456) (xy 56.510699 -313.850486)
			(xy 56.530991 -313.804224) (xy 56.55862 -313.761933) (xy 56.592833 -313.724766) (xy 56.632697 -313.693738)
			(xy 56.677124 -313.669693) (xy 56.724903 -313.653289) (xy 56.77473 -313.644973) (xy 56.799988 -313.644534)
			(xy 56.831738 -313.646058) (xy 56.842152 -313.647328) (xy 56.86298 -313.640724) (xy 56.926988 -313.583066)
			(xy 56.934639 -313.575545) (xy 56.943304 -313.555941) (xy 56.943752 -313.54522) (xy 56.943752 -313.474862)
			(xy 56.943942 -313.459788) (xy 56.946745 -313.429769) (xy 56.94934 -313.414918) (xy 56.94934 -313.413902)
			(xy 56.950356 -313.408568) (xy 56.943244 -313.385962) (xy 56.870346 -313.309762) (xy 56.847994 -313.301634)
			(xy 56.836056 -313.303158) (xy 56.827072 -313.304141) (xy 56.809026 -313.30516) (xy 56.799988 -313.30519)
			(xy 56.775169 -313.304703) (xy 56.726186 -313.296671) (xy 56.679147 -313.28082) (xy 56.635292 -313.257568)
			(xy 56.595776 -313.227528) (xy 56.561641 -313.19149) (xy 56.533786 -313.150405) (xy 56.512944 -313.105354)
			(xy 56.499665 -313.057526) (xy 56.494299 -313.008179) (xy 56.496987 -312.958614) (xy 56.507657 -312.910137)
			(xy 56.52603 -312.864025) (xy 56.551621 -312.821492) (xy 56.583755 -312.78366) (xy 56.621587 -312.751524)
			(xy 56.664119 -312.725933) (xy 56.710231 -312.707559) (xy 56.758708 -312.696888) (xy 56.808273 -312.694199)
			(xy 56.85762 -312.699564) (xy 56.905449 -312.712842) (xy 56.9505 -312.733683) (xy 56.991585 -312.761538)
			(xy 57.027624 -312.795672) (xy 57.057665 -312.835187) (xy 57.080918 -312.879041) (xy 57.09677 -312.92608)
			(xy 57.104803 -312.975063) (xy 57.105296 -312.999882) (xy 57.105257 -313.008983) (xy 57.104242 -313.027156)
			(xy 57.103264 -313.036204) (xy 57.10174 -313.048142) (xy 57.109868 -313.070494) (xy 57.185814 -313.143392)
			(xy 57.20842 -313.150504) (xy 57.212992 -313.149742) (xy 57.228276 -313.147005) (xy 57.259188 -313.144076)
			(xy 57.274714 -313.1439) (xy 57.275476 -313.1439) (xy 57.28984 -313.14407) (xy 57.318457 -313.146611)
			(xy 57.332626 -313.14898) (xy 57.333134 -313.14898) (xy 57.341262 -313.15025) (xy 57.363868 -313.143392)
			(xy 57.431432 -313.078622) (xy 57.439522 -313.070135) (xy 57.447621 -313.04816) (xy 57.446926 -313.036458)
			(xy 57.446926 -313.036204) (xy 57.445878 -313.02716) (xy 57.444736 -313.008986) (xy 57.44464 -312.999882)
			(xy 57.445127 -312.975066) (xy 57.453159 -312.926089) (xy 57.469009 -312.879056) (xy 57.492258 -312.835207)
			(xy 57.522295 -312.795696) (xy 57.558328 -312.761565) (xy 57.599408 -312.733713) (xy 57.644453 -312.712874)
			(xy 57.692275 -312.699596) (xy 57.741616 -312.694229) (xy 57.791175 -312.696915) (xy 57.839646 -312.707584)
			(xy 57.885754 -312.725953) (xy 57.928282 -312.751539) (xy 57.966111 -312.783668) (xy 57.998243 -312.821494)
			(xy 58.023834 -312.864019) (xy 58.042207 -312.910125) (xy 58.05288 -312.958595) (xy 58.055123 -312.999882)
			(xy 58.394104 -312.999882) (xy 58.398064 -312.950828) (xy 58.409841 -312.903044) (xy 58.429132 -312.857768)
			(xy 58.455435 -312.816172) (xy 58.48807 -312.779335) (xy 58.526191 -312.74821) (xy 58.568812 -312.723603)
			(xy 58.614828 -312.706151) (xy 58.663047 -312.696307) (xy 58.712222 -312.694326) (xy 58.761077 -312.700258)
			(xy 58.808348 -312.71395) (xy 58.85281 -312.735048) (xy 58.893313 -312.763004) (xy 58.928806 -312.797096)
			(xy 58.958371 -312.83644) (xy 58.981242 -312.880017) (xy 58.996826 -312.926698) (xy 59.004721 -312.975275)
			(xy 59.005216 -312.999882) (xy 59.004721 -313.024489) (xy 58.996826 -313.073066) (xy 58.981242 -313.119747)
			(xy 58.958371 -313.163324) (xy 58.928806 -313.202668) (xy 58.893313 -313.23676) (xy 58.85281 -313.264716)
			(xy 58.808348 -313.285814) (xy 58.761077 -313.299506) (xy 58.712222 -313.305438) (xy 58.663047 -313.303457)
			(xy 58.614828 -313.293613) (xy 58.568812 -313.276161) (xy 58.526191 -313.251554) (xy 58.48807 -313.220429)
			(xy 58.455435 -313.183592) (xy 58.429132 -313.141996) (xy 58.409841 -313.09672) (xy 58.398064 -313.048936)
			(xy 58.394104 -312.999882) (xy 58.055123 -312.999882) (xy 58.055572 -313.008154) (xy 58.05021 -313.057495)
			(xy 58.036937 -313.105319) (xy 58.016102 -313.150366) (xy 57.988254 -313.191448) (xy 57.954126 -313.227485)
			(xy 57.914619 -313.257526) (xy 57.870772 -313.280779) (xy 57.82374 -313.296634) (xy 57.774764 -313.30467)
			(xy 57.749948 -313.30519) (xy 57.740844 -313.305092) (xy 57.722671 -313.303948) (xy 57.713626 -313.302904)
			(xy 57.713372 -313.302904) (xy 57.701565 -313.302079) (xy 57.679299 -313.310014) (xy 57.6707 -313.318144)
			(xy 57.606184 -313.385708) (xy 57.599072 -313.408314) (xy 57.600088 -313.414918) (xy 57.602671 -313.42977)
			(xy 57.605469 -313.459788) (xy 57.605676 -313.474862) (xy 57.605676 -313.54522) (xy 57.606238 -313.555913)
			(xy 57.614893 -313.575471) (xy 57.62244 -313.583066) (xy 57.678574 -313.633612) (xy 57.686795 -313.640397)
			(xy 57.707051 -313.646971) (xy 57.71769 -313.646312) (xy 57.717944 -313.646312) (xy 57.749948 -313.644534)
			(xy 57.773936 -313.645008) (xy 57.821319 -313.652521) (xy 57.866944 -313.667353) (xy 57.909687 -313.68914)
			(xy 57.948495 -313.717344) (xy 57.982414 -313.751273) (xy 58.010608 -313.79009) (xy 58.032382 -313.832839)
			(xy 58.0472 -313.878469) (xy 58.054699 -313.925854) (xy 58.055256 -313.949842) (xy 58.055072 -313.964025)
			(xy 58.052404 -313.992265) (xy 58.049922 -314.00623) (xy 58.047636 -314.018676) (xy 58.055002 -314.042298)
			(xy 58.131964 -314.119514) (xy 58.156094 -314.12688) (xy 58.16854 -314.124594) (xy 58.182449 -314.122197)
			(xy 58.210561 -314.119653) (xy 58.224674 -314.119514) (xy 58.227722 -314.119514) (xy 58.240494 -314.119781)
			(xy 58.265928 -314.122198) (xy 58.278522 -314.12434) (xy 58.281316 -314.124848) (xy 58.293762 -314.127134)
			(xy 58.317384 -314.119768) (xy 58.385964 -314.051442) (xy 58.394113 -314.042202) (xy 58.401422 -314.018713)
			(xy 58.399934 -314.006484) (xy 58.399934 -314.00623) (xy 58.397447 -313.992265) (xy 58.394771 -313.964025)
			(xy 58.3946 -313.949842) (xy 58.395082 -313.925021) (xy 58.403107 -313.876032) (xy 58.418952 -313.828987)
			(xy 58.442199 -313.785126) (xy 58.472236 -313.745603) (xy 58.508271 -313.71146) (xy 58.549356 -313.683597)
			(xy 58.594407 -313.662748) (xy 58.642238 -313.649462) (xy 58.691588 -313.64409) (xy 58.741157 -313.646773)
			(xy 58.789639 -313.657439) (xy 58.835756 -313.675809) (xy 58.878294 -313.701399) (xy 58.916132 -313.733533)
			(xy 58.948272 -313.771365) (xy 58.973868 -313.813899) (xy 58.992246 -313.860013) (xy 59.002921 -313.908494)
			(xy 59.005611 -313.958062) (xy 59.000247 -314.007413) (xy 58.986969 -314.055246) (xy 58.966128 -314.100301)
			(xy 58.938272 -314.14139) (xy 58.904135 -314.177431) (xy 58.864617 -314.207474) (xy 58.820759 -314.230729)
			(xy 58.773716 -314.246581) (xy 58.724729 -314.254613) (xy 58.699908 -314.25515) (xy 58.677176 -314.254736)
			(xy 58.632215 -314.247992) (xy 58.588757 -314.234636) (xy 58.568082 -314.225178) (xy 58.558405 -314.221079)
			(xy 58.537427 -314.220279) (xy 58.517882 -314.227942) (xy 58.503038 -314.242787) (xy 58.495378 -314.262333)
			(xy 58.496181 -314.283311) (xy 58.500264 -314.292996) (xy 58.504459 -314.301925) (xy 58.511832 -314.320227)
			(xy 58.514996 -314.329572) (xy 58.517536 -314.3377) (xy 58.519314 -314.34405) (xy 58.523578 -314.360263)
			(xy 58.528924 -314.393359) (xy 58.529982 -314.41009) (xy 58.53049 -314.417456) (xy 58.531269 -314.421021)
			(xy 58.533693 -314.427904) (xy 58.535316 -314.431172) (xy 58.547 -314.44819) (xy 58.548016 -314.449714)
			(xy 58.55589 -314.46089) (xy 58.56478 -314.470034) (xy 58.569352 -314.473844) (xy 58.577226 -314.476892)
			(xy 58.621676 -314.494968) (xy 58.707087 -314.538714) (xy 58.787733 -314.590725) (xy 58.825638 -314.620148)
			(xy 58.834782 -314.62599) (xy 58.8571 -314.63752) (xy 58.897953 -314.666746) (xy 58.933469 -314.702266)
			(xy 58.962692 -314.743121) (xy 58.974228 -314.765436) (xy 58.98007 -314.77458) (xy 59.007569 -314.810097)
			(xy 59.056582 -314.885378) (xy 59.098376 -314.964895) (xy 59.11596 -315.006228) (xy 59.131966 -315.046122)
			(xy 59.157654 -315.128161) (xy 59.167268 -315.170058) (xy 59.167522 -315.171074) (xy 59.1693 -315.177678)
			(xy 59.171812 -315.183831) (xy 59.179535 -315.194641) (xy 59.18454 -315.199014) (xy 59.191144 -315.204348)
			(xy 59.199018 -315.207142) (xy 59.203196 -315.208554) (xy 59.211881 -315.210091) (xy 59.21629 -315.21019)
		)
		(stroke
			(width 0)
			(type solid)
		)
		(fill yes)
		(layer "In5.Cu")
		(net "P1V8_VDDA_PEX0")
	)
	(gr_poly
		(pts
			(xy 291.50056 -315.21019) (xy 291.509512 -315.209836) (xy 291.526323 -315.203679) (xy 291.540006 -315.192132)
			(xy 291.544756 -315.184536) (xy 291.595048 -315.095636) (xy 291.594794 -315.068458) (xy 291.587682 -315.05652)
			(xy 291.574168 -315.032678) (xy 291.554927 -314.98137) (xy 291.545135 -314.927454) (xy 291.544502 -314.900056)
			(xy 291.544502 -314.899802) (xy 291.544948 -314.875809) (xy 291.552455 -314.828414) (xy 291.567283 -314.782777)
			(xy 291.589068 -314.740021) (xy 291.617274 -314.7012) (xy 291.651206 -314.667269) (xy 291.690028 -314.639064)
			(xy 291.732784 -314.61728) (xy 291.778422 -314.602453) (xy 291.825817 -314.594947) (xy 291.84981 -314.594494)
			(xy 291.858847 -314.594542) (xy 291.876892 -314.595561) (xy 291.885878 -314.596526) (xy 291.886132 -314.596526)
			(xy 291.897937 -314.597349) (xy 291.920195 -314.589404) (xy 291.928804 -314.581286) (xy 291.99332 -314.513976)
			(xy 292.000432 -314.49137) (xy 291.999162 -314.484258) (xy 291.996676 -314.469653) (xy 291.994003 -314.440144)
			(xy 291.993828 -314.42533) (xy 291.993828 -314.354464) (xy 291.993263 -314.343773) (xy 291.984604 -314.324218)
			(xy 291.977064 -314.316618) (xy 291.92093 -314.266072) (xy 291.912709 -314.259288) (xy 291.892453 -314.252714)
			(xy 291.881814 -314.253372) (xy 291.88156 -314.253372) (xy 291.84981 -314.25515) (xy 291.824548 -314.254658)
			(xy 291.774714 -314.246344) (xy 291.726927 -314.22994) (xy 291.682493 -314.205894) (xy 291.642622 -314.174863)
			(xy 291.608403 -314.137692) (xy 291.580769 -314.095396) (xy 291.560473 -314.049128) (xy 291.54807 -314.000151)
			(xy 291.543898 -313.9498) (xy 291.54807 -313.899449) (xy 291.560473 -313.850472) (xy 291.580769 -313.804204)
			(xy 291.608403 -313.761908) (xy 291.642622 -313.724737) (xy 291.682493 -313.693706) (xy 291.726927 -313.66966)
			(xy 291.774714 -313.653256) (xy 291.824548 -313.644942) (xy 291.84981 -313.644534) (xy 291.881306 -313.646312)
			(xy 291.881814 -313.646312) (xy 291.892432 -313.646822) (xy 291.912625 -313.640251) (xy 291.92093 -313.633612)
			(xy 291.977064 -313.583066) (xy 291.984718 -313.575547) (xy 291.993388 -313.555942) (xy 291.993828 -313.54522)
			(xy 291.993828 -313.474862) (xy 291.994003 -313.460048) (xy 291.996672 -313.430539) (xy 291.999162 -313.415934)
			(xy 291.999162 -313.415172) (xy 292.000432 -313.408568) (xy 291.99332 -313.385962) (xy 291.920422 -313.309762)
			(xy 291.89807 -313.301634) (xy 291.886132 -313.303158) (xy 291.877085 -313.304146) (xy 291.858911 -313.305162)
			(xy 291.84981 -313.30519) (xy 291.824991 -313.304705) (xy 291.776006 -313.296676) (xy 291.728965 -313.280828)
			(xy 291.685108 -313.257578) (xy 291.64559 -313.22754) (xy 291.611452 -313.191504) (xy 291.583594 -313.15042)
			(xy 291.56275 -313.10537) (xy 291.549468 -313.057541) (xy 291.544099 -313.008194) (xy 291.546785 -312.958628)
			(xy 291.557454 -312.91015) (xy 291.575825 -312.864036) (xy 291.601414 -312.821502) (xy 291.633548 -312.783667)
			(xy 291.671379 -312.75153) (xy 291.713911 -312.725937) (xy 291.760023 -312.707562) (xy 291.8085 -312.696889)
			(xy 291.858066 -312.694199) (xy 291.907414 -312.699563) (xy 291.955244 -312.71284) (xy 292.000295 -312.733681)
			(xy 292.041382 -312.761535) (xy 292.077421 -312.795669) (xy 292.107463 -312.835185) (xy 292.130717 -312.879039)
			(xy 292.146569 -312.926079) (xy 292.154603 -312.975063) (xy 292.155118 -312.999882) (xy 292.155071 -313.008919)
			(xy 292.154054 -313.026965) (xy 292.153086 -313.03595) (xy 292.151562 -313.047888) (xy 292.15969 -313.07024)
			(xy 292.23589 -313.143138) (xy 292.258496 -313.149996) (xy 292.26383 -313.149234) (xy 292.278994 -313.146584)
			(xy 292.309651 -313.143784) (xy 292.325044 -313.143646) (xy 292.338693 -313.143746) (xy 292.365905 -313.145911)
			(xy 292.3794 -313.147964) (xy 292.391338 -313.149996) (xy 292.413944 -313.142884) (xy 292.48989 -313.07024)
			(xy 292.498018 -313.047888) (xy 292.496494 -313.03595) (xy 292.495511 -313.026966) (xy 292.494492 -313.00892)
			(xy 292.494462 -312.999882) (xy 292.494949 -312.975059) (xy 292.502984 -312.926066) (xy 292.51884 -312.879019)
			(xy 292.542097 -312.835157) (xy 292.572145 -312.795635) (xy 292.608191 -312.761495) (xy 292.649285 -312.733637)
			(xy 292.694345 -312.712793) (xy 292.742183 -312.699515) (xy 292.791539 -312.694151) (xy 292.841113 -312.696842)
			(xy 292.889599 -312.707518) (xy 292.935718 -312.725898) (xy 292.978257 -312.751497) (xy 293.016093 -312.783641)
			(xy 293.048231 -312.821482) (xy 293.073823 -312.864025) (xy 293.092196 -312.910147) (xy 293.102864 -312.958634)
			(xy 293.105548 -313.008209) (xy 293.100176 -313.057564) (xy 293.08689 -313.1054) (xy 293.06604 -313.150457)
			(xy 293.038175 -313.191547) (xy 293.004029 -313.227587) (xy 292.964503 -313.257628) (xy 292.920637 -313.280879)
			(xy 292.873587 -313.296727) (xy 292.824594 -313.304754) (xy 292.79977 -313.30519) (xy 292.790796 -313.30515)
			(xy 292.772877 -313.304134) (xy 292.763956 -313.303158) (xy 292.752018 -313.301634) (xy 292.729666 -313.309762)
			(xy 292.656768 -313.385962) (xy 292.649656 -313.408568) (xy 292.650926 -313.41568) (xy 292.653428 -313.430347)
			(xy 292.656103 -313.459984) (xy 292.65626 -313.474862) (xy 292.65626 -313.54522) (xy 292.656824 -313.555911)
			(xy 292.66549 -313.57546) (xy 292.673024 -313.583066) (xy 292.737032 -313.64047) (xy 292.757352 -313.647074)
			(xy 292.76802 -313.646058) (xy 292.79977 -313.644534) (xy 292.823763 -313.644978) (xy 292.87116 -313.652481)
			(xy 292.916799 -313.667308) (xy 292.959556 -313.689092) (xy 292.998379 -313.717298) (xy 293.03231 -313.75123)
			(xy 293.060514 -313.790054) (xy 293.082297 -313.832812) (xy 293.097122 -313.878452) (xy 293.104623 -313.925848)
			(xy 293.105078 -313.949842) (xy 293.104945 -313.963892) (xy 293.102397 -313.991877) (xy 293.099998 -314.005722)
			(xy 293.097712 -314.018168) (xy 293.105078 -314.042298) (xy 293.182294 -314.11926) (xy 293.205916 -314.126626)
			(xy 293.213536 -314.125356) (xy 293.241855 -314.120229) (xy 293.299392 -314.119457) (xy 293.327836 -314.123832)
			(xy 293.328852 -314.123832) (xy 293.330884 -314.12434) (xy 293.331138 -314.12434) (xy 293.343371 -314.125842)
			(xy 293.366868 -314.11854) (xy 293.376096 -314.11037) (xy 293.444422 -314.042298) (xy 293.451788 -314.018168)
			(xy 293.449502 -314.005722) (xy 293.447113 -313.991876) (xy 293.444571 -313.963892) (xy 293.444422 -313.949842)
			(xy 293.444865 -313.925848) (xy 293.452367 -313.878449) (xy 293.467192 -313.832807) (xy 293.488976 -313.790048)
			(xy 293.517181 -313.751223) (xy 293.551114 -313.717289) (xy 293.589937 -313.689082) (xy 293.632696 -313.667297)
			(xy 293.678337 -313.65247) (xy 293.725736 -313.644966) (xy 293.74973 -313.644534) (xy 293.78148 -313.646312)
			(xy 293.781988 -313.646312) (xy 293.792629 -313.646982) (xy 293.812894 -313.640414) (xy 293.821104 -313.633612)
			(xy 293.877492 -313.583066) (xy 293.885143 -313.575545) (xy 293.893807 -313.555941) (xy 293.894256 -313.54522)
			(xy 293.894256 -313.474862) (xy 293.894345 -313.461149) (xy 293.896503 -313.433808) (xy 293.898574 -313.420252)
			(xy 293.900606 -313.408568) (xy 293.893494 -313.385708) (xy 293.829232 -313.318144) (xy 293.820588 -313.310089)
			(xy 293.798355 -313.302173) (xy 293.78656 -313.302904) (xy 293.786306 -313.302904) (xy 293.777198 -313.303959)
			(xy 293.758898 -313.305102) (xy 293.74973 -313.30519) (xy 293.72491 -313.304707) (xy 293.675924 -313.296681)
			(xy 293.628882 -313.280835) (xy 293.585023 -313.257588) (xy 293.545503 -313.227551) (xy 293.511363 -313.191517)
			(xy 293.483502 -313.150433) (xy 293.462655 -313.105384) (xy 293.449371 -313.057555) (xy 293.444 -313.008207)
			(xy 293.446683 -312.958641) (xy 293.45735 -312.910161) (xy 293.47572 -312.864046) (xy 293.501308 -312.82151)
			(xy 293.533441 -312.783675) (xy 293.571271 -312.751536) (xy 293.613803 -312.725941) (xy 293.659915 -312.707564)
			(xy 293.708393 -312.69689) (xy 293.757959 -312.694199) (xy 293.807308 -312.699562) (xy 293.855139 -312.712839)
			(xy 293.900191 -312.733678) (xy 293.941279 -312.761533) (xy 293.977319 -312.795667) (xy 294.007362 -312.835183)
			(xy 294.030616 -312.879038) (xy 294.046469 -312.926078) (xy 294.054503 -312.975062) (xy 294.055038 -312.999882)
			(xy 294.054939 -313.008986) (xy 294.053793 -313.027159) (xy 294.052752 -313.036204) (xy 294.051953 -313.048098)
			(xy 294.060032 -313.070492) (xy 294.068246 -313.07913) (xy 294.127174 -313.135518) (xy 294.136146 -313.143147)
			(xy 294.158646 -313.150013) (xy 294.170354 -313.148726) (xy 294.170608 -313.148726) (xy 294.184096 -313.146595)
			(xy 294.211309 -313.144302) (xy 294.224964 -313.144154) (xy 294.225472 -313.144154) (xy 294.238994 -313.144273)
			(xy 294.265951 -313.146436) (xy 294.27932 -313.148472) (xy 294.291004 -313.150504) (xy 294.313864 -313.143392)
			(xy 294.381428 -313.078876) (xy 294.389413 -313.070344) (xy 294.397324 -313.048382) (xy 294.396668 -313.036712)
			(xy 294.396668 -313.03595) (xy 294.396414 -313.033156) (xy 294.394382 -313.000136) (xy 294.394382 -312.999628)
			(xy 294.394873 -312.97565) (xy 294.402413 -312.928291) (xy 294.417264 -312.882693) (xy 294.439062 -312.839977)
			(xy 294.46727 -312.801195) (xy 294.501194 -312.767299) (xy 294.540001 -312.739125) (xy 294.582735 -312.717364)
			(xy 294.628346 -312.702551) (xy 294.675712 -312.695052) (xy 294.69969 -312.694574) (xy 294.722712 -312.695056)
			(xy 294.768218 -312.702087) (xy 294.812158 -312.715857) (xy 294.83304 -312.725562) (xy 294.833548 -312.725562)
			(xy 294.841356 -312.728979) (xy 294.858275 -312.730938) (xy 294.874897 -312.727218) (xy 294.882316 -312.723022)
			(xy 294.955722 -312.677302) (xy 294.962861 -312.672466) (xy 294.97363 -312.659014) (xy 294.979292 -312.64274)
			(xy 294.979598 -312.634122) (xy 294.979598 -312.415682) (xy 294.979248 -312.407079) (xy 294.973542 -312.390846)
			(xy 294.962805 -312.3774) (xy 294.955722 -312.372502) (xy 294.882316 -312.326782) (xy 294.8749 -312.322584)
			(xy 294.858276 -312.318883) (xy 294.841357 -312.320831) (xy 294.833548 -312.324242) (xy 294.833294 -312.324242)
			(xy 294.812387 -312.334002) (xy 294.768362 -312.347803) (xy 294.722759 -312.354806) (xy 294.69969 -312.35523)
			(xy 294.674433 -312.354708) (xy 294.624609 -312.346392) (xy 294.576833 -312.329989) (xy 294.532409 -312.305946)
			(xy 294.492548 -312.27492) (xy 294.458336 -312.237755) (xy 294.430709 -312.195467) (xy 294.410418 -312.149208)
			(xy 294.398018 -312.100241) (xy 294.393847 -312.0499) (xy 294.398018 -311.999559) (xy 294.410418 -311.950592)
			(xy 294.430709 -311.904333) (xy 294.458336 -311.862045) (xy 294.492548 -311.82488) (xy 294.532409 -311.793854)
			(xy 294.576833 -311.769811) (xy 294.624609 -311.753408) (xy 294.674433 -311.745092) (xy 294.69969 -311.744614)
			(xy 294.722712 -311.745096) (xy 294.768219 -311.752126) (xy 294.812159 -311.765893) (xy 294.83304 -311.775602)
			(xy 294.833548 -311.775602) (xy 294.841356 -311.779017) (xy 294.858275 -311.780974) (xy 294.874897 -311.777257)
			(xy 294.882316 -311.773062) (xy 294.955722 -311.727342) (xy 294.962865 -311.722507) (xy 294.973645 -311.709058)
			(xy 294.97932 -311.692782) (xy 294.979598 -311.684162) (xy 294.979598 -311.465722) (xy 294.979255 -311.457116)
			(xy 294.973557 -311.440873) (xy 294.962824 -311.427416) (xy 294.955722 -311.422542) (xy 294.882316 -311.376822)
			(xy 294.874901 -311.372621) (xy 294.858276 -311.368918) (xy 294.841356 -311.370867) (xy 294.833548 -311.374282)
			(xy 294.833294 -311.374282) (xy 294.812387 -311.384041) (xy 294.768361 -311.39784) (xy 294.722758 -311.404842)
			(xy 294.69969 -311.40527) (xy 294.674438 -311.404748) (xy 294.624624 -311.396434) (xy 294.576858 -311.380034)
			(xy 294.532442 -311.355996) (xy 294.492588 -311.324976) (xy 294.458384 -311.287819) (xy 294.430762 -311.245539)
			(xy 294.410475 -311.199289) (xy 294.398077 -311.150331) (xy 294.393907 -311.1) (xy 294.398077 -311.049669)
			(xy 294.410475 -311.000711) (xy 294.430762 -310.954461) (xy 294.458384 -310.912181) (xy 294.492588 -310.875024)
			(xy 294.532442 -310.844004) (xy 294.576858 -310.819966) (xy 294.624624 -310.803566) (xy 294.674438 -310.795252)
			(xy 294.69969 -310.794654) (xy 294.722712 -310.795136) (xy 294.768219 -310.802167) (xy 294.812158 -310.815936)
			(xy 294.83304 -310.825642) (xy 294.833548 -310.825642) (xy 294.841357 -310.829055) (xy 294.858275 -310.831011)
			(xy 294.874897 -310.827296) (xy 294.882316 -310.823102) (xy 294.955722 -310.777382) (xy 294.96287 -310.772549)
			(xy 294.97366 -310.759101) (xy 294.979347 -310.742824) (xy 294.979598 -310.734202) (xy 294.979598 -310.515508)
			(xy 294.979252 -310.506903) (xy 294.973551 -310.490664) (xy 294.962817 -310.47721) (xy 294.955722 -310.472328)
			(xy 294.882316 -310.426608) (xy 294.874901 -310.422408) (xy 294.858276 -310.418706) (xy 294.841356 -310.420654)
			(xy 294.833548 -310.424068) (xy 294.833294 -310.424068) (xy 294.812387 -310.433827) (xy 294.768361 -310.447627)
			(xy 294.722758 -310.454629) (xy 294.69969 -310.455056) (xy 294.674431 -310.454534) (xy 294.624603 -310.446218)
			(xy 294.576823 -310.429813) (xy 294.532394 -310.405769) (xy 294.49253 -310.374739) (xy 294.458316 -310.337572)
			(xy 294.430686 -310.29528) (xy 294.410393 -310.249017) (xy 294.397992 -310.200045) (xy 294.39382 -310.1497)
			(xy 294.397992 -310.099355) (xy 294.410393 -310.050383) (xy 294.430686 -310.00412) (xy 294.458316 -309.961828)
			(xy 294.49253 -309.924661) (xy 294.532394 -309.893631) (xy 294.576823 -309.869587) (xy 294.624603 -309.853182)
			(xy 294.674431 -309.844866) (xy 294.69969 -309.84444) (xy 294.722712 -309.844922) (xy 294.768219 -309.851953)
			(xy 294.812159 -309.865721) (xy 294.83304 -309.875428) (xy 294.833548 -309.875428) (xy 294.841356 -309.878842)
			(xy 294.858275 -309.880798) (xy 294.874897 -309.877082) (xy 294.882316 -309.872888) (xy 294.955722 -309.827168)
			(xy 294.962868 -309.822335) (xy 294.973655 -309.808886) (xy 294.979338 -309.792609) (xy 294.979598 -309.783988)
			(xy 294.979598 -308.982364) (xy 294.979117 -308.972027) (xy 294.970999 -308.953014) (xy 294.96385 -308.945534)
			(xy 294.946308 -308.928118) (xy 294.916528 -308.888667) (xy 294.893487 -308.844937) (xy 294.877786 -308.798068)
			(xy 294.869835 -308.749283) (xy 294.86984 -308.699854) (xy 294.877802 -308.65107) (xy 294.893512 -308.604205)
			(xy 294.916562 -308.560479) (xy 294.94635 -308.521034) (xy 294.96385 -308.503574) (xy 294.97147 -308.496208)
			(xy 294.979598 -308.477412) (xy 294.979598 -308.429152) (xy 294.979166 -308.419086) (xy 294.971439 -308.400494)
			(xy 294.964612 -308.393084) (xy 294.760396 -308.188868) (xy 294.733345 -308.160908) (xy 294.686101 -308.0991)
			(xy 294.647434 -308.031593) (xy 294.632126 -307.995828) (xy 294.62846 -307.987871) (xy 294.616749 -307.974858)
			(xy 294.601353 -307.966523) (xy 294.592756 -307.96484) (xy 294.493188 -307.9496) (xy 294.46855 -307.958998)
			(xy 294.459914 -307.969412) (xy 294.44236 -307.989771) (xy 294.401396 -308.024574) (xy 294.354966 -308.05166)
			(xy 294.30451 -308.070191) (xy 294.251586 -308.079594) (xy 294.22471 -308.080156) (xy 294.199448 -308.079664)
			(xy 294.149612 -308.071349) (xy 294.101825 -308.054945) (xy 294.057389 -308.030899) (xy 294.017518 -307.999867)
			(xy 293.983298 -307.962696) (xy 293.955663 -307.920399) (xy 293.935368 -307.87413) (xy 293.922964 -307.825152)
			(xy 293.918792 -307.7748) (xy 293.922964 -307.724448) (xy 293.935368 -307.67547) (xy 293.955663 -307.629201)
			(xy 293.983298 -307.586904) (xy 294.017518 -307.549733) (xy 294.057389 -307.518701) (xy 294.101825 -307.494655)
			(xy 294.149612 -307.478251) (xy 294.199448 -307.469936) (xy 294.22471 -307.46954) (xy 294.25157 -307.470104)
			(xy 294.304462 -307.479494) (xy 294.354899 -307.497985) (xy 294.401329 -307.525006) (xy 294.44232 -307.559726)
			(xy 294.459914 -307.58003) (xy 294.46855 -307.590444) (xy 294.493188 -307.599842) (xy 294.606218 -307.582316)
			(xy 294.627046 -307.56606) (xy 294.632126 -307.553614) (xy 294.645147 -307.522903) (xy 294.677166 -307.464383)
			(xy 294.715618 -307.409875) (xy 294.760008 -307.360081) (xy 294.809761 -307.315647) (xy 294.864236 -307.277145)
			(xy 294.922727 -307.245073) (xy 294.953436 -307.23205) (xy 294.961391 -307.228385) (xy 294.974396 -307.21667)
			(xy 294.982715 -307.201271) (xy 294.984424 -307.19268) (xy 294.999918 -307.093366) (xy 294.990266 -307.06822)
			(xy 294.979852 -307.059838) (xy 294.959585 -307.042259) (xy 294.924955 -307.001289) (xy 294.898003 -306.954905)
			(xy 294.879557 -306.904531) (xy 294.870182 -306.851711) (xy 294.869616 -306.824888) (xy 294.870138 -306.799633)
			(xy 294.878451 -306.749811) (xy 294.894852 -306.702037) (xy 294.918893 -306.657614) (xy 294.949917 -306.617754)
			(xy 294.987079 -306.583544) (xy 295.029365 -306.555918) (xy 295.075621 -306.535628) (xy 295.124586 -306.523228)
			(xy 295.174924 -306.519057) (xy 295.225262 -306.523228) (xy 295.274227 -306.535628) (xy 295.320483 -306.555918)
			(xy 295.362769 -306.583544) (xy 295.399931 -306.617754) (xy 295.430955 -306.657614) (xy 295.454996 -306.702037)
			(xy 295.471397 -306.749811) (xy 295.47971 -306.799633) (xy 295.480232 -306.824888) (xy 295.479669 -306.851727)
			(xy 295.470281 -306.904576) (xy 295.451792 -306.954969) (xy 295.424772 -307.00135) (xy 295.390056 -307.042289)
			(xy 295.369742 -307.059838) (xy 295.369488 -307.060092) (xy 295.363091 -307.065953) (xy 295.354335 -307.080918)
			(xy 295.351057 -307.097944) (xy 295.351962 -307.106574) (xy 295.367456 -307.206396) (xy 295.383712 -307.227224)
			(xy 295.396158 -307.232304) (xy 295.418238 -307.241563) (xy 295.460962 -307.263181) (xy 295.481502 -307.275484)
			(xy 295.491541 -307.280932) (xy 295.514224 -307.283343) (xy 295.53573 -307.275738) (xy 295.54424 -307.268118)
			(xy 295.66235 -307.150008) (xy 295.669751 -307.143168) (xy 295.688349 -307.135451) (xy 295.698418 -307.135022)
			(xy 295.87825 -307.135022) (xy 295.888317 -307.13459) (xy 295.90691 -307.126866) (xy 295.914318 -307.120036)
			(xy 295.915588 -307.118766) (xy 295.92226 -307.111354) (xy 295.929837 -307.092928) (xy 295.929823 -307.073005)
			(xy 295.922222 -307.054589) (xy 295.915588 -307.047138) (xy 295.914064 -307.045614) (xy 295.913556 -307.04536)
			(xy 295.896126 -307.028002) (xy 295.866537 -306.988708) (xy 295.843635 -306.945176) (xy 295.828013 -306.898534)
			(xy 295.820075 -306.84999) (xy 295.819576 -306.825396) (xy 295.819576 -306.824888) (xy 295.820047 -306.800897)
			(xy 295.827555 -306.753506) (xy 295.842383 -306.707872) (xy 295.864167 -306.66512) (xy 295.892371 -306.626302)
			(xy 295.926299 -306.592373) (xy 295.965117 -306.564169) (xy 296.007869 -306.542385) (xy 296.053502 -306.527556)
			(xy 296.100893 -306.520048) (xy 296.124884 -306.51958) (xy 296.149608 -306.520055) (xy 296.19841 -306.528016)
			(xy 296.245293 -306.543732) (xy 296.289033 -306.566792) (xy 296.328489 -306.596596) (xy 296.36263 -306.632364)
			(xy 296.390565 -306.673164) (xy 296.40149 -306.695348) (xy 296.406765 -306.705205) (xy 296.423927 -306.719491)
			(xy 296.445516 -306.725195) (xy 296.456608 -306.723796) (xy 296.482979 -306.719249) (xy 296.536276 -306.714412)
			(xy 296.563034 -306.714144) (xy 296.757344 -306.714144) (xy 296.766713 -306.713766) (xy 296.784225 -306.707114)
			(xy 296.798171 -306.694606) (xy 296.80281 -306.686458) (xy 296.80281 -306.686204) (xy 296.814125 -306.665045)
			(xy 296.842333 -306.626235) (xy 296.876265 -306.592315) (xy 296.915084 -306.564119) (xy 296.957835 -306.542341)
			(xy 297.003467 -306.527518) (xy 297.050855 -306.520014) (xy 297.098833 -306.520014) (xy 297.146221 -306.527518)
			(xy 297.191853 -306.542341) (xy 297.234604 -306.564119) (xy 297.273423 -306.592315) (xy 297.307355 -306.626235)
			(xy 297.335563 -306.665045) (xy 297.346878 -306.686204) (xy 297.346878 -306.686458) (xy 297.351521 -306.694599)
			(xy 297.365473 -306.707086) (xy 297.38298 -306.713729) (xy 297.392344 -306.714144) (xy 297.707304 -306.714144)
			(xy 297.716677 -306.713773) (xy 297.7342 -306.70713) (xy 297.748157 -306.694624) (xy 297.75277 -306.686458)
			(xy 297.75277 -306.686204) (xy 297.764085 -306.665045) (xy 297.792293 -306.626235) (xy 297.826225 -306.592315)
			(xy 297.865044 -306.564119) (xy 297.907795 -306.542341) (xy 297.953427 -306.527518) (xy 298.000815 -306.520014)
			(xy 298.048793 -306.520014) (xy 298.096181 -306.527518) (xy 298.141813 -306.542341) (xy 298.184564 -306.564119)
			(xy 298.223383 -306.592315) (xy 298.257315 -306.626235) (xy 298.285523 -306.665045) (xy 298.296838 -306.686204)
			(xy 298.296838 -306.686458) (xy 298.301479 -306.694603) (xy 298.315429 -306.707102) (xy 298.332937 -306.713758)
			(xy 298.342304 -306.714144) (xy 298.657264 -306.714144) (xy 298.666631 -306.713763) (xy 298.684137 -306.707106)
			(xy 298.698077 -306.694598) (xy 298.70273 -306.686458) (xy 298.70273 -306.686204) (xy 298.714045 -306.665045)
			(xy 298.742253 -306.626235) (xy 298.776185 -306.592315) (xy 298.815004 -306.564119) (xy 298.857755 -306.542341)
			(xy 298.903387 -306.527518) (xy 298.950775 -306.520014) (xy 298.998753 -306.520014) (xy 299.046141 -306.527518)
			(xy 299.091773 -306.542341) (xy 299.134524 -306.564119) (xy 299.173343 -306.592315) (xy 299.207275 -306.626235)
			(xy 299.235483 -306.665045) (xy 299.246798 -306.686204) (xy 299.246798 -306.686458) (xy 299.251438 -306.694607)
			(xy 299.265386 -306.707117) (xy 299.282895 -306.713786) (xy 299.292264 -306.714144) (xy 299.607224 -306.714144)
			(xy 299.616595 -306.71377) (xy 299.634112 -306.707122) (xy 299.648064 -306.694615) (xy 299.65269 -306.686458)
			(xy 299.65269 -306.686204) (xy 299.664005 -306.665045) (xy 299.692213 -306.626235) (xy 299.726145 -306.592315)
			(xy 299.764964 -306.564119) (xy 299.807715 -306.542341) (xy 299.853347 -306.527518) (xy 299.900735 -306.520014)
			(xy 299.948713 -306.520014) (xy 299.996101 -306.527518) (xy 300.041733 -306.542341) (xy 300.084484 -306.564119)
			(xy 300.123303 -306.592315) (xy 300.157235 -306.626235) (xy 300.185443 -306.665045) (xy 300.196758 -306.686204)
			(xy 300.196758 -306.686458) (xy 300.2014 -306.694601) (xy 300.215351 -306.707094) (xy 300.232859 -306.713743)
			(xy 300.242224 -306.714144) (xy 300.557184 -306.714144) (xy 300.566559 -306.713777) (xy 300.584087 -306.707137)
			(xy 300.598051 -306.694633) (xy 300.60265 -306.686458) (xy 300.60265 -306.686204) (xy 300.613965 -306.665045)
			(xy 300.642173 -306.626235) (xy 300.676105 -306.592315) (xy 300.714924 -306.564119) (xy 300.757675 -306.542341)
			(xy 300.803307 -306.527518) (xy 300.850695 -306.520014) (xy 300.898673 -306.520014) (xy 300.946061 -306.527518)
			(xy 300.991693 -306.542341) (xy 301.034444 -306.564119) (xy 301.073263 -306.592315) (xy 301.107195 -306.626235)
			(xy 301.135403 -306.665045) (xy 301.146718 -306.686204) (xy 301.146718 -306.686458) (xy 301.151358 -306.694605)
			(xy 301.165308 -306.707109) (xy 301.182816 -306.713772) (xy 301.192184 -306.714144) (xy 301.507398 -306.714144)
			(xy 301.516771 -306.713774) (xy 301.534296 -306.707132) (xy 301.548255 -306.694627) (xy 301.552864 -306.686458)
			(xy 301.552864 -306.686204) (xy 301.564179 -306.665045) (xy 301.592387 -306.626235) (xy 301.626319 -306.592315)
			(xy 301.665138 -306.564119) (xy 301.707889 -306.542341) (xy 301.753521 -306.527518) (xy 301.800909 -306.520014)
			(xy 301.848887 -306.520014) (xy 301.896275 -306.527518) (xy 301.941907 -306.542341) (xy 301.984658 -306.564119)
			(xy 302.023477 -306.592315) (xy 302.057409 -306.626235) (xy 302.085617 -306.665045) (xy 302.096932 -306.686204)
			(xy 302.096932 -306.686458) (xy 302.101573 -306.694604) (xy 302.115523 -306.707104) (xy 302.133031 -306.713762)
			(xy 302.142398 -306.714144) (xy 302.457358 -306.714144) (xy 302.466725 -306.713764) (xy 302.484234 -306.707109)
			(xy 302.498175 -306.6946) (xy 302.502824 -306.686458) (xy 302.502824 -306.686204) (xy 302.514139 -306.665045)
			(xy 302.542347 -306.626235) (xy 302.576279 -306.592315) (xy 302.615098 -306.564119) (xy 302.657849 -306.542341)
			(xy 302.703481 -306.527518) (xy 302.750869 -306.520014) (xy 302.798847 -306.520014) (xy 302.846235 -306.527518)
			(xy 302.891867 -306.542341) (xy 302.934618 -306.564119) (xy 302.973437 -306.592315) (xy 303.007369 -306.626235)
			(xy 303.035577 -306.665045) (xy 303.046892 -306.686204) (xy 303.046892 -306.686458) (xy 303.051531 -306.694608)
			(xy 303.065479 -306.707119) (xy 303.082988 -306.71379) (xy 303.092358 -306.714144) (xy 303.407318 -306.714144)
			(xy 303.416689 -306.713771) (xy 303.434209 -306.707124) (xy 303.448162 -306.694618) (xy 303.452784 -306.686458)
			(xy 303.452784 -306.686204) (xy 303.463916 -306.665334) (xy 303.491643 -306.627014) (xy 303.524961 -306.593443)
			(xy 303.56307 -306.565427) (xy 303.583848 -306.554124) (xy 303.591256 -306.549897) (xy 303.602949 -306.537494)
			(xy 303.609931 -306.521943) (xy 303.611026 -306.513484) (xy 303.614641 -306.476547) (xy 303.630019 -306.40394)
			(xy 303.654439 -306.333854) (xy 303.670462 -306.300378) (xy 303.675288 -306.290472) (xy 303.676304 -306.269644)
			(xy 303.645062 -306.189126) (xy 303.640672 -306.179435) (xy 303.62558 -306.164477) (xy 303.615852 -306.16017)
			(xy 303.591459 -306.150269) (xy 303.546226 -306.123341) (xy 303.506282 -306.089055) (xy 303.472809 -306.048427)
			(xy 303.446799 -306.002661) (xy 303.429023 -305.953112) (xy 303.420008 -305.901249) (xy 303.41951 -305.874928)
			(xy 303.420049 -305.848064) (xy 303.429407 -305.795158) (xy 303.447891 -305.744711) (xy 303.47493 -305.698283)
			(xy 303.509686 -305.657313) (xy 303.53 -305.639724) (xy 303.530508 -305.639724) (xy 303.530508 -305.63947)
			(xy 303.536913 -305.633611) (xy 303.545689 -305.618647) (xy 303.548987 -305.601616) (xy 303.548034 -305.592988)
			(xy 303.53254 -305.493166) (xy 303.516284 -305.472338) (xy 303.503838 -305.467258) (xy 303.473131 -305.454234)
			(xy 303.414617 -305.422209) (xy 303.360115 -305.383752) (xy 303.310329 -305.339359) (xy 303.265901 -305.289604)
			(xy 303.227406 -305.235129) (xy 303.195341 -305.176638) (xy 303.182274 -305.145948) (xy 303.178608 -305.137993)
			(xy 303.166894 -305.124987) (xy 303.151496 -305.116664) (xy 303.142904 -305.11496) (xy 303.056798 -305.101498)
			(xy 303.048169 -305.100545) (xy 303.031135 -305.10383) (xy 303.016177 -305.112619) (xy 303.010316 -305.119024)
			(xy 303.010062 -305.119278) (xy 302.992498 -305.139626) (xy 302.951524 -305.174411) (xy 302.905096 -305.201492)
			(xy 302.854647 -305.220033) (xy 302.801732 -305.229463) (xy 302.774858 -305.230022) (xy 302.749604 -305.229497)
			(xy 302.699785 -305.221178) (xy 302.652015 -305.204772) (xy 302.607596 -305.180729) (xy 302.567741 -305.149702)
			(xy 302.533534 -305.11254) (xy 302.505911 -305.070254) (xy 302.485624 -305.023999) (xy 302.473226 -304.975036)
			(xy 302.469055 -304.9247) (xy 302.473226 -304.874364) (xy 302.485624 -304.825401) (xy 302.505911 -304.779146)
			(xy 302.533534 -304.73686) (xy 302.567741 -304.699698) (xy 302.607596 -304.668671) (xy 302.652015 -304.644628)
			(xy 302.699785 -304.628222) (xy 302.749604 -304.619903) (xy 302.774858 -304.619406) (xy 302.801731 -304.619991)
			(xy 302.854642 -304.629427) (xy 302.90509 -304.647963) (xy 302.951524 -304.675028) (xy 302.992515 -304.70979)
			(xy 303.010062 -304.73015) (xy 303.010062 -304.730404) (xy 303.010316 -304.730404) (xy 303.016174 -304.736812)
			(xy 303.031138 -304.745592) (xy 303.048171 -304.748895) (xy 303.056798 -304.74793) (xy 303.142904 -304.734468)
			(xy 303.151514 -304.732806) (xy 303.166941 -304.724499) (xy 303.178648 -304.711463) (xy 303.182274 -304.70348)
			(xy 303.197549 -304.667698) (xy 303.236208 -304.600182) (xy 303.283478 -304.538388) (xy 303.310544 -304.51044)
			(xy 303.497996 -304.322988) (xy 303.504603 -304.315816) (xy 303.512307 -304.297919) (xy 303.512982 -304.28819)
			(xy 303.514252 -304.217578) (xy 303.514026 -304.207881) (xy 303.507255 -304.18972) (xy 303.501044 -304.182272)
			(xy 303.50079 -304.182018) (xy 303.485605 -304.165006) (xy 303.459938 -304.127316) (xy 303.440171 -304.086224)
			(xy 303.426745 -304.042646) (xy 303.41996 -303.997554) (xy 303.41951 -303.974754) (xy 303.419984 -303.950766)
			(xy 303.427496 -303.903381) (xy 303.442328 -303.857754) (xy 303.464114 -303.815009) (xy 303.492318 -303.776198)
			(xy 303.526247 -303.742277) (xy 303.565064 -303.71408) (xy 303.607813 -303.692303) (xy 303.653443 -303.677481)
			(xy 303.70083 -303.669979) (xy 303.724818 -303.669446) (xy 303.748712 -303.669909) (xy 303.795917 -303.677349)
			(xy 303.841388 -303.692044) (xy 303.884019 -303.713637) (xy 303.92277 -303.741602) (xy 303.956697 -303.775257)
			(xy 303.984972 -303.813781) (xy 303.996344 -303.8348) (xy 303.996344 -303.835308) (xy 304.000381 -303.842341)
			(xy 304.012045 -303.853594) (xy 304.019204 -303.857406) (xy 304.046382 -303.87036) (xy 304.054054 -303.873689)
			(xy 304.070639 -303.875763) (xy 304.078894 -303.874424) (xy 304.109194 -303.868286) (xy 304.170664 -303.861666)
			(xy 304.201576 -303.861216) (xy 304.358802 -303.861216) (xy 304.368092 -303.860796) (xy 304.385455 -303.854173)
			(xy 304.399342 -303.841826) (xy 304.404014 -303.833784) (xy 304.417629 -303.808899) (xy 304.452607 -303.764249)
			(xy 304.495237 -303.726837) (xy 304.51933 -303.711864) (xy 304.526831 -303.707114) (xy 304.538195 -303.693488)
			(xy 304.544209 -303.676795) (xy 304.544476 -303.667922) (xy 304.544476 -303.331626) (xy 304.54409 -303.322775)
			(xy 304.538068 -303.306128) (xy 304.526762 -303.292506) (xy 304.51933 -303.287684) (xy 304.498607 -303.274861)
			(xy 304.461149 -303.24369) (xy 304.429115 -303.206969) (xy 304.403316 -303.165628) (xy 304.384406 -303.120717)
			(xy 304.372865 -303.073373) (xy 304.368985 -303.024797) (xy 304.372866 -302.976221) (xy 304.384408 -302.928877)
			(xy 304.403318 -302.883966) (xy 304.429119 -302.842626) (xy 304.461154 -302.805905) (xy 304.498612 -302.774736)
			(xy 304.51933 -302.761904) (xy 304.526824 -302.757151) (xy 304.538172 -302.743522) (xy 304.544166 -302.726831)
			(xy 304.544476 -302.717962) (xy 304.544476 -302.381666) (xy 304.544097 -302.372812) (xy 304.538083 -302.356155)
			(xy 304.52678 -302.342522) (xy 304.51933 -302.337724) (xy 304.498603 -302.324901) (xy 304.46114 -302.293729)
			(xy 304.429099 -302.257006) (xy 304.403294 -302.215662) (xy 304.384379 -302.170747) (xy 304.372834 -302.123398)
			(xy 304.368951 -302.074817) (xy 304.372828 -302.026236) (xy 304.384369 -301.978886) (xy 304.403278 -301.933968)
			(xy 304.429079 -301.892622) (xy 304.461115 -301.855895) (xy 304.498575 -301.824719) (xy 304.51933 -301.811944)
			(xy 304.526828 -301.807193) (xy 304.538187 -301.793566) (xy 304.544194 -301.776873) (xy 304.544476 -301.768002)
			(xy 304.544476 -301.431706) (xy 304.544087 -301.422857) (xy 304.538061 -301.406215) (xy 304.526753 -301.392599)
			(xy 304.51933 -301.387764) (xy 304.498608 -301.374941) (xy 304.461154 -301.343771) (xy 304.429123 -301.307051)
			(xy 304.403326 -301.265712) (xy 304.384419 -301.220802) (xy 304.37288 -301.17346) (xy 304.369002 -301.124887)
			(xy 304.372884 -301.076314) (xy 304.384427 -301.028973) (xy 304.403338 -300.984065) (xy 304.429138 -300.942728)
			(xy 304.461173 -300.906011) (xy 304.49863 -300.874844) (xy 304.51933 -300.861984) (xy 304.526822 -300.857231)
			(xy 304.538164 -300.8436) (xy 304.544153 -300.82691) (xy 304.544476 -300.818042) (xy 304.544476 -300.481746)
			(xy 304.544094 -300.472893) (xy 304.538076 -300.456242) (xy 304.526771 -300.442614) (xy 304.51933 -300.437804)
			(xy 304.498605 -300.424981) (xy 304.461145 -300.39381) (xy 304.429107 -300.357088) (xy 304.403305 -300.315745)
			(xy 304.384393 -300.270832) (xy 304.372849 -300.223485) (xy 304.368968 -300.174907) (xy 304.372847 -300.126329)
			(xy 304.384388 -300.078982) (xy 304.403298 -300.034067) (xy 304.429099 -299.992724) (xy 304.461134 -299.956)
			(xy 304.498593 -299.924827) (xy 304.51933 -299.912024) (xy 304.526826 -299.907272) (xy 304.538179 -299.893644)
			(xy 304.54418 -299.876952) (xy 304.544476 -299.868082) (xy 304.544476 -299.531786) (xy 304.544084 -299.522939)
			(xy 304.538053 -299.506302) (xy 304.526744 -299.492691) (xy 304.51933 -299.487844) (xy 304.49861 -299.475021)
			(xy 304.461159 -299.443851) (xy 304.42913 -299.407132) (xy 304.403337 -299.365795) (xy 304.384432 -299.320887)
			(xy 304.372895 -299.273547) (xy 304.36902 -299.224977) (xy 304.372903 -299.176407) (xy 304.384447 -299.129069)
			(xy 304.403358 -299.084164) (xy 304.429158 -299.04283) (xy 304.461192 -299.006116) (xy 304.498648 -298.974952)
			(xy 304.51933 -298.962064) (xy 304.526831 -298.957314) (xy 304.538195 -298.943688) (xy 304.544209 -298.926995)
			(xy 304.544476 -298.918122) (xy 304.544476 -298.581572) (xy 304.544082 -298.572726) (xy 304.538048 -298.556093)
			(xy 304.526738 -298.542486) (xy 304.51933 -298.53763) (xy 304.496903 -298.523696) (xy 304.456779 -298.489384)
			(xy 304.423145 -298.44869) (xy 304.397003 -298.402822) (xy 304.379127 -298.353146) (xy 304.370052 -298.301137)
			(xy 304.36947 -298.27474) (xy 304.370018 -298.248525) (xy 304.378981 -298.196865) (xy 304.396634 -298.147495)
			(xy 304.422458 -298.101865) (xy 304.455695 -298.061315) (xy 304.495369 -298.027036) (xy 304.540313 -298.000035)
			(xy 304.564542 -297.990006) (xy 304.573738 -297.985852) (xy 304.588259 -297.97187) (xy 304.592736 -297.962828)
			(xy 304.607881 -297.929357) (xy 304.645315 -297.866144) (xy 304.690357 -297.808105) (xy 304.715926 -297.781726)
			(xy 304.789586 -297.708066) (xy 304.79631 -297.700633) (xy 304.803961 -297.682129) (xy 304.803968 -297.662106)
			(xy 304.79633 -297.643597) (xy 304.789586 -297.636184) (xy 304.768758 -297.615356) (xy 304.746 -297.622215)
			(xy 304.69905 -297.629616) (xy 304.675286 -297.630088) (xy 304.674778 -297.630088) (xy 304.64996 -297.6296)
			(xy 304.600977 -297.621567) (xy 304.553939 -297.605715) (xy 304.510086 -297.582462) (xy 304.470572 -297.552421)
			(xy 304.436438 -297.516383) (xy 304.408584 -297.475297) (xy 304.387744 -297.430247) (xy 304.374466 -297.382419)
			(xy 304.369101 -297.333073) (xy 304.371789 -297.283509) (xy 304.382461 -297.235032) (xy 304.400834 -297.188921)
			(xy 304.426425 -297.14639) (xy 304.45856 -297.108558) (xy 304.496391 -297.076424) (xy 304.538923 -297.050833)
			(xy 304.585034 -297.03246) (xy 304.633511 -297.021789) (xy 304.683075 -297.019101) (xy 304.732421 -297.024467)
			(xy 304.780249 -297.037745) (xy 304.825299 -297.058585) (xy 304.866384 -297.086439) (xy 304.902422 -297.120573)
			(xy 304.932463 -297.160087) (xy 304.955715 -297.203941) (xy 304.971567 -297.250979) (xy 304.979601 -297.299962)
			(xy 304.980086 -297.32478) (xy 304.979836 -297.341818) (xy 304.976015 -297.375678) (xy 304.972466 -297.392344)
			(xy 304.972466 -297.392598) (xy 304.970904 -297.400984) (xy 304.972807 -297.417927) (xy 304.980151 -297.433313)
			(xy 304.985928 -297.439588) (xy 304.986182 -297.439588) (xy 304.993548 -297.446428) (xy 305.012081 -297.45417)
			(xy 305.032165 -297.45417) (xy 305.050698 -297.446428) (xy 305.058064 -297.439588) (xy 305.112166 -297.385486)
			(xy 305.140345 -297.358227) (xy 305.202714 -297.310717) (xy 305.270863 -297.271954) (xy 305.306984 -297.256708)
			(xy 305.316903 -297.252069) (xy 305.331916 -297.236156) (xy 305.33594 -297.225974) (xy 305.344036 -297.203705)
			(xy 305.366122 -297.161784) (xy 305.394417 -297.123777) (xy 305.428242 -297.090596) (xy 305.466785 -297.063037)
			(xy 305.509122 -297.04176) (xy 305.554237 -297.027277) (xy 305.601047 -297.019935) (xy 305.624738 -297.019472)
			(xy 305.648725 -297.019945) (xy 305.696107 -297.027451) (xy 305.741734 -297.042273) (xy 305.784481 -297.064046)
			(xy 305.8233 -297.092235) (xy 305.857233 -297.126146) (xy 305.885448 -297.164945) (xy 305.896772 -297.186096)
			(xy 305.896772 -297.18635) (xy 305.901414 -297.194492) (xy 305.915366 -297.206984) (xy 305.932873 -297.213629)
			(xy 305.942238 -297.214036) (xy 306.257452 -297.214036) (xy 306.26682 -297.213657) (xy 306.284329 -297.207002)
			(xy 306.298271 -297.194493) (xy 306.302918 -297.18635) (xy 306.302918 -297.186096) (xy 306.314233 -297.164937)
			(xy 306.342441 -297.126127) (xy 306.376373 -297.092207) (xy 306.415192 -297.064011) (xy 306.457943 -297.042233)
			(xy 306.503575 -297.02741) (xy 306.550963 -297.019906) (xy 306.598941 -297.019906) (xy 306.646329 -297.02741)
			(xy 306.691961 -297.042233) (xy 306.734712 -297.064011) (xy 306.773531 -297.092207) (xy 306.807463 -297.126127)
			(xy 306.835671 -297.164937) (xy 306.846986 -297.186096) (xy 306.846986 -297.18635) (xy 306.851624 -297.194502)
			(xy 306.865572 -297.207017) (xy 306.883081 -297.213691) (xy 306.892452 -297.214036) (xy 307.207412 -297.214036)
			(xy 307.216783 -297.213664) (xy 307.234304 -297.207018) (xy 307.248257 -297.194511) (xy 307.252878 -297.18635)
			(xy 307.252878 -297.186096) (xy 307.264193 -297.164937) (xy 307.292401 -297.126127) (xy 307.326333 -297.092207)
			(xy 307.365152 -297.064011) (xy 307.407903 -297.042233) (xy 307.453535 -297.02741) (xy 307.500923 -297.019906)
			(xy 307.548901 -297.019906) (xy 307.596289 -297.02741) (xy 307.641921 -297.042233) (xy 307.684672 -297.064011)
			(xy 307.723491 -297.092207) (xy 307.757423 -297.126127) (xy 307.785631 -297.164937) (xy 307.796946 -297.186096)
			(xy 307.796946 -297.18635) (xy 307.801587 -297.194495) (xy 307.815537 -297.206993) (xy 307.833045 -297.213648)
			(xy 307.842412 -297.214036) (xy 308.157372 -297.214036) (xy 308.166738 -297.213654) (xy 308.184241 -297.206995)
			(xy 308.198177 -297.194484) (xy 308.202838 -297.18635) (xy 308.202838 -297.186096) (xy 308.214153 -297.164937)
			(xy 308.242361 -297.126127) (xy 308.276293 -297.092207) (xy 308.315112 -297.064011) (xy 308.357863 -297.042233)
			(xy 308.403495 -297.02741) (xy 308.450883 -297.019906) (xy 308.498861 -297.019906) (xy 308.546249 -297.02741)
			(xy 308.591881 -297.042233) (xy 308.634632 -297.064011) (xy 308.673451 -297.092207) (xy 308.707383 -297.126127)
			(xy 308.735591 -297.164937) (xy 308.746906 -297.186096) (xy 308.746906 -297.18635) (xy 308.751545 -297.1945)
			(xy 308.765493 -297.207009) (xy 308.783003 -297.213677) (xy 308.792372 -297.214036) (xy 309.107332 -297.214036)
			(xy 309.116702 -297.21366) (xy 309.134216 -297.20701) (xy 309.148164 -297.194502) (xy 309.152798 -297.18635)
			(xy 309.152798 -297.186096) (xy 309.164113 -297.164937) (xy 309.192321 -297.126127) (xy 309.226253 -297.092207)
			(xy 309.265072 -297.064011) (xy 309.307823 -297.042233) (xy 309.353455 -297.02741) (xy 309.400843 -297.019906)
			(xy 309.448821 -297.019906) (xy 309.496209 -297.02741) (xy 309.541841 -297.042233) (xy 309.584592 -297.064011)
			(xy 309.623411 -297.092207) (xy 309.657343 -297.126127) (xy 309.685551 -297.164937) (xy 309.696866 -297.186096)
			(xy 309.696866 -297.18635) (xy 309.701508 -297.194493) (xy 309.715459 -297.206986) (xy 309.732967 -297.213633)
			(xy 309.742332 -297.214036) (xy 310.057292 -297.214036) (xy 310.066665 -297.213667) (xy 310.084191 -297.207026)
			(xy 310.098151 -297.19452) (xy 310.102758 -297.18635) (xy 310.102758 -297.186096) (xy 310.114073 -297.164937)
			(xy 310.142281 -297.126127) (xy 310.176213 -297.092207) (xy 310.215032 -297.064011) (xy 310.257783 -297.042233)
			(xy 310.303415 -297.02741) (xy 310.350803 -297.019906) (xy 310.398781 -297.019906) (xy 310.446169 -297.02741)
			(xy 310.491801 -297.042233) (xy 310.534552 -297.064011) (xy 310.573371 -297.092207) (xy 310.607303 -297.126127)
			(xy 310.635511 -297.164937) (xy 310.646826 -297.186096) (xy 310.646826 -297.18635) (xy 310.651466 -297.194497)
			(xy 310.665415 -297.207001) (xy 310.682924 -297.213662) (xy 310.692292 -297.214036) (xy 311.007252 -297.214036)
			(xy 311.01662 -297.213657) (xy 311.034129 -297.207002) (xy 311.048071 -297.194493) (xy 311.052718 -297.18635)
			(xy 311.052718 -297.186096) (xy 311.064033 -297.164937) (xy 311.092241 -297.126127) (xy 311.126173 -297.092207)
			(xy 311.164992 -297.064011) (xy 311.207743 -297.042233) (xy 311.253375 -297.02741) (xy 311.300763 -297.019906)
			(xy 311.348741 -297.019906) (xy 311.396129 -297.02741) (xy 311.441761 -297.042233) (xy 311.484512 -297.064011)
			(xy 311.523331 -297.092207) (xy 311.557263 -297.126127) (xy 311.585471 -297.164937) (xy 311.596786 -297.186096)
			(xy 311.596786 -297.18635) (xy 311.601424 -297.194502) (xy 311.615372 -297.207017) (xy 311.632881 -297.213691)
			(xy 311.642252 -297.214036) (xy 311.957212 -297.214036) (xy 311.966583 -297.213664) (xy 311.984104 -297.207018)
			(xy 311.998057 -297.194511) (xy 312.002678 -297.18635) (xy 312.002678 -297.186096) (xy 312.013993 -297.164937)
			(xy 312.042201 -297.126127) (xy 312.076133 -297.092207) (xy 312.114952 -297.064011) (xy 312.157703 -297.042233)
			(xy 312.203335 -297.02741) (xy 312.250723 -297.019906) (xy 312.298701 -297.019906) (xy 312.346089 -297.02741)
			(xy 312.391721 -297.042233) (xy 312.434472 -297.064011) (xy 312.473291 -297.092207) (xy 312.507223 -297.126127)
			(xy 312.535431 -297.164937) (xy 312.546746 -297.186096) (xy 312.546746 -297.18635) (xy 312.551387 -297.194495)
			(xy 312.565337 -297.206993) (xy 312.582845 -297.213648) (xy 312.592212 -297.214036) (xy 312.907426 -297.214036)
			(xy 312.916796 -297.213661) (xy 312.934313 -297.207012) (xy 312.948262 -297.194505) (xy 312.952892 -297.18635)
			(xy 312.952892 -297.186096) (xy 312.964207 -297.164937) (xy 312.992415 -297.126127) (xy 313.026347 -297.092207)
			(xy 313.065166 -297.064011) (xy 313.107917 -297.042233) (xy 313.153549 -297.02741) (xy 313.200937 -297.019906)
			(xy 313.248915 -297.019906) (xy 313.296303 -297.02741) (xy 313.341935 -297.042233) (xy 313.384686 -297.064011)
			(xy 313.423505 -297.092207) (xy 313.457437 -297.126127) (xy 313.485645 -297.164937) (xy 313.49696 -297.186096)
			(xy 313.49696 -297.18635) (xy 313.501602 -297.194493) (xy 313.515552 -297.206988) (xy 313.53306 -297.213638)
			(xy 313.542426 -297.214036) (xy 313.857386 -297.214036) (xy 313.86676 -297.213668) (xy 313.884288 -297.207028)
			(xy 313.898249 -297.194522) (xy 313.902852 -297.18635) (xy 313.902852 -297.186096) (xy 313.914167 -297.164937)
			(xy 313.942375 -297.126127) (xy 313.976307 -297.092207) (xy 314.015126 -297.064011) (xy 314.057877 -297.042233)
			(xy 314.103509 -297.02741) (xy 314.150897 -297.019906) (xy 314.198875 -297.019906) (xy 314.246263 -297.02741)
			(xy 314.291895 -297.042233) (xy 314.334646 -297.064011) (xy 314.373465 -297.092207) (xy 314.407397 -297.126127)
			(xy 314.435605 -297.164937) (xy 314.44692 -297.186096) (xy 314.44692 -297.18635) (xy 314.45156 -297.194498)
			(xy 314.465509 -297.207004) (xy 314.483018 -297.213667) (xy 314.492386 -297.214036) (xy 314.807346 -297.214036)
			(xy 314.816714 -297.213658) (xy 314.834225 -297.207005) (xy 314.848169 -297.194496) (xy 314.852812 -297.18635)
			(xy 314.852812 -297.186096) (xy 314.864105 -297.164927) (xy 314.892315 -297.126118) (xy 314.92625 -297.092203)
			(xy 314.965074 -297.064014) (xy 315.007831 -297.042248) (xy 315.053466 -297.027441) (xy 315.100857 -297.019956)
			(xy 315.124846 -297.019472) (xy 315.1251 -297.019472) (xy 315.141877 -297.019692) (xy 315.175228 -297.023385)
			(xy 315.191648 -297.026838) (xy 315.191902 -297.026838) (xy 315.200307 -297.028346) (xy 315.217254 -297.02634)
			(xy 315.232621 -297.018917) (xy 315.238892 -297.013122) (xy 315.372242 -296.879772) (xy 315.37909 -296.872375)
			(xy 315.386824 -296.853776) (xy 315.387228 -296.843704) (xy 315.387228 -296.748708) (xy 315.386553 -296.736066)
			(xy 315.37455 -296.713814) (xy 315.364368 -296.70629) (xy 315.292994 -296.659554) (xy 315.282172 -296.653277)
			(xy 315.257282 -296.651034) (xy 315.245496 -296.655236) (xy 315.245242 -296.655236) (xy 315.226147 -296.663077)
			(xy 315.186379 -296.674137) (xy 315.145484 -296.679755) (xy 315.124846 -296.680128) (xy 315.099584 -296.679639)
			(xy 315.049749 -296.67133) (xy 315.00196 -296.65493) (xy 314.957524 -296.630888) (xy 314.917651 -296.59986)
			(xy 314.88343 -296.562691) (xy 314.855793 -296.520396) (xy 314.835497 -296.474128) (xy 314.823093 -296.425151)
			(xy 314.81892 -296.3748) (xy 314.823093 -296.324449) (xy 314.835497 -296.275472) (xy 314.855793 -296.229204)
			(xy 314.88343 -296.186909) (xy 314.917651 -296.14974) (xy 314.957524 -296.118712) (xy 315.001961 -296.09467)
			(xy 315.049749 -296.07827) (xy 315.099584 -296.069961) (xy 315.124846 -296.069512) (xy 315.145487 -296.069866)
			(xy 315.186387 -296.075465) (xy 315.226155 -296.08654) (xy 315.245242 -296.094404) (xy 315.245496 -296.094404)
			(xy 315.257266 -296.098691) (xy 315.28218 -296.096412) (xy 315.292994 -296.090086) (xy 315.364368 -296.04335)
			(xy 315.374556 -296.035833) (xy 315.386555 -296.013575) (xy 315.387228 -296.000932) (xy 315.387228 -294.848788)
			(xy 315.386548 -294.836149) (xy 315.374541 -294.813904) (xy 315.364368 -294.80637) (xy 315.292994 -294.759634)
			(xy 315.282171 -294.753359) (xy 315.257283 -294.751117) (xy 315.245496 -294.755316) (xy 315.245242 -294.755316)
			(xy 315.226148 -294.763158) (xy 315.186379 -294.774219) (xy 315.145485 -294.779837) (xy 315.124846 -294.780208)
			(xy 315.099586 -294.779719) (xy 315.049753 -294.77141) (xy 315.001969 -294.755012) (xy 314.957535 -294.730972)
			(xy 314.917665 -294.699945) (xy 314.883445 -294.662778) (xy 314.855811 -294.620486) (xy 314.835515 -294.574222)
			(xy 314.823112 -294.525248) (xy 314.81894 -294.4749) (xy 314.823112 -294.424552) (xy 314.835515 -294.375578)
			(xy 314.855811 -294.329314) (xy 314.883445 -294.287022) (xy 314.917665 -294.249855) (xy 314.957535 -294.218828)
			(xy 315.001969 -294.194788) (xy 315.049753 -294.17839) (xy 315.099586 -294.170081) (xy 315.124846 -294.169592)
			(xy 315.145486 -294.169946) (xy 315.186386 -294.175547) (xy 315.226153 -294.186625) (xy 315.245242 -294.194484)
			(xy 315.245496 -294.194484) (xy 315.257266 -294.198772) (xy 315.28218 -294.196492) (xy 315.292994 -294.190166)
			(xy 315.364368 -294.14343) (xy 315.374553 -294.135912) (xy 315.386543 -294.113653) (xy 315.387228 -294.101012)
			(xy 315.387228 -293.898828) (xy 315.386557 -293.886184) (xy 315.37456 -293.863924) (xy 315.364368 -293.85641)
			(xy 315.292994 -293.809674) (xy 315.282172 -293.803395) (xy 315.257282 -293.801152) (xy 315.245496 -293.805356)
			(xy 315.245242 -293.805356) (xy 315.226147 -293.813197) (xy 315.186378 -293.824256) (xy 315.145484 -293.829874)
			(xy 315.124846 -293.830248) (xy 315.099582 -293.829759) (xy 315.049744 -293.821449) (xy 315.001952 -293.805049)
			(xy 314.957513 -293.781005) (xy 314.917637 -293.749974) (xy 314.883414 -293.712803) (xy 314.855776 -293.670505)
			(xy 314.835478 -293.624235) (xy 314.823073 -293.575254) (xy 314.8189 -293.5249) (xy 314.823073 -293.474546)
			(xy 314.835478 -293.425565) (xy 314.855776 -293.379295) (xy 314.883414 -293.336997) (xy 314.917637 -293.299826)
			(xy 314.957513 -293.268795) (xy 315.001952 -293.244751) (xy 315.049744 -293.228351) (xy 315.099582 -293.220041)
			(xy 315.124846 -293.219632) (xy 315.145487 -293.219986) (xy 315.186387 -293.225586) (xy 315.226154 -293.236661)
			(xy 315.245242 -293.244524) (xy 315.245496 -293.244524) (xy 315.257265 -293.248816) (xy 315.28218 -293.246533)
			(xy 315.292994 -293.240206) (xy 315.364368 -293.19347) (xy 315.374559 -293.185954) (xy 315.386567 -293.163696)
			(xy 315.387228 -293.151052) (xy 315.387228 -292.948868) (xy 315.386544 -292.936231) (xy 315.374532 -292.913994)
			(xy 315.364368 -292.90645) (xy 315.292994 -292.859714) (xy 315.282171 -292.853441) (xy 315.257283 -292.8512)
			(xy 315.245496 -292.855396) (xy 315.245242 -292.855396) (xy 315.226147 -292.863238) (xy 315.186379 -292.874299)
			(xy 315.145485 -292.879918) (xy 315.124846 -292.880288) (xy 315.099587 -292.879799) (xy 315.049758 -292.871491)
			(xy 315.001977 -292.855094) (xy 314.957546 -292.831055) (xy 314.917678 -292.80003) (xy 314.883461 -292.762866)
			(xy 314.855829 -292.720577) (xy 314.835534 -292.674315) (xy 314.823132 -292.625344) (xy 314.81896 -292.575)
			(xy 314.823132 -292.524656) (xy 314.835534 -292.475685) (xy 314.855829 -292.429423) (xy 314.883461 -292.387134)
			(xy 314.917678 -292.34997) (xy 314.957546 -292.318945) (xy 315.001977 -292.294906) (xy 315.049758 -292.278509)
			(xy 315.099587 -292.270201) (xy 315.124846 -292.269672) (xy 315.145486 -292.270026) (xy 315.186386 -292.275626)
			(xy 315.226154 -292.286704) (xy 315.245242 -292.294564) (xy 315.245496 -292.294564) (xy 315.257266 -292.298853)
			(xy 315.28218 -292.296573) (xy 315.292994 -292.290246) (xy 315.364368 -292.24351) (xy 315.374549 -292.23599)
			(xy 315.386531 -292.213731) (xy 315.387228 -292.201092) (xy 315.387228 -291.998654) (xy 315.386563 -291.986007)
			(xy 315.374571 -291.963737) (xy 315.364368 -291.956236) (xy 315.292994 -291.9095) (xy 315.282171 -291.903228)
			(xy 315.257284 -291.900988) (xy 315.245496 -291.905182) (xy 315.245242 -291.905182) (xy 315.226148 -291.913024)
			(xy 315.186379 -291.924086) (xy 315.145485 -291.929705) (xy 315.124846 -291.930074) (xy 315.099589 -291.929585)
			(xy 315.049762 -291.921277) (xy 315.001982 -291.904881) (xy 314.957553 -291.880843) (xy 314.917688 -291.84982)
			(xy 314.883472 -291.812658) (xy 314.855841 -291.77037) (xy 314.835548 -291.724111) (xy 314.823146 -291.675142)
			(xy 314.818974 -291.6248) (xy 314.823146 -291.574458) (xy 314.835548 -291.525489) (xy 314.855841 -291.47923)
			(xy 314.883472 -291.436942) (xy 314.917688 -291.39978) (xy 314.957553 -291.368757) (xy 315.001982 -291.344719)
			(xy 315.049762 -291.328323) (xy 315.099589 -291.320015) (xy 315.124846 -291.319458) (xy 315.145487 -291.319812)
			(xy 315.186386 -291.325412) (xy 315.226154 -291.336489) (xy 315.245242 -291.34435) (xy 315.245496 -291.34435)
			(xy 315.257266 -291.34864) (xy 315.28218 -291.346359) (xy 315.292994 -291.340032) (xy 315.364368 -291.293296)
			(xy 315.374547 -291.285775) (xy 315.386523 -291.263516) (xy 315.387228 -291.250878) (xy 315.387228 -291.048694)
			(xy 315.38655 -291.036054) (xy 315.374544 -291.013807) (xy 315.364368 -291.006276) (xy 315.292994 -290.95954)
			(xy 315.282172 -290.953264) (xy 315.257283 -290.951022) (xy 315.245496 -290.955222) (xy 315.245242 -290.955222)
			(xy 315.226147 -290.963063) (xy 315.186379 -290.974124) (xy 315.145485 -290.979742) (xy 315.124846 -290.980114)
			(xy 315.099585 -290.979625) (xy 315.049752 -290.971316) (xy 315.001966 -290.954918) (xy 314.957532 -290.930877)
			(xy 314.91766 -290.899849) (xy 314.883441 -290.862682) (xy 314.855806 -290.820389) (xy 314.83551 -290.774124)
			(xy 314.823106 -290.725149) (xy 314.818934 -290.6748) (xy 314.823106 -290.624451) (xy 314.83551 -290.575476)
			(xy 314.855806 -290.529211) (xy 314.883441 -290.486918) (xy 314.91766 -290.449751) (xy 314.957532 -290.418723)
			(xy 315.001966 -290.394682) (xy 315.049752 -290.378284) (xy 315.099585 -290.369975) (xy 315.124846 -290.369498)
			(xy 315.145487 -290.369852) (xy 315.186387 -290.375451) (xy 315.226155 -290.386526) (xy 315.245242 -290.39439)
			(xy 315.245496 -290.39439) (xy 315.257266 -290.398678) (xy 315.28218 -290.396399) (xy 315.292994 -290.390072)
			(xy 315.364368 -290.343336) (xy 315.374554 -290.335818) (xy 315.386547 -290.31356) (xy 315.387228 -290.300918)
			(xy 315.387228 -290.098734) (xy 315.386558 -290.086089) (xy 315.374562 -290.063827) (xy 315.364368 -290.056316)
			(xy 315.292994 -290.00958) (xy 315.282172 -290.003301) (xy 315.257282 -290.001057) (xy 315.245496 -290.005262)
			(xy 315.245242 -290.005262) (xy 315.226147 -290.013102) (xy 315.186378 -290.024162) (xy 315.145484 -290.029779)
			(xy 315.124846 -290.030154) (xy 315.099582 -290.029665) (xy 315.049742 -290.021355) (xy 315.00195 -290.004954)
			(xy 314.95751 -289.98091) (xy 314.917633 -289.949879) (xy 314.883409 -289.912707) (xy 314.855771 -289.870408)
			(xy 314.835472 -289.824137) (xy 314.823067 -289.775155) (xy 314.818894 -289.7248) (xy 314.823067 -289.674445)
			(xy 314.835472 -289.625463) (xy 314.855771 -289.579192) (xy 314.883409 -289.536893) (xy 314.917633 -289.499721)
			(xy 314.95751 -289.46869) (xy 315.00195 -289.444646) (xy 315.049742 -289.428245) (xy 315.099582 -289.419935)
			(xy 315.124846 -289.419538) (xy 315.145487 -289.419892) (xy 315.186386 -289.425492) (xy 315.226154 -289.436568)
			(xy 315.245242 -289.44443) (xy 315.245496 -289.44443) (xy 315.257265 -289.448721) (xy 315.28218 -289.446439)
			(xy 315.292994 -289.440112) (xy 315.364368 -289.393376) (xy 315.37456 -289.385861) (xy 315.386571 -289.363603)
			(xy 315.387228 -289.350958) (xy 315.387228 -289.310826) (xy 315.373766 -289.287458) (xy 315.364368 -289.282124)
			(xy 315.363098 -289.281362) (xy 315.359842 -289.279528) (xy 315.353844 -289.275072) (xy 315.35116 -289.272472)
			(xy 315.172598 -289.09391) (xy 315.163454 -289.086798) (xy 315.159898 -289.08502) (xy 315.147198 -289.07994)
			(xy 315.134752 -289.07994) (xy 315.1251 -289.080194) (xy 315.124592 -289.080194) (xy 315.101054 -289.079735)
			(xy 315.054543 -289.072464) (xy 315.009699 -289.058142) (xy 314.967583 -289.037108) (xy 314.929194 -289.00986)
			(xy 314.895441 -288.977044) (xy 314.867123 -288.939437) (xy 314.855606 -288.918904) (xy 314.855606 -288.91865)
			(xy 314.850901 -288.910758) (xy 314.837043 -288.898717) (xy 314.819829 -288.892332) (xy 314.810648 -288.89198)
			(xy 314.489084 -288.89198) (xy 314.479898 -288.892318) (xy 314.462673 -288.898697) (xy 314.448803 -288.910739)
			(xy 314.444126 -288.91865) (xy 314.444126 -288.918904) (xy 314.431715 -288.941041) (xy 314.40071 -288.981217)
			(xy 314.363489 -289.015713) (xy 314.321077 -289.043581) (xy 314.274641 -289.064053) (xy 314.225459 -289.076566)
			(xy 314.174886 -289.080776) (xy 314.124313 -289.076566) (xy 314.075131 -289.064053) (xy 314.028695 -289.043581)
			(xy 313.986283 -289.015713) (xy 313.949062 -288.981217) (xy 313.918057 -288.941041) (xy 313.905646 -288.918904)
			(xy 313.905646 -288.91865) (xy 313.900943 -288.910754) (xy 313.887086 -288.898701) (xy 313.869872 -288.892303)
			(xy 313.860688 -288.89198) (xy 313.54522 -288.89198) (xy 313.533706 -288.892452) (xy 313.512924 -288.902355)
			(xy 313.505342 -288.91103) (xy 313.486038 -288.934652) (xy 313.481974 -288.939986) (xy 313.469535 -288.958579)
			(xy 313.440074 -288.99224) (xy 313.4233 -289.007042) (xy 313.415356 -289.013751) (xy 313.398704 -289.026206)
			(xy 313.390026 -289.031934) (xy 313.384184 -289.035998) (xy 313.351141 -289.063862) (xy 313.280919 -289.114271)
			(xy 313.206501 -289.158249) (xy 313.128474 -289.19545) (xy 313.047454 -289.22558) (xy 312.964079 -289.248401)
			(xy 312.879008 -289.263734) (xy 312.792912 -289.271457) (xy 312.749692 -289.271964) (xy 312.484262 -289.271964)
			(xy 312.434112 -289.271349) (xy 312.334343 -289.261041) (xy 312.285126 -289.25139) (xy 312.279961 -289.250443)
			(xy 312.269463 -289.250443) (xy 312.264298 -289.25139) (xy 312.215081 -289.261041) (xy 312.115312 -289.271353)
			(xy 312.065162 -289.271964) (xy 311.799732 -289.271964) (xy 311.756468 -289.271462) (xy 311.670286 -289.263716)
			(xy 311.585134 -289.248344) (xy 311.501684 -289.225469) (xy 311.420595 -289.19527) (xy 311.342511 -289.157987)
			(xy 311.268047 -289.113915) (xy 311.197792 -289.063402) (xy 311.164732 -289.03549) (xy 311.159144 -289.031426)
			(xy 311.141199 -289.019392) (xy 311.108569 -288.991071) (xy 311.080256 -288.958433) (xy 311.068212 -288.940494)
			(xy 311.064148 -288.934906) (xy 311.035596 -288.901162) (xy 310.984036 -288.829357) (xy 310.9392 -288.753173)
			(xy 310.919876 -288.713418) (xy 310.915957 -288.705825) (xy 310.90402 -288.693613) (xy 310.896508 -288.689542)
			(xy 310.8579 -288.669476) (xy 310.857138 -288.668968) (xy 310.854598 -288.667698) (xy 310.841898 -288.66211)
			(xy 310.837326 -288.661094) (xy 310.82869 -288.661348) (xy 310.824445 -288.661691) (xy 310.816148 -288.66361)
			(xy 310.81218 -288.665158) (xy 310.785002 -288.681414) (xy 310.784494 -288.681414) (xy 310.725312 -288.718244)
			(xy 310.721765 -288.721122) (xy 310.71564 -288.727896) (xy 310.71312 -288.731706) (xy 310.711342 -288.735008)
			(xy 310.709818 -288.738056) (xy 310.707528 -288.743482) (xy 310.705215 -288.755027) (xy 310.705246 -288.760916)
			(xy 310.7055 -288.763964) (xy 310.705754 -288.773108) (xy 310.705754 -288.774886) (xy 310.705246 -288.800881)
			(xy 310.697118 -288.852232) (xy 310.681062 -288.90168) (xy 310.657471 -288.948009) (xy 310.626925 -288.990079)
			(xy 310.590177 -289.026856) (xy 310.548131 -289.057435) (xy 310.50182 -289.081062) (xy 310.452385 -289.097158)
			(xy 310.401041 -289.105325) (xy 310.375046 -289.105848) (xy 309.424832 -289.105848) (xy 309.398822 -289.105367)
			(xy 309.34744 -289.097233) (xy 309.297965 -289.081161) (xy 309.251612 -289.057547) (xy 309.209525 -289.026972)
			(xy 309.17274 -288.990188) (xy 309.142162 -288.948103) (xy 309.118545 -288.901752) (xy 309.102471 -288.852277)
			(xy 309.094334 -288.800896) (xy 309.09387 -288.774886) (xy 309.094026 -288.75962) (xy 309.096823 -288.729217)
			(xy 309.099458 -288.71418) (xy 309.099712 -288.712656) (xy 309.100474 -288.708592) (xy 309.093362 -288.685986)
			(xy 309.020464 -288.609786) (xy 308.998112 -288.601658) (xy 308.986174 -288.603182) (xy 308.977127 -288.604172)
			(xy 308.958953 -288.60519) (xy 308.949852 -288.605214) (xy 308.925031 -288.604724) (xy 308.876045 -288.596686)
			(xy 308.829005 -288.580828) (xy 308.78515 -288.55757) (xy 308.745635 -288.527523) (xy 308.711501 -288.491479)
			(xy 308.683649 -288.450388) (xy 308.66281 -288.405332) (xy 308.649536 -288.357498) (xy 308.644174 -288.308148)
			(xy 308.646867 -288.258579) (xy 308.657544 -288.2101) (xy 308.675922 -288.163986) (xy 308.701519 -288.121453)
			(xy 308.73366 -288.083621) (xy 308.771497 -288.051488) (xy 308.814035 -288.025898) (xy 308.860152 -288.007528)
			(xy 308.908633 -287.99686) (xy 308.958202 -287.994176) (xy 309.007552 -287.999546) (xy 309.055383 -288.012829)
			(xy 309.100435 -288.033675) (xy 309.141521 -288.061535) (xy 309.177559 -288.095675) (xy 309.207599 -288.135195)
			(xy 309.23085 -288.179055) (xy 309.246699 -288.226098) (xy 309.254729 -288.275085) (xy 309.25516 -288.299906)
			(xy 309.255121 -288.309007) (xy 309.254104 -288.32718) (xy 309.253128 -288.336228) (xy 309.251604 -288.348166)
			(xy 309.259732 -288.370518) (xy 309.335932 -288.443416) (xy 309.358538 -288.450528) (xy 309.363364 -288.449766)
			(xy 309.378585 -288.447041) (xy 309.40937 -288.444119) (xy 309.424832 -288.443924) (xy 309.49519 -288.443924)
			(xy 309.505886 -288.443368) (xy 309.525453 -288.43472) (xy 309.533036 -288.42716) (xy 309.590948 -288.362644)
			(xy 309.597552 -288.342832) (xy 309.596536 -288.332926) (xy 309.596282 -288.332418) (xy 309.596282 -288.330894)
			(xy 309.594504 -288.30016) (xy 309.594504 -288.299652) (xy 309.594993 -288.275674) (xy 309.60253 -288.228313)
			(xy 309.61738 -288.182713) (xy 309.639176 -288.139995) (xy 309.667384 -288.101212) (xy 309.70131 -288.067315)
			(xy 309.740117 -288.03914) (xy 309.782853 -288.01738) (xy 309.828466 -288.002569) (xy 309.875833 -287.995073)
			(xy 309.899812 -287.994598) (xy 309.913867 -287.994807) (xy 309.941851 -287.997481) (xy 309.955692 -287.999932)
			(xy 309.9562 -287.999932) (xy 309.968436 -288.001443) (xy 309.991946 -287.994153) (xy 310.001158 -287.985962)
			(xy 310.060594 -287.926526) (xy 310.068681 -287.917403) (xy 310.07599 -287.894183) (xy 310.074564 -287.882076)
			(xy 310.074564 -287.881822) (xy 310.072532 -287.868614) (xy 310.072532 -287.86836) (xy 310.070754 -287.855406)
			(xy 310.06923 -287.824926) (xy 310.06923 -287.824418) (xy 310.069361 -287.810367) (xy 310.071905 -287.782382)
			(xy 310.07431 -287.768538) (xy 310.076596 -287.756346) (xy 310.06923 -287.732216) (xy 309.992522 -287.655254)
			(xy 309.968392 -287.647888) (xy 309.955946 -287.650174) (xy 309.942037 -287.652571) (xy 309.913925 -287.655114)
			(xy 309.899812 -287.655254) (xy 309.875819 -287.654784) (xy 309.828423 -287.64728) (xy 309.782784 -287.632454)
			(xy 309.740027 -287.610672) (xy 309.701203 -287.58247) (xy 309.667268 -287.548541) (xy 309.639058 -287.509723)
			(xy 309.617268 -287.466969) (xy 309.602434 -287.421333) (xy 309.59492 -287.373939) (xy 309.594504 -287.349946)
			(xy 309.596282 -287.318196) (xy 309.596282 -287.317688) (xy 309.596947 -287.307049) (xy 309.590368 -287.286793)
			(xy 309.583582 -287.278572) (xy 309.533036 -287.222184) (xy 309.525524 -287.214513) (xy 309.505918 -287.205807)
			(xy 309.49519 -287.20542) (xy 309.424832 -287.20542) (xy 309.411119 -287.20533) (xy 309.383779 -287.203169)
			(xy 309.370222 -287.201102) (xy 309.358538 -287.19907) (xy 309.335678 -287.206182) (xy 309.268114 -287.270444)
			(xy 309.260046 -287.279083) (xy 309.252108 -287.30132) (xy 309.252874 -287.313116) (xy 309.252874 -287.31337)
			(xy 309.253929 -287.322478) (xy 309.255074 -287.340778) (xy 309.25516 -287.349946) (xy 309.254671 -287.374761)
			(xy 309.246634 -287.423737) (xy 309.230781 -287.470768) (xy 309.207529 -287.514614) (xy 309.177489 -287.554122)
			(xy 309.141454 -287.588249) (xy 309.100373 -287.616098) (xy 309.055328 -287.636934) (xy 309.007505 -287.650208)
			(xy 308.958165 -287.655571) (xy 308.908607 -287.652882) (xy 308.860137 -287.642211) (xy 308.814032 -287.62384)
			(xy 308.771506 -287.598252) (xy 308.733679 -287.566122) (xy 308.701549 -287.528296) (xy 308.675961 -287.48577)
			(xy 308.657589 -287.439664) (xy 308.646918 -287.391195) (xy 308.644229 -287.341637) (xy 308.649592 -287.292297)
			(xy 308.662866 -287.244474) (xy 308.683701 -287.199429) (xy 308.71155 -287.158347) (xy 308.745677 -287.122312)
			(xy 308.785184 -287.092272) (xy 308.829031 -287.06902) (xy 308.876061 -287.053166) (xy 308.925037 -287.045129)
			(xy 308.949852 -287.044638) (xy 308.958956 -287.044736) (xy 308.977129 -287.04588) (xy 308.986174 -287.046924)
			(xy 308.99807 -287.047729) (xy 309.020472 -287.039657) (xy 309.0291 -287.03143) (xy 309.085488 -286.972502)
			(xy 309.093135 -286.963535) (xy 309.100039 -286.941029) (xy 309.098696 -286.929322) (xy 309.098696 -286.929068)
			(xy 309.096565 -286.91558) (xy 309.094274 -286.888367) (xy 309.094124 -286.874712) (xy 309.094124 -286.874204)
			(xy 309.094244 -286.860682) (xy 309.09641 -286.833725) (xy 309.098442 -286.820356) (xy 309.100474 -286.808672)
			(xy 309.093362 -286.785812) (xy 309.028846 -286.718248) (xy 309.020322 -286.71024) (xy 308.998354 -286.702287)
			(xy 308.986682 -286.703008) (xy 308.986174 -286.703008) (xy 308.97713 -286.704055) (xy 308.958956 -286.705196)
			(xy 308.949852 -286.705294) (xy 308.925033 -286.704804) (xy 308.876051 -286.696767) (xy 308.829015 -286.680911)
			(xy 308.785163 -286.657654) (xy 308.745651 -286.62761) (xy 308.711519 -286.591569) (xy 308.683668 -286.550482)
			(xy 308.662831 -286.50543) (xy 308.649556 -286.4576) (xy 308.644194 -286.408254) (xy 308.646886 -286.358689)
			(xy 308.65756 -286.310213) (xy 308.675936 -286.264103) (xy 308.70153 -286.221572) (xy 308.733667 -286.183743)
			(xy 308.7715 -286.15161) (xy 308.814033 -286.126021) (xy 308.860146 -286.10765) (xy 308.908623 -286.096981)
			(xy 308.958188 -286.094295) (xy 309.007534 -286.099663) (xy 309.055362 -286.112943) (xy 309.100411 -286.133785)
			(xy 309.141496 -286.161641) (xy 309.177532 -286.195776) (xy 309.207572 -286.235291) (xy 309.230824 -286.279146)
			(xy 309.246675 -286.326184) (xy 309.254707 -286.375167) (xy 309.25516 -286.399986) (xy 309.255121 -286.409087)
			(xy 309.254105 -286.42726) (xy 309.253128 -286.436308) (xy 309.251604 -286.448246) (xy 309.259732 -286.470598)
			(xy 309.335932 -286.543496) (xy 309.358538 -286.550354) (xy 309.363618 -286.549592) (xy 309.378783 -286.546954)
			(xy 309.40944 -286.544158) (xy 309.424832 -286.544004) (xy 309.49519 -286.544004) (xy 309.505885 -286.543447)
			(xy 309.52545 -286.534797) (xy 309.533036 -286.52724) (xy 309.590948 -286.462724) (xy 309.597552 -286.442912)
			(xy 309.596536 -286.433006) (xy 309.596282 -286.432498) (xy 309.596282 -286.430974) (xy 309.594504 -286.40024)
			(xy 309.594504 -286.399732) (xy 309.594995 -286.375755) (xy 309.602534 -286.328396) (xy 309.617385 -286.282799)
			(xy 309.639183 -286.240084) (xy 309.667392 -286.201303) (xy 309.701316 -286.167409) (xy 309.740123 -286.139237)
			(xy 309.782858 -286.117478) (xy 309.828469 -286.102669) (xy 309.875834 -286.095173) (xy 309.899812 -286.094678)
			(xy 309.913931 -286.094876) (xy 309.942043 -286.097544) (xy 309.955946 -286.100012) (xy 309.956454 -286.100012)
			(xy 309.968687 -286.10151) (xy 309.992184 -286.094211) (xy 310.001412 -286.086042) (xy 310.060848 -286.026352)
			(xy 310.069001 -286.017113) (xy 310.076317 -285.993623) (xy 310.074818 -285.981394) (xy 310.074818 -285.98114)
			(xy 310.070264 -285.95319) (xy 310.070268 -285.896569) (xy 310.074818 -285.868618) (xy 310.074818 -285.868364)
			(xy 310.07632 -285.856129) (xy 310.069028 -285.832626) (xy 310.060848 -285.823406) (xy 310.001158 -285.763716)
			(xy 309.991918 -285.755573) (xy 309.968431 -285.748291) (xy 309.9562 -285.749746) (xy 309.955946 -285.749746)
			(xy 309.942044 -285.75222) (xy 309.913931 -285.754887) (xy 309.899812 -285.75508) (xy 309.875834 -285.754611)
			(xy 309.828467 -285.747114) (xy 309.782854 -285.732303) (xy 309.740119 -285.710542) (xy 309.701312 -285.682366)
			(xy 309.667389 -285.648469) (xy 309.639183 -285.609684) (xy 309.617388 -285.566966) (xy 309.602541 -285.521365)
			(xy 309.595008 -285.474004) (xy 309.594504 -285.450026) (xy 309.594504 -285.449518) (xy 309.596028 -285.420562)
			(xy 309.596282 -285.418022) (xy 309.596282 -285.417514) (xy 309.596798 -285.406893) (xy 309.590243 -285.386687)
			(xy 309.583582 -285.378398) (xy 309.533036 -285.322264) (xy 309.525522 -285.314595) (xy 309.505917 -285.305894)
			(xy 309.49519 -285.3055) (xy 309.424832 -285.3055) (xy 309.409503 -285.305349) (xy 309.378974 -285.302546)
			(xy 309.363872 -285.299912) (xy 309.36311 -285.299912) (xy 309.358538 -285.29915) (xy 309.335932 -285.306008)
			(xy 309.268368 -285.370524) (xy 309.260155 -285.379163) (xy 309.252081 -285.401556) (xy 309.252874 -285.41345)
			(xy 309.253923 -285.422494) (xy 309.255068 -285.440668) (xy 309.25516 -285.449772) (xy 309.254677 -285.474589)
			(xy 309.246651 -285.523569) (xy 309.230808 -285.570605) (xy 309.207564 -285.614459) (xy 309.177531 -285.653975)
			(xy 309.141501 -285.688111) (xy 309.100423 -285.715969) (xy 309.055379 -285.736815) (xy 309.007557 -285.750098)
			(xy 308.958215 -285.75547) (xy 308.908654 -285.752789) (xy 308.86018 -285.742124) (xy 308.81407 -285.723759)
			(xy 308.771538 -285.698175) (xy 308.733706 -285.666048) (xy 308.701569 -285.628224) (xy 308.675975 -285.585698)
			(xy 308.657598 -285.539593) (xy 308.646922 -285.491121) (xy 308.644228 -285.441561) (xy 308.649588 -285.392218)
			(xy 308.662859 -285.344392) (xy 308.683693 -285.299343) (xy 308.711541 -285.258258) (xy 308.745668 -285.22222)
			(xy 308.785177 -285.192177) (xy 308.829025 -285.168922) (xy 308.876057 -285.153067) (xy 308.925035 -285.14503)
			(xy 308.949852 -285.144464) (xy 308.958956 -285.144562) (xy 308.977129 -285.145707) (xy 308.986174 -285.14675)
			(xy 308.99807 -285.147556) (xy 309.020475 -285.139486) (xy 309.0291 -285.131256) (xy 309.093616 -285.063692)
			(xy 309.100474 -285.041086) (xy 309.099712 -285.036006) (xy 309.097073 -285.020841) (xy 309.094275 -284.990184)
			(xy 309.094124 -284.974792) (xy 309.094273 -284.959463) (xy 309.09707 -284.928933) (xy 309.099712 -284.913832)
			(xy 309.099712 -284.91307) (xy 309.100474 -284.908498) (xy 309.093616 -284.885892) (xy 309.0291 -284.818328)
			(xy 309.02046 -284.810116) (xy 308.998068 -284.802038) (xy 308.986174 -284.802834) (xy 308.97713 -284.803881)
			(xy 308.958956 -284.805022) (xy 308.949852 -284.80512) (xy 308.925031 -284.80463) (xy 308.876044 -284.796591)
			(xy 308.829002 -284.780734) (xy 308.785146 -284.757474) (xy 308.74563 -284.727426) (xy 308.711496 -284.691382)
			(xy 308.683643 -284.650289) (xy 308.662804 -284.605232) (xy 308.64953 -284.557398) (xy 308.644168 -284.508046)
			(xy 308.646862 -284.458476) (xy 308.657539 -284.409996) (xy 308.675918 -284.363881) (xy 308.701516 -284.321347)
			(xy 308.733658 -284.283515) (xy 308.771496 -284.251381) (xy 308.814035 -284.225791) (xy 308.860153 -284.207421)
			(xy 308.908636 -284.196753) (xy 308.958206 -284.19407) (xy 309.007557 -284.199441) (xy 309.055389 -284.212725)
			(xy 309.100442 -284.233572) (xy 309.141528 -284.261434) (xy 309.177567 -284.295575) (xy 309.207607 -284.335097)
			(xy 309.230857 -284.378957) (xy 309.246706 -284.426002) (xy 309.254735 -284.474991) (xy 309.25516 -284.499812)
			(xy 309.255063 -284.508916) (xy 309.253921 -284.52709) (xy 309.252874 -284.536134) (xy 309.252082 -284.548025)
			(xy 309.260173 -284.570407) (xy 309.268368 -284.57906) (xy 309.335932 -284.643576) (xy 309.358538 -284.650434)
			(xy 309.363618 -284.649672) (xy 309.378783 -284.647034) (xy 309.40944 -284.644239) (xy 309.424832 -284.644084)
			(xy 309.49519 -284.644084) (xy 309.505884 -284.643527) (xy 309.525447 -284.634874) (xy 309.533036 -284.62732)
			(xy 309.590948 -284.562804) (xy 309.597552 -284.542992) (xy 309.596536 -284.533086) (xy 309.596282 -284.532578)
			(xy 309.596282 -284.531054) (xy 309.594504 -284.500066) (xy 309.594504 -284.499558) (xy 309.594993 -284.47558)
			(xy 309.602529 -284.428218) (xy 309.617378 -284.382617) (xy 309.639174 -284.339899) (xy 309.667382 -284.301114)
			(xy 309.701307 -284.267217) (xy 309.740116 -284.239041) (xy 309.782852 -284.21728) (xy 309.828465 -284.202469)
			(xy 309.875833 -284.194973) (xy 309.899812 -284.194504) (xy 309.913867 -284.194713) (xy 309.941851 -284.197387)
			(xy 309.955692 -284.199838) (xy 309.9562 -284.199838) (xy 309.968436 -284.201349) (xy 309.991946 -284.194059)
			(xy 310.001158 -284.185868) (xy 310.069738 -284.117288) (xy 310.077104 -284.093666) (xy 310.07558 -284.085538)
			(xy 310.070267 -284.055478) (xy 310.070275 -283.994442) (xy 310.07558 -283.96438) (xy 310.07558 -283.963618)
			(xy 310.077104 -283.955998) (xy 310.069738 -283.932376) (xy 310.001158 -283.863796) (xy 309.991917 -283.855656)
			(xy 309.968431 -283.848376) (xy 309.9562 -283.849826) (xy 309.955946 -283.849826) (xy 309.942044 -283.8523)
			(xy 309.913931 -283.854968) (xy 309.899812 -283.85516) (xy 309.875834 -283.854691) (xy 309.828468 -283.847194)
			(xy 309.782857 -283.832383) (xy 309.740124 -283.810621) (xy 309.701319 -283.782445) (xy 309.667397 -283.748547)
			(xy 309.639193 -283.709762) (xy 309.617401 -283.667044) (xy 309.602557 -283.621444) (xy 309.595026 -283.574083)
			(xy 309.594504 -283.550106) (xy 309.594504 -283.549598) (xy 309.596028 -283.520642) (xy 309.596282 -283.518102)
			(xy 309.596282 -283.517594) (xy 309.596794 -283.506974) (xy 309.590233 -283.486774) (xy 309.583582 -283.478478)
			(xy 309.533036 -283.422344) (xy 309.525521 -283.414678) (xy 309.505917 -283.405979) (xy 309.49519 -283.40558)
			(xy 309.424832 -283.40558) (xy 309.409503 -283.405429) (xy 309.378974 -283.402626) (xy 309.363872 -283.399992)
			(xy 309.36311 -283.399992) (xy 309.358538 -283.39923) (xy 309.335932 -283.406088) (xy 309.268368 -283.470604)
			(xy 309.260152 -283.479242) (xy 309.252069 -283.501636) (xy 309.252874 -283.51353) (xy 309.253924 -283.522574)
			(xy 309.25507 -283.540748) (xy 309.25516 -283.549852) (xy 309.254678 -283.574669) (xy 309.246656 -283.62365)
			(xy 309.230815 -283.670689) (xy 309.207573 -283.714544) (xy 309.177542 -283.754062) (xy 309.141514 -283.788201)
			(xy 309.100437 -283.816062) (xy 309.055393 -283.836909) (xy 309.007571 -283.850195) (xy 308.958228 -283.85557)
			(xy 308.908667 -283.85289) (xy 308.860192 -283.842228) (xy 308.81408 -283.823864) (xy 308.771547 -283.798282)
			(xy 308.733713 -283.766155) (xy 308.701574 -283.728331) (xy 308.675979 -283.685806) (xy 308.6576 -283.6397)
			(xy 308.646923 -283.591228) (xy 308.644228 -283.541668) (xy 308.649586 -283.492324) (xy 308.662857 -283.444497)
			(xy 308.683691 -283.399447) (xy 308.711539 -283.358361) (xy 308.745666 -283.322322) (xy 308.785175 -283.292279)
			(xy 308.829023 -283.269023) (xy 308.876056 -283.253167) (xy 308.925035 -283.24513) (xy 308.949852 -283.244544)
			(xy 308.958956 -283.244642) (xy 308.977129 -283.245786) (xy 308.986174 -283.24683) (xy 308.99807 -283.247635)
			(xy 309.020472 -283.239563) (xy 309.0291 -283.231336) (xy 309.093616 -283.163772) (xy 309.100474 -283.141166)
			(xy 309.099712 -283.136086) (xy 309.097074 -283.120921) (xy 309.094277 -283.090264) (xy 309.094124 -283.074872)
			(xy 309.094273 -283.059543) (xy 309.097073 -283.029013) (xy 309.099712 -283.013912) (xy 309.099712 -283.01315)
			(xy 309.100474 -283.008578) (xy 309.093616 -282.985972) (xy 309.0291 -282.918408) (xy 309.020459 -282.910198)
			(xy 308.998067 -282.902123) (xy 308.986174 -282.902914) (xy 308.97713 -282.903961) (xy 308.958956 -282.905102)
			(xy 308.949852 -282.9052) (xy 308.925033 -282.90471) (xy 308.876049 -282.896672) (xy 308.829012 -282.880816)
			(xy 308.785159 -282.857559) (xy 308.745646 -282.827514) (xy 308.711514 -282.791472) (xy 308.683662 -282.750383)
			(xy 308.662825 -282.70533) (xy 308.64955 -282.6575) (xy 308.644188 -282.608152) (xy 308.64688 -282.558586)
			(xy 308.657555 -282.510109) (xy 308.675932 -282.463998) (xy 308.701527 -282.421467) (xy 308.733665 -282.383636)
			(xy 308.771499 -282.351503) (xy 308.814034 -282.325914) (xy 308.860148 -282.307544) (xy 308.908626 -282.296875)
			(xy 308.958192 -282.294189) (xy 309.007539 -282.299558) (xy 309.055368 -282.312839) (xy 309.100418 -282.333682)
			(xy 309.141503 -282.361539) (xy 309.17754 -282.395676) (xy 309.20758 -282.435192) (xy 309.230832 -282.479049)
			(xy 309.246682 -282.526088) (xy 309.254714 -282.575073) (xy 309.25516 -282.599892) (xy 309.255061 -282.608996)
			(xy 309.253914 -282.627169) (xy 309.252874 -282.636214) (xy 309.252078 -282.648106) (xy 309.260162 -282.670495)
			(xy 309.268368 -282.67914) (xy 309.335932 -282.743656) (xy 309.358538 -282.750514) (xy 309.363618 -282.749752)
			(xy 309.378783 -282.747114) (xy 309.40944 -282.744319) (xy 309.424832 -282.744164) (xy 309.49519 -282.744164)
			(xy 309.505884 -282.743606) (xy 309.525445 -282.734952) (xy 309.533036 -282.7274) (xy 309.590948 -282.662884)
			(xy 309.597552 -282.643072) (xy 309.596536 -282.633166) (xy 309.596282 -282.632658) (xy 309.596282 -282.631134)
			(xy 309.594504 -282.600146) (xy 309.594504 -282.599638) (xy 309.594994 -282.575661) (xy 309.602533 -282.528301)
			(xy 309.617384 -282.482703) (xy 309.639181 -282.439988) (xy 309.667389 -282.401206) (xy 309.701314 -282.367311)
			(xy 309.740122 -282.339138) (xy 309.782857 -282.317379) (xy 309.828468 -282.302569) (xy 309.875834 -282.295073)
			(xy 309.899812 -282.294584) (xy 309.913867 -282.294793) (xy 309.941851 -282.297467) (xy 309.955692 -282.299918)
			(xy 309.9562 -282.299918) (xy 309.968438 -282.301429) (xy 309.991953 -282.294148) (xy 310.001158 -282.285948)
			(xy 310.060848 -282.226258) (xy 310.068982 -282.217015) (xy 310.076256 -282.193532) (xy 310.074818 -282.1813)
			(xy 310.074818 -282.181046) (xy 310.070264 -282.153096) (xy 310.070266 -282.096474) (xy 310.074818 -282.068524)
			(xy 310.074818 -282.06827) (xy 310.076322 -282.056035) (xy 310.069031 -282.032529) (xy 310.060848 -282.023312)
			(xy 310.001158 -281.963622) (xy 309.991918 -281.955479) (xy 309.968431 -281.948195) (xy 309.9562 -281.949652)
			(xy 309.955946 -281.949652) (xy 309.941981 -281.952136) (xy 309.913741 -281.954804) (xy 309.899558 -281.954986)
			(xy 309.874307 -281.954461) (xy 309.824494 -281.946143) (xy 309.77673 -281.929739) (xy 309.732316 -281.905699)
			(xy 309.692465 -281.874676) (xy 309.658263 -281.837518) (xy 309.630643 -281.795237) (xy 309.610358 -281.748988)
			(xy 309.597961 -281.70003) (xy 309.593791 -281.6497) (xy 309.597961 -281.59937) (xy 309.610358 -281.550412)
			(xy 309.630643 -281.504163) (xy 309.658263 -281.461882) (xy 309.692465 -281.424724) (xy 309.732316 -281.393701)
			(xy 309.77673 -281.369661) (xy 309.824494 -281.353257) (xy 309.874307 -281.344939) (xy 309.899558 -281.34437)
			(xy 309.900066 -281.34437) (xy 309.913602 -281.344531) (xy 309.940566 -281.346945) (xy 309.953914 -281.349196)
			(xy 309.96636 -281.351482) (xy 309.989982 -281.344116) (xy 310.06669 -281.2669) (xy 310.074056 -281.243278)
			(xy 310.07177 -281.230832) (xy 310.06841 -281.210888) (xy 310.066375 -281.170495) (xy 310.067706 -281.150314)
			(xy 310.067706 -281.149806) (xy 310.072024 -281.119326) (xy 310.072024 -281.118818) (xy 310.073515 -281.106589)
			(xy 310.066198 -281.083108) (xy 310.058054 -281.07386) (xy 309.990236 -281.005534) (xy 309.96636 -280.997914)
			(xy 309.954168 -281.0002) (xy 309.94082 -281.002453) (xy 309.913856 -281.004866) (xy 309.90032 -281.005026)
			(xy 309.899812 -281.005026) (xy 309.874552 -281.004534) (xy 309.824721 -280.996221) (xy 309.776938 -280.979818)
			(xy 309.732507 -280.955775) (xy 309.692639 -280.924746) (xy 309.658422 -280.887578) (xy 309.63079 -280.845285)
			(xy 309.610496 -280.799021) (xy 309.598094 -280.750047) (xy 309.593922 -280.6997) (xy 309.598094 -280.649353)
			(xy 309.610496 -280.600379) (xy 309.63079 -280.554115) (xy 309.658422 -280.511822) (xy 309.692639 -280.474654)
			(xy 309.732507 -280.443625) (xy 309.776938 -280.419582) (xy 309.824721 -280.403179) (xy 309.874552 -280.394866)
			(xy 309.899812 -280.39441) (xy 309.913412 -280.394559) (xy 309.940503 -280.396974) (xy 309.953914 -280.399236)
			(xy 309.966248 -280.400873) (xy 309.989959 -280.393423) (xy 309.999126 -280.385012) (xy 310.058054 -280.32583)
			(xy 310.066147 -280.316709) (xy 310.073463 -280.293487) (xy 310.072024 -280.28138) (xy 310.072024 -280.281126)
			(xy 310.069658 -280.267405) (xy 310.067113 -280.239676) (xy 310.066944 -280.225754) (xy 310.066944 -280.2255)
			(xy 310.067113 -280.21119) (xy 310.069788 -280.182696) (xy 310.072278 -280.168604) (xy 310.074564 -280.156412)
			(xy 310.067452 -280.132282) (xy 309.99049 -280.055066) (xy 309.966868 -280.0477) (xy 309.954422 -280.049986)
			(xy 309.940886 -280.052272) (xy 309.913539 -280.054689) (xy 309.899812 -280.054812) (xy 309.874553 -280.05432)
			(xy 309.824725 -280.046007) (xy 309.776944 -280.029606) (xy 309.732515 -280.005563) (xy 309.692649 -279.974536)
			(xy 309.658433 -279.93737) (xy 309.630802 -279.895079) (xy 309.610509 -279.848816) (xy 309.598108 -279.799845)
			(xy 309.593936 -279.7495) (xy 309.598108 -279.699155) (xy 309.610509 -279.650184) (xy 309.630802 -279.603921)
			(xy 309.658433 -279.56163) (xy 309.692649 -279.524464) (xy 309.732515 -279.493437) (xy 309.776944 -279.469394)
			(xy 309.824725 -279.452993) (xy 309.874553 -279.44468) (xy 309.899812 -279.444196) (xy 309.913867 -279.444405)
			(xy 309.941851 -279.447079) (xy 309.955692 -279.44953) (xy 309.9562 -279.44953) (xy 309.968436 -279.451041)
			(xy 309.991945 -279.443751) (xy 310.001158 -279.43556) (xy 310.069484 -279.367488) (xy 310.07685 -279.343358)
			(xy 310.074564 -279.330912) (xy 310.072235 -279.317442) (xy 310.069689 -279.290224) (xy 310.069484 -279.276556)
			(xy 310.070754 -279.2476) (xy 310.070754 -279.247092) (xy 310.074564 -279.21839) (xy 310.07685 -279.206198)
			(xy 310.069484 -279.182068) (xy 310.001158 -279.113742) (xy 309.991914 -279.105609) (xy 309.968432 -279.098337)
			(xy 309.9562 -279.099772) (xy 309.955946 -279.099772) (xy 309.942044 -279.102246) (xy 309.913931 -279.104914)
			(xy 309.899812 -279.105106) (xy 309.875833 -279.104637) (xy 309.828464 -279.097141) (xy 309.78285 -279.08233)
			(xy 309.740113 -279.060569) (xy 309.701304 -279.032393) (xy 309.667378 -278.998497) (xy 309.639169 -278.959712)
			(xy 309.617372 -278.916994) (xy 309.602521 -278.871393) (xy 309.594984 -278.824031) (xy 309.594504 -278.800052)
			(xy 309.594504 -278.799544) (xy 309.594619 -278.79063) (xy 309.595761 -278.772839) (xy 309.59679 -278.763984)
			(xy 309.59679 -278.76373) (xy 309.597605 -278.751927) (xy 309.589657 -278.729675) (xy 309.58155 -278.721058)
			(xy 309.522368 -278.66467) (xy 309.513434 -278.656952) (xy 309.490923 -278.649922) (xy 309.479188 -278.651208)
			(xy 309.478934 -278.651208) (xy 309.465446 -278.653337) (xy 309.438232 -278.655626) (xy 309.424578 -278.65578)
			(xy 309.409312 -278.655624) (xy 309.378909 -278.652827) (xy 309.363872 -278.650192) (xy 309.362348 -278.649938)
			(xy 309.358284 -278.649176) (xy 309.335678 -278.656288) (xy 309.259478 -278.729186) (xy 309.25135 -278.751538)
			(xy 309.252874 -278.763476) (xy 309.253862 -278.772523) (xy 309.254878 -278.790697) (xy 309.254906 -278.799798)
			(xy 309.25442 -278.824619) (xy 309.24639 -278.873606) (xy 309.230539 -278.920649) (xy 309.207287 -278.964508)
			(xy 309.177246 -279.004027) (xy 309.141206 -279.038166) (xy 309.100119 -279.066024) (xy 309.055066 -279.086869)
			(xy 309.007234 -279.100149) (xy 308.957884 -279.105517) (xy 308.908315 -279.10283) (xy 308.859834 -279.092158)
			(xy 308.813718 -279.073785) (xy 308.771183 -279.048192) (xy 308.733348 -279.016055) (xy 308.70121 -278.978221)
			(xy 308.675617 -278.935685) (xy 308.657243 -278.88957) (xy 308.646571 -278.841089) (xy 308.643883 -278.79152)
			(xy 308.64925 -278.74217) (xy 308.66253 -278.694338) (xy 308.683374 -278.649284) (xy 308.711232 -278.608197)
			(xy 308.74537 -278.572157) (xy 308.784889 -278.542115) (xy 308.828747 -278.518862) (xy 308.87579 -278.503011)
			(xy 308.924777 -278.49498) (xy 308.949598 -278.49449) (xy 308.958699 -278.494529) (xy 308.976872 -278.495546)
			(xy 308.98592 -278.496522) (xy 308.997858 -278.498046) (xy 309.02021 -278.489918) (xy 309.093108 -278.413718)
			(xy 309.10022 -278.391112) (xy 309.099458 -278.386286) (xy 309.096731 -278.371065) (xy 309.093804 -278.34028)
			(xy 309.093616 -278.324818) (xy 309.093616 -278.25446) (xy 309.09305 -278.243769) (xy 309.084389 -278.224217)
			(xy 309.076852 -278.216614) (xy 309.020718 -278.166068) (xy 309.012496 -278.159286) (xy 308.992241 -278.152718)
			(xy 308.981602 -278.153368) (xy 308.981348 -278.153368) (xy 308.949598 -278.155146) (xy 308.925606 -278.154675)
			(xy 308.878212 -278.147169) (xy 308.832576 -278.132342) (xy 308.789821 -278.110559) (xy 308.750999 -278.082356)
			(xy 308.717067 -278.048428) (xy 308.68886 -278.00961) (xy 308.667072 -277.966857) (xy 308.652239 -277.921223)
			(xy 308.644728 -277.87383) (xy 308.64429 -277.849838) (xy 308.644497 -277.835783) (xy 308.647166 -277.807798)
			(xy 308.649624 -277.793958) (xy 308.649624 -277.79345) (xy 308.651123 -277.781218) (xy 308.643815 -277.757726)
			(xy 308.635654 -277.748492) (xy 308.567582 -277.680166) (xy 308.543452 -277.6728) (xy 308.531006 -277.675086)
			(xy 308.516535 -277.677597) (xy 308.487273 -277.680143) (xy 308.472586 -277.680166) (xy 308.451504 -277.67915)
			(xy 308.450996 -277.67915) (xy 308.418484 -277.675086) (xy 308.406292 -277.6728) (xy 308.382162 -277.680166)
			(xy 308.313836 -277.748492) (xy 308.305694 -277.757734) (xy 308.2984 -277.78122) (xy 308.299866 -277.79345)
			(xy 308.299866 -277.793958) (xy 308.302335 -277.807797) (xy 308.305011 -277.835782) (xy 308.3052 -277.849838)
			(xy 308.304727 -277.873827) (xy 308.297216 -277.921214) (xy 308.282385 -277.966842) (xy 308.260599 -278.009589)
			(xy 308.232395 -278.048402) (xy 308.198467 -278.082325) (xy 308.15965 -278.110523) (xy 308.1169 -278.132302)
			(xy 308.071269 -278.147126) (xy 308.023881 -278.15463) (xy 307.999892 -278.155146) (xy 307.968396 -278.153368)
			(xy 307.967888 -278.153368) (xy 307.957269 -278.152857) (xy 307.937074 -278.159426) (xy 307.928772 -278.166068)
			(xy 307.872638 -278.216614) (xy 307.86498 -278.224132) (xy 307.856303 -278.243737) (xy 307.855874 -278.25446)
			(xy 307.855874 -278.299418) (xy 307.85562 -278.305006) (xy 307.85562 -278.324818) (xy 307.855395 -278.340539)
			(xy 307.852337 -278.371833) (xy 307.849524 -278.387302) (xy 307.849524 -278.388318) (xy 307.849016 -278.390858)
			(xy 307.856128 -278.413718) (xy 307.920644 -278.481536) (xy 307.929285 -278.489598) (xy 307.951521 -278.497527)
			(xy 307.963316 -278.496776) (xy 307.96357 -278.496776) (xy 307.972614 -278.495727) (xy 307.990788 -278.494583)
			(xy 307.999892 -278.49449) (xy 308.02515 -278.494982) (xy 308.074978 -278.503296) (xy 308.122758 -278.519697)
			(xy 308.167186 -278.54374) (xy 308.207052 -278.574767) (xy 308.241266 -278.611933) (xy 308.268896 -278.654224)
			(xy 308.289189 -278.700485) (xy 308.30159 -278.749456) (xy 308.305762 -278.7998) (xy 308.30159 -278.850144)
			(xy 308.289189 -278.899115) (xy 308.268896 -278.945376) (xy 308.241266 -278.987667) (xy 308.207052 -279.024833)
			(xy 308.167186 -279.05586) (xy 308.122758 -279.079903) (xy 308.074978 -279.096304) (xy 308.02515 -279.104618)
			(xy 307.999892 -279.105106) (xy 307.975914 -279.104636) (xy 307.928548 -279.097137) (xy 307.882937 -279.082324)
			(xy 307.840202 -279.060562) (xy 307.801396 -279.032386) (xy 307.767472 -278.99849) (xy 307.739266 -278.959706)
			(xy 307.71747 -278.916989) (xy 307.702621 -278.87139) (xy 307.695083 -278.82403) (xy 307.694584 -278.800052)
			(xy 307.694584 -278.799544) (xy 307.694699 -278.79063) (xy 307.695842 -278.772839) (xy 307.69687 -278.763984)
			(xy 307.69687 -278.76373) (xy 307.697685 -278.751928) (xy 307.689734 -278.729677) (xy 307.68163 -278.721058)
			(xy 307.622448 -278.66467) (xy 307.613512 -278.656956) (xy 307.591004 -278.649935) (xy 307.579268 -278.651208)
			(xy 307.579014 -278.651208) (xy 307.565526 -278.653336) (xy 307.538312 -278.655623) (xy 307.524658 -278.65578)
			(xy 307.509392 -278.655623) (xy 307.47899 -278.652824) (xy 307.463952 -278.650192) (xy 307.462428 -278.649938)
			(xy 307.458364 -278.649176) (xy 307.435758 -278.656288) (xy 307.359558 -278.729186) (xy 307.35143 -278.751538)
			(xy 307.352954 -278.763476) (xy 307.353942 -278.772523) (xy 307.354957 -278.790697) (xy 307.354986 -278.799798)
			(xy 307.3545 -278.824617) (xy 307.34647 -278.8736) (xy 307.330622 -278.92064) (xy 307.307372 -278.964495)
			(xy 307.277333 -279.004012) (xy 307.241297 -279.038148) (xy 307.200213 -279.066005) (xy 307.155164 -279.086848)
			(xy 307.107336 -279.100129) (xy 307.05799 -279.105497) (xy 307.008425 -279.102811) (xy 306.959948 -279.092142)
			(xy 306.913835 -279.073771) (xy 306.871302 -279.048181) (xy 306.833469 -279.016048) (xy 306.801333 -278.978218)
			(xy 306.77574 -278.935687) (xy 306.757365 -278.889575) (xy 306.746692 -278.841099) (xy 306.744003 -278.791534)
			(xy 306.749367 -278.742188) (xy 306.762644 -278.694359) (xy 306.783483 -278.649308) (xy 306.811337 -278.608222)
			(xy 306.84547 -278.572183) (xy 306.884985 -278.542141) (xy 306.928838 -278.518888) (xy 306.975876 -278.503035)
			(xy 307.024859 -278.495002) (xy 307.049678 -278.49449) (xy 307.058779 -278.494529) (xy 307.076952 -278.495544)
			(xy 307.086 -278.496522) (xy 307.097938 -278.498046) (xy 307.12029 -278.489918) (xy 307.193188 -278.413718)
			(xy 307.2003 -278.391112) (xy 307.199538 -278.386286) (xy 307.196811 -278.371065) (xy 307.193884 -278.34028)
			(xy 307.193696 -278.324818) (xy 307.193696 -278.25446) (xy 307.193129 -278.24377) (xy 307.184466 -278.22422)
			(xy 307.176932 -278.216614) (xy 307.120798 -278.166068) (xy 307.112575 -278.15929) (xy 307.09232 -278.15273)
			(xy 307.081682 -278.153368) (xy 307.081428 -278.153368) (xy 307.049678 -278.155146) (xy 307.025687 -278.154674)
			(xy 306.978296 -278.147165) (xy 306.932662 -278.132336) (xy 306.88991 -278.110552) (xy 306.851091 -278.082349)
			(xy 306.817161 -278.048421) (xy 306.788956 -278.009604) (xy 306.76717 -277.966853) (xy 306.752339 -277.92122)
			(xy 306.744827 -277.873829) (xy 306.74437 -277.849838) (xy 306.744577 -277.835783) (xy 306.747246 -277.807798)
			(xy 306.749704 -277.793958) (xy 306.749704 -277.79345) (xy 306.751203 -277.781217) (xy 306.743904 -277.757719)
			(xy 306.735734 -277.748492) (xy 306.667154 -277.679912) (xy 306.643532 -277.672546) (xy 306.635404 -277.67407)
			(xy 306.605343 -277.679387) (xy 306.544307 -277.679387) (xy 306.514246 -277.67407) (xy 306.513484 -277.67407)
			(xy 306.505864 -277.672546) (xy 306.482242 -277.679912) (xy 306.413662 -277.748492) (xy 306.405516 -277.757733)
			(xy 306.398219 -277.78122) (xy 306.399692 -277.79345) (xy 306.399692 -277.793958) (xy 306.402161 -277.807797)
			(xy 306.404836 -277.835782) (xy 306.405026 -277.849838) (xy 306.404553 -277.873828) (xy 306.397042 -277.921216)
			(xy 306.382211 -277.966846) (xy 306.360426 -278.009595) (xy 306.332222 -278.04841) (xy 306.298294 -278.082335)
			(xy 306.259478 -278.110536) (xy 306.216728 -278.132319) (xy 306.171096 -278.147147) (xy 306.123708 -278.154654)
			(xy 306.099718 -278.155146) (xy 306.067714 -278.153622) (xy 306.057046 -278.152606) (xy 306.036726 -278.15921)
			(xy 305.972718 -278.216868) (xy 305.965055 -278.224385) (xy 305.956364 -278.243989) (xy 305.955954 -278.254714)
			(xy 305.955954 -278.299418) (xy 305.9557 -278.305006) (xy 305.9557 -278.324818) (xy 305.955544 -278.340084)
			(xy 305.952747 -278.370487) (xy 305.950112 -278.385524) (xy 305.949858 -278.387048) (xy 305.949096 -278.391112)
			(xy 305.956208 -278.413718) (xy 306.029106 -278.489918) (xy 306.051458 -278.498046) (xy 306.063396 -278.496522)
			(xy 306.072443 -278.495534) (xy 306.090617 -278.49452) (xy 306.099718 -278.49449) (xy 306.124539 -278.494977)
			(xy 306.173526 -278.503011) (xy 306.220568 -278.518864) (xy 306.264425 -278.542119) (xy 306.303943 -278.572163)
			(xy 306.33808 -278.608204) (xy 306.365936 -278.649293) (xy 306.386778 -278.694348) (xy 306.400056 -278.74218)
			(xy 306.405421 -278.791531) (xy 306.402732 -278.8411) (xy 306.392058 -278.88958) (xy 306.373682 -278.935695)
			(xy 306.348088 -278.97823) (xy 306.31595 -279.016064) (xy 306.278114 -279.0482) (xy 306.235577 -279.073791)
			(xy 306.189461 -279.092164) (xy 306.14098 -279.102834) (xy 306.091411 -279.105521) (xy 306.042061 -279.100152)
			(xy 305.994229 -279.086871) (xy 305.949176 -279.066026) (xy 305.908089 -279.038167) (xy 305.87205 -279.004028)
			(xy 305.842008 -278.964509) (xy 305.818757 -278.920649) (xy 305.802906 -278.873606) (xy 305.794876 -278.824619)
			(xy 305.79441 -278.799798) (xy 305.794449 -278.790697) (xy 305.795466 -278.772524) (xy 305.796442 -278.763476)
			(xy 305.797966 -278.751538) (xy 305.789838 -278.729186) (xy 305.713638 -278.656288) (xy 305.691032 -278.649176)
			(xy 305.686206 -278.649938) (xy 305.670985 -278.652666) (xy 305.6402 -278.655595) (xy 305.624738 -278.65578)
			(xy 305.611147 -278.655613) (xy 305.584061 -278.653328) (xy 305.570636 -278.651208) (xy 305.570128 -278.651208)
			(xy 305.55839 -278.649921) (xy 305.535876 -278.656942) (xy 305.526948 -278.66467) (xy 305.467766 -278.721058)
			(xy 305.459706 -278.7297) (xy 305.451783 -278.751935) (xy 305.452526 -278.76373) (xy 305.452526 -278.763984)
			(xy 305.453552 -278.772839) (xy 305.454694 -278.790631) (xy 305.454812 -278.799544) (xy 305.454812 -278.800052)
			(xy 305.454323 -278.82403) (xy 305.446785 -278.871392) (xy 305.431936 -278.916992) (xy 305.410139 -278.95971)
			(xy 305.381931 -278.998495) (xy 305.348006 -279.032392) (xy 305.309199 -279.060569) (xy 305.266463 -279.082331)
			(xy 305.22085 -279.097143) (xy 305.173483 -279.104642) (xy 305.149504 -279.105106) (xy 305.124246 -279.104614)
			(xy 305.07442 -279.0963) (xy 305.026641 -279.079898) (xy 304.982214 -279.055855) (xy 304.94235 -279.024828)
			(xy 304.908136 -278.987663) (xy 304.880507 -278.945373) (xy 304.860215 -278.899113) (xy 304.847814 -278.850143)
			(xy 304.843642 -278.7998) (xy 304.847814 -278.749457) (xy 304.860215 -278.700487) (xy 304.880507 -278.654227)
			(xy 304.908136 -278.611937) (xy 304.94235 -278.574772) (xy 304.982214 -278.543745) (xy 305.026641 -278.519702)
			(xy 305.07442 -278.5033) (xy 305.124246 -278.494986) (xy 305.149504 -278.49449) (xy 305.158608 -278.494587)
			(xy 305.176782 -278.495728) (xy 305.185826 -278.496776) (xy 305.18608 -278.496776) (xy 305.197882 -278.497589)
			(xy 305.220129 -278.489636) (xy 305.228752 -278.481536) (xy 305.293268 -278.413718) (xy 305.30038 -278.390858)
			(xy 305.299872 -278.38781) (xy 305.297025 -278.372218) (xy 305.293969 -278.340667) (xy 305.293776 -278.324818)
			(xy 305.293776 -278.25446) (xy 305.293209 -278.24377) (xy 305.284543 -278.224223) (xy 305.277012 -278.216614)
			(xy 305.220878 -278.166068) (xy 305.212659 -278.159275) (xy 305.192401 -278.152684) (xy 305.181762 -278.153368)
			(xy 305.181508 -278.153368) (xy 305.149504 -278.155146) (xy 305.125511 -278.154676) (xy 305.078117 -278.14717)
			(xy 305.03248 -278.132344) (xy 304.989724 -278.110561) (xy 304.950902 -278.082358) (xy 304.916969 -278.04843)
			(xy 304.888761 -278.009612) (xy 304.866972 -277.966859) (xy 304.852139 -277.921224) (xy 304.844628 -277.87383)
			(xy 304.844196 -277.849838) (xy 304.844403 -277.835783) (xy 304.847072 -277.807798) (xy 304.84953 -277.793958)
			(xy 304.84953 -277.79345) (xy 304.851029 -277.781218) (xy 304.843722 -277.757726) (xy 304.83556 -277.748492)
			(xy 304.767488 -277.680166) (xy 304.743358 -277.6728) (xy 304.730912 -277.675086) (xy 304.716441 -277.677597)
			(xy 304.687179 -277.680144) (xy 304.672492 -277.680166) (xy 304.65141 -277.67915) (xy 304.650902 -277.67915)
			(xy 304.61839 -277.675086) (xy 304.606198 -277.6728) (xy 304.582068 -277.680166) (xy 304.513742 -277.748492)
			(xy 304.505599 -277.757734) (xy 304.498305 -277.78122) (xy 304.499772 -277.79345) (xy 304.499772 -277.793958)
			(xy 304.502241 -277.807797) (xy 304.504917 -277.835782) (xy 304.505106 -277.849838) (xy 304.504633 -277.873827)
			(xy 304.497122 -277.921214) (xy 304.482291 -277.966843) (xy 304.460505 -278.00959) (xy 304.432301 -278.048404)
			(xy 304.398373 -278.082327) (xy 304.359556 -278.110526) (xy 304.316806 -278.132306) (xy 304.271175 -278.147131)
			(xy 304.223787 -278.154636) (xy 304.199798 -278.155146) (xy 304.168302 -278.153368) (xy 304.167794 -278.153368)
			(xy 304.157175 -278.152856) (xy 304.136978 -278.159423) (xy 304.128678 -278.166068) (xy 304.072544 -278.216614)
			(xy 304.064886 -278.224132) (xy 304.056207 -278.243737) (xy 304.05578 -278.25446) (xy 304.05578 -278.315674)
			(xy 304.055526 -278.322532) (xy 304.055272 -278.323802) (xy 304.055272 -278.328374) (xy 304.055079 -278.338759)
			(xy 304.053555 -278.359475) (xy 304.052224 -278.369776) (xy 304.052224 -278.370284) (xy 304.050954 -278.379174)
			(xy 304.048922 -278.391112) (xy 304.056034 -278.413972) (xy 304.12055 -278.481536) (xy 304.129192 -278.489597)
			(xy 304.151427 -278.497524) (xy 304.163222 -278.496776) (xy 304.163476 -278.496776) (xy 304.17252 -278.495728)
			(xy 304.190694 -278.494584) (xy 304.199798 -278.49449) (xy 304.225056 -278.494983) (xy 304.274883 -278.503297)
			(xy 304.322662 -278.519699) (xy 304.36709 -278.543742) (xy 304.406954 -278.574769) (xy 304.441168 -278.611935)
			(xy 304.468797 -278.654225) (xy 304.489089 -278.700486) (xy 304.50149 -278.749457) (xy 304.505662 -278.7998)
			(xy 304.50149 -278.850143) (xy 304.489089 -278.899114) (xy 304.468797 -278.945375) (xy 304.441168 -278.987665)
			(xy 304.406954 -279.024831) (xy 304.36709 -279.055858) (xy 304.322662 -279.079901) (xy 304.274883 -279.096303)
			(xy 304.225056 -279.104617) (xy 304.199798 -279.105106) (xy 304.17582 -279.104636) (xy 304.128453 -279.097138)
			(xy 304.082841 -279.082326) (xy 304.040106 -279.060564) (xy 304.001299 -279.032388) (xy 303.967374 -278.998492)
			(xy 303.939167 -278.959708) (xy 303.91737 -278.916991) (xy 303.902521 -278.871391) (xy 303.894984 -278.82403)
			(xy 303.89449 -278.800052) (xy 303.89449 -278.799544) (xy 303.894605 -278.79063) (xy 303.895748 -278.772839)
			(xy 303.896776 -278.763984) (xy 303.896776 -278.76373) (xy 303.897591 -278.751927) (xy 303.889641 -278.729676)
			(xy 303.881536 -278.721058) (xy 303.813718 -278.656542) (xy 303.790858 -278.64943) (xy 303.779174 -278.651462)
			(xy 303.765681 -278.65353) (xy 303.738468 -278.655692) (xy 303.724818 -278.65578) (xy 303.72431 -278.65578)
			(xy 303.709045 -278.655621) (xy 303.678643 -278.652819) (xy 303.663604 -278.650192) (xy 303.662842 -278.650192)
			(xy 303.65827 -278.64943) (xy 303.635664 -278.656288) (xy 303.559464 -278.729186) (xy 303.551336 -278.751538)
			(xy 303.55286 -278.763476) (xy 303.553848 -278.772523) (xy 303.554863 -278.790697) (xy 303.554892 -278.799798)
			(xy 303.554406 -278.824617) (xy 303.546376 -278.873602) (xy 303.530527 -278.920642) (xy 303.507276 -278.964499)
			(xy 303.477237 -279.004016) (xy 303.4412 -279.038153) (xy 303.400115 -279.066011) (xy 303.355064 -279.086854)
			(xy 303.307235 -279.100135) (xy 303.257888 -279.105503) (xy 303.208322 -279.102816) (xy 303.159844 -279.092147)
			(xy 303.11373 -279.073775) (xy 303.071196 -279.048185) (xy 303.033363 -279.01605) (xy 303.001226 -278.978219)
			(xy 302.975633 -278.935686) (xy 302.957259 -278.889574) (xy 302.946586 -278.841096) (xy 302.943897 -278.79153)
			(xy 302.949262 -278.742182) (xy 302.96254 -278.694352) (xy 302.983381 -278.649301) (xy 303.011235 -278.608214)
			(xy 303.04537 -278.572175) (xy 303.084886 -278.542133) (xy 303.128741 -278.51888) (xy 303.17578 -278.503028)
			(xy 303.224765 -278.494995) (xy 303.249584 -278.49449) (xy 303.258625 -278.494595) (xy 303.27667 -278.495738)
			(xy 303.285652 -278.496776) (xy 303.286414 -278.496776) (xy 303.298086 -278.497484) (xy 303.320053 -278.489541)
			(xy 303.328578 -278.481536) (xy 303.393094 -278.413972) (xy 303.400206 -278.391112) (xy 303.398174 -278.379428)
			(xy 303.396119 -278.365998) (xy 303.393959 -278.338912) (xy 303.393856 -278.325326) (xy 303.393856 -278.25446)
			(xy 303.393288 -278.243771) (xy 303.38462 -278.224225) (xy 303.377092 -278.216614) (xy 303.320958 -278.166068)
			(xy 303.312738 -278.159279) (xy 303.292481 -278.152696) (xy 303.281842 -278.153368) (xy 303.281588 -278.153368)
			(xy 303.249584 -278.155146) (xy 303.225593 -278.154674) (xy 303.178201 -278.147166) (xy 303.132566 -278.132338)
			(xy 303.089813 -278.110554) (xy 303.050993 -278.082351) (xy 303.017063 -278.048423) (xy 302.988857 -278.009606)
			(xy 302.96707 -277.966854) (xy 302.952239 -277.921221) (xy 302.944728 -277.873829) (xy 302.944276 -277.849838)
			(xy 302.944483 -277.835783) (xy 302.947152 -277.807798) (xy 302.94961 -277.793958) (xy 302.94961 -277.79345)
			(xy 302.951109 -277.781217) (xy 302.943811 -277.757718) (xy 302.93564 -277.748492) (xy 302.867568 -277.680166)
			(xy 302.843438 -277.6728) (xy 302.830992 -277.675086) (xy 302.816521 -277.677596) (xy 302.787259 -277.680141)
			(xy 302.772572 -277.680166) (xy 302.75149 -277.67915) (xy 302.750982 -277.67915) (xy 302.71847 -277.675086)
			(xy 302.706278 -277.6728) (xy 302.682148 -277.680166) (xy 302.613822 -277.748492) (xy 302.605669 -277.75773)
			(xy 302.598362 -277.78122) (xy 302.599852 -277.79345) (xy 302.599852 -277.793958) (xy 302.602321 -277.807797)
			(xy 302.604997 -277.835782) (xy 302.605186 -277.849838) (xy 302.604713 -277.873827) (xy 302.597202 -277.921212)
			(xy 302.582371 -277.96684) (xy 302.560585 -278.009586) (xy 302.53238 -278.048397) (xy 302.498452 -278.082319)
			(xy 302.459635 -278.110516) (xy 302.416884 -278.132294) (xy 302.371254 -278.147116) (xy 302.323867 -278.154617)
			(xy 302.299878 -278.155146) (xy 302.268382 -278.153368) (xy 302.267874 -278.153368) (xy 302.257256 -278.15286)
			(xy 302.237065 -278.159433) (xy 302.228758 -278.166068) (xy 302.172624 -278.216614) (xy 302.164968 -278.224133)
			(xy 302.156293 -278.243737) (xy 302.15586 -278.25446) (xy 302.15586 -278.315674) (xy 302.155606 -278.322532)
			(xy 302.155352 -278.323802) (xy 302.155352 -278.328374) (xy 302.155159 -278.338759) (xy 302.153635 -278.359475)
			(xy 302.152304 -278.369776) (xy 302.152304 -278.370284) (xy 302.151034 -278.379174) (xy 302.149002 -278.391112)
			(xy 302.156114 -278.413972) (xy 302.22063 -278.481536) (xy 302.229271 -278.489601) (xy 302.251506 -278.497536)
			(xy 302.263302 -278.496776) (xy 302.263556 -278.496776) (xy 302.2726 -278.495727) (xy 302.290774 -278.494582)
			(xy 302.299878 -278.49449) (xy 302.325137 -278.494981) (xy 302.374967 -278.503293) (xy 302.422748 -278.519693)
			(xy 302.467179 -278.543735) (xy 302.507046 -278.574762) (xy 302.541262 -278.611928) (xy 302.568894 -278.65422)
			(xy 302.589188 -278.700482) (xy 302.60159 -278.749454) (xy 302.605762 -278.7998) (xy 302.60159 -278.850146)
			(xy 302.589188 -278.899118) (xy 302.568894 -278.94538) (xy 302.541262 -278.987672) (xy 302.507046 -279.024838)
			(xy 302.467179 -279.055865) (xy 302.422748 -279.079907) (xy 302.374967 -279.096307) (xy 302.325137 -279.104619)
			(xy 302.299878 -279.105106) (xy 302.275901 -279.104635) (xy 302.228536 -279.097134) (xy 302.182927 -279.08232)
			(xy 302.140195 -279.060557) (xy 302.10139 -279.032381) (xy 302.067468 -278.998485) (xy 302.039263 -278.959702)
			(xy 302.017468 -278.916986) (xy 302.00262 -278.871388) (xy 301.995083 -278.824029) (xy 301.99457 -278.800052)
			(xy 301.99457 -278.799544) (xy 301.994685 -278.79063) (xy 301.995828 -278.772839) (xy 301.996856 -278.763984)
			(xy 301.996856 -278.76373) (xy 301.997671 -278.751928) (xy 301.989718 -278.729679) (xy 301.981616 -278.721058)
			(xy 301.913798 -278.656542) (xy 301.890938 -278.64943) (xy 301.879254 -278.651462) (xy 301.865761 -278.653529)
			(xy 301.838548 -278.65569) (xy 301.824898 -278.65578) (xy 301.82439 -278.65578) (xy 301.809124 -278.655625)
			(xy 301.778721 -278.65283) (xy 301.763684 -278.650192) (xy 301.762922 -278.650192) (xy 301.75835 -278.64943)
			(xy 301.735744 -278.656288) (xy 301.659544 -278.729186) (xy 301.651416 -278.751538) (xy 301.65294 -278.763476)
			(xy 301.653928 -278.772523) (xy 301.654943 -278.790697) (xy 301.654972 -278.799798) (xy 301.654486 -278.824615)
			(xy 301.646457 -278.873596) (xy 301.630609 -278.920633) (xy 301.607361 -278.964486) (xy 301.577324 -279.004001)
			(xy 301.54129 -279.038135) (xy 301.500209 -279.065991) (xy 301.455162 -279.086834) (xy 301.407337 -279.100114)
			(xy 301.357994 -279.105483) (xy 301.308432 -279.102798) (xy 301.259957 -279.09213) (xy 301.213847 -279.073761)
			(xy 301.171315 -279.048174) (xy 301.133484 -279.016043) (xy 301.101348 -278.978216) (xy 301.075756 -278.935687)
			(xy 301.057381 -278.889579) (xy 301.046708 -278.841106) (xy 301.044016 -278.791544) (xy 301.049379 -278.7422)
			(xy 301.062653 -278.694373) (xy 301.08349 -278.649324) (xy 301.111341 -278.608239) (xy 301.145471 -278.572202)
			(xy 301.184982 -278.54216) (xy 301.228832 -278.518906) (xy 301.275867 -278.503052) (xy 301.324847 -278.495017)
			(xy 301.349664 -278.49449) (xy 301.358705 -278.494594) (xy 301.376751 -278.495737) (xy 301.385732 -278.496776)
			(xy 301.386494 -278.496776) (xy 301.398168 -278.497488) (xy 301.420142 -278.489552) (xy 301.428658 -278.481536)
			(xy 301.493174 -278.413972) (xy 301.500286 -278.391112) (xy 301.498254 -278.379428) (xy 301.496199 -278.365998)
			(xy 301.494039 -278.338912) (xy 301.493936 -278.325326) (xy 301.493936 -278.25446) (xy 301.493368 -278.243771)
			(xy 301.484697 -278.224228) (xy 301.477172 -278.216614) (xy 301.421038 -278.166068) (xy 301.412817 -278.159283)
			(xy 301.392561 -278.152707) (xy 301.381922 -278.153368) (xy 301.381668 -278.153368) (xy 301.349664 -278.155146)
			(xy 301.325674 -278.154673) (xy 301.278284 -278.147162) (xy 301.232652 -278.132332) (xy 301.189902 -278.110547)
			(xy 301.151085 -278.082344) (xy 301.117157 -278.048416) (xy 301.088954 -278.0096) (xy 301.067168 -277.96685)
			(xy 301.052338 -277.921218) (xy 301.044827 -277.873828) (xy 301.044356 -277.849838) (xy 301.044563 -277.835783)
			(xy 301.047232 -277.807798) (xy 301.04969 -277.793958) (xy 301.04969 -277.79345) (xy 301.051189 -277.781217)
			(xy 301.043889 -277.75772) (xy 301.03572 -277.748492) (xy 300.96714 -277.679912) (xy 300.943518 -277.672546)
			(xy 300.93539 -277.67407) (xy 300.905329 -277.679387) (xy 300.844293 -277.679387) (xy 300.814232 -277.67407)
			(xy 300.81347 -277.67407) (xy 300.80585 -277.672546) (xy 300.782228 -277.679912) (xy 300.713648 -277.748492)
			(xy 300.705504 -277.757733) (xy 300.698209 -277.78122) (xy 300.699678 -277.79345) (xy 300.699678 -277.793958)
			(xy 300.702147 -277.807797) (xy 300.704823 -277.835782) (xy 300.705012 -277.849838) (xy 300.704539 -277.873827)
			(xy 300.697028 -277.921215) (xy 300.682197 -277.966844) (xy 300.660412 -278.009592) (xy 300.632208 -278.048405)
			(xy 300.598279 -278.08233) (xy 300.559463 -278.110529) (xy 300.516712 -278.13231) (xy 300.471082 -278.147136)
			(xy 300.423693 -278.154641) (xy 300.399704 -278.155146) (xy 300.3677 -278.153622) (xy 300.357032 -278.152606)
			(xy 300.336712 -278.15921) (xy 300.272704 -278.216614) (xy 300.26505 -278.224134) (xy 300.256379 -278.243738)
			(xy 300.25594 -278.25446) (xy 300.25594 -278.315674) (xy 300.255686 -278.322532) (xy 300.255432 -278.323802)
			(xy 300.255432 -278.328374) (xy 300.255239 -278.338759) (xy 300.253714 -278.359475) (xy 300.252384 -278.369776)
			(xy 300.252384 -278.370284) (xy 300.251114 -278.379174) (xy 300.249082 -278.391112) (xy 300.256194 -278.413972)
			(xy 300.32071 -278.481536) (xy 300.329237 -278.489535) (xy 300.351202 -278.497467) (xy 300.362874 -278.496776)
			(xy 300.363382 -278.496776) (xy 300.372426 -278.495728) (xy 300.3906 -278.494584) (xy 300.399704 -278.49449)
			(xy 300.424525 -278.494976) (xy 300.473513 -278.503008) (xy 300.520556 -278.518859) (xy 300.564415 -278.542113)
			(xy 300.603934 -278.572155) (xy 300.638073 -278.608195) (xy 300.665931 -278.649284) (xy 300.686774 -278.694338)
			(xy 300.700054 -278.742171) (xy 300.705421 -278.791522) (xy 300.702733 -278.841091) (xy 300.692061 -278.889572)
			(xy 300.673686 -278.935688) (xy 300.648092 -278.978224) (xy 300.615954 -279.016059) (xy 300.578119 -279.048196)
			(xy 300.535583 -279.073789) (xy 300.489466 -279.092163) (xy 300.440985 -279.102834) (xy 300.391416 -279.105521)
			(xy 300.342065 -279.100153) (xy 300.294232 -279.086872) (xy 300.249179 -279.066028) (xy 300.208091 -279.038169)
			(xy 300.172051 -279.00403) (xy 300.142009 -278.96451) (xy 300.118757 -278.920651) (xy 300.102907 -278.873607)
			(xy 300.094876 -278.824619) (xy 300.094396 -278.799798) (xy 300.094435 -278.790697) (xy 300.095452 -278.772524)
			(xy 300.096428 -278.763476) (xy 300.097952 -278.751538) (xy 300.089824 -278.729186) (xy 300.013624 -278.656288)
			(xy 299.991018 -278.64943) (xy 299.985938 -278.650192) (xy 299.970835 -278.652819) (xy 299.940307 -278.655621)
			(xy 299.924978 -278.65578) (xy 299.92447 -278.65578) (xy 299.91082 -278.655682) (xy 299.883608 -278.653521)
			(xy 299.870114 -278.651462) (xy 299.85843 -278.64943) (xy 299.83557 -278.656542) (xy 299.767752 -278.721058)
			(xy 299.759694 -278.729701) (xy 299.751773 -278.751935) (xy 299.752512 -278.76373) (xy 299.752512 -278.763984)
			(xy 299.753537 -278.772839) (xy 299.754679 -278.790631) (xy 299.754798 -278.799544) (xy 299.754798 -278.800052)
			(xy 299.754309 -278.82403) (xy 299.746771 -278.871391) (xy 299.731921 -278.91699) (xy 299.710124 -278.959707)
			(xy 299.681916 -278.998491) (xy 299.647991 -279.032387) (xy 299.609184 -279.060561) (xy 299.566448 -279.082322)
			(xy 299.520836 -279.097132) (xy 299.473468 -279.104629) (xy 299.44949 -279.105106) (xy 299.424235 -279.104584)
			(xy 299.374415 -279.096269) (xy 299.326643 -279.079867) (xy 299.282222 -279.055826) (xy 299.242364 -279.024802)
			(xy 299.208155 -278.987641) (xy 299.18053 -278.945356) (xy 299.160241 -278.899101) (xy 299.147842 -278.850137)
			(xy 299.143671 -278.7998) (xy 299.147842 -278.749463) (xy 299.160241 -278.700499) (xy 299.18053 -278.654244)
			(xy 299.208155 -278.611959) (xy 299.242364 -278.574798) (xy 299.282222 -278.543774) (xy 299.326643 -278.519733)
			(xy 299.374415 -278.503331) (xy 299.424235 -278.495016) (xy 299.44949 -278.49449) (xy 299.458594 -278.494589)
			(xy 299.476767 -278.495736) (xy 299.485812 -278.496776) (xy 299.486066 -278.496776) (xy 299.497869 -278.497592)
			(xy 299.520121 -278.489643) (xy 299.528738 -278.481536) (xy 299.593254 -278.413972) (xy 299.600366 -278.391112)
			(xy 299.598334 -278.379428) (xy 299.596279 -278.365998) (xy 299.59412 -278.338912) (xy 299.594016 -278.325326)
			(xy 299.594016 -278.25446) (xy 299.59345 -278.243769) (xy 299.584789 -278.224217) (xy 299.577252 -278.216614)
			(xy 299.520864 -278.166068) (xy 299.512575 -278.159406) (xy 299.49237 -278.152846) (xy 299.481748 -278.153368)
			(xy 299.481494 -278.153368) (xy 299.44949 -278.155146) (xy 299.425498 -278.154675) (xy 299.378105 -278.147168)
			(xy 299.33247 -278.13234) (xy 299.289716 -278.110556) (xy 299.250896 -278.082353) (xy 299.216965 -278.048425)
			(xy 299.188758 -278.009608) (xy 299.166971 -277.966856) (xy 299.152139 -277.921222) (xy 299.144628 -277.87383)
			(xy 299.144182 -277.849838) (xy 299.144389 -277.835783) (xy 299.147058 -277.807798) (xy 299.149516 -277.793958)
			(xy 299.149516 -277.79345) (xy 299.151015 -277.781217) (xy 299.143718 -277.757718) (xy 299.135546 -277.748492)
			(xy 299.067474 -277.680166) (xy 299.043344 -277.6728) (xy 299.030898 -277.675086) (xy 299.016427 -277.677597)
			(xy 298.987165 -277.680142) (xy 298.972478 -277.680166) (xy 298.951396 -277.67915) (xy 298.950888 -277.67915)
			(xy 298.918376 -277.675086) (xy 298.906184 -277.6728) (xy 298.882054 -277.680166) (xy 298.813728 -277.748492)
			(xy 298.805574 -277.75773) (xy 298.798267 -277.78122) (xy 298.799758 -277.79345) (xy 298.799758 -277.793958)
			(xy 298.802227 -277.807797) (xy 298.804903 -277.835782) (xy 298.805092 -277.849838) (xy 298.804619 -277.873827)
			(xy 298.797108 -277.921213) (xy 298.782277 -277.966841) (xy 298.760491 -278.009587) (xy 298.732286 -278.048399)
			(xy 298.698358 -278.082322) (xy 298.659541 -278.110519) (xy 298.616791 -278.132297) (xy 298.57116 -278.14712)
			(xy 298.523773 -278.154623) (xy 298.499784 -278.155146) (xy 298.468288 -278.153368) (xy 298.46778 -278.153368)
			(xy 298.457162 -278.152859) (xy 298.436969 -278.15943) (xy 298.428664 -278.166068) (xy 298.37253 -278.216614)
			(xy 298.364873 -278.224132) (xy 298.356197 -278.243737) (xy 298.355766 -278.25446) (xy 298.355766 -278.299418)
			(xy 298.355512 -278.305006) (xy 298.355512 -278.324818) (xy 298.355288 -278.340539) (xy 298.352231 -278.371833)
			(xy 298.349416 -278.387302) (xy 298.349416 -278.388318) (xy 298.348908 -278.390858) (xy 298.35602 -278.413718)
			(xy 298.420536 -278.481536) (xy 298.429177 -278.489599) (xy 298.451412 -278.497532) (xy 298.463208 -278.496776)
			(xy 298.463462 -278.496776) (xy 298.472506 -278.495727) (xy 298.49068 -278.494582) (xy 298.499784 -278.49449)
			(xy 298.525043 -278.494981) (xy 298.574872 -278.503294) (xy 298.622653 -278.519695) (xy 298.667082 -278.543737)
			(xy 298.706948 -278.574764) (xy 298.741164 -278.61193) (xy 298.768795 -278.654221) (xy 298.789088 -278.700484)
			(xy 298.80149 -278.749455) (xy 298.805662 -278.7998) (xy 298.80149 -278.850145) (xy 298.789088 -278.899116)
			(xy 298.768795 -278.945379) (xy 298.741164 -278.98767) (xy 298.706948 -279.024836) (xy 298.667082 -279.055863)
			(xy 298.622653 -279.079905) (xy 298.574872 -279.096306) (xy 298.525043 -279.104619) (xy 298.499784 -279.105106)
			(xy 298.475806 -279.104635) (xy 298.428441 -279.097135) (xy 298.382831 -279.082322) (xy 298.340098 -279.060559)
			(xy 298.301293 -279.032383) (xy 298.26737 -278.998487) (xy 298.239164 -278.959704) (xy 298.217369 -278.916987)
			(xy 298.20252 -278.871389) (xy 298.194983 -278.824029) (xy 298.194476 -278.800052) (xy 298.194476 -278.799544)
			(xy 298.194591 -278.79063) (xy 298.195734 -278.772839) (xy 298.196762 -278.763984) (xy 298.196762 -278.76373)
			(xy 298.197577 -278.751928) (xy 298.189625 -278.729678) (xy 298.181522 -278.721058) (xy 298.12234 -278.66467)
			(xy 298.113404 -278.656957) (xy 298.090896 -278.64994) (xy 298.07916 -278.651208) (xy 298.078906 -278.651208)
			(xy 298.065418 -278.653336) (xy 298.038204 -278.655622) (xy 298.02455 -278.65578) (xy 298.009284 -278.655623)
			(xy 297.978882 -278.652823) (xy 297.963844 -278.650192) (xy 297.96232 -278.649938) (xy 297.958256 -278.649176)
			(xy 297.93565 -278.656288) (xy 297.85945 -278.729186) (xy 297.851322 -278.751538) (xy 297.852846 -278.763476)
			(xy 297.853834 -278.772523) (xy 297.854849 -278.790697) (xy 297.854878 -278.799798) (xy 297.854392 -278.824616)
			(xy 297.846363 -278.873598) (xy 297.830515 -278.920636) (xy 297.807265 -278.96449) (xy 297.777228 -279.004005)
			(xy 297.741193 -279.038141) (xy 297.700111 -279.065997) (xy 297.655063 -279.08684) (xy 297.607237 -279.10012)
			(xy 297.557892 -279.105489) (xy 297.508329 -279.102803) (xy 297.459853 -279.092135) (xy 297.413742 -279.073765)
			(xy 297.37121 -279.048177) (xy 297.333377 -279.016045) (xy 297.301242 -278.978216) (xy 297.275649 -278.935687)
			(xy 297.257274 -278.889578) (xy 297.246601 -278.841103) (xy 297.243911 -278.79154) (xy 297.249274 -278.742195)
			(xy 297.262549 -278.694367) (xy 297.283387 -278.649317) (xy 297.311239 -278.608232) (xy 297.345371 -278.572194)
			(xy 297.384883 -278.542152) (xy 297.428735 -278.518898) (xy 297.475771 -278.503045) (xy 297.524752 -278.49501)
			(xy 297.54957 -278.49449) (xy 297.558671 -278.494528) (xy 297.576844 -278.495543) (xy 297.585892 -278.496522)
			(xy 297.59783 -278.498046) (xy 297.620182 -278.489918) (xy 297.69308 -278.413718) (xy 297.700192 -278.391112)
			(xy 297.69943 -278.386286) (xy 297.696703 -278.371065) (xy 297.693776 -278.34028) (xy 297.693588 -278.324818)
			(xy 297.693588 -278.25446) (xy 297.693021 -278.24377) (xy 297.684357 -278.224221) (xy 297.676824 -278.216614)
			(xy 297.62069 -278.166068) (xy 297.612472 -278.159273) (xy 297.592213 -278.152677) (xy 297.581574 -278.153368)
			(xy 297.58132 -278.153368) (xy 297.54957 -278.155146) (xy 297.525579 -278.154673) (xy 297.478189 -278.147164)
			(xy 297.432556 -278.132334) (xy 297.389805 -278.110549) (xy 297.350988 -278.082346) (xy 297.317059 -278.048419)
			(xy 297.288855 -278.009602) (xy 297.267069 -277.966851) (xy 297.252238 -277.921219) (xy 297.244727 -277.873829)
			(xy 297.244262 -277.849838) (xy 297.244469 -277.835783) (xy 297.247138 -277.807798) (xy 297.249596 -277.793958)
			(xy 297.249596 -277.79345) (xy 297.251095 -277.781217) (xy 297.243795 -277.75772) (xy 297.235626 -277.748492)
			(xy 297.167554 -277.680166) (xy 297.143424 -277.6728) (xy 297.130978 -277.675086) (xy 297.116507 -277.677596)
			(xy 297.087245 -277.680139) (xy 297.072558 -277.680166) (xy 297.051476 -277.67915) (xy 297.050968 -277.67915)
			(xy 297.018456 -277.675086) (xy 297.006264 -277.6728) (xy 296.982134 -277.680166) (xy 296.913808 -277.748492)
			(xy 296.905656 -277.75773) (xy 296.898352 -277.78122) (xy 296.899838 -277.79345) (xy 296.899838 -277.793958)
			(xy 296.902307 -277.807797) (xy 296.904983 -277.835782) (xy 296.905172 -277.849838) (xy 296.904699 -277.873826)
			(xy 296.897187 -277.921211) (xy 296.882356 -277.966838) (xy 296.86057 -278.009583) (xy 296.832365 -278.048393)
			(xy 296.798437 -278.082314) (xy 296.759619 -278.110509) (xy 296.716869 -278.132285) (xy 296.671239 -278.147105)
			(xy 296.623852 -278.154604) (xy 296.599864 -278.155146) (xy 296.568368 -278.153368) (xy 296.56786 -278.153368)
			(xy 296.557236 -278.152843) (xy 296.537022 -278.15939) (xy 296.528744 -278.166068) (xy 296.47261 -278.216614)
			(xy 296.464956 -278.224134) (xy 296.456283 -278.243738) (xy 296.455846 -278.25446) (xy 296.455846 -278.299418)
			(xy 296.455592 -278.305006) (xy 296.455592 -278.324818) (xy 296.455368 -278.340539) (xy 296.452311 -278.371833)
			(xy 296.449496 -278.387302) (xy 296.449496 -278.388318) (xy 296.448988 -278.390858) (xy 296.4561 -278.413718)
			(xy 296.520616 -278.481536) (xy 296.529256 -278.489603) (xy 296.551492 -278.497545) (xy 296.563288 -278.496776)
			(xy 296.563542 -278.496776) (xy 296.572586 -278.495727) (xy 296.59076 -278.494581) (xy 296.599864 -278.49449)
			(xy 296.625124 -278.49498) (xy 296.674955 -278.50329) (xy 296.722739 -278.519689) (xy 296.767172 -278.54373)
			(xy 296.807041 -278.574757) (xy 296.841259 -278.611924) (xy 296.868892 -278.654216) (xy 296.889187 -278.70048)
			(xy 296.90159 -278.749453) (xy 296.905762 -278.7998) (xy 296.90159 -278.850147) (xy 296.889187 -278.89912)
			(xy 296.868892 -278.945384) (xy 296.841259 -278.987676) (xy 296.807041 -279.024843) (xy 296.767172 -279.05587)
			(xy 296.722739 -279.079911) (xy 296.674955 -279.09631) (xy 296.625124 -279.10462) (xy 296.599864 -279.105106)
			(xy 296.575887 -279.104634) (xy 296.528525 -279.097131) (xy 296.482917 -279.082316) (xy 296.440187 -279.060553)
			(xy 296.401384 -279.032376) (xy 296.367464 -278.99848) (xy 296.339261 -278.959698) (xy 296.317467 -278.916983)
			(xy 296.30262 -278.871386) (xy 296.295083 -278.824028) (xy 296.294556 -278.800052) (xy 296.294556 -278.799544)
			(xy 296.294671 -278.79063) (xy 296.295814 -278.772839) (xy 296.296842 -278.763984) (xy 296.296842 -278.76373)
			(xy 296.297657 -278.751928) (xy 296.289703 -278.72968) (xy 296.281602 -278.721058) (xy 296.22242 -278.66467)
			(xy 296.213483 -278.656961) (xy 296.190976 -278.649952) (xy 296.17924 -278.651208) (xy 296.178986 -278.651208)
			(xy 296.165498 -278.653339) (xy 296.138285 -278.655632) (xy 296.12463 -278.65578) (xy 296.109364 -278.655622)
			(xy 296.078963 -278.65282) (xy 296.063924 -278.650192) (xy 296.0624 -278.649938) (xy 296.058336 -278.649176)
			(xy 296.03573 -278.656288) (xy 295.95953 -278.729186) (xy 295.951402 -278.751538) (xy 295.952926 -278.763476)
			(xy 295.953914 -278.772523) (xy 295.954929 -278.790697) (xy 295.954958 -278.799798) (xy 295.954473 -278.824614)
			(xy 295.946444 -278.873592) (xy 295.930597 -278.920626) (xy 295.90735 -278.964477) (xy 295.877315 -279.00399)
			(xy 295.841284 -279.038123) (xy 295.800205 -279.065977) (xy 295.755161 -279.086819) (xy 295.707339 -279.100099)
			(xy 295.657998 -279.105468) (xy 295.608439 -279.102784) (xy 295.559967 -279.092118) (xy 295.513858 -279.073751)
			(xy 295.471329 -279.048166) (xy 295.433499 -279.016038) (xy 295.401364 -278.978213) (xy 295.375772 -278.935688)
			(xy 295.357397 -278.889583) (xy 295.346723 -278.841113) (xy 295.34403 -278.791554) (xy 295.349391 -278.742212)
			(xy 295.362663 -278.694388) (xy 295.383497 -278.649341) (xy 295.411345 -278.608257) (xy 295.445471 -278.57222)
			(xy 295.484979 -278.542178) (xy 295.528826 -278.518924) (xy 295.575857 -278.503069) (xy 295.624834 -278.495032)
			(xy 295.64965 -278.49449) (xy 295.658751 -278.494531) (xy 295.676923 -278.49555) (xy 295.685972 -278.496522)
			(xy 295.69791 -278.498046) (xy 295.720262 -278.489918) (xy 295.79316 -278.413718) (xy 295.800272 -278.391112)
			(xy 295.79951 -278.386286) (xy 295.796784 -278.371065) (xy 295.793857 -278.34028) (xy 295.793668 -278.324818)
			(xy 295.793668 -278.25446) (xy 295.793101 -278.24377) (xy 295.784434 -278.224224) (xy 295.776904 -278.216614)
			(xy 295.72077 -278.166068) (xy 295.712551 -278.159277) (xy 295.692293 -278.152688) (xy 295.681654 -278.153368)
			(xy 295.6814 -278.153368) (xy 295.64965 -278.155146) (xy 295.62566 -278.154672) (xy 295.578272 -278.14716)
			(xy 295.532643 -278.132328) (xy 295.489894 -278.110543) (xy 295.451079 -278.082339) (xy 295.417153 -278.048412)
			(xy 295.388951 -278.009596) (xy 295.367167 -277.966846) (xy 295.352338 -277.921216) (xy 295.344827 -277.873828)
			(xy 295.344342 -277.849838) (xy 295.344549 -277.835783) (xy 295.347218 -277.807798) (xy 295.349676 -277.793958)
			(xy 295.349676 -277.79345) (xy 295.351175 -277.781217) (xy 295.343873 -277.757721) (xy 295.335706 -277.748492)
			(xy 295.267634 -277.680166) (xy 295.243504 -277.6728) (xy 295.231058 -277.675086) (xy 295.217149 -277.677484)
			(xy 295.189037 -277.680027) (xy 295.174924 -277.680166) (xy 295.17467 -277.680166) (xy 295.160615 -277.679956)
			(xy 295.132632 -277.677281) (xy 295.11879 -277.674832) (xy 295.118282 -277.674832) (xy 295.106047 -277.673325)
			(xy 295.082541 -277.680617) (xy 295.073324 -277.688802) (xy 295.013634 -277.748238) (xy 295.005502 -277.757482)
			(xy 294.998229 -277.780965) (xy 294.999664 -277.793196) (xy 294.999664 -277.79345) (xy 295.002148 -277.807415)
			(xy 295.004816 -277.835655) (xy 295.004998 -277.849838) (xy 295.004525 -277.873827) (xy 294.997014 -277.921214)
			(xy 294.982183 -277.966842) (xy 294.960397 -278.009588) (xy 294.932193 -278.048401) (xy 294.898265 -278.082324)
			(xy 294.859447 -278.110522) (xy 294.816697 -278.132301) (xy 294.771067 -278.147125) (xy 294.723679 -278.154628)
			(xy 294.69969 -278.155146) (xy 294.667686 -278.153622) (xy 294.657018 -278.152606) (xy 294.636698 -278.15921)
			(xy 294.57269 -278.216868) (xy 294.565031 -278.224386) (xy 294.556344 -278.24399) (xy 294.555926 -278.254714)
			(xy 294.555926 -278.299418) (xy 294.555672 -278.305006) (xy 294.555672 -278.324818) (xy 294.555516 -278.340084)
			(xy 294.552719 -278.370487) (xy 294.550084 -278.385524) (xy 294.54983 -278.387048) (xy 294.549068 -278.391112)
			(xy 294.55618 -278.413718) (xy 294.629078 -278.489918) (xy 294.65143 -278.498046) (xy 294.663368 -278.496522)
			(xy 294.672415 -278.495533) (xy 294.690589 -278.494518) (xy 294.69969 -278.49449) (xy 294.724511 -278.494975)
			(xy 294.7735 -278.503005) (xy 294.820544 -278.518854) (xy 294.864405 -278.542106) (xy 294.903925 -278.572147)
			(xy 294.938065 -278.608187) (xy 294.965925 -278.649274) (xy 294.986771 -278.694328) (xy 295.000052 -278.742161)
			(xy 295.005421 -278.791512) (xy 295.002734 -278.841082) (xy 294.992063 -278.889564) (xy 294.973689 -278.935681)
			(xy 294.948097 -278.978218) (xy 294.915959 -279.016054) (xy 294.878124 -279.048192) (xy 294.835588 -279.073786)
			(xy 294.789472 -279.092161) (xy 294.74099 -279.102833) (xy 294.69142 -279.105521) (xy 294.642069 -279.100154)
			(xy 294.594236 -279.086873) (xy 294.549181 -279.066029) (xy 294.508093 -279.038171) (xy 294.472053 -279.004031)
			(xy 294.44201 -278.964511) (xy 294.418757 -278.920652) (xy 294.402907 -278.873608) (xy 294.394876 -278.824619)
			(xy 294.394382 -278.799798) (xy 294.394421 -278.790697) (xy 294.395438 -278.772524) (xy 294.396414 -278.763476)
			(xy 294.397938 -278.751538) (xy 294.38981 -278.729186) (xy 294.31361 -278.656288) (xy 294.291004 -278.649176)
			(xy 294.286178 -278.649938) (xy 294.270957 -278.652664) (xy 294.240172 -278.655591) (xy 294.22471 -278.65578)
			(xy 294.211119 -278.655611) (xy 294.184034 -278.653324) (xy 294.170608 -278.651208) (xy 294.1701 -278.651208)
			(xy 294.158365 -278.649927) (xy 294.13586 -278.656958) (xy 294.12692 -278.66467) (xy 294.067738 -278.721058)
			(xy 294.059682 -278.729702) (xy 294.051763 -278.751935) (xy 294.052498 -278.76373) (xy 294.052498 -278.763984)
			(xy 294.053523 -278.772839) (xy 294.054665 -278.790631) (xy 294.054784 -278.799544) (xy 294.054784 -278.800052)
			(xy 294.054295 -278.82403) (xy 294.046757 -278.871389) (xy 294.031907 -278.916988) (xy 294.01011 -278.959704)
			(xy 293.981902 -278.998486) (xy 293.947976 -279.032381) (xy 293.909168 -279.060554) (xy 293.866433 -279.082313)
			(xy 293.820821 -279.097122) (xy 293.773454 -279.104616) (xy 293.749476 -279.105106) (xy 293.724222 -279.104583)
			(xy 293.674404 -279.096266) (xy 293.626634 -279.079863) (xy 293.582215 -279.055821) (xy 293.542358 -279.024797)
			(xy 293.508152 -278.987636) (xy 293.480528 -278.945352) (xy 293.46024 -278.899098) (xy 293.447842 -278.850135)
			(xy 293.443671 -278.7998) (xy 293.447842 -278.749465) (xy 293.46024 -278.700502) (xy 293.480528 -278.654248)
			(xy 293.508152 -278.611964) (xy 293.542358 -278.574803) (xy 293.582215 -278.543779) (xy 293.626634 -278.519737)
			(xy 293.674404 -278.503334) (xy 293.724222 -278.495017) (xy 293.749476 -278.49449) (xy 293.75858 -278.494589)
			(xy 293.776753 -278.495734) (xy 293.785798 -278.496776) (xy 293.786052 -278.496776) (xy 293.797856 -278.497595)
			(xy 293.820113 -278.489651) (xy 293.828724 -278.481536) (xy 293.89324 -278.413718) (xy 293.900352 -278.390858)
			(xy 293.899844 -278.38781) (xy 293.896997 -278.372218) (xy 293.893942 -278.340667) (xy 293.893748 -278.324818)
			(xy 293.893748 -278.25446) (xy 293.89318 -278.243771) (xy 293.884511 -278.224227) (xy 293.876984 -278.216614)
			(xy 293.82085 -278.166068) (xy 293.81263 -278.159281) (xy 293.792373 -278.1527) (xy 293.781734 -278.153368)
			(xy 293.78148 -278.153368) (xy 293.749476 -278.155146) (xy 293.725485 -278.154674) (xy 293.678094 -278.147165)
			(xy 293.632461 -278.132336) (xy 293.589709 -278.110552) (xy 293.55089 -278.082348) (xy 293.516961 -278.048421)
			(xy 293.488756 -278.009603) (xy 293.46697 -277.966852) (xy 293.452138 -277.92122) (xy 293.444627 -277.873829)
			(xy 293.444168 -277.849838) (xy 293.444375 -277.835783) (xy 293.447044 -277.807798) (xy 293.449502 -277.793958)
			(xy 293.449502 -277.79345) (xy 293.451001 -277.781217) (xy 293.443702 -277.757719) (xy 293.435532 -277.748492)
			(xy 293.36746 -277.680166) (xy 293.34333 -277.6728) (xy 293.330884 -277.675086) (xy 293.316413 -277.677596)
			(xy 293.287151 -277.68014) (xy 293.272464 -277.680166) (xy 293.251382 -277.67915) (xy 293.250874 -277.67915)
			(xy 293.218362 -277.675086) (xy 293.20617 -277.6728) (xy 293.18204 -277.680166) (xy 293.113714 -277.748492)
			(xy 293.105562 -277.75773) (xy 293.098256 -277.78122) (xy 293.099744 -277.79345) (xy 293.099744 -277.793958)
			(xy 293.102213 -277.807797) (xy 293.104889 -277.835782) (xy 293.105078 -277.849838) (xy 293.104605 -277.873826)
			(xy 293.097093 -277.921212) (xy 293.082262 -277.966839) (xy 293.060476 -278.009584) (xy 293.032272 -278.048395)
			(xy 292.998343 -278.082316) (xy 292.959526 -278.110512) (xy 292.916776 -278.132288) (xy 292.871146 -278.147109)
			(xy 292.823759 -278.15461) (xy 292.79977 -278.155146) (xy 292.768274 -278.153368) (xy 292.767766 -278.153368)
			(xy 292.757149 -278.152862) (xy 292.73696 -278.159437) (xy 292.72865 -278.166068) (xy 292.672516 -278.216614)
			(xy 292.664861 -278.224133) (xy 292.656188 -278.243738) (xy 292.655752 -278.25446) (xy 292.655752 -278.315674)
			(xy 292.655498 -278.322532) (xy 292.655244 -278.323802) (xy 292.655244 -278.328374) (xy 292.655051 -278.338759)
			(xy 292.653526 -278.359475) (xy 292.652196 -278.369776) (xy 292.652196 -278.370284) (xy 292.650926 -278.379174)
			(xy 292.648894 -278.391112) (xy 292.656006 -278.413972) (xy 292.720522 -278.481536) (xy 292.729162 -278.489602)
			(xy 292.751398 -278.497541) (xy 292.763194 -278.496776) (xy 292.763448 -278.496776) (xy 292.772492 -278.495727)
			(xy 292.790666 -278.494581) (xy 292.79977 -278.49449) (xy 292.82503 -278.49498) (xy 292.87486 -278.503291)
			(xy 292.922643 -278.519691) (xy 292.967075 -278.543732) (xy 293.006943 -278.574759) (xy 293.04116 -278.611926)
			(xy 293.068793 -278.654217) (xy 293.089088 -278.700481) (xy 293.10149 -278.749454) (xy 293.105662 -278.7998)
			(xy 293.10149 -278.850146) (xy 293.089087 -278.899119) (xy 293.068793 -278.945383) (xy 293.04116 -278.987674)
			(xy 293.006943 -279.024841) (xy 292.967075 -279.055868) (xy 292.922643 -279.079909) (xy 292.87486 -279.096309)
			(xy 292.82503 -279.10462) (xy 292.79977 -279.105106) (xy 292.775793 -279.104634) (xy 292.72843 -279.097132)
			(xy 292.682821 -279.082318) (xy 292.64009 -279.060555) (xy 292.601287 -279.032378) (xy 292.567366 -278.998482)
			(xy 292.539162 -278.959699) (xy 292.517368 -278.916984) (xy 292.50252 -278.871387) (xy 292.494983 -278.824029)
			(xy 292.494462 -278.800052) (xy 292.494462 -278.799544) (xy 292.494577 -278.79063) (xy 292.49572 -278.772839)
			(xy 292.496748 -278.763984) (xy 292.496748 -278.76373) (xy 292.497563 -278.751928) (xy 292.489609 -278.72968)
			(xy 292.481508 -278.721058) (xy 292.41369 -278.656542) (xy 292.39083 -278.64943) (xy 292.379146 -278.651462)
			(xy 292.365653 -278.653528) (xy 292.33844 -278.655689) (xy 292.32479 -278.65578) (xy 292.324282 -278.65578)
			(xy 292.309016 -278.655624) (xy 292.278613 -278.652829) (xy 292.263576 -278.650192) (xy 292.262814 -278.650192)
			(xy 292.258242 -278.64943) (xy 292.235636 -278.656288) (xy 292.159436 -278.729186) (xy 292.151308 -278.751538)
			(xy 292.152832 -278.763476) (xy 292.15382 -278.772523) (xy 292.154835 -278.790697) (xy 292.154864 -278.799798)
			(xy 292.154378 -278.824615) (xy 292.146349 -278.873594) (xy 292.130502 -278.920629) (xy 292.107254 -278.964481)
			(xy 292.077219 -279.003994) (xy 292.041186 -279.038128) (xy 292.000107 -279.065983) (xy 291.955062 -279.086825)
			(xy 291.907238 -279.100106) (xy 291.857896 -279.105474) (xy 291.808336 -279.10279) (xy 291.759862 -279.092123)
			(xy 291.713753 -279.073755) (xy 291.671223 -279.048169) (xy 291.633392 -279.01604) (xy 291.601257 -278.978214)
			(xy 291.575665 -278.935688) (xy 291.55729 -278.889582) (xy 291.546616 -278.84111) (xy 291.543924 -278.79155)
			(xy 291.549286 -278.742207) (xy 291.562559 -278.694382) (xy 291.583394 -278.649334) (xy 291.611243 -278.60825)
			(xy 291.645371 -278.572212) (xy 291.68488 -278.54217) (xy 291.728729 -278.518916) (xy 291.775761 -278.503062)
			(xy 291.82474 -278.495025) (xy 291.849556 -278.49449) (xy 291.858597 -278.494594) (xy 291.876643 -278.495736)
			(xy 291.885624 -278.496776) (xy 291.886386 -278.496776) (xy 291.898061 -278.49749) (xy 291.920037 -278.489556)
			(xy 291.92855 -278.481536) (xy 291.993066 -278.413972) (xy 292.000178 -278.391112) (xy 291.998146 -278.379428)
			(xy 291.996091 -278.365998) (xy 291.993931 -278.338912) (xy 291.993828 -278.325326) (xy 291.993828 -278.25446)
			(xy 291.993262 -278.243769) (xy 291.984603 -278.224216) (xy 291.977064 -278.216614) (xy 291.92093 -278.166068)
			(xy 291.912709 -278.159284) (xy 291.892453 -278.152712) (xy 291.881814 -278.153368) (xy 291.88156 -278.153368)
			(xy 291.849556 -278.155146) (xy 291.8243 -278.154621) (xy 291.774478 -278.1463) (xy 291.726704 -278.129894)
			(xy 291.682282 -278.105848) (xy 291.642423 -278.074819) (xy 291.608215 -278.037654) (xy 291.58059 -277.995365)
			(xy 291.560301 -277.949107) (xy 291.547902 -277.90014) (xy 291.543731 -277.8498) (xy 291.547902 -277.79946)
			(xy 291.560301 -277.750493) (xy 291.58059 -277.704235) (xy 291.608215 -277.661946) (xy 291.642423 -277.624781)
			(xy 291.682282 -277.593752) (xy 291.726704 -277.569706) (xy 291.774478 -277.5533) (xy 291.8243 -277.544979)
			(xy 291.849556 -277.54453) (xy 291.881306 -277.546308) (xy 291.881814 -277.546308) (xy 291.892432 -277.546818)
			(xy 291.912625 -277.540246) (xy 291.92093 -277.533608) (xy 291.977064 -277.483062) (xy 291.984718 -277.475543)
			(xy 291.993386 -277.455938) (xy 291.993828 -277.445216) (xy 291.993828 -277.34895) (xy 291.995606 -277.314914)
			(xy 291.996876 -277.303484) (xy 291.989256 -277.281894) (xy 291.924994 -277.217886) (xy 291.91642 -277.210267)
			(xy 291.894787 -277.202737) (xy 291.883338 -277.203408) (xy 291.84981 -277.205186) (xy 291.827088 -277.204769)
			(xy 291.782147 -277.198032) (xy 291.738701 -277.184705) (xy 291.697712 -277.165083) (xy 291.660086 -277.1396)
			(xy 291.626654 -277.10882) (xy 291.612066 -277.091394) (xy 291.604445 -277.083004) (xy 291.584012 -277.07326)
			(xy 291.572696 -277.072598) (xy 291.176964 -277.072598) (xy 291.165635 -277.073204) (xy 291.145188 -277.082965)
			(xy 291.137594 -277.091394) (xy 291.123014 -277.108825) (xy 291.089574 -277.139595) (xy 291.051944 -277.16507)
			(xy 291.010954 -277.184687) (xy 290.96751 -277.198013) (xy 290.922571 -277.204755) (xy 290.89985 -277.205186)
			(xy 290.885795 -277.20498) (xy 290.85781 -277.202311) (xy 290.84397 -277.199852) (xy 290.843462 -277.199852)
			(xy 290.831229 -277.19835) (xy 290.807731 -277.205651) (xy 290.798504 -277.213822) (xy 290.739068 -277.273258)
			(xy 290.730915 -277.282497) (xy 290.723601 -277.305987) (xy 290.725098 -277.318216) (xy 290.725098 -277.31847)
			(xy 290.727207 -277.330368) (xy 290.729752 -277.3544) (xy 290.730178 -277.366476) (xy 290.730178 -277.378414)
			(xy 290.729801 -277.392612) (xy 290.726745 -277.420851) (xy 290.724082 -277.434802) (xy 290.724082 -277.435818)
			(xy 290.722558 -277.443692) (xy 290.729924 -277.467314) (xy 290.798504 -277.535894) (xy 290.807743 -277.544043)
			(xy 290.831232 -277.551342) (xy 290.843462 -277.549864) (xy 290.843716 -277.549864) (xy 290.857618 -277.547388)
			(xy 290.885731 -277.544717) (xy 290.89985 -277.54453) (xy 290.924666 -277.54502) (xy 290.973644 -277.553057)
			(xy 291.020676 -277.568911) (xy 291.064524 -277.592166) (xy 291.104032 -277.622207) (xy 291.13816 -277.658244)
			(xy 291.166009 -277.699327) (xy 291.186845 -277.744374) (xy 291.200119 -277.792199) (xy 291.205481 -277.841541)
			(xy 291.202791 -277.8911) (xy 291.192119 -277.939572) (xy 291.173746 -277.985678) (xy 291.148156 -278.028205)
			(xy 291.116024 -278.066033) (xy 291.078196 -278.098163) (xy 291.035667 -278.123751) (xy 290.98956 -278.142123)
			(xy 290.941088 -278.152793) (xy 290.891528 -278.155481) (xy 290.842187 -278.150117) (xy 290.794363 -278.136841)
			(xy 290.749316 -278.116003) (xy 290.708234 -278.088153) (xy 290.672199 -278.054023) (xy 290.642159 -278.014513)
			(xy 290.618907 -277.970665) (xy 290.603054 -277.923632) (xy 290.595019 -277.874654) (xy 290.594542 -277.849838)
			(xy 290.594749 -277.835783) (xy 290.597418 -277.807798) (xy 290.599876 -277.793958) (xy 290.599876 -277.79345)
			(xy 290.601375 -277.781217) (xy 290.594073 -277.757721) (xy 290.585906 -277.748492) (xy 290.517326 -277.679912)
			(xy 290.493704 -277.672546) (xy 290.485576 -277.67407) (xy 290.455515 -277.679387) (xy 290.394479 -277.679387)
			(xy 290.364418 -277.67407) (xy 290.363656 -277.67407) (xy 290.356036 -277.672546) (xy 290.332414 -277.679912)
			(xy 290.263834 -277.748492) (xy 290.255692 -277.757734) (xy 290.248399 -277.78122) (xy 290.249864 -277.79345)
			(xy 290.249864 -277.793958) (xy 290.252333 -277.807797) (xy 290.255009 -277.835782) (xy 290.255198 -277.849838)
			(xy 290.254725 -277.873827) (xy 290.247214 -277.921214) (xy 290.232383 -277.966842) (xy 290.210597 -278.009588)
			(xy 290.182393 -278.048401) (xy 290.148465 -278.082324) (xy 290.109647 -278.110522) (xy 290.066897 -278.132301)
			(xy 290.021267 -278.147125) (xy 289.973879 -278.154628) (xy 289.94989 -278.155146) (xy 289.91814 -278.153368)
			(xy 289.917632 -278.153368) (xy 289.90701 -278.152849) (xy 289.886803 -278.159404) (xy 289.878516 -278.166068)
			(xy 289.822382 -278.216614) (xy 289.814719 -278.224129) (xy 289.806034 -278.243735) (xy 289.805618 -278.25446)
			(xy 289.805618 -278.299418) (xy 289.805364 -278.305006) (xy 289.805364 -278.324818) (xy 289.80514 -278.340539)
			(xy 289.802082 -278.371833) (xy 289.799268 -278.387302) (xy 289.799268 -278.388318) (xy 289.79876 -278.390858)
			(xy 289.805872 -278.413718) (xy 289.870388 -278.481536) (xy 289.879027 -278.489609) (xy 289.901264 -278.497562)
			(xy 289.91306 -278.496776) (xy 289.913314 -278.496776) (xy 289.922422 -278.495722) (xy 289.940722 -278.494579)
			(xy 289.94989 -278.49449) (xy 289.975148 -278.494982) (xy 290.024977 -278.503295) (xy 290.072757 -278.519697)
			(xy 290.117185 -278.543739) (xy 290.157051 -278.574766) (xy 290.191266 -278.611932) (xy 290.218896 -278.654223)
			(xy 290.239189 -278.700485) (xy 290.25159 -278.749456) (xy 290.255762 -278.799798) (xy 290.594046 -278.799798)
			(xy 290.598006 -278.750744) (xy 290.609783 -278.70296) (xy 290.629074 -278.657684) (xy 290.655377 -278.616088)
			(xy 290.688012 -278.579251) (xy 290.726133 -278.548126) (xy 290.768754 -278.523519) (xy 290.81477 -278.506067)
			(xy 290.862989 -278.496223) (xy 290.912164 -278.494242) (xy 290.961019 -278.500174) (xy 291.00829 -278.513866)
			(xy 291.052752 -278.534964) (xy 291.093255 -278.56292) (xy 291.128748 -278.597012) (xy 291.158313 -278.636356)
			(xy 291.181184 -278.679933) (xy 291.196768 -278.726614) (xy 291.204663 -278.775191) (xy 291.205158 -278.799798)
			(xy 291.204663 -278.824405) (xy 291.196768 -278.872982) (xy 291.181184 -278.919663) (xy 291.158313 -278.96324)
			(xy 291.128748 -279.002584) (xy 291.093255 -279.036676) (xy 291.052752 -279.064632) (xy 291.00829 -279.08573)
			(xy 290.961019 -279.099422) (xy 290.912164 -279.105354) (xy 290.862989 -279.103373) (xy 290.81477 -279.093529)
			(xy 290.768754 -279.076077) (xy 290.726133 -279.05147) (xy 290.688012 -279.020345) (xy 290.655377 -278.983508)
			(xy 290.629074 -278.941912) (xy 290.609783 -278.896636) (xy 290.598006 -278.848852) (xy 290.594046 -278.799798)
			(xy 290.255762 -278.799798) (xy 290.255762 -278.7998) (xy 290.25159 -278.850144) (xy 290.239189 -278.899115)
			(xy 290.218896 -278.945377) (xy 290.191266 -278.987668) (xy 290.157051 -279.024834) (xy 290.117185 -279.055861)
			(xy 290.072757 -279.079903) (xy 290.024977 -279.096305) (xy 289.975148 -279.104618) (xy 289.94989 -279.105106)
			(xy 289.925912 -279.104636) (xy 289.878546 -279.097136) (xy 289.832935 -279.082323) (xy 289.790201 -279.060561)
			(xy 289.751395 -279.032386) (xy 289.717472 -278.998489) (xy 289.689265 -278.959705) (xy 289.667469 -278.916989)
			(xy 289.65262 -278.87139) (xy 289.645083 -278.82403) (xy 289.644582 -278.800052) (xy 289.644582 -278.799544)
			(xy 289.644697 -278.79063) (xy 289.64584 -278.772839) (xy 289.646868 -278.763984) (xy 289.646868 -278.76373)
			(xy 289.647683 -278.751928) (xy 289.639732 -278.729677) (xy 289.631628 -278.721058) (xy 289.572446 -278.66467)
			(xy 289.56351 -278.656956) (xy 289.541002 -278.649936) (xy 289.529266 -278.651208) (xy 289.529012 -278.651208)
			(xy 289.515524 -278.653336) (xy 289.48831 -278.655623) (xy 289.474656 -278.65578) (xy 289.474402 -278.65578)
			(xy 289.46088 -278.65566) (xy 289.433923 -278.653494) (xy 289.420554 -278.651462) (xy 289.408616 -278.64943)
			(xy 289.385756 -278.656542) (xy 289.318446 -278.720804) (xy 289.310379 -278.729444) (xy 289.302435 -278.75168)
			(xy 289.303206 -278.763476) (xy 289.303206 -278.76373) (xy 289.30419 -278.772714) (xy 289.30521 -278.79076)
			(xy 289.305238 -278.799798) (xy 289.304752 -278.824622) (xy 289.29672 -278.873616) (xy 289.280868 -278.920664)
			(xy 289.257612 -278.964529) (xy 289.227566 -279.004052) (xy 289.191522 -279.038195) (xy 289.150429 -279.066056)
			(xy 289.105369 -279.086901) (xy 289.057531 -279.100182) (xy 289.008174 -279.105549) (xy 288.958599 -279.10286)
			(xy 288.910113 -279.092185) (xy 288.863992 -279.073807) (xy 288.821452 -279.048209) (xy 288.783614 -279.016066)
			(xy 288.751474 -278.978225) (xy 288.72588 -278.935683) (xy 288.707506 -278.889561) (xy 288.696836 -278.841073)
			(xy 288.694152 -278.791498) (xy 288.699523 -278.742142) (xy 288.712808 -278.694305) (xy 288.733658 -278.649247)
			(xy 288.761523 -278.608156) (xy 288.795668 -278.572115) (xy 288.835195 -278.542073) (xy 288.879061 -278.518821)
			(xy 288.926112 -278.502973) (xy 288.975106 -278.494946) (xy 288.99993 -278.49449) (xy 289.008904 -278.49453)
			(xy 289.026823 -278.495546) (xy 289.035744 -278.496522) (xy 289.047682 -278.498046) (xy 289.070034 -278.489918)
			(xy 289.142932 -278.413718) (xy 289.150044 -278.391112) (xy 289.149282 -278.386286) (xy 289.146555 -278.371065)
			(xy 289.143628 -278.34028) (xy 289.14344 -278.324818) (xy 289.14344 -278.25446) (xy 289.142872 -278.243771)
			(xy 289.134202 -278.224228) (xy 289.126676 -278.216614) (xy 289.062668 -278.15921) (xy 289.042348 -278.152606)
			(xy 289.03168 -278.153622) (xy 288.99993 -278.155146) (xy 288.975936 -278.154678) (xy 288.928539 -278.147176)
			(xy 288.882898 -278.132351) (xy 288.840139 -278.11057) (xy 288.801313 -278.082368) (xy 288.767377 -278.048439)
			(xy 288.739166 -278.00962) (xy 288.717375 -277.966865) (xy 288.70254 -277.921228) (xy 288.695028 -277.873832)
			(xy 288.694622 -277.849838) (xy 288.694822 -277.835719) (xy 288.697496 -277.807608) (xy 288.699956 -277.793704)
			(xy 288.699956 -277.793196) (xy 288.701466 -277.78096) (xy 288.694177 -277.75745) (xy 288.685986 -277.748238)
			(xy 288.626296 -277.688802) (xy 288.617057 -277.680654) (xy 288.593568 -277.673355) (xy 288.581338 -277.674832)
			(xy 288.581084 -277.674832) (xy 288.553134 -277.679388) (xy 288.496512 -277.679388) (xy 288.468562 -277.674832)
			(xy 288.468308 -277.674832) (xy 288.456079 -277.673343) (xy 288.432598 -277.680659) (xy 288.42335 -277.688802)
			(xy 288.36366 -277.748492) (xy 288.355515 -277.757733) (xy 288.348217 -277.78122) (xy 288.34969 -277.79345)
			(xy 288.34969 -277.793958) (xy 288.352159 -277.807797) (xy 288.354834 -277.835782) (xy 288.355024 -277.849838)
			(xy 288.354551 -277.873828) (xy 288.34704 -277.921216) (xy 288.332209 -277.966846) (xy 288.310424 -278.009594)
			(xy 288.28222 -278.048409) (xy 288.248292 -278.082335) (xy 288.209475 -278.110535) (xy 288.166725 -278.132318)
			(xy 288.121094 -278.147145) (xy 288.073706 -278.154652) (xy 288.049716 -278.155146) (xy 288.017966 -278.153368)
			(xy 288.017458 -278.153368) (xy 288.006834 -278.152843) (xy 287.98662 -278.159391) (xy 287.978342 -278.166068)
			(xy 287.922208 -278.216614) (xy 287.914554 -278.224134) (xy 287.905882 -278.243738) (xy 287.905444 -278.25446)
			(xy 287.905444 -278.315674) (xy 287.90519 -278.322532) (xy 287.904936 -278.323802) (xy 287.904936 -278.328374)
			(xy 287.904743 -278.338759) (xy 287.903218 -278.359475) (xy 287.901888 -278.369776) (xy 287.901888 -278.370284)
			(xy 287.900618 -278.379174) (xy 287.898586 -278.391112) (xy 287.905698 -278.413972) (xy 287.970214 -278.481536)
			(xy 287.978854 -278.489604) (xy 288.00109 -278.497546) (xy 288.012886 -278.496776) (xy 288.01314 -278.496776)
			(xy 288.022248 -278.495723) (xy 288.040548 -278.494582) (xy 288.049716 -278.49449) (xy 288.074971 -278.495013)
			(xy 288.124791 -278.503329) (xy 288.172563 -278.519731) (xy 288.216983 -278.543772) (xy 288.256841 -278.574797)
			(xy 288.291049 -278.611959) (xy 288.318675 -278.654244) (xy 288.338963 -278.700499) (xy 288.351362 -278.749463)
			(xy 288.355533 -278.7998) (xy 288.351362 -278.850137) (xy 288.338963 -278.899101) (xy 288.318675 -278.945356)
			(xy 288.291049 -278.987641) (xy 288.256841 -279.024803) (xy 288.216983 -279.055828) (xy 288.172563 -279.079869)
			(xy 288.124791 -279.096271) (xy 288.074971 -279.104587) (xy 288.049716 -279.105106) (xy 288.025737 -279.104638)
			(xy 287.978368 -279.097141) (xy 287.932753 -279.082331) (xy 287.890016 -279.06057) (xy 287.851206 -279.032395)
			(xy 287.817279 -278.998498) (xy 287.78907 -278.959713) (xy 287.767272 -278.916995) (xy 287.752421 -278.871393)
			(xy 287.744884 -278.824031) (xy 287.744408 -278.800052) (xy 287.744408 -278.799544) (xy 287.744523 -278.79063)
			(xy 287.745665 -278.772839) (xy 287.746694 -278.763984) (xy 287.746694 -278.76373) (xy 287.747509 -278.751927)
			(xy 287.739561 -278.729675) (xy 287.731454 -278.721058) (xy 287.663636 -278.656288) (xy 287.64103 -278.649176)
			(xy 287.631886 -278.6507) (xy 287.617589 -278.653068) (xy 287.588719 -278.655611) (xy 287.574228 -278.65578)
			(xy 287.560706 -278.655661) (xy 287.533749 -278.653497) (xy 287.52038 -278.651462) (xy 287.508442 -278.64943)
			(xy 287.485582 -278.656542) (xy 287.418272 -278.720804) (xy 287.410201 -278.729443) (xy 287.402254 -278.75168)
			(xy 287.403032 -278.763476) (xy 287.403032 -278.76373) (xy 287.404016 -278.772714) (xy 287.405036 -278.79076)
			(xy 287.405064 -278.799798) (xy 287.404578 -278.824615) (xy 287.396549 -278.873594) (xy 287.380702 -278.920629)
			(xy 287.357454 -278.964481) (xy 287.327419 -279.003994) (xy 287.291386 -279.038128) (xy 287.250307 -279.065983)
			(xy 287.205262 -279.086825) (xy 287.157438 -279.100106) (xy 287.108096 -279.105474) (xy 287.058536 -279.10279)
			(xy 287.010062 -279.092123) (xy 286.963953 -279.073755) (xy 286.921423 -279.048169) (xy 286.883592 -279.01604)
			(xy 286.851457 -278.978214) (xy 286.825865 -278.935688) (xy 286.80749 -278.889582) (xy 286.796816 -278.84111)
			(xy 286.794124 -278.79155) (xy 286.799486 -278.742207) (xy 286.812759 -278.694382) (xy 286.833594 -278.649334)
			(xy 286.861443 -278.60825) (xy 286.895571 -278.572212) (xy 286.93508 -278.54217) (xy 286.978929 -278.518916)
			(xy 287.025961 -278.503062) (xy 287.07494 -278.495025) (xy 287.099756 -278.49449) (xy 287.108793 -278.494536)
			(xy 287.126839 -278.495552) (xy 287.135824 -278.496522) (xy 287.147762 -278.498046) (xy 287.170114 -278.489918)
			(xy 287.242758 -278.413718) (xy 287.24987 -278.390858) (xy 287.247838 -278.379174) (xy 287.245788 -278.365807)
			(xy 287.243623 -278.338849) (xy 287.24352 -278.325326) (xy 287.24352 -278.25446) (xy 287.242954 -278.243769)
			(xy 287.234294 -278.224217) (xy 287.226756 -278.216614) (xy 287.162748 -278.15921) (xy 287.142428 -278.152606)
			(xy 287.13176 -278.153622) (xy 287.099756 -278.155146) (xy 287.075766 -278.154672) (xy 287.028377 -278.147161)
			(xy 286.982747 -278.13233) (xy 286.939997 -278.110545) (xy 286.901182 -278.082341) (xy 286.867255 -278.048414)
			(xy 286.839052 -278.009597) (xy 286.817268 -277.966848) (xy 286.802438 -277.921217) (xy 286.794927 -277.873828)
			(xy 286.794448 -277.849838) (xy 286.794655 -277.835783) (xy 286.797324 -277.807798) (xy 286.799782 -277.793958)
			(xy 286.799782 -277.79345) (xy 286.801281 -277.781217) (xy 286.79398 -277.757721) (xy 286.785812 -277.748492)
			(xy 286.717232 -277.679912) (xy 286.69361 -277.672546) (xy 286.685482 -277.67407) (xy 286.655421 -277.679387)
			(xy 286.594385 -277.679387) (xy 286.564324 -277.67407) (xy 286.563562 -277.67407) (xy 286.555942 -277.672546)
			(xy 286.53232 -277.679912) (xy 286.46374 -277.748492) (xy 286.455597 -277.757734) (xy 286.448303 -277.78122)
			(xy 286.44977 -277.79345) (xy 286.44977 -277.793958) (xy 286.452239 -277.807797) (xy 286.454915 -277.835782)
			(xy 286.455104 -277.849838) (xy 286.454631 -277.873827) (xy 286.44712 -277.921214) (xy 286.432289 -277.966843)
			(xy 286.410503 -278.00959) (xy 286.382299 -278.048403) (xy 286.348371 -278.082326) (xy 286.309554 -278.110525)
			(xy 286.266804 -278.132305) (xy 286.221173 -278.14713) (xy 286.173785 -278.154634) (xy 286.149796 -278.155146)
			(xy 286.117792 -278.153368) (xy 286.117284 -278.153368) (xy 286.106665 -278.152858) (xy 286.086471 -278.159428)
			(xy 286.078168 -278.166068) (xy 286.022034 -278.216614) (xy 286.014377 -278.224132) (xy 286.0057 -278.243737)
			(xy 286.00527 -278.25446) (xy 286.00527 -278.299418) (xy 286.005016 -278.305006) (xy 286.005016 -278.324818)
			(xy 286.004791 -278.340539) (xy 286.001733 -278.371833) (xy 285.99892 -278.387302) (xy 285.99892 -278.388318)
			(xy 285.998412 -278.390858) (xy 286.005524 -278.413718) (xy 286.070294 -278.481536) (xy 286.078933 -278.489607)
			(xy 286.10117 -278.497558) (xy 286.112966 -278.496776) (xy 286.11322 -278.496776) (xy 286.122328 -278.495722)
			(xy 286.140628 -278.49458) (xy 286.149796 -278.49449) (xy 286.175054 -278.494982) (xy 286.224881 -278.503296)
			(xy 286.272661 -278.519699) (xy 286.317089 -278.543741) (xy 286.356953 -278.574769) (xy 286.391167 -278.611934)
			(xy 286.418797 -278.654225) (xy 286.439089 -278.700486) (xy 286.45149 -278.749456) (xy 286.455662 -278.7998)
			(xy 286.45149 -278.850144) (xy 286.439089 -278.899114) (xy 286.418797 -278.945375) (xy 286.391167 -278.987666)
			(xy 286.356953 -279.024831) (xy 286.317089 -279.055859) (xy 286.272661 -279.079901) (xy 286.224881 -279.096304)
			(xy 286.175054 -279.104618) (xy 286.149796 -279.105106) (xy 286.125818 -279.104636) (xy 286.078451 -279.097137)
			(xy 286.032839 -279.082325) (xy 285.990105 -279.060563) (xy 285.951298 -279.032388) (xy 285.917374 -278.998491)
			(xy 285.889166 -278.959707) (xy 285.86737 -278.91699) (xy 285.852521 -278.87139) (xy 285.844984 -278.82403)
			(xy 285.844488 -278.800052) (xy 285.844488 -278.799544) (xy 285.844603 -278.79063) (xy 285.845746 -278.772839)
			(xy 285.846774 -278.763984) (xy 285.846774 -278.76373) (xy 285.847589 -278.751928) (xy 285.839639 -278.729677)
			(xy 285.831534 -278.721058) (xy 285.763716 -278.656288) (xy 285.740856 -278.649176) (xy 285.73222 -278.6507)
			(xy 285.717798 -278.65309) (xy 285.688672 -278.655638) (xy 285.674054 -278.65578) (xy 285.6738 -278.65578)
			(xy 285.660405 -278.655648) (xy 285.633701 -278.65349) (xy 285.62046 -278.651462) (xy 285.620206 -278.651462)
			(xy 285.608471 -278.65018) (xy 285.585968 -278.657215) (xy 285.577026 -278.664924) (xy 285.509716 -278.72944)
			(xy 285.501588 -278.751792) (xy 285.503112 -278.76373) (xy 285.504096 -278.772714) (xy 285.505116 -278.79076)
			(xy 285.505144 -278.799798) (xy 285.504658 -278.824622) (xy 285.496626 -278.873617) (xy 285.480773 -278.920667)
			(xy 285.457517 -278.964532) (xy 285.42747 -279.004057) (xy 285.391425 -279.0382) (xy 285.35033 -279.066062)
			(xy 285.30527 -279.086908) (xy 285.25743 -279.100189) (xy 285.208072 -279.105555) (xy 285.158496 -279.102865)
			(xy 285.110009 -279.09219) (xy 285.063887 -279.073811) (xy 285.021346 -279.048213) (xy 284.983507 -279.016069)
			(xy 284.951368 -278.978226) (xy 284.925774 -278.935683) (xy 284.9074 -278.889559) (xy 284.89673 -278.84107)
			(xy 284.894046 -278.791494) (xy 284.899418 -278.742136) (xy 284.912704 -278.694298) (xy 284.933555 -278.64924)
			(xy 284.961421 -278.608149) (xy 284.995568 -278.572107) (xy 285.035096 -278.542065) (xy 285.078964 -278.518814)
			(xy 285.126016 -278.502966) (xy 285.175012 -278.494939) (xy 285.199836 -278.49449) (xy 285.200598 -278.49449)
			(xy 285.209318 -278.494556) (xy 285.226728 -278.495571) (xy 285.235396 -278.496522) (xy 285.24729 -278.497323)
			(xy 285.269684 -278.489243) (xy 285.278322 -278.481028) (xy 285.342584 -278.413718) (xy 285.349696 -278.391112)
			(xy 285.348426 -278.383746) (xy 285.34594 -278.369141) (xy 285.343271 -278.339632) (xy 285.343092 -278.324818)
			(xy 285.343092 -278.254714) (xy 285.342535 -278.244019) (xy 285.333885 -278.224454) (xy 285.326328 -278.216868)
			(xy 285.270448 -278.166576) (xy 285.262189 -278.159834) (xy 285.241979 -278.153121) (xy 285.231332 -278.153622)
			(xy 285.231078 -278.153622) (xy 285.199836 -278.155146) (xy 285.175842 -278.154678) (xy 285.128444 -278.147177)
			(xy 285.082802 -278.132353) (xy 285.040042 -278.110572) (xy 285.001215 -278.08237) (xy 284.967278 -278.048441)
			(xy 284.939067 -278.009621) (xy 284.917275 -277.966866) (xy 284.902441 -277.921229) (xy 284.894928 -277.873832)
			(xy 284.894528 -277.849838) (xy 284.894735 -277.835783) (xy 284.897404 -277.807798) (xy 284.899862 -277.793958)
			(xy 284.899862 -277.79345) (xy 284.901361 -277.781218) (xy 284.894058 -277.757723) (xy 284.885892 -277.748492)
			(xy 284.817312 -277.679912) (xy 284.79369 -277.672546) (xy 284.785562 -277.67407) (xy 284.755501 -277.679387)
			(xy 284.694465 -277.679387) (xy 284.664404 -277.67407) (xy 284.663642 -277.67407) (xy 284.656022 -277.672546)
			(xy 284.6324 -277.679912) (xy 284.56382 -277.748492) (xy 284.555667 -277.75773) (xy 284.548361 -277.78122)
			(xy 284.54985 -277.79345) (xy 284.54985 -277.793958) (xy 284.552319 -277.807797) (xy 284.554995 -277.835782)
			(xy 284.555184 -277.849838) (xy 284.554711 -277.873827) (xy 284.5472 -277.921212) (xy 284.532368 -277.96684)
			(xy 284.510583 -278.009585) (xy 284.482378 -278.048397) (xy 284.44845 -278.082318) (xy 284.409632 -278.110515)
			(xy 284.366882 -278.132292) (xy 284.321252 -278.147114) (xy 284.273865 -278.154615) (xy 284.249876 -278.155146)
			(xy 284.217872 -278.153368) (xy 284.217364 -278.153368) (xy 284.20674 -278.152842) (xy 284.186524 -278.159388)
			(xy 284.178248 -278.166068) (xy 284.122114 -278.216614) (xy 284.11446 -278.224133) (xy 284.105786 -278.243738)
			(xy 284.10535 -278.25446) (xy 284.10535 -278.299418) (xy 284.105096 -278.305006) (xy 284.105096 -278.324818)
			(xy 284.104872 -278.340539) (xy 284.101815 -278.371833) (xy 284.099 -278.387302) (xy 284.099 -278.388318)
			(xy 284.098492 -278.390858) (xy 284.105604 -278.413718) (xy 284.170374 -278.481536) (xy 284.179012 -278.489611)
			(xy 284.20125 -278.497571) (xy 284.213046 -278.496776) (xy 284.2133 -278.496776) (xy 284.222408 -278.495722)
			(xy 284.240708 -278.494578) (xy 284.249876 -278.49449) (xy 284.275135 -278.494981) (xy 284.324965 -278.503292)
			(xy 284.372747 -278.519693) (xy 284.417178 -278.543734) (xy 284.457045 -278.574761) (xy 284.491262 -278.611928)
			(xy 284.518894 -278.654219) (xy 284.539188 -278.700482) (xy 284.55159 -278.749454) (xy 284.555762 -278.7998)
			(xy 284.55159 -278.850146) (xy 284.539188 -278.899118) (xy 284.518894 -278.945381) (xy 284.491262 -278.987672)
			(xy 284.457045 -279.024839) (xy 284.417178 -279.055866) (xy 284.372747 -279.079907) (xy 284.324965 -279.096308)
			(xy 284.275135 -279.104619) (xy 284.249876 -279.105106) (xy 284.225899 -279.104635) (xy 284.178534 -279.097133)
			(xy 284.132925 -279.082319) (xy 284.090193 -279.060557) (xy 284.051389 -279.032381) (xy 284.017468 -278.998484)
			(xy 283.989263 -278.959701) (xy 283.967468 -278.916985) (xy 283.95262 -278.871388) (xy 283.945083 -278.824029)
			(xy 283.944568 -278.800052) (xy 283.944568 -278.799544) (xy 283.944683 -278.79063) (xy 283.945826 -278.772839)
			(xy 283.946854 -278.763984) (xy 283.946854 -278.76373) (xy 283.947669 -278.751928) (xy 283.939716 -278.729679)
			(xy 283.931614 -278.721058) (xy 283.863796 -278.656288) (xy 283.840936 -278.649176) (xy 283.8323 -278.6507)
			(xy 283.817878 -278.653089) (xy 283.788752 -278.655636) (xy 283.774134 -278.65578) (xy 283.77388 -278.65578)
			(xy 283.760485 -278.655648) (xy 283.733782 -278.653488) (xy 283.72054 -278.651462) (xy 283.720286 -278.651462)
			(xy 283.708545 -278.650162) (xy 283.686016 -278.65717) (xy 283.677106 -278.664924) (xy 283.609796 -278.72944)
			(xy 283.601668 -278.751792) (xy 283.603192 -278.76373) (xy 283.604176 -278.772714) (xy 283.605195 -278.79076)
			(xy 283.605224 -278.799798) (xy 283.604738 -278.82462) (xy 283.596707 -278.873611) (xy 283.580855 -278.920658)
			(xy 283.557601 -278.96452) (xy 283.527557 -279.004041) (xy 283.491515 -279.038182) (xy 283.450424 -279.066042)
			(xy 283.405368 -279.086887) (xy 283.357532 -279.100168) (xy 283.308178 -279.105535) (xy 283.258606 -279.102847)
			(xy 283.210122 -279.092174) (xy 283.164003 -279.073797) (xy 283.121465 -279.048202) (xy 283.083629 -279.016062)
			(xy 283.05149 -278.978223) (xy 283.025896 -278.935684) (xy 283.007522 -278.889565) (xy 282.996852 -278.84108)
			(xy 282.994165 -278.791508) (xy 282.999535 -278.742154) (xy 283.012818 -278.694319) (xy 283.033665 -278.649263)
			(xy 283.061527 -278.608174) (xy 283.095669 -278.572133) (xy 283.135192 -278.542091) (xy 283.179055 -278.518839)
			(xy 283.226102 -278.50299) (xy 283.275094 -278.494961) (xy 283.299916 -278.49449) (xy 283.300678 -278.49449)
			(xy 283.309398 -278.494555) (xy 283.326808 -278.495569) (xy 283.335476 -278.496522) (xy 283.347372 -278.497327)
			(xy 283.369773 -278.489253) (xy 283.378402 -278.481028) (xy 283.442664 -278.413718) (xy 283.449776 -278.391112)
			(xy 283.448506 -278.383746) (xy 283.44602 -278.369141) (xy 283.443351 -278.339632) (xy 283.443172 -278.324818)
			(xy 283.443172 -278.254714) (xy 283.442615 -278.244019) (xy 283.433962 -278.224457) (xy 283.426408 -278.216868)
			(xy 283.370528 -278.166576) (xy 283.362268 -278.159838) (xy 283.342059 -278.153133) (xy 283.331412 -278.153622)
			(xy 283.331158 -278.153622) (xy 283.299916 -278.155146) (xy 283.275923 -278.154677) (xy 283.228527 -278.147173)
			(xy 283.182888 -278.132347) (xy 283.140131 -278.110565) (xy 283.101307 -278.082363) (xy 283.067372 -278.048434)
			(xy 283.039163 -278.009615) (xy 283.017373 -277.966862) (xy 283.00254 -277.921226) (xy 282.995028 -277.873831)
			(xy 282.994608 -277.849838) (xy 282.994815 -277.835783) (xy 282.997484 -277.807798) (xy 282.999942 -277.793958)
			(xy 282.999942 -277.79345) (xy 283.001441 -277.781218) (xy 282.994136 -277.757724) (xy 282.985972 -277.748492)
			(xy 282.926282 -277.688802) (xy 282.917042 -277.680657) (xy 282.893555 -277.673365) (xy 282.881324 -277.674832)
			(xy 282.88107 -277.674832) (xy 282.85312 -277.679388) (xy 282.796498 -277.679388) (xy 282.768548 -277.674832)
			(xy 282.768294 -277.674832) (xy 282.756058 -277.673323) (xy 282.732548 -277.680611) (xy 282.723336 -277.688802)
			(xy 282.663646 -277.748238) (xy 282.655512 -277.757482) (xy 282.648238 -277.780965) (xy 282.649676 -277.793196)
			(xy 282.649676 -277.79345) (xy 282.65216 -277.807415) (xy 282.654828 -277.835655) (xy 282.65501 -277.849838)
			(xy 282.654537 -277.873827) (xy 282.647026 -277.921215) (xy 282.632195 -277.966844) (xy 282.610409 -278.009591)
			(xy 282.582205 -278.048405) (xy 282.548277 -278.082329) (xy 282.50946 -278.110528) (xy 282.46671 -278.132309)
			(xy 282.421079 -278.147134) (xy 282.373691 -278.154639) (xy 282.349702 -278.155146) (xy 282.317952 -278.153368)
			(xy 282.317444 -278.153368) (xy 282.306821 -278.152846) (xy 282.286611 -278.159398) (xy 282.278328 -278.166068)
			(xy 282.222194 -278.216614) (xy 282.214542 -278.224134) (xy 282.205872 -278.243739) (xy 282.20543 -278.25446)
			(xy 282.20543 -278.299418) (xy 282.205176 -278.305006) (xy 282.205176 -278.324818) (xy 282.204952 -278.340539)
			(xy 282.201894 -278.371833) (xy 282.19908 -278.387302) (xy 282.19908 -278.388318) (xy 282.198572 -278.390858)
			(xy 282.205684 -278.413718) (xy 282.2702 -278.481536) (xy 282.278839 -278.489606) (xy 282.301076 -278.497555)
			(xy 282.312872 -278.496776) (xy 282.313126 -278.496776) (xy 282.322234 -278.495723) (xy 282.340534 -278.494581)
			(xy 282.349702 -278.49449) (xy 282.374957 -278.495012) (xy 282.424779 -278.503326) (xy 282.472553 -278.519727)
			(xy 282.516976 -278.543768) (xy 282.556836 -278.574792) (xy 282.591046 -278.611954) (xy 282.618672 -278.65424)
			(xy 282.638962 -278.700497) (xy 282.651362 -278.749462) (xy 282.655533 -278.7998) (xy 282.651362 -278.850138)
			(xy 282.638962 -278.899103) (xy 282.618672 -278.94536) (xy 282.591046 -278.987646) (xy 282.556836 -279.024808)
			(xy 282.516976 -279.055832) (xy 282.472553 -279.079873) (xy 282.424779 -279.096274) (xy 282.374957 -279.104588)
			(xy 282.349702 -279.105106) (xy 282.325723 -279.104637) (xy 282.278356 -279.097139) (xy 282.232744 -279.082327)
			(xy 282.190008 -279.060565) (xy 282.1512 -279.03239) (xy 282.117275 -278.998493) (xy 282.089068 -278.959709)
			(xy 282.067271 -278.916991) (xy 282.052421 -278.871391) (xy 282.044884 -278.82403) (xy 282.044394 -278.800052)
			(xy 282.044394 -278.799544) (xy 282.044509 -278.79063) (xy 282.045652 -278.772839) (xy 282.04668 -278.763984)
			(xy 282.04668 -278.76373) (xy 282.047495 -278.751927) (xy 282.039546 -278.729676) (xy 282.03144 -278.721058)
			(xy 281.972258 -278.66467) (xy 281.963323 -278.656954) (xy 281.940813 -278.649928) (xy 281.929078 -278.651208)
			(xy 281.928824 -278.651208) (xy 281.915336 -278.653337) (xy 281.888122 -278.655624) (xy 281.874468 -278.65578)
			(xy 281.874214 -278.65578) (xy 281.860692 -278.65566) (xy 281.833735 -278.653495) (xy 281.820366 -278.651462)
			(xy 281.808428 -278.64943) (xy 281.785568 -278.656542) (xy 281.718258 -278.720804) (xy 281.710189 -278.729444)
			(xy 281.702244 -278.75168) (xy 281.703018 -278.763476) (xy 281.703018 -278.76373) (xy 281.704002 -278.772714)
			(xy 281.705022 -278.79076) (xy 281.70505 -278.799798) (xy 281.704564 -278.824623) (xy 281.696532 -278.873619)
			(xy 281.680678 -278.92067) (xy 281.657421 -278.964536) (xy 281.627374 -279.004062) (xy 281.591328 -279.038205)
			(xy 281.550232 -279.066067) (xy 281.50517 -279.086914) (xy 281.45733 -279.100195) (xy 281.40797 -279.105561)
			(xy 281.358393 -279.102871) (xy 281.309905 -279.092195) (xy 281.263782 -279.073816) (xy 281.22124 -279.048216)
			(xy 281.183401 -279.016071) (xy 281.151261 -278.978227) (xy 281.125667 -278.935682) (xy 281.107293 -278.889557)
			(xy 281.096624 -278.841067) (xy 281.09394 -278.79149) (xy 281.099313 -278.742131) (xy 281.1126 -278.694292)
			(xy 281.133452 -278.649233) (xy 281.16132 -278.608141) (xy 281.195468 -278.572099) (xy 281.234998 -278.542057)
			(xy 281.278867 -278.518806) (xy 281.32592 -278.502959) (xy 281.374917 -278.494933) (xy 281.399742 -278.49449)
			(xy 281.408716 -278.49453) (xy 281.426635 -278.495547) (xy 281.435556 -278.496522) (xy 281.447494 -278.498046)
			(xy 281.469846 -278.489918) (xy 281.542744 -278.413718) (xy 281.549856 -278.391112) (xy 281.549094 -278.386286)
			(xy 281.546368 -278.371065) (xy 281.543441 -278.34028) (xy 281.543252 -278.324818) (xy 281.543252 -278.25446)
			(xy 281.542684 -278.243771) (xy 281.534015 -278.224226) (xy 281.526488 -278.216614) (xy 281.46248 -278.15921)
			(xy 281.44216 -278.152606) (xy 281.431492 -278.153622) (xy 281.399742 -278.155146) (xy 281.375746 -278.154703)
			(xy 281.328343 -278.147202) (xy 281.282697 -278.132377) (xy 281.239932 -278.110595) (xy 281.201102 -278.082391)
			(xy 281.167161 -278.048459) (xy 281.138947 -278.009636) (xy 281.117153 -277.966877) (xy 281.102317 -277.921235)
			(xy 281.094803 -277.873834) (xy 281.094434 -277.849838) (xy 281.094641 -277.835783) (xy 281.09731 -277.807798)
			(xy 281.099768 -277.793958) (xy 281.099768 -277.79345) (xy 281.101267 -277.781218) (xy 281.093964 -277.757722)
			(xy 281.085798 -277.748492) (xy 281.017218 -277.679912) (xy 280.993596 -277.672546) (xy 280.985468 -277.67407)
			(xy 280.955407 -277.679387) (xy 280.894371 -277.679387) (xy 280.86431 -277.67407) (xy 280.863548 -277.67407)
			(xy 280.855928 -277.672546) (xy 280.832306 -277.679912) (xy 280.763726 -277.748492) (xy 280.755572 -277.75773)
			(xy 280.748265 -277.78122) (xy 280.749756 -277.79345) (xy 280.749756 -277.793958) (xy 280.752225 -277.807797)
			(xy 280.754901 -277.835782) (xy 280.75509 -277.849838) (xy 280.754617 -277.873827) (xy 280.747106 -277.921213)
			(xy 280.732275 -277.966841) (xy 280.710489 -278.009587) (xy 280.682284 -278.048399) (xy 280.648356 -278.082321)
			(xy 280.609539 -278.110518) (xy 280.566789 -278.132296) (xy 280.521158 -278.147119) (xy 280.473771 -278.154621)
			(xy 280.449782 -278.155146) (xy 280.418032 -278.153368) (xy 280.417524 -278.153368) (xy 280.406883 -278.152696)
			(xy 280.38662 -278.159269) (xy 280.378408 -278.166068) (xy 280.32202 -278.216614) (xy 280.314365 -278.224133)
			(xy 280.30569 -278.243738) (xy 280.305256 -278.25446) (xy 280.305256 -278.315674) (xy 280.305002 -278.322532)
			(xy 280.304748 -278.323802) (xy 280.304748 -278.328374) (xy 280.304555 -278.338759) (xy 280.30303 -278.359475)
			(xy 280.3017 -278.369776) (xy 280.3017 -278.370284) (xy 280.30043 -278.379174) (xy 280.298398 -278.390858)
			(xy 280.30551 -278.413718) (xy 280.370026 -278.481536) (xy 280.378666 -278.489602) (xy 280.400902 -278.497539)
			(xy 280.412698 -278.496776) (xy 280.412952 -278.496776) (xy 280.422123 -278.495716) (xy 280.440551 -278.494574)
			(xy 280.449782 -278.49449) (xy 280.475041 -278.494981) (xy 280.52487 -278.503294) (xy 280.572651 -278.519694)
			(xy 280.617081 -278.543736) (xy 280.656948 -278.574764) (xy 280.691163 -278.61193) (xy 280.718795 -278.654221)
			(xy 280.739088 -278.700483) (xy 280.75149 -278.749455) (xy 280.755662 -278.7998) (xy 280.75149 -278.850145)
			(xy 280.739088 -278.899117) (xy 280.718795 -278.945379) (xy 280.691163 -278.98767) (xy 280.656948 -279.024836)
			(xy 280.617081 -279.055864) (xy 280.572651 -279.079906) (xy 280.52487 -279.096306) (xy 280.475041 -279.104619)
			(xy 280.449782 -279.105106) (xy 280.425804 -279.104635) (xy 280.378439 -279.097135) (xy 280.33283 -279.082321)
			(xy 280.290097 -279.060559) (xy 280.251292 -279.032383) (xy 280.217369 -278.998486) (xy 280.189164 -278.959703)
			(xy 280.167369 -278.916987) (xy 280.15252 -278.871388) (xy 280.144983 -278.824029) (xy 280.144474 -278.800052)
			(xy 280.144474 -278.799544) (xy 280.144589 -278.79063) (xy 280.145732 -278.772839) (xy 280.14676 -278.763984)
			(xy 280.14676 -278.76373) (xy 280.147575 -278.751928) (xy 280.139623 -278.729678) (xy 280.13152 -278.721058)
			(xy 280.063702 -278.656288) (xy 280.040842 -278.649176) (xy 280.028904 -278.651208) (xy 280.01529 -278.653356)
			(xy 279.987822 -278.655648) (xy 279.97404 -278.65578) (xy 279.973786 -278.65578) (xy 279.960391 -278.655644)
			(xy 279.933689 -278.653479) (xy 279.920446 -278.651462) (xy 279.920192 -278.651462) (xy 279.908458 -278.650183)
			(xy 279.88596 -278.657222) (xy 279.877012 -278.664924) (xy 279.809702 -278.72944) (xy 279.801574 -278.751792)
			(xy 279.803098 -278.76373) (xy 279.804082 -278.772714) (xy 279.805101 -278.79076) (xy 279.80513 -278.799798)
			(xy 279.804644 -278.824621) (xy 279.796613 -278.873613) (xy 279.78076 -278.92066) (xy 279.757506 -278.964523)
			(xy 279.727461 -279.004046) (xy 279.691418 -279.038188) (xy 279.650326 -279.066048) (xy 279.605268 -279.086893)
			(xy 279.557432 -279.100174) (xy 279.508076 -279.105541) (xy 279.458503 -279.102852) (xy 279.410018 -279.092179)
			(xy 279.363898 -279.073802) (xy 279.32136 -279.048205) (xy 279.283522 -279.016064) (xy 279.251383 -278.978224)
			(xy 279.22579 -278.935684) (xy 279.207415 -278.889563) (xy 279.196745 -278.841077) (xy 279.19406 -278.791504)
			(xy 279.19943 -278.742149) (xy 279.212714 -278.694313) (xy 279.233562 -278.649256) (xy 279.261425 -278.608166)
			(xy 279.295569 -278.572126) (xy 279.335093 -278.542083) (xy 279.378958 -278.518832) (xy 279.426006 -278.502983)
			(xy 279.474999 -278.494954) (xy 279.499822 -278.49449) (xy 279.508796 -278.49453) (xy 279.526715 -278.495545)
			(xy 279.535636 -278.496522) (xy 279.547574 -278.498046) (xy 279.569926 -278.489918) (xy 279.64257 -278.413972)
			(xy 279.649682 -278.391366) (xy 279.64765 -278.379428) (xy 279.645595 -278.365998) (xy 279.643435 -278.338912)
			(xy 279.643332 -278.325326) (xy 279.643332 -278.25446) (xy 279.642764 -278.243771) (xy 279.634092 -278.224229)
			(xy 279.626568 -278.216614) (xy 279.56256 -278.15921) (xy 279.54224 -278.152606) (xy 279.531572 -278.153622)
			(xy 279.499822 -278.155146) (xy 279.475829 -278.154677) (xy 279.428432 -278.147174) (xy 279.382793 -278.132349)
			(xy 279.340034 -278.110567) (xy 279.301209 -278.082365) (xy 279.267274 -278.048436) (xy 279.239064 -278.009617)
			(xy 279.217274 -277.966863) (xy 279.20244 -277.921226) (xy 279.194928 -277.873831) (xy 279.194514 -277.849838)
			(xy 279.194721 -277.835783) (xy 279.19739 -277.807798) (xy 279.199848 -277.793958) (xy 279.199848 -277.79345)
			(xy 279.201347 -277.781218) (xy 279.194042 -277.757724) (xy 279.185878 -277.748492) (xy 279.117298 -277.679912)
			(xy 279.093676 -277.672546) (xy 279.085548 -277.67407) (xy 279.055487 -277.679387) (xy 278.994451 -277.679387)
			(xy 278.96439 -277.67407) (xy 278.963628 -277.67407) (xy 278.956008 -277.672546) (xy 278.932386 -277.679912)
			(xy 278.863806 -277.748492) (xy 278.855655 -277.75773) (xy 278.848351 -277.78122) (xy 278.849836 -277.79345)
			(xy 278.849836 -277.793958) (xy 278.852305 -277.807797) (xy 278.854981 -277.835782) (xy 278.85517 -277.849838)
			(xy 278.854697 -277.873826) (xy 278.847185 -277.921211) (xy 278.832354 -277.966838) (xy 278.810568 -278.009582)
			(xy 278.782363 -278.048392) (xy 278.748435 -278.082313) (xy 278.709617 -278.110508) (xy 278.666867 -278.132283)
			(xy 278.621237 -278.147103) (xy 278.57385 -278.154602) (xy 278.549862 -278.155146) (xy 278.518112 -278.153368)
			(xy 278.517604 -278.153368) (xy 278.506965 -278.152701) (xy 278.486707 -278.159279) (xy 278.478488 -278.166068)
			(xy 278.4221 -278.216614) (xy 278.414447 -278.224134) (xy 278.405776 -278.243738) (xy 278.405336 -278.25446)
			(xy 278.405336 -278.315674) (xy 278.405082 -278.322532) (xy 278.404828 -278.323802) (xy 278.404828 -278.328374)
			(xy 278.404635 -278.338759) (xy 278.40311 -278.359475) (xy 278.40178 -278.369776) (xy 278.40178 -278.370284)
			(xy 278.40051 -278.379174) (xy 278.398478 -278.390858) (xy 278.40559 -278.413718) (xy 278.470106 -278.481536)
			(xy 278.478745 -278.489605) (xy 278.500982 -278.497551) (xy 278.512778 -278.496776) (xy 278.513032 -278.496776)
			(xy 278.522203 -278.495715) (xy 278.54063 -278.494573) (xy 278.549862 -278.49449) (xy 278.575122 -278.49498)
			(xy 278.624954 -278.503289) (xy 278.672738 -278.519688) (xy 278.717171 -278.543729) (xy 278.75704 -278.574756)
			(xy 278.791258 -278.611923) (xy 278.818892 -278.654215) (xy 278.839187 -278.700479) (xy 278.85159 -278.749453)
			(xy 278.855762 -278.7998) (xy 278.85159 -278.850147) (xy 278.839187 -278.899121) (xy 278.818892 -278.945385)
			(xy 278.791258 -278.987677) (xy 278.75704 -279.024844) (xy 278.717171 -279.055871) (xy 278.672738 -279.079912)
			(xy 278.624954 -279.096311) (xy 278.575122 -279.10462) (xy 278.549862 -279.105106) (xy 278.525885 -279.104634)
			(xy 278.478523 -279.097131) (xy 278.432916 -279.082315) (xy 278.390186 -279.060552) (xy 278.351384 -279.032376)
			(xy 278.317464 -278.998479) (xy 278.28926 -278.959697) (xy 278.267467 -278.916982) (xy 278.252619 -278.871385)
			(xy 278.245083 -278.824028) (xy 278.244554 -278.800052) (xy 278.244554 -278.799544) (xy 278.244669 -278.79063)
			(xy 278.245812 -278.772839) (xy 278.24684 -278.763984) (xy 278.24684 -278.76373) (xy 278.247655 -278.751928)
			(xy 278.239701 -278.729681) (xy 278.2316 -278.721058) (xy 278.163782 -278.656288) (xy 278.140922 -278.649176)
			(xy 278.128984 -278.651208) (xy 278.11537 -278.653355) (xy 278.087902 -278.655645) (xy 278.07412 -278.65578)
			(xy 278.073866 -278.65578) (xy 278.060471 -278.655647) (xy 278.033768 -278.653489) (xy 278.020526 -278.651462)
			(xy 278.020272 -278.651462) (xy 278.008532 -278.650165) (xy 277.986008 -278.657179) (xy 277.977092 -278.664924)
			(xy 277.909782 -278.72944) (xy 277.901654 -278.751792) (xy 277.903178 -278.76373) (xy 277.904162 -278.772714)
			(xy 277.905181 -278.79076) (xy 277.90521 -278.799798) (xy 277.904724 -278.824619) (xy 277.896693 -278.873607)
			(xy 277.880843 -278.920651) (xy 277.85759 -278.964511) (xy 277.827548 -279.004031) (xy 277.791508 -279.03817)
			(xy 277.75042 -279.066028) (xy 277.705366 -279.086873) (xy 277.657534 -279.100153) (xy 277.608182 -279.105521)
			(xy 277.558613 -279.102833) (xy 277.510132 -279.092162) (xy 277.464015 -279.073787) (xy 277.421479 -279.048194)
			(xy 277.383643 -279.016057) (xy 277.351506 -278.978221) (xy 277.325913 -278.935685) (xy 277.307538 -278.889568)
			(xy 277.296867 -278.841087) (xy 277.294179 -278.791518) (xy 277.299547 -278.742166) (xy 277.312827 -278.694334)
			(xy 277.333672 -278.64928) (xy 277.36153 -278.608192) (xy 277.395669 -278.572152) (xy 277.435189 -278.54211)
			(xy 277.479049 -278.518857) (xy 277.526093 -278.503007) (xy 277.575081 -278.494976) (xy 277.599902 -278.49449)
			(xy 277.608876 -278.494529) (xy 277.626795 -278.495543) (xy 277.635716 -278.496522) (xy 277.647654 -278.498046)
			(xy 277.670006 -278.489918) (xy 277.74265 -278.413972) (xy 277.749762 -278.391366) (xy 277.74773 -278.379428)
			(xy 277.745675 -278.365998) (xy 277.743516 -278.338912) (xy 277.743412 -278.325326) (xy 277.743412 -278.25446)
			(xy 277.742846 -278.243769) (xy 277.734184 -278.224218) (xy 277.726648 -278.216614) (xy 277.66264 -278.15921)
			(xy 277.64232 -278.152606) (xy 277.631652 -278.153622) (xy 277.599902 -278.155146) (xy 277.57591 -278.154676)
			(xy 277.528515 -278.14717) (xy 277.482879 -278.132343) (xy 277.440123 -278.11056) (xy 277.401301 -278.082358)
			(xy 277.367368 -278.04843) (xy 277.339161 -278.009611) (xy 277.317372 -277.966858) (xy 277.302539 -277.921224)
			(xy 277.295028 -277.87383) (xy 277.294594 -277.849838) (xy 277.294801 -277.835783) (xy 277.29747 -277.807798)
			(xy 277.299928 -277.793958) (xy 277.299928 -277.79345) (xy 277.301427 -277.781218) (xy 277.29412 -277.757726)
			(xy 277.285958 -277.748492) (xy 277.226268 -277.688802) (xy 277.217027 -277.680659) (xy 277.193541 -277.673374)
			(xy 277.18131 -277.674832) (xy 277.181056 -277.674832) (xy 277.153106 -277.679388) (xy 277.096484 -277.679388)
			(xy 277.068534 -277.674832) (xy 277.06828 -277.674832) (xy 277.056045 -277.673326) (xy 277.03254 -277.680619)
			(xy 277.023322 -277.688802) (xy 276.963632 -277.748238) (xy 276.955487 -277.757477) (xy 276.9482 -277.780965)
			(xy 276.949662 -277.793196) (xy 276.949662 -277.79345) (xy 276.952146 -277.807415) (xy 276.954814 -277.835655)
			(xy 276.954996 -277.849838) (xy 276.954523 -277.873827) (xy 276.947012 -277.921213) (xy 276.932181 -277.966841)
			(xy 276.910395 -278.009588) (xy 276.882191 -278.0484) (xy 276.848262 -278.082323) (xy 276.809445 -278.110521)
			(xy 276.766695 -278.1323) (xy 276.721065 -278.147123) (xy 276.673677 -278.154626) (xy 276.649688 -278.155146)
			(xy 276.617938 -278.153368) (xy 276.61743 -278.153368) (xy 276.606808 -278.152849) (xy 276.586602 -278.159405)
			(xy 276.578314 -278.166068) (xy 276.52218 -278.216614) (xy 276.514517 -278.22413) (xy 276.505832 -278.243735)
			(xy 276.505416 -278.25446) (xy 276.505416 -278.315674) (xy 276.505162 -278.322532) (xy 276.504908 -278.323802)
			(xy 276.504908 -278.328374) (xy 276.504715 -278.338759) (xy 276.50319 -278.359475) (xy 276.50186 -278.369776)
			(xy 276.50186 -278.370284) (xy 276.50059 -278.379174) (xy 276.498558 -278.391112) (xy 276.50567 -278.413972)
			(xy 276.570186 -278.481536) (xy 276.578824 -278.489609) (xy 276.601062 -278.497563) (xy 276.612858 -278.496776)
			(xy 276.613112 -278.496776) (xy 276.62222 -278.495722) (xy 276.64052 -278.494579) (xy 276.649688 -278.49449)
			(xy 276.674947 -278.494982) (xy 276.724775 -278.503295) (xy 276.772555 -278.519696) (xy 276.816984 -278.543738)
			(xy 276.85685 -278.574766) (xy 276.891065 -278.611932) (xy 276.918696 -278.654222) (xy 276.938989 -278.700484)
			(xy 276.95139 -278.749456) (xy 276.955562 -278.7998) (xy 276.95139 -278.850144) (xy 276.938989 -278.899116)
			(xy 276.918696 -278.945378) (xy 276.891065 -278.987668) (xy 276.85685 -279.024834) (xy 276.816984 -279.055862)
			(xy 276.772555 -279.079904) (xy 276.724775 -279.096305) (xy 276.674947 -279.104618) (xy 276.649688 -279.105106)
			(xy 276.62571 -279.104635) (xy 276.578344 -279.097136) (xy 276.532734 -279.082323) (xy 276.49 -279.060561)
			(xy 276.451194 -279.032385) (xy 276.417271 -278.998488) (xy 276.389065 -278.959705) (xy 276.367269 -278.916988)
			(xy 276.35242 -278.871389) (xy 276.344883 -278.824029) (xy 276.34438 -278.800052) (xy 276.34438 -278.799544)
			(xy 276.344495 -278.79063) (xy 276.345638 -278.772839) (xy 276.346666 -278.763984) (xy 276.346666 -278.76373)
			(xy 276.347481 -278.751928) (xy 276.33953 -278.729678) (xy 276.331426 -278.721058) (xy 276.263608 -278.656288)
			(xy 276.241002 -278.649176) (xy 276.231858 -278.6507) (xy 276.217561 -278.653067) (xy 276.188691 -278.655607)
			(xy 276.1742 -278.65578) (xy 276.148226 -278.655271) (xy 276.096918 -278.647149) (xy 276.047511 -278.631103)
			(xy 276.00122 -278.607529) (xy 275.959186 -278.577006) (xy 275.922441 -278.540286) (xy 275.89189 -278.498273)
			(xy 275.868284 -278.451998) (xy 275.852204 -278.402602) (xy 275.844046 -278.351299) (xy 275.843492 -278.325326)
			(xy 275.843492 -277.349458) (xy 275.84409 -277.322842) (xy 275.852736 -277.270315) (xy 275.869669 -277.219845)
			(xy 275.881592 -277.196042) (xy 275.88337 -277.19274) (xy 275.885656 -277.188422) (xy 275.889212 -277.181818)
			(xy 275.892006 -277.170388) (xy 275.892006 -277.162768) (xy 275.891796 -277.156886) (xy 275.888975 -277.145463)
			(xy 275.886418 -277.140162) (xy 275.860002 -277.094188) (xy 275.85243 -277.084598) (xy 275.830798 -277.073319)
			(xy 275.8186 -277.072598) (xy 275.57857 -277.072598) (xy 275.56647 -277.073329) (xy 275.54497 -277.084452)
			(xy 275.537422 -277.093934) (xy 275.496274 -277.164292) (xy 275.490686 -277.17369) (xy 275.487445 -277.179539)
			(xy 275.48383 -277.192409) (xy 275.483574 -277.19909) (xy 275.483574 -277.200106) (xy 275.483728 -277.204792)
			(xy 275.48551 -277.213995) (xy 275.48713 -277.218394) (xy 275.490432 -277.224236) (xy 275.50227 -277.246113)
			(xy 275.519463 -277.292787) (xy 275.528869 -277.341629) (xy 275.530056 -277.366476) (xy 275.530056 -277.378414)
			(xy 275.529258 -277.403477) (xy 275.52049 -277.452844) (xy 275.503774 -277.500116) (xy 275.479559 -277.544022)
			(xy 275.448496 -277.583381) (xy 275.41142 -277.617136) (xy 275.369327 -277.64438) (xy 275.323348 -277.66438)
			(xy 275.27472 -277.6766) (xy 275.224748 -277.68071) (xy 275.174776 -277.6766) (xy 275.126148 -277.66438)
			(xy 275.080169 -277.64438) (xy 275.038076 -277.617136) (xy 275.001 -277.583381) (xy 274.969937 -277.544022)
			(xy 274.945722 -277.500116) (xy 274.929006 -277.452844) (xy 274.920238 -277.403477) (xy 274.91944 -277.378414)
			(xy 274.91944 -277.374096) (xy 274.919991 -277.348927) (xy 274.928332 -277.299283) (xy 274.944721 -277.251685)
			(xy 274.95627 -277.229316) (xy 274.956524 -277.228554) (xy 274.95754 -277.226522) (xy 274.958048 -277.22576)
			(xy 274.961604 -277.218902) (xy 274.963512 -277.214041) (xy 274.965558 -277.203803) (xy 274.965668 -277.198582)
			(xy 274.965414 -277.18512) (xy 274.953222 -277.164292) (xy 274.912074 -277.093934) (xy 274.904511 -277.084459)
			(xy 274.883027 -277.073302) (xy 274.870926 -277.072598) (xy 274.62861 -277.072598) (xy 274.616517 -277.073342)
			(xy 274.595039 -277.084479) (xy 274.587462 -277.093934) (xy 274.546314 -277.164292) (xy 274.540726 -277.17369)
			(xy 274.537506 -277.179548) (xy 274.533897 -277.192412) (xy 274.533614 -277.19909) (xy 274.533614 -277.200106)
			(xy 274.533768 -277.204792) (xy 274.535552 -277.213994) (xy 274.53717 -277.218394) (xy 274.540472 -277.224236)
			(xy 274.552308 -277.246114) (xy 274.569499 -277.292788) (xy 274.578904 -277.34163) (xy 274.580096 -277.366476)
			(xy 274.580096 -277.378414) (xy 274.579298 -277.403477) (xy 274.57053 -277.452844) (xy 274.553814 -277.500116)
			(xy 274.529599 -277.544022) (xy 274.498536 -277.583381) (xy 274.46146 -277.617136) (xy 274.419367 -277.64438)
			(xy 274.373388 -277.66438) (xy 274.32476 -277.6766) (xy 274.274788 -277.68071) (xy 274.224816 -277.6766)
			(xy 274.176188 -277.66438) (xy 274.130209 -277.64438) (xy 274.088116 -277.617136) (xy 274.05104 -277.583381)
			(xy 274.019977 -277.544022) (xy 273.995762 -277.500116) (xy 273.979046 -277.452844) (xy 273.970278 -277.403477)
			(xy 273.96948 -277.378414) (xy 273.96948 -277.374096) (xy 273.970031 -277.348927) (xy 273.978373 -277.299283)
			(xy 273.994764 -277.251687) (xy 274.00631 -277.229316) (xy 274.006564 -277.228554) (xy 274.00758 -277.226522)
			(xy 274.008088 -277.22576) (xy 274.011644 -277.218902) (xy 274.013554 -277.214041) (xy 274.015603 -277.203803)
			(xy 274.015708 -277.198582) (xy 274.015454 -277.18512) (xy 274.003262 -277.164292) (xy 273.962114 -277.093934)
			(xy 273.954547 -277.084469) (xy 273.933062 -277.073337) (xy 273.920966 -277.072598) (xy 273.67865 -277.072598)
			(xy 273.666552 -277.073333) (xy 273.64506 -277.084461) (xy 273.637502 -277.093934) (xy 273.596354 -277.164292)
			(xy 273.590766 -277.17369) (xy 273.587544 -277.179547) (xy 273.583932 -277.192412) (xy 273.583654 -277.19909)
			(xy 273.583654 -277.200106) (xy 273.583808 -277.204792) (xy 273.585589 -277.213995) (xy 273.58721 -277.218394)
			(xy 273.590512 -277.224236) (xy 273.602347 -277.246114) (xy 273.619535 -277.292789) (xy 273.628939 -277.34163)
			(xy 273.630136 -277.366476) (xy 273.630136 -277.378414) (xy 273.629338 -277.403477) (xy 273.62057 -277.452844)
			(xy 273.603854 -277.500116) (xy 273.579639 -277.544022) (xy 273.548576 -277.583381) (xy 273.5115 -277.617136)
			(xy 273.469407 -277.64438) (xy 273.423428 -277.66438) (xy 273.3748 -277.6766) (xy 273.324828 -277.68071)
			(xy 273.274856 -277.6766) (xy 273.226228 -277.66438) (xy 273.180249 -277.64438) (xy 273.138156 -277.617136)
			(xy 273.10108 -277.583381) (xy 273.070017 -277.544022) (xy 273.045802 -277.500116) (xy 273.029086 -277.452844)
			(xy 273.020318 -277.403477) (xy 273.01952 -277.378414) (xy 273.01952 -277.374096) (xy 273.020071 -277.348927)
			(xy 273.028412 -277.299283) (xy 273.044799 -277.251685) (xy 273.05635 -277.229316) (xy 273.056604 -277.228554)
			(xy 273.05762 -277.226522) (xy 273.058128 -277.22576) (xy 273.061684 -277.218902) (xy 273.063592 -277.214041)
			(xy 273.06564 -277.203803) (xy 273.065748 -277.198582) (xy 273.065494 -277.18512) (xy 273.053302 -277.164292)
			(xy 273.012154 -277.093934) (xy 273.004589 -277.084462) (xy 272.983105 -277.073313) (xy 272.971006 -277.072598)
			(xy 272.72869 -277.072598) (xy 272.716599 -277.073346) (xy 272.695128 -277.084488) (xy 272.687542 -277.093934)
			(xy 272.646394 -277.164292) (xy 272.640806 -277.17369) (xy 272.637564 -277.179539) (xy 272.633947 -277.192408)
			(xy 272.633694 -277.19909) (xy 272.633694 -277.200106) (xy 272.633848 -277.204792) (xy 272.635631 -277.213995)
			(xy 272.63725 -277.218394) (xy 272.640552 -277.224236) (xy 272.652389 -277.246114) (xy 272.669581 -277.292788)
			(xy 272.678986 -277.34163) (xy 272.680176 -277.366476) (xy 272.680176 -277.378414) (xy 272.679378 -277.403477)
			(xy 272.67061 -277.452844) (xy 272.653894 -277.500116) (xy 272.629679 -277.544022) (xy 272.598616 -277.583381)
			(xy 272.56154 -277.617136) (xy 272.519447 -277.64438) (xy 272.473468 -277.66438) (xy 272.42484 -277.6766)
			(xy 272.374868 -277.68071) (xy 272.324896 -277.6766) (xy 272.276268 -277.66438) (xy 272.230289 -277.64438)
			(xy 272.188196 -277.617136) (xy 272.15112 -277.583381) (xy 272.120057 -277.544022) (xy 272.095842 -277.500116)
			(xy 272.079126 -277.452844) (xy 272.070358 -277.403477) (xy 272.06956 -277.378414) (xy 272.06956 -277.374096)
			(xy 272.070111 -277.348927) (xy 272.078453 -277.299283) (xy 272.094842 -277.251686) (xy 272.10639 -277.229316)
			(xy 272.106644 -277.228554) (xy 272.10766 -277.226522) (xy 272.108168 -277.22576) (xy 272.111724 -277.218902)
			(xy 272.113631 -277.214041) (xy 272.115677 -277.203803) (xy 272.115788 -277.198582) (xy 272.115534 -277.18512)
			(xy 272.103342 -277.164292) (xy 272.062194 -277.093934) (xy 272.054632 -277.084456) (xy 272.033149 -277.07329)
			(xy 272.021046 -277.072598) (xy 271.77873 -277.072598) (xy 271.766635 -277.073337) (xy 271.745149 -277.08447)
			(xy 271.737582 -277.093934) (xy 271.696434 -277.164292) (xy 271.690846 -277.17369) (xy 271.687625 -277.179547)
			(xy 271.684014 -277.192412) (xy 271.683734 -277.19909) (xy 271.683734 -277.200106) (xy 271.683887 -277.204792)
			(xy 271.685669 -277.213995) (xy 271.68729 -277.218394) (xy 271.690592 -277.224236) (xy 271.702428 -277.246114)
			(xy 271.719617 -277.292788) (xy 271.729021 -277.34163) (xy 271.730216 -277.366476) (xy 271.730216 -277.378414)
			(xy 271.729418 -277.403477) (xy 271.72065 -277.452844) (xy 271.703934 -277.500116) (xy 271.679719 -277.544022)
			(xy 271.648656 -277.583381) (xy 271.61158 -277.617136) (xy 271.569487 -277.64438) (xy 271.523508 -277.66438)
			(xy 271.47488 -277.6766) (xy 271.424908 -277.68071) (xy 271.374936 -277.6766) (xy 271.326308 -277.66438)
			(xy 271.280329 -277.64438) (xy 271.238236 -277.617136) (xy 271.20116 -277.583381) (xy 271.170097 -277.544022)
			(xy 271.145882 -277.500116) (xy 271.129166 -277.452844) (xy 271.120398 -277.403477) (xy 271.1196 -277.378414)
			(xy 271.1196 -277.374096) (xy 271.120151 -277.348927) (xy 271.128491 -277.299282) (xy 271.144878 -277.251684)
			(xy 271.15643 -277.229316) (xy 271.156684 -277.228554) (xy 271.1577 -277.226522) (xy 271.158208 -277.22576)
			(xy 271.161764 -277.218902) (xy 271.163673 -277.214041) (xy 271.165721 -277.203803) (xy 271.165828 -277.198582)
			(xy 271.165574 -277.18512) (xy 271.153382 -277.164292) (xy 271.112234 -277.093934) (xy 271.104668 -277.084466)
			(xy 271.083184 -277.073325) (xy 271.071086 -277.072598) (xy 270.82877 -277.072598) (xy 270.81667 -277.073329)
			(xy 270.79517 -277.084452) (xy 270.787622 -277.093934) (xy 270.746474 -277.164292) (xy 270.740886 -277.17369)
			(xy 270.737645 -277.179539) (xy 270.73403 -277.192409) (xy 270.733774 -277.19909) (xy 270.733774 -277.200106)
			(xy 270.733928 -277.204792) (xy 270.73571 -277.213995) (xy 270.73733 -277.218394) (xy 270.740632 -277.224236)
			(xy 270.75247 -277.246113) (xy 270.769663 -277.292787) (xy 270.779069 -277.341629) (xy 270.780256 -277.366476)
			(xy 270.780256 -277.378414) (xy 270.779458 -277.403477) (xy 270.77069 -277.452844) (xy 270.753974 -277.500116)
			(xy 270.729759 -277.544022) (xy 270.698696 -277.583381) (xy 270.66162 -277.617136) (xy 270.619527 -277.64438)
			(xy 270.573548 -277.66438) (xy 270.52492 -277.6766) (xy 270.474948 -277.68071) (xy 270.424976 -277.6766)
			(xy 270.376348 -277.66438) (xy 270.330369 -277.64438) (xy 270.288276 -277.617136) (xy 270.2512 -277.583381)
			(xy 270.220137 -277.544022) (xy 270.195922 -277.500116) (xy 270.179206 -277.452844) (xy 270.170438 -277.403477)
			(xy 270.16964 -277.378414) (xy 270.16964 -277.374096) (xy 270.170191 -277.348927) (xy 270.178532 -277.299283)
			(xy 270.194921 -277.251685) (xy 270.20647 -277.229316) (xy 270.206724 -277.228554) (xy 270.20774 -277.226522)
			(xy 270.208248 -277.22576) (xy 270.211804 -277.218902) (xy 270.213712 -277.214041) (xy 270.215758 -277.203803)
			(xy 270.215868 -277.198582) (xy 270.215614 -277.18512) (xy 270.203422 -277.164292) (xy 270.162274 -277.093934)
			(xy 270.154711 -277.084459) (xy 270.133227 -277.073302) (xy 270.121126 -277.072598) (xy 269.907766 -277.072598)
			(xy 269.904087 -277.072697) (xy 269.896819 -277.073848) (xy 269.893288 -277.074884) (xy 269.89278 -277.074884)
			(xy 269.886535 -277.076993) (xy 269.875336 -277.083934) (xy 269.870682 -277.0886) (xy 269.864332 -277.096982)
			(xy 269.819374 -277.17115) (xy 269.815056 -277.179786) (xy 269.812033 -277.188902) (xy 269.812298 -277.208091)
			(xy 269.815564 -277.217124) (xy 269.81785 -277.221442) (xy 269.829661 -277.245184) (xy 269.846398 -277.295498)
			(xy 269.854887 -277.347838) (xy 269.855442 -277.37435) (xy 269.855442 -277.374858) (xy 269.854932 -277.400845)
			(xy 269.846802 -277.45218) (xy 269.830741 -277.50161) (xy 269.807145 -277.54792) (xy 269.776595 -277.589968)
			(xy 269.739844 -277.626719) (xy 269.697796 -277.657269) (xy 269.651486 -277.680865) (xy 269.602056 -277.696926)
			(xy 269.550721 -277.705056) (xy 269.498747 -277.705056) (xy 269.447412 -277.696926) (xy 269.397982 -277.680865)
			(xy 269.351672 -277.657269) (xy 269.309624 -277.626719) (xy 269.272873 -277.589968) (xy 269.242323 -277.54792)
			(xy 269.218727 -277.50161) (xy 269.202666 -277.45218) (xy 269.194536 -277.400845) (xy 269.194026 -277.374858)
			(xy 269.194026 -277.37435) (xy 269.194487 -277.34832) (xy 269.202603 -277.296897) (xy 269.218687 -277.247384)
			(xy 269.230094 -277.223982) (xy 269.233142 -277.21814) (xy 269.237714 -277.19782) (xy 269.237617 -277.193207)
			(xy 269.235962 -277.184131) (xy 269.234412 -277.179786) (xy 269.230094 -277.17115) (xy 269.206218 -277.13178)
			(xy 269.205964 -277.131526) (xy 269.195042 -277.113492) (xy 269.185136 -277.096982) (xy 269.178786 -277.0886)
			(xy 269.174112 -277.083957) (xy 269.162925 -277.077005) (xy 269.156688 -277.074884) (xy 269.15618 -277.074884)
			(xy 269.152645 -277.073864) (xy 269.145379 -277.072715) (xy 269.141702 -277.072598) (xy 268.967966 -277.072598)
			(xy 268.96187 -277.073106) (xy 268.961362 -277.073106) (xy 268.955771 -277.073973) (xy 268.945136 -277.077822)
			(xy 268.94028 -277.080726) (xy 268.93393 -277.086822) (xy 268.933676 -277.087076) (xy 268.930628 -277.08987)
			(xy 268.930374 -277.090124) (xy 268.92758 -277.092664) (xy 268.92504 -277.094442) (xy 268.869922 -277.14956)
			(xy 268.864166 -277.155675) (xy 268.856749 -277.17073) (xy 268.855444 -277.179024) (xy 268.855444 -277.179278)
			(xy 268.855054 -277.182891) (xy 268.855186 -277.190158) (xy 268.855698 -277.193756) (xy 268.856206 -277.19655)
			(xy 268.859762 -277.206964) (xy 268.861794 -277.21052) (xy 268.875508 -277.235718) (xy 268.89499 -277.289672)
			(xy 268.904882 -277.346176) (xy 268.905482 -277.374858) (xy 268.905002 -277.400849) (xy 268.896876 -277.452191)
			(xy 268.880817 -277.501629) (xy 268.857221 -277.547946) (xy 268.826669 -277.590002) (xy 268.789914 -277.626759)
			(xy 268.74786 -277.657313) (xy 268.701544 -277.680911) (xy 268.652106 -277.696972) (xy 268.600765 -277.705101)
			(xy 268.574774 -277.705566) (xy 268.548167 -277.705016) (xy 268.495643 -277.696463) (xy 268.445166 -277.679613)
			(xy 268.421358 -277.66772) (xy 268.415828 -277.665019) (xy 268.403887 -277.662054) (xy 268.397736 -277.661878)
			(xy 268.360144 -277.661878) (xy 268.355318 -277.664164) (xy 267.694664 -278.324818) (xy 268.26897 -278.324818)
			(xy 268.27293 -278.275764) (xy 268.284707 -278.22798) (xy 268.303998 -278.182704) (xy 268.330301 -278.141108)
			(xy 268.362936 -278.104271) (xy 268.401057 -278.073146) (xy 268.443678 -278.048539) (xy 268.489694 -278.031087)
			(xy 268.537913 -278.021243) (xy 268.587088 -278.019262) (xy 268.635943 -278.025194) (xy 268.683214 -278.038886)
			(xy 268.727676 -278.059984) (xy 268.768179 -278.08794) (xy 268.803672 -278.122032) (xy 268.833237 -278.161376)
			(xy 268.856108 -278.204953) (xy 268.871692 -278.251634) (xy 268.879587 -278.300211) (xy 268.880082 -278.324818)
			(xy 269.21893 -278.324818) (xy 269.22289 -278.275764) (xy 269.234667 -278.22798) (xy 269.253958 -278.182704)
			(xy 269.280261 -278.141108) (xy 269.312896 -278.104271) (xy 269.351017 -278.073146) (xy 269.393638 -278.048539)
			(xy 269.439654 -278.031087) (xy 269.487873 -278.021243) (xy 269.537048 -278.019262) (xy 269.585903 -278.025194)
			(xy 269.633174 -278.038886) (xy 269.677636 -278.059984) (xy 269.718139 -278.08794) (xy 269.753632 -278.122032)
			(xy 269.783197 -278.161376) (xy 269.806068 -278.204953) (xy 269.821652 -278.251634) (xy 269.829547 -278.300211)
			(xy 269.830042 -278.324818) (xy 270.169144 -278.324818) (xy 270.173104 -278.275764) (xy 270.184881 -278.22798)
			(xy 270.204172 -278.182704) (xy 270.230475 -278.141108) (xy 270.26311 -278.104271) (xy 270.301231 -278.073146)
			(xy 270.343852 -278.048539) (xy 270.389868 -278.031087) (xy 270.438087 -278.021243) (xy 270.487262 -278.019262)
			(xy 270.536117 -278.025194) (xy 270.583388 -278.038886) (xy 270.62785 -278.059984) (xy 270.668353 -278.08794)
			(xy 270.703846 -278.122032) (xy 270.733411 -278.161376) (xy 270.756282 -278.204953) (xy 270.771866 -278.251634)
			(xy 270.779761 -278.300211) (xy 270.780256 -278.324818) (xy 271.119104 -278.324818) (xy 271.123064 -278.275764)
			(xy 271.134841 -278.22798) (xy 271.154132 -278.182704) (xy 271.180435 -278.141108) (xy 271.21307 -278.104271)
			(xy 271.251191 -278.073146) (xy 271.293812 -278.048539) (xy 271.339828 -278.031087) (xy 271.388047 -278.021243)
			(xy 271.437222 -278.019262) (xy 271.486077 -278.025194) (xy 271.533348 -278.038886) (xy 271.57781 -278.059984)
			(xy 271.618313 -278.08794) (xy 271.653806 -278.122032) (xy 271.683371 -278.161376) (xy 271.706242 -278.204953)
			(xy 271.721826 -278.251634) (xy 271.729721 -278.300211) (xy 271.730216 -278.324818) (xy 272.069064 -278.324818)
			(xy 272.073024 -278.275764) (xy 272.084801 -278.22798) (xy 272.104092 -278.182704) (xy 272.130395 -278.141108)
			(xy 272.16303 -278.104271) (xy 272.201151 -278.073146) (xy 272.243772 -278.048539) (xy 272.289788 -278.031087)
			(xy 272.338007 -278.021243) (xy 272.387182 -278.019262) (xy 272.436037 -278.025194) (xy 272.483308 -278.038886)
			(xy 272.52777 -278.059984) (xy 272.568273 -278.08794) (xy 272.603766 -278.122032) (xy 272.633331 -278.161376)
			(xy 272.656202 -278.204953) (xy 272.671786 -278.251634) (xy 272.679681 -278.300211) (xy 272.680176 -278.324818)
			(xy 273.019024 -278.324818) (xy 273.022984 -278.275764) (xy 273.034761 -278.22798) (xy 273.054052 -278.182704)
			(xy 273.080355 -278.141108) (xy 273.11299 -278.104271) (xy 273.151111 -278.073146) (xy 273.193732 -278.048539)
			(xy 273.239748 -278.031087) (xy 273.287967 -278.021243) (xy 273.337142 -278.019262) (xy 273.385997 -278.025194)
			(xy 273.433268 -278.038886) (xy 273.47773 -278.059984) (xy 273.518233 -278.08794) (xy 273.553726 -278.122032)
			(xy 273.583291 -278.161376) (xy 273.606162 -278.204953) (xy 273.621746 -278.251634) (xy 273.629641 -278.300211)
			(xy 273.630136 -278.324818) (xy 273.968984 -278.324818) (xy 273.972944 -278.275764) (xy 273.984721 -278.22798)
			(xy 274.004012 -278.182704) (xy 274.030315 -278.141108) (xy 274.06295 -278.104271) (xy 274.101071 -278.073146)
			(xy 274.143692 -278.048539) (xy 274.189708 -278.031087) (xy 274.237927 -278.021243) (xy 274.287102 -278.019262)
			(xy 274.335957 -278.025194) (xy 274.383228 -278.038886) (xy 274.42769 -278.059984) (xy 274.468193 -278.08794)
			(xy 274.503686 -278.122032) (xy 274.533251 -278.161376) (xy 274.556122 -278.204953) (xy 274.571706 -278.251634)
			(xy 274.579601 -278.300211) (xy 274.580096 -278.324818) (xy 274.918944 -278.324818) (xy 274.922904 -278.275764)
			(xy 274.934681 -278.22798) (xy 274.953972 -278.182704) (xy 274.980275 -278.141108) (xy 275.01291 -278.104271)
			(xy 275.051031 -278.073146) (xy 275.093652 -278.048539) (xy 275.139668 -278.031087) (xy 275.187887 -278.021243)
			(xy 275.237062 -278.019262) (xy 275.285917 -278.025194) (xy 275.333188 -278.038886) (xy 275.37765 -278.059984)
			(xy 275.418153 -278.08794) (xy 275.453646 -278.122032) (xy 275.483211 -278.161376) (xy 275.506082 -278.204953)
			(xy 275.521666 -278.251634) (xy 275.529561 -278.300211) (xy 275.530056 -278.324818) (xy 275.529561 -278.349425)
			(xy 275.521666 -278.398002) (xy 275.506082 -278.444683) (xy 275.483211 -278.48826) (xy 275.453646 -278.527604)
			(xy 275.418153 -278.561696) (xy 275.37765 -278.589652) (xy 275.333188 -278.61075) (xy 275.285917 -278.624442)
			(xy 275.237062 -278.630374) (xy 275.187887 -278.628393) (xy 275.139668 -278.618549) (xy 275.093652 -278.601097)
			(xy 275.051031 -278.57649) (xy 275.01291 -278.545365) (xy 274.980275 -278.508528) (xy 274.953972 -278.466932)
			(xy 274.934681 -278.421656) (xy 274.922904 -278.373872) (xy 274.918944 -278.324818) (xy 274.580096 -278.324818)
			(xy 274.579601 -278.349425) (xy 274.571706 -278.398002) (xy 274.556122 -278.444683) (xy 274.533251 -278.48826)
			(xy 274.503686 -278.527604) (xy 274.468193 -278.561696) (xy 274.42769 -278.589652) (xy 274.383228 -278.61075)
			(xy 274.335957 -278.624442) (xy 274.287102 -278.630374) (xy 274.237927 -278.628393) (xy 274.189708 -278.618549)
			(xy 274.143692 -278.601097) (xy 274.101071 -278.57649) (xy 274.06295 -278.545365) (xy 274.030315 -278.508528)
			(xy 274.004012 -278.466932) (xy 273.984721 -278.421656) (xy 273.972944 -278.373872) (xy 273.968984 -278.324818)
			(xy 273.630136 -278.324818) (xy 273.629641 -278.349425) (xy 273.621746 -278.398002) (xy 273.606162 -278.444683)
			(xy 273.583291 -278.48826) (xy 273.553726 -278.527604) (xy 273.518233 -278.561696) (xy 273.47773 -278.589652)
			(xy 273.433268 -278.61075) (xy 273.385997 -278.624442) (xy 273.337142 -278.630374) (xy 273.287967 -278.628393)
			(xy 273.239748 -278.618549) (xy 273.193732 -278.601097) (xy 273.151111 -278.57649) (xy 273.11299 -278.545365)
			(xy 273.080355 -278.508528) (xy 273.054052 -278.466932) (xy 273.034761 -278.421656) (xy 273.022984 -278.373872)
			(xy 273.019024 -278.324818) (xy 272.680176 -278.324818) (xy 272.679681 -278.349425) (xy 272.671786 -278.398002)
			(xy 272.656202 -278.444683) (xy 272.633331 -278.48826) (xy 272.603766 -278.527604) (xy 272.568273 -278.561696)
			(xy 272.52777 -278.589652) (xy 272.483308 -278.61075) (xy 272.436037 -278.624442) (xy 272.387182 -278.630374)
			(xy 272.338007 -278.628393) (xy 272.289788 -278.618549) (xy 272.243772 -278.601097) (xy 272.201151 -278.57649)
			(xy 272.16303 -278.545365) (xy 272.130395 -278.508528) (xy 272.104092 -278.466932) (xy 272.084801 -278.421656)
			(xy 272.073024 -278.373872) (xy 272.069064 -278.324818) (xy 271.730216 -278.324818) (xy 271.729721 -278.349425)
			(xy 271.721826 -278.398002) (xy 271.706242 -278.444683) (xy 271.683371 -278.48826) (xy 271.653806 -278.527604)
			(xy 271.618313 -278.561696) (xy 271.57781 -278.589652) (xy 271.533348 -278.61075) (xy 271.486077 -278.624442)
			(xy 271.437222 -278.630374) (xy 271.388047 -278.628393) (xy 271.339828 -278.618549) (xy 271.293812 -278.601097)
			(xy 271.251191 -278.57649) (xy 271.21307 -278.545365) (xy 271.180435 -278.508528) (xy 271.154132 -278.466932)
			(xy 271.134841 -278.421656) (xy 271.123064 -278.373872) (xy 271.119104 -278.324818) (xy 270.780256 -278.324818)
			(xy 270.779761 -278.349425) (xy 270.771866 -278.398002) (xy 270.756282 -278.444683) (xy 270.733411 -278.48826)
			(xy 270.703846 -278.527604) (xy 270.668353 -278.561696) (xy 270.62785 -278.589652) (xy 270.583388 -278.61075)
			(xy 270.536117 -278.624442) (xy 270.487262 -278.630374) (xy 270.438087 -278.628393) (xy 270.389868 -278.618549)
			(xy 270.343852 -278.601097) (xy 270.301231 -278.57649) (xy 270.26311 -278.545365) (xy 270.230475 -278.508528)
			(xy 270.204172 -278.466932) (xy 270.184881 -278.421656) (xy 270.173104 -278.373872) (xy 270.169144 -278.324818)
			(xy 269.830042 -278.324818) (xy 269.829547 -278.349425) (xy 269.821652 -278.398002) (xy 269.806068 -278.444683)
			(xy 269.783197 -278.48826) (xy 269.753632 -278.527604) (xy 269.718139 -278.561696) (xy 269.677636 -278.589652)
			(xy 269.633174 -278.61075) (xy 269.585903 -278.624442) (xy 269.537048 -278.630374) (xy 269.487873 -278.628393)
			(xy 269.439654 -278.618549) (xy 269.393638 -278.601097) (xy 269.351017 -278.57649) (xy 269.312896 -278.545365)
			(xy 269.280261 -278.508528) (xy 269.253958 -278.466932) (xy 269.234667 -278.421656) (xy 269.22289 -278.373872)
			(xy 269.21893 -278.324818) (xy 268.880082 -278.324818) (xy 268.879587 -278.349425) (xy 268.871692 -278.398002)
			(xy 268.856108 -278.444683) (xy 268.833237 -278.48826) (xy 268.803672 -278.527604) (xy 268.768179 -278.561696)
			(xy 268.727676 -278.589652) (xy 268.683214 -278.61075) (xy 268.635943 -278.624442) (xy 268.587088 -278.630374)
			(xy 268.537913 -278.628393) (xy 268.489694 -278.618549) (xy 268.443678 -278.601097) (xy 268.401057 -278.57649)
			(xy 268.362936 -278.545365) (xy 268.330301 -278.508528) (xy 268.303998 -278.466932) (xy 268.284707 -278.421656)
			(xy 268.27293 -278.373872) (xy 268.26897 -278.324818) (xy 267.694664 -278.324818) (xy 266.744704 -279.274778)
			(xy 268.26897 -279.274778) (xy 268.27293 -279.225724) (xy 268.284707 -279.17794) (xy 268.303998 -279.132664)
			(xy 268.330301 -279.091068) (xy 268.362936 -279.054231) (xy 268.401057 -279.023106) (xy 268.443678 -278.998499)
			(xy 268.489694 -278.981047) (xy 268.537913 -278.971203) (xy 268.587088 -278.969222) (xy 268.635943 -278.975154)
			(xy 268.683214 -278.988846) (xy 268.727676 -279.009944) (xy 268.768179 -279.0379) (xy 268.803672 -279.071992)
			(xy 268.833237 -279.111336) (xy 268.856108 -279.154913) (xy 268.871692 -279.201594) (xy 268.879587 -279.250171)
			(xy 268.880082 -279.274778) (xy 269.21893 -279.274778) (xy 269.22289 -279.225724) (xy 269.234667 -279.17794)
			(xy 269.253958 -279.132664) (xy 269.280261 -279.091068) (xy 269.312896 -279.054231) (xy 269.351017 -279.023106)
			(xy 269.393638 -278.998499) (xy 269.439654 -278.981047) (xy 269.487873 -278.971203) (xy 269.537048 -278.969222)
			(xy 269.585903 -278.975154) (xy 269.633174 -278.988846) (xy 269.677636 -279.009944) (xy 269.718139 -279.0379)
			(xy 269.753632 -279.071992) (xy 269.783197 -279.111336) (xy 269.806068 -279.154913) (xy 269.821652 -279.201594)
			(xy 269.829547 -279.250171) (xy 269.830042 -279.274778) (xy 270.169144 -279.274778) (xy 270.173104 -279.225724)
			(xy 270.184881 -279.17794) (xy 270.204172 -279.132664) (xy 270.230475 -279.091068) (xy 270.26311 -279.054231)
			(xy 270.301231 -279.023106) (xy 270.343852 -278.998499) (xy 270.389868 -278.981047) (xy 270.438087 -278.971203)
			(xy 270.487262 -278.969222) (xy 270.536117 -278.975154) (xy 270.583388 -278.988846) (xy 270.62785 -279.009944)
			(xy 270.668353 -279.0379) (xy 270.703846 -279.071992) (xy 270.733411 -279.111336) (xy 270.756282 -279.154913)
			(xy 270.771866 -279.201594) (xy 270.779761 -279.250171) (xy 270.780256 -279.274778) (xy 271.119104 -279.274778)
			(xy 271.123064 -279.225724) (xy 271.134841 -279.17794) (xy 271.154132 -279.132664) (xy 271.180435 -279.091068)
			(xy 271.21307 -279.054231) (xy 271.251191 -279.023106) (xy 271.293812 -278.998499) (xy 271.339828 -278.981047)
			(xy 271.388047 -278.971203) (xy 271.437222 -278.969222) (xy 271.486077 -278.975154) (xy 271.533348 -278.988846)
			(xy 271.57781 -279.009944) (xy 271.618313 -279.0379) (xy 271.653806 -279.071992) (xy 271.683371 -279.111336)
			(xy 271.706242 -279.154913) (xy 271.721826 -279.201594) (xy 271.729721 -279.250171) (xy 271.730216 -279.274778)
			(xy 272.069064 -279.274778) (xy 272.073024 -279.225724) (xy 272.084801 -279.17794) (xy 272.104092 -279.132664)
			(xy 272.130395 -279.091068) (xy 272.16303 -279.054231) (xy 272.201151 -279.023106) (xy 272.243772 -278.998499)
			(xy 272.289788 -278.981047) (xy 272.338007 -278.971203) (xy 272.387182 -278.969222) (xy 272.436037 -278.975154)
			(xy 272.483308 -278.988846) (xy 272.52777 -279.009944) (xy 272.568273 -279.0379) (xy 272.603766 -279.071992)
			(xy 272.633331 -279.111336) (xy 272.656202 -279.154913) (xy 272.671786 -279.201594) (xy 272.679681 -279.250171)
			(xy 272.680176 -279.274778) (xy 273.019024 -279.274778) (xy 273.022984 -279.225724) (xy 273.034761 -279.17794)
			(xy 273.054052 -279.132664) (xy 273.080355 -279.091068) (xy 273.11299 -279.054231) (xy 273.151111 -279.023106)
			(xy 273.193732 -278.998499) (xy 273.239748 -278.981047) (xy 273.287967 -278.971203) (xy 273.337142 -278.969222)
			(xy 273.385997 -278.975154) (xy 273.433268 -278.988846) (xy 273.47773 -279.009944) (xy 273.518233 -279.0379)
			(xy 273.553726 -279.071992) (xy 273.583291 -279.111336) (xy 273.606162 -279.154913) (xy 273.621746 -279.201594)
			(xy 273.629641 -279.250171) (xy 273.630136 -279.274778) (xy 273.968984 -279.274778) (xy 273.972944 -279.225724)
			(xy 273.984721 -279.17794) (xy 274.004012 -279.132664) (xy 274.030315 -279.091068) (xy 274.06295 -279.054231)
			(xy 274.101071 -279.023106) (xy 274.143692 -278.998499) (xy 274.189708 -278.981047) (xy 274.237927 -278.971203)
			(xy 274.287102 -278.969222) (xy 274.335957 -278.975154) (xy 274.383228 -278.988846) (xy 274.42769 -279.009944)
			(xy 274.468193 -279.0379) (xy 274.503686 -279.071992) (xy 274.533251 -279.111336) (xy 274.556122 -279.154913)
			(xy 274.571706 -279.201594) (xy 274.579601 -279.250171) (xy 274.580096 -279.274778) (xy 274.918944 -279.274778)
			(xy 274.922904 -279.225724) (xy 274.934681 -279.17794) (xy 274.953972 -279.132664) (xy 274.980275 -279.091068)
			(xy 275.01291 -279.054231) (xy 275.051031 -279.023106) (xy 275.093652 -278.998499) (xy 275.139668 -278.981047)
			(xy 275.187887 -278.971203) (xy 275.237062 -278.969222) (xy 275.285917 -278.975154) (xy 275.333188 -278.988846)
			(xy 275.37765 -279.009944) (xy 275.418153 -279.0379) (xy 275.453646 -279.071992) (xy 275.483211 -279.111336)
			(xy 275.506082 -279.154913) (xy 275.521666 -279.201594) (xy 275.529561 -279.250171) (xy 275.530056 -279.274778)
			(xy 275.529561 -279.299385) (xy 275.521666 -279.347962) (xy 275.506082 -279.394643) (xy 275.483211 -279.43822)
			(xy 275.453646 -279.477564) (xy 275.418153 -279.511656) (xy 275.37765 -279.539612) (xy 275.333188 -279.56071)
			(xy 275.285917 -279.574402) (xy 275.237062 -279.580334) (xy 275.187887 -279.578353) (xy 275.139668 -279.568509)
			(xy 275.093652 -279.551057) (xy 275.051031 -279.52645) (xy 275.01291 -279.495325) (xy 274.980275 -279.458488)
			(xy 274.953972 -279.416892) (xy 274.934681 -279.371616) (xy 274.922904 -279.323832) (xy 274.918944 -279.274778)
			(xy 274.580096 -279.274778) (xy 274.579601 -279.299385) (xy 274.571706 -279.347962) (xy 274.556122 -279.394643)
			(xy 274.533251 -279.43822) (xy 274.503686 -279.477564) (xy 274.468193 -279.511656) (xy 274.42769 -279.539612)
			(xy 274.383228 -279.56071) (xy 274.335957 -279.574402) (xy 274.287102 -279.580334) (xy 274.237927 -279.578353)
			(xy 274.189708 -279.568509) (xy 274.143692 -279.551057) (xy 274.101071 -279.52645) (xy 274.06295 -279.495325)
			(xy 274.030315 -279.458488) (xy 274.004012 -279.416892) (xy 273.984721 -279.371616) (xy 273.972944 -279.323832)
			(xy 273.968984 -279.274778) (xy 273.630136 -279.274778) (xy 273.629641 -279.299385) (xy 273.621746 -279.347962)
			(xy 273.606162 -279.394643) (xy 273.583291 -279.43822) (xy 273.553726 -279.477564) (xy 273.518233 -279.511656)
			(xy 273.47773 -279.539612) (xy 273.433268 -279.56071) (xy 273.385997 -279.574402) (xy 273.337142 -279.580334)
			(xy 273.287967 -279.578353) (xy 273.239748 -279.568509) (xy 273.193732 -279.551057) (xy 273.151111 -279.52645)
			(xy 273.11299 -279.495325) (xy 273.080355 -279.458488) (xy 273.054052 -279.416892) (xy 273.034761 -279.371616)
			(xy 273.022984 -279.323832) (xy 273.019024 -279.274778) (xy 272.680176 -279.274778) (xy 272.679681 -279.299385)
			(xy 272.671786 -279.347962) (xy 272.656202 -279.394643) (xy 272.633331 -279.43822) (xy 272.603766 -279.477564)
			(xy 272.568273 -279.511656) (xy 272.52777 -279.539612) (xy 272.483308 -279.56071) (xy 272.436037 -279.574402)
			(xy 272.387182 -279.580334) (xy 272.338007 -279.578353) (xy 272.289788 -279.568509) (xy 272.243772 -279.551057)
			(xy 272.201151 -279.52645) (xy 272.16303 -279.495325) (xy 272.130395 -279.458488) (xy 272.104092 -279.416892)
			(xy 272.084801 -279.371616) (xy 272.073024 -279.323832) (xy 272.069064 -279.274778) (xy 271.730216 -279.274778)
			(xy 271.729721 -279.299385) (xy 271.721826 -279.347962) (xy 271.706242 -279.394643) (xy 271.683371 -279.43822)
			(xy 271.653806 -279.477564) (xy 271.618313 -279.511656) (xy 271.57781 -279.539612) (xy 271.533348 -279.56071)
			(xy 271.486077 -279.574402) (xy 271.437222 -279.580334) (xy 271.388047 -279.578353) (xy 271.339828 -279.568509)
			(xy 271.293812 -279.551057) (xy 271.251191 -279.52645) (xy 271.21307 -279.495325) (xy 271.180435 -279.458488)
			(xy 271.154132 -279.416892) (xy 271.134841 -279.371616) (xy 271.123064 -279.323832) (xy 271.119104 -279.274778)
			(xy 270.780256 -279.274778) (xy 270.779761 -279.299385) (xy 270.771866 -279.347962) (xy 270.756282 -279.394643)
			(xy 270.733411 -279.43822) (xy 270.703846 -279.477564) (xy 270.668353 -279.511656) (xy 270.62785 -279.539612)
			(xy 270.583388 -279.56071) (xy 270.536117 -279.574402) (xy 270.487262 -279.580334) (xy 270.438087 -279.578353)
			(xy 270.389868 -279.568509) (xy 270.343852 -279.551057) (xy 270.301231 -279.52645) (xy 270.26311 -279.495325)
			(xy 270.230475 -279.458488) (xy 270.204172 -279.416892) (xy 270.184881 -279.371616) (xy 270.173104 -279.323832)
			(xy 270.169144 -279.274778) (xy 269.830042 -279.274778) (xy 269.829547 -279.299385) (xy 269.821652 -279.347962)
			(xy 269.806068 -279.394643) (xy 269.783197 -279.43822) (xy 269.753632 -279.477564) (xy 269.718139 -279.511656)
			(xy 269.677636 -279.539612) (xy 269.633174 -279.56071) (xy 269.585903 -279.574402) (xy 269.537048 -279.580334)
			(xy 269.487873 -279.578353) (xy 269.439654 -279.568509) (xy 269.393638 -279.551057) (xy 269.351017 -279.52645)
			(xy 269.312896 -279.495325) (xy 269.280261 -279.458488) (xy 269.253958 -279.416892) (xy 269.234667 -279.371616)
			(xy 269.22289 -279.323832) (xy 269.21893 -279.274778) (xy 268.880082 -279.274778) (xy 268.879587 -279.299385)
			(xy 268.871692 -279.347962) (xy 268.856108 -279.394643) (xy 268.833237 -279.43822) (xy 268.803672 -279.477564)
			(xy 268.768179 -279.511656) (xy 268.727676 -279.539612) (xy 268.683214 -279.56071) (xy 268.635943 -279.574402)
			(xy 268.587088 -279.580334) (xy 268.537913 -279.578353) (xy 268.489694 -279.568509) (xy 268.443678 -279.551057)
			(xy 268.401057 -279.52645) (xy 268.362936 -279.495325) (xy 268.330301 -279.458488) (xy 268.303998 -279.416892)
			(xy 268.284707 -279.371616) (xy 268.27293 -279.323832) (xy 268.26897 -279.274778) (xy 266.744704 -279.274778)
			(xy 266.605258 -279.414224) (xy 266.602552 -279.417075) (xy 266.59796 -279.423454) (xy 266.596114 -279.426924)
			(xy 266.593528 -279.43235) (xy 266.590699 -279.44403) (xy 266.590526 -279.450038) (xy 266.590526 -279.749758)
			(xy 276.343884 -279.749758) (xy 276.347844 -279.700704) (xy 276.359621 -279.65292) (xy 276.378912 -279.607644)
			(xy 276.405215 -279.566048) (xy 276.43785 -279.529211) (xy 276.475971 -279.498086) (xy 276.518592 -279.473479)
			(xy 276.564608 -279.456027) (xy 276.612827 -279.446183) (xy 276.662002 -279.444202) (xy 276.710857 -279.450134)
			(xy 276.758128 -279.463826) (xy 276.80259 -279.484924) (xy 276.843093 -279.51288) (xy 276.878586 -279.546972)
			(xy 276.908151 -279.586316) (xy 276.931022 -279.629893) (xy 276.946606 -279.676574) (xy 276.954501 -279.725151)
			(xy 276.954991 -279.749504) (xy 277.294098 -279.749504) (xy 277.298058 -279.70045) (xy 277.309835 -279.652666)
			(xy 277.329126 -279.60739) (xy 277.355429 -279.565794) (xy 277.388064 -279.528957) (xy 277.426185 -279.497832)
			(xy 277.468806 -279.473225) (xy 277.514822 -279.455773) (xy 277.563041 -279.445929) (xy 277.612216 -279.443948)
			(xy 277.661071 -279.44988) (xy 277.708342 -279.463572) (xy 277.752804 -279.48467) (xy 277.793307 -279.512626)
			(xy 277.8288 -279.546718) (xy 277.858365 -279.586062) (xy 277.881236 -279.629639) (xy 277.89682 -279.67632)
			(xy 277.904715 -279.724897) (xy 277.90521 -279.749504) (xy 277.905205 -279.749758) (xy 278.244058 -279.749758)
			(xy 278.248018 -279.700704) (xy 278.259795 -279.65292) (xy 278.279086 -279.607644) (xy 278.305389 -279.566048)
			(xy 278.338024 -279.529211) (xy 278.376145 -279.498086) (xy 278.418766 -279.473479) (xy 278.464782 -279.456027)
			(xy 278.513001 -279.446183) (xy 278.562176 -279.444202) (xy 278.611031 -279.450134) (xy 278.658302 -279.463826)
			(xy 278.702764 -279.484924) (xy 278.743267 -279.51288) (xy 278.77876 -279.546972) (xy 278.808325 -279.586316)
			(xy 278.831196 -279.629893) (xy 278.84678 -279.676574) (xy 278.854675 -279.725151) (xy 278.855165 -279.749504)
			(xy 279.194018 -279.749504) (xy 279.197978 -279.70045) (xy 279.209755 -279.652666) (xy 279.229046 -279.60739)
			(xy 279.255349 -279.565794) (xy 279.287984 -279.528957) (xy 279.326105 -279.497832) (xy 279.368726 -279.473225)
			(xy 279.414742 -279.455773) (xy 279.462961 -279.445929) (xy 279.512136 -279.443948) (xy 279.560991 -279.44988)
			(xy 279.608262 -279.463572) (xy 279.652724 -279.48467) (xy 279.693227 -279.512626) (xy 279.72872 -279.546718)
			(xy 279.758285 -279.586062) (xy 279.781156 -279.629639) (xy 279.79674 -279.67632) (xy 279.804635 -279.724897)
			(xy 279.80513 -279.749504) (xy 279.805125 -279.749758) (xy 280.143978 -279.749758) (xy 280.147938 -279.700704)
			(xy 280.159715 -279.65292) (xy 280.179006 -279.607644) (xy 280.205309 -279.566048) (xy 280.237944 -279.529211)
			(xy 280.276065 -279.498086) (xy 280.318686 -279.473479) (xy 280.364702 -279.456027) (xy 280.412921 -279.446183)
			(xy 280.462096 -279.444202) (xy 280.510951 -279.450134) (xy 280.558222 -279.463826) (xy 280.602684 -279.484924)
			(xy 280.643187 -279.51288) (xy 280.67868 -279.546972) (xy 280.708245 -279.586316) (xy 280.731116 -279.629893)
			(xy 280.7467 -279.676574) (xy 280.754595 -279.725151) (xy 280.755085 -279.749504) (xy 281.093938 -279.749504)
			(xy 281.097898 -279.70045) (xy 281.109675 -279.652666) (xy 281.128966 -279.60739) (xy 281.155269 -279.565794)
			(xy 281.187904 -279.528957) (xy 281.226025 -279.497832) (xy 281.268646 -279.473225) (xy 281.314662 -279.455773)
			(xy 281.362881 -279.445929) (xy 281.412056 -279.443948) (xy 281.460911 -279.44988) (xy 281.508182 -279.463572)
			(xy 281.552644 -279.48467) (xy 281.593147 -279.512626) (xy 281.62864 -279.546718) (xy 281.658205 -279.586062)
			(xy 281.681076 -279.629639) (xy 281.69666 -279.67632) (xy 281.704555 -279.724897) (xy 281.70505 -279.749504)
			(xy 281.705045 -279.749758) (xy 282.043898 -279.749758) (xy 282.047858 -279.700704) (xy 282.059635 -279.65292)
			(xy 282.078926 -279.607644) (xy 282.105229 -279.566048) (xy 282.137864 -279.529211) (xy 282.175985 -279.498086)
			(xy 282.218606 -279.473479) (xy 282.264622 -279.456027) (xy 282.312841 -279.446183) (xy 282.362016 -279.444202)
			(xy 282.410871 -279.450134) (xy 282.458142 -279.463826) (xy 282.502604 -279.484924) (xy 282.543107 -279.51288)
			(xy 282.5786 -279.546972) (xy 282.608165 -279.586316) (xy 282.631036 -279.629893) (xy 282.64662 -279.676574)
			(xy 282.654515 -279.725151) (xy 282.655005 -279.749504) (xy 282.994112 -279.749504) (xy 282.998072 -279.70045)
			(xy 283.009849 -279.652666) (xy 283.02914 -279.60739) (xy 283.055443 -279.565794) (xy 283.088078 -279.528957)
			(xy 283.126199 -279.497832) (xy 283.16882 -279.473225) (xy 283.214836 -279.455773) (xy 283.263055 -279.445929)
			(xy 283.31223 -279.443948) (xy 283.361085 -279.44988) (xy 283.408356 -279.463572) (xy 283.452818 -279.48467)
			(xy 283.493321 -279.512626) (xy 283.528814 -279.546718) (xy 283.558379 -279.586062) (xy 283.58125 -279.629639)
			(xy 283.596834 -279.67632) (xy 283.604729 -279.724897) (xy 283.605224 -279.749504) (xy 283.605219 -279.749758)
			(xy 283.944072 -279.749758) (xy 283.948032 -279.700704) (xy 283.959809 -279.65292) (xy 283.9791 -279.607644)
			(xy 284.005403 -279.566048) (xy 284.038038 -279.529211) (xy 284.076159 -279.498086) (xy 284.11878 -279.473479)
			(xy 284.164796 -279.456027) (xy 284.213015 -279.446183) (xy 284.26219 -279.444202) (xy 284.311045 -279.450134)
			(xy 284.358316 -279.463826) (xy 284.402778 -279.484924) (xy 284.443281 -279.51288) (xy 284.478774 -279.546972)
			(xy 284.508339 -279.586316) (xy 284.53121 -279.629893) (xy 284.546794 -279.676574) (xy 284.554689 -279.725151)
			(xy 284.555179 -279.749504) (xy 284.894032 -279.749504) (xy 284.897992 -279.70045) (xy 284.909769 -279.652666)
			(xy 284.92906 -279.60739) (xy 284.955363 -279.565794) (xy 284.987998 -279.528957) (xy 285.026119 -279.497832)
			(xy 285.06874 -279.473225) (xy 285.114756 -279.455773) (xy 285.162975 -279.445929) (xy 285.21215 -279.443948)
			(xy 285.261005 -279.44988) (xy 285.308276 -279.463572) (xy 285.352738 -279.48467) (xy 285.393241 -279.512626)
			(xy 285.428734 -279.546718) (xy 285.458299 -279.586062) (xy 285.48117 -279.629639) (xy 285.496754 -279.67632)
			(xy 285.504649 -279.724897) (xy 285.505144 -279.749504) (xy 285.505139 -279.749758) (xy 285.843992 -279.749758)
			(xy 285.847952 -279.700704) (xy 285.859729 -279.65292) (xy 285.87902 -279.607644) (xy 285.905323 -279.566048)
			(xy 285.937958 -279.529211) (xy 285.976079 -279.498086) (xy 286.0187 -279.473479) (xy 286.064716 -279.456027)
			(xy 286.112935 -279.446183) (xy 286.16211 -279.444202) (xy 286.210965 -279.450134) (xy 286.258236 -279.463826)
			(xy 286.302698 -279.484924) (xy 286.343201 -279.51288) (xy 286.378694 -279.546972) (xy 286.408259 -279.586316)
			(xy 286.43113 -279.629893) (xy 286.446714 -279.676574) (xy 286.454609 -279.725151) (xy 286.455099 -279.749504)
			(xy 286.793952 -279.749504) (xy 286.797912 -279.70045) (xy 286.809689 -279.652666) (xy 286.82898 -279.60739)
			(xy 286.855283 -279.565794) (xy 286.887918 -279.528957) (xy 286.926039 -279.497832) (xy 286.96866 -279.473225)
			(xy 287.014676 -279.455773) (xy 287.062895 -279.445929) (xy 287.11207 -279.443948) (xy 287.160925 -279.44988)
			(xy 287.208196 -279.463572) (xy 287.252658 -279.48467) (xy 287.293161 -279.512626) (xy 287.328654 -279.546718)
			(xy 287.358219 -279.586062) (xy 287.38109 -279.629639) (xy 287.396674 -279.67632) (xy 287.404569 -279.724897)
			(xy 287.405064 -279.749504) (xy 287.405059 -279.749758) (xy 287.743912 -279.749758) (xy 287.747872 -279.700704)
			(xy 287.759649 -279.65292) (xy 287.77894 -279.607644) (xy 287.805243 -279.566048) (xy 287.837878 -279.529211)
			(xy 287.875999 -279.498086) (xy 287.91862 -279.473479) (xy 287.964636 -279.456027) (xy 288.012855 -279.446183)
			(xy 288.06203 -279.444202) (xy 288.110885 -279.450134) (xy 288.158156 -279.463826) (xy 288.202618 -279.484924)
			(xy 288.243121 -279.51288) (xy 288.278614 -279.546972) (xy 288.308179 -279.586316) (xy 288.33105 -279.629893)
			(xy 288.346634 -279.676574) (xy 288.354529 -279.725151) (xy 288.355019 -279.749504) (xy 288.693872 -279.749504)
			(xy 288.697832 -279.70045) (xy 288.709609 -279.652666) (xy 288.7289 -279.60739) (xy 288.755203 -279.565794)
			(xy 288.787838 -279.528957) (xy 288.825959 -279.497832) (xy 288.86858 -279.473225) (xy 288.914596 -279.455773)
			(xy 288.962815 -279.445929) (xy 289.01199 -279.443948) (xy 289.060845 -279.44988) (xy 289.108116 -279.463572)
			(xy 289.152578 -279.48467) (xy 289.193081 -279.512626) (xy 289.228574 -279.546718) (xy 289.258139 -279.586062)
			(xy 289.28101 -279.629639) (xy 289.296594 -279.67632) (xy 289.304489 -279.724897) (xy 289.304984 -279.749504)
			(xy 289.304979 -279.749758) (xy 289.644086 -279.749758) (xy 289.648046 -279.700704) (xy 289.659823 -279.65292)
			(xy 289.679114 -279.607644) (xy 289.705417 -279.566048) (xy 289.738052 -279.529211) (xy 289.776173 -279.498086)
			(xy 289.818794 -279.473479) (xy 289.86481 -279.456027) (xy 289.913029 -279.446183) (xy 289.962204 -279.444202)
			(xy 290.011059 -279.450134) (xy 290.05833 -279.463826) (xy 290.102792 -279.484924) (xy 290.143295 -279.51288)
			(xy 290.178788 -279.546972) (xy 290.208353 -279.586316) (xy 290.231224 -279.629893) (xy 290.246808 -279.676574)
			(xy 290.254703 -279.725151) (xy 290.255193 -279.749504) (xy 290.594046 -279.749504) (xy 290.598006 -279.70045)
			(xy 290.609783 -279.652666) (xy 290.629074 -279.60739) (xy 290.655377 -279.565794) (xy 290.688012 -279.528957)
			(xy 290.726133 -279.497832) (xy 290.768754 -279.473225) (xy 290.81477 -279.455773) (xy 290.862989 -279.445929)
			(xy 290.912164 -279.443948) (xy 290.961019 -279.44988) (xy 291.00829 -279.463572) (xy 291.052752 -279.48467)
			(xy 291.093255 -279.512626) (xy 291.128748 -279.546718) (xy 291.158313 -279.586062) (xy 291.181184 -279.629639)
			(xy 291.196768 -279.67632) (xy 291.204663 -279.724897) (xy 291.205158 -279.749504) (xy 291.205153 -279.749758)
			(xy 291.544006 -279.749758) (xy 291.547966 -279.700704) (xy 291.559743 -279.65292) (xy 291.579034 -279.607644)
			(xy 291.605337 -279.566048) (xy 291.637972 -279.529211) (xy 291.676093 -279.498086) (xy 291.718714 -279.473479)
			(xy 291.76473 -279.456027) (xy 291.812949 -279.446183) (xy 291.862124 -279.444202) (xy 291.910979 -279.450134)
			(xy 291.95825 -279.463826) (xy 292.002712 -279.484924) (xy 292.043215 -279.51288) (xy 292.078708 -279.546972)
			(xy 292.108273 -279.586316) (xy 292.131144 -279.629893) (xy 292.146728 -279.676574) (xy 292.154623 -279.725151)
			(xy 292.155113 -279.749504) (xy 292.493966 -279.749504) (xy 292.497926 -279.70045) (xy 292.509703 -279.652666)
			(xy 292.528994 -279.60739) (xy 292.555297 -279.565794) (xy 292.587932 -279.528957) (xy 292.626053 -279.497832)
			(xy 292.668674 -279.473225) (xy 292.71469 -279.455773) (xy 292.762909 -279.445929) (xy 292.812084 -279.443948)
			(xy 292.860939 -279.44988) (xy 292.90821 -279.463572) (xy 292.952672 -279.48467) (xy 292.993175 -279.512626)
			(xy 293.028668 -279.546718) (xy 293.058233 -279.586062) (xy 293.081104 -279.629639) (xy 293.096688 -279.67632)
			(xy 293.104583 -279.724897) (xy 293.105078 -279.749504) (xy 293.105073 -279.749758) (xy 293.443926 -279.749758)
			(xy 293.447886 -279.700704) (xy 293.459663 -279.65292) (xy 293.478954 -279.607644) (xy 293.505257 -279.566048)
			(xy 293.537892 -279.529211) (xy 293.576013 -279.498086) (xy 293.618634 -279.473479) (xy 293.66465 -279.456027)
			(xy 293.712869 -279.446183) (xy 293.762044 -279.444202) (xy 293.810899 -279.450134) (xy 293.85817 -279.463826)
			(xy 293.902632 -279.484924) (xy 293.943135 -279.51288) (xy 293.978628 -279.546972) (xy 294.008193 -279.586316)
			(xy 294.031064 -279.629893) (xy 294.046648 -279.676574) (xy 294.054543 -279.725151) (xy 294.055033 -279.749504)
			(xy 294.393886 -279.749504) (xy 294.397846 -279.70045) (xy 294.409623 -279.652666) (xy 294.428914 -279.60739)
			(xy 294.455217 -279.565794) (xy 294.487852 -279.528957) (xy 294.525973 -279.497832) (xy 294.568594 -279.473225)
			(xy 294.61461 -279.455773) (xy 294.662829 -279.445929) (xy 294.712004 -279.443948) (xy 294.760859 -279.44988)
			(xy 294.80813 -279.463572) (xy 294.852592 -279.48467) (xy 294.893095 -279.512626) (xy 294.928588 -279.546718)
			(xy 294.958153 -279.586062) (xy 294.981024 -279.629639) (xy 294.996608 -279.67632) (xy 295.004503 -279.724897)
			(xy 295.004998 -279.749504) (xy 295.004993 -279.749758) (xy 295.3441 -279.749758) (xy 295.34806 -279.700704)
			(xy 295.359837 -279.65292) (xy 295.379128 -279.607644) (xy 295.405431 -279.566048) (xy 295.438066 -279.529211)
			(xy 295.476187 -279.498086) (xy 295.518808 -279.473479) (xy 295.564824 -279.456027) (xy 295.613043 -279.446183)
			(xy 295.662218 -279.444202) (xy 295.711073 -279.450134) (xy 295.758344 -279.463826) (xy 295.802806 -279.484924)
			(xy 295.843309 -279.51288) (xy 295.878802 -279.546972) (xy 295.908367 -279.586316) (xy 295.931238 -279.629893)
			(xy 295.946822 -279.676574) (xy 295.954717 -279.725151) (xy 295.955207 -279.749504) (xy 296.29406 -279.749504)
			(xy 296.29802 -279.70045) (xy 296.309797 -279.652666) (xy 296.329088 -279.60739) (xy 296.355391 -279.565794)
			(xy 296.388026 -279.528957) (xy 296.426147 -279.497832) (xy 296.468768 -279.473225) (xy 296.514784 -279.455773)
			(xy 296.563003 -279.445929) (xy 296.612178 -279.443948) (xy 296.661033 -279.44988) (xy 296.708304 -279.463572)
			(xy 296.752766 -279.48467) (xy 296.793269 -279.512626) (xy 296.828762 -279.546718) (xy 296.858327 -279.586062)
			(xy 296.881198 -279.629639) (xy 296.896782 -279.67632) (xy 296.904677 -279.724897) (xy 296.905172 -279.749504)
			(xy 296.905167 -279.749758) (xy 297.24402 -279.749758) (xy 297.24798 -279.700704) (xy 297.259757 -279.65292)
			(xy 297.279048 -279.607644) (xy 297.305351 -279.566048) (xy 297.337986 -279.529211) (xy 297.376107 -279.498086)
			(xy 297.418728 -279.473479) (xy 297.464744 -279.456027) (xy 297.512963 -279.446183) (xy 297.562138 -279.444202)
			(xy 297.610993 -279.450134) (xy 297.658264 -279.463826) (xy 297.702726 -279.484924) (xy 297.743229 -279.51288)
			(xy 297.778722 -279.546972) (xy 297.808287 -279.586316) (xy 297.831158 -279.629893) (xy 297.846742 -279.676574)
			(xy 297.854637 -279.725151) (xy 297.855127 -279.749504) (xy 298.19398 -279.749504) (xy 298.19794 -279.70045)
			(xy 298.209717 -279.652666) (xy 298.229008 -279.60739) (xy 298.255311 -279.565794) (xy 298.287946 -279.528957)
			(xy 298.326067 -279.497832) (xy 298.368688 -279.473225) (xy 298.414704 -279.455773) (xy 298.462923 -279.445929)
			(xy 298.512098 -279.443948) (xy 298.560953 -279.44988) (xy 298.608224 -279.463572) (xy 298.652686 -279.48467)
			(xy 298.693189 -279.512626) (xy 298.728682 -279.546718) (xy 298.758247 -279.586062) (xy 298.781118 -279.629639)
			(xy 298.796702 -279.67632) (xy 298.804597 -279.724897) (xy 298.805092 -279.749504) (xy 298.805087 -279.749758)
			(xy 299.14394 -279.749758) (xy 299.1479 -279.700704) (xy 299.159677 -279.65292) (xy 299.178968 -279.607644)
			(xy 299.205271 -279.566048) (xy 299.237906 -279.529211) (xy 299.276027 -279.498086) (xy 299.318648 -279.473479)
			(xy 299.364664 -279.456027) (xy 299.412883 -279.446183) (xy 299.462058 -279.444202) (xy 299.510913 -279.450134)
			(xy 299.558184 -279.463826) (xy 299.602646 -279.484924) (xy 299.643149 -279.51288) (xy 299.678642 -279.546972)
			(xy 299.708207 -279.586316) (xy 299.731078 -279.629893) (xy 299.746662 -279.676574) (xy 299.754557 -279.725151)
			(xy 299.755047 -279.749504) (xy 300.0939 -279.749504) (xy 300.09786 -279.70045) (xy 300.109637 -279.652666)
			(xy 300.128928 -279.60739) (xy 300.155231 -279.565794) (xy 300.187866 -279.528957) (xy 300.225987 -279.497832)
			(xy 300.268608 -279.473225) (xy 300.314624 -279.455773) (xy 300.362843 -279.445929) (xy 300.412018 -279.443948)
			(xy 300.460873 -279.44988) (xy 300.508144 -279.463572) (xy 300.552606 -279.48467) (xy 300.593109 -279.512626)
			(xy 300.628602 -279.546718) (xy 300.658167 -279.586062) (xy 300.681038 -279.629639) (xy 300.696622 -279.67632)
			(xy 300.704517 -279.724897) (xy 300.705012 -279.749504) (xy 300.705007 -279.749758) (xy 301.044114 -279.749758)
			(xy 301.048074 -279.700704) (xy 301.059851 -279.65292) (xy 301.079142 -279.607644) (xy 301.105445 -279.566048)
			(xy 301.13808 -279.529211) (xy 301.176201 -279.498086) (xy 301.218822 -279.473479) (xy 301.264838 -279.456027)
			(xy 301.313057 -279.446183) (xy 301.362232 -279.444202) (xy 301.411087 -279.450134) (xy 301.458358 -279.463826)
			(xy 301.50282 -279.484924) (xy 301.543323 -279.51288) (xy 301.578816 -279.546972) (xy 301.608381 -279.586316)
			(xy 301.631252 -279.629893) (xy 301.646836 -279.676574) (xy 301.654731 -279.725151) (xy 301.655221 -279.749504)
			(xy 301.994074 -279.749504) (xy 301.998034 -279.70045) (xy 302.009811 -279.652666) (xy 302.029102 -279.60739)
			(xy 302.055405 -279.565794) (xy 302.08804 -279.528957) (xy 302.126161 -279.497832) (xy 302.168782 -279.473225)
			(xy 302.214798 -279.455773) (xy 302.263017 -279.445929) (xy 302.312192 -279.443948) (xy 302.361047 -279.44988)
			(xy 302.408318 -279.463572) (xy 302.45278 -279.48467) (xy 302.493283 -279.512626) (xy 302.528776 -279.546718)
			(xy 302.558341 -279.586062) (xy 302.581212 -279.629639) (xy 302.596796 -279.67632) (xy 302.604691 -279.724897)
			(xy 302.605186 -279.749504) (xy 302.605181 -279.749758) (xy 302.944034 -279.749758) (xy 302.947994 -279.700704)
			(xy 302.959771 -279.65292) (xy 302.979062 -279.607644) (xy 303.005365 -279.566048) (xy 303.038 -279.529211)
			(xy 303.076121 -279.498086) (xy 303.118742 -279.473479) (xy 303.164758 -279.456027) (xy 303.212977 -279.446183)
			(xy 303.262152 -279.444202) (xy 303.311007 -279.450134) (xy 303.358278 -279.463826) (xy 303.40274 -279.484924)
			(xy 303.443243 -279.51288) (xy 303.478736 -279.546972) (xy 303.508301 -279.586316) (xy 303.531172 -279.629893)
			(xy 303.546756 -279.676574) (xy 303.554651 -279.725151) (xy 303.555141 -279.749504) (xy 303.893994 -279.749504)
			(xy 303.897954 -279.70045) (xy 303.909731 -279.652666) (xy 303.929022 -279.60739) (xy 303.955325 -279.565794)
			(xy 303.98796 -279.528957) (xy 304.026081 -279.497832) (xy 304.068702 -279.473225) (xy 304.114718 -279.455773)
			(xy 304.162937 -279.445929) (xy 304.212112 -279.443948) (xy 304.260967 -279.44988) (xy 304.308238 -279.463572)
			(xy 304.3527 -279.48467) (xy 304.393203 -279.512626) (xy 304.428696 -279.546718) (xy 304.458261 -279.586062)
			(xy 304.481132 -279.629639) (xy 304.496716 -279.67632) (xy 304.504611 -279.724897) (xy 304.505106 -279.749504)
			(xy 304.505101 -279.749758) (xy 304.843954 -279.749758) (xy 304.847914 -279.700704) (xy 304.859691 -279.65292)
			(xy 304.878982 -279.607644) (xy 304.905285 -279.566048) (xy 304.93792 -279.529211) (xy 304.976041 -279.498086)
			(xy 305.018662 -279.473479) (xy 305.064678 -279.456027) (xy 305.112897 -279.446183) (xy 305.162072 -279.444202)
			(xy 305.210927 -279.450134) (xy 305.258198 -279.463826) (xy 305.30266 -279.484924) (xy 305.343163 -279.51288)
			(xy 305.378656 -279.546972) (xy 305.408221 -279.586316) (xy 305.431092 -279.629893) (xy 305.446676 -279.676574)
			(xy 305.454571 -279.725151) (xy 305.455061 -279.749504) (xy 305.793914 -279.749504) (xy 305.797874 -279.70045)
			(xy 305.809651 -279.652666) (xy 305.828942 -279.60739) (xy 305.855245 -279.565794) (xy 305.88788 -279.528957)
			(xy 305.926001 -279.497832) (xy 305.968622 -279.473225) (xy 306.014638 -279.455773) (xy 306.062857 -279.445929)
			(xy 306.112032 -279.443948) (xy 306.160887 -279.44988) (xy 306.208158 -279.463572) (xy 306.25262 -279.48467)
			(xy 306.293123 -279.512626) (xy 306.328616 -279.546718) (xy 306.358181 -279.586062) (xy 306.381052 -279.629639)
			(xy 306.396636 -279.67632) (xy 306.404531 -279.724897) (xy 306.405026 -279.749504) (xy 306.405021 -279.749758)
			(xy 306.743874 -279.749758) (xy 306.747834 -279.700704) (xy 306.759611 -279.65292) (xy 306.778902 -279.607644)
			(xy 306.805205 -279.566048) (xy 306.83784 -279.529211) (xy 306.875961 -279.498086) (xy 306.918582 -279.473479)
			(xy 306.964598 -279.456027) (xy 307.012817 -279.446183) (xy 307.061992 -279.444202) (xy 307.110847 -279.450134)
			(xy 307.158118 -279.463826) (xy 307.20258 -279.484924) (xy 307.243083 -279.51288) (xy 307.278576 -279.546972)
			(xy 307.308141 -279.586316) (xy 307.331012 -279.629893) (xy 307.346596 -279.676574) (xy 307.354491 -279.725151)
			(xy 307.354981 -279.749504) (xy 307.694088 -279.749504) (xy 307.698048 -279.70045) (xy 307.709825 -279.652666)
			(xy 307.729116 -279.60739) (xy 307.755419 -279.565794) (xy 307.788054 -279.528957) (xy 307.826175 -279.497832)
			(xy 307.868796 -279.473225) (xy 307.914812 -279.455773) (xy 307.963031 -279.445929) (xy 308.012206 -279.443948)
			(xy 308.061061 -279.44988) (xy 308.108332 -279.463572) (xy 308.152794 -279.48467) (xy 308.193297 -279.512626)
			(xy 308.22879 -279.546718) (xy 308.258355 -279.586062) (xy 308.281226 -279.629639) (xy 308.29681 -279.67632)
			(xy 308.304705 -279.724897) (xy 308.3052 -279.749504) (xy 308.305195 -279.749758) (xy 308.644048 -279.749758)
			(xy 308.648008 -279.700704) (xy 308.659785 -279.65292) (xy 308.679076 -279.607644) (xy 308.705379 -279.566048)
			(xy 308.738014 -279.529211) (xy 308.776135 -279.498086) (xy 308.818756 -279.473479) (xy 308.864772 -279.456027)
			(xy 308.912991 -279.446183) (xy 308.962166 -279.444202) (xy 309.011021 -279.450134) (xy 309.058292 -279.463826)
			(xy 309.102754 -279.484924) (xy 309.143257 -279.51288) (xy 309.17875 -279.546972) (xy 309.208315 -279.586316)
			(xy 309.231186 -279.629893) (xy 309.24677 -279.676574) (xy 309.254665 -279.725151) (xy 309.25516 -279.749758)
			(xy 309.254665 -279.774365) (xy 309.24677 -279.822942) (xy 309.231186 -279.869623) (xy 309.208315 -279.9132)
			(xy 309.17875 -279.952544) (xy 309.143257 -279.986636) (xy 309.102754 -280.014592) (xy 309.058292 -280.03569)
			(xy 309.011021 -280.049382) (xy 308.962166 -280.055314) (xy 308.912991 -280.053333) (xy 308.864772 -280.043489)
			(xy 308.818756 -280.026037) (xy 308.776135 -280.00143) (xy 308.738014 -279.970305) (xy 308.705379 -279.933468)
			(xy 308.679076 -279.891872) (xy 308.659785 -279.846596) (xy 308.648008 -279.798812) (xy 308.644048 -279.749758)
			(xy 308.305195 -279.749758) (xy 308.304705 -279.774111) (xy 308.29681 -279.822688) (xy 308.281226 -279.869369)
			(xy 308.258355 -279.912946) (xy 308.22879 -279.95229) (xy 308.193297 -279.986382) (xy 308.152794 -280.014338)
			(xy 308.108332 -280.035436) (xy 308.061061 -280.049128) (xy 308.012206 -280.05506) (xy 307.963031 -280.053079)
			(xy 307.914812 -280.043235) (xy 307.868796 -280.025783) (xy 307.826175 -280.001176) (xy 307.788054 -279.970051)
			(xy 307.755419 -279.933214) (xy 307.729116 -279.891618) (xy 307.709825 -279.846342) (xy 307.698048 -279.798558)
			(xy 307.694088 -279.749504) (xy 307.354981 -279.749504) (xy 307.354986 -279.749758) (xy 307.354491 -279.774365)
			(xy 307.346596 -279.822942) (xy 307.331012 -279.869623) (xy 307.308141 -279.9132) (xy 307.278576 -279.952544)
			(xy 307.243083 -279.986636) (xy 307.20258 -280.014592) (xy 307.158118 -280.03569) (xy 307.110847 -280.049382)
			(xy 307.061992 -280.055314) (xy 307.012817 -280.053333) (xy 306.964598 -280.043489) (xy 306.918582 -280.026037)
			(xy 306.875961 -280.00143) (xy 306.83784 -279.970305) (xy 306.805205 -279.933468) (xy 306.778902 -279.891872)
			(xy 306.759611 -279.846596) (xy 306.747834 -279.798812) (xy 306.743874 -279.749758) (xy 306.405021 -279.749758)
			(xy 306.404531 -279.774111) (xy 306.396636 -279.822688) (xy 306.381052 -279.869369) (xy 306.358181 -279.912946)
			(xy 306.328616 -279.95229) (xy 306.293123 -279.986382) (xy 306.25262 -280.014338) (xy 306.208158 -280.035436)
			(xy 306.160887 -280.049128) (xy 306.112032 -280.05506) (xy 306.062857 -280.053079) (xy 306.014638 -280.043235)
			(xy 305.968622 -280.025783) (xy 305.926001 -280.001176) (xy 305.88788 -279.970051) (xy 305.855245 -279.933214)
			(xy 305.828942 -279.891618) (xy 305.809651 -279.846342) (xy 305.797874 -279.798558) (xy 305.793914 -279.749504)
			(xy 305.455061 -279.749504) (xy 305.455066 -279.749758) (xy 305.454571 -279.774365) (xy 305.446676 -279.822942)
			(xy 305.431092 -279.869623) (xy 305.408221 -279.9132) (xy 305.378656 -279.952544) (xy 305.343163 -279.986636)
			(xy 305.30266 -280.014592) (xy 305.258198 -280.03569) (xy 305.210927 -280.049382) (xy 305.162072 -280.055314)
			(xy 305.112897 -280.053333) (xy 305.064678 -280.043489) (xy 305.018662 -280.026037) (xy 304.976041 -280.00143)
			(xy 304.93792 -279.970305) (xy 304.905285 -279.933468) (xy 304.878982 -279.891872) (xy 304.859691 -279.846596)
			(xy 304.847914 -279.798812) (xy 304.843954 -279.749758) (xy 304.505101 -279.749758) (xy 304.504611 -279.774111)
			(xy 304.496716 -279.822688) (xy 304.481132 -279.869369) (xy 304.458261 -279.912946) (xy 304.428696 -279.95229)
			(xy 304.393203 -279.986382) (xy 304.3527 -280.014338) (xy 304.308238 -280.035436) (xy 304.260967 -280.049128)
			(xy 304.212112 -280.05506) (xy 304.162937 -280.053079) (xy 304.114718 -280.043235) (xy 304.068702 -280.025783)
			(xy 304.026081 -280.001176) (xy 303.98796 -279.970051) (xy 303.955325 -279.933214) (xy 303.929022 -279.891618)
			(xy 303.909731 -279.846342) (xy 303.897954 -279.798558) (xy 303.893994 -279.749504) (xy 303.555141 -279.749504)
			(xy 303.555146 -279.749758) (xy 303.554651 -279.774365) (xy 303.546756 -279.822942) (xy 303.531172 -279.869623)
			(xy 303.508301 -279.9132) (xy 303.478736 -279.952544) (xy 303.443243 -279.986636) (xy 303.40274 -280.014592)
			(xy 303.358278 -280.03569) (xy 303.311007 -280.049382) (xy 303.262152 -280.055314) (xy 303.212977 -280.053333)
			(xy 303.164758 -280.043489) (xy 303.118742 -280.026037) (xy 303.076121 -280.00143) (xy 303.038 -279.970305)
			(xy 303.005365 -279.933468) (xy 302.979062 -279.891872) (xy 302.959771 -279.846596) (xy 302.947994 -279.798812)
			(xy 302.944034 -279.749758) (xy 302.605181 -279.749758) (xy 302.604691 -279.774111) (xy 302.596796 -279.822688)
			(xy 302.581212 -279.869369) (xy 302.558341 -279.912946) (xy 302.528776 -279.95229) (xy 302.493283 -279.986382)
			(xy 302.45278 -280.014338) (xy 302.408318 -280.035436) (xy 302.361047 -280.049128) (xy 302.312192 -280.05506)
			(xy 302.263017 -280.053079) (xy 302.214798 -280.043235) (xy 302.168782 -280.025783) (xy 302.126161 -280.001176)
			(xy 302.08804 -279.970051) (xy 302.055405 -279.933214) (xy 302.029102 -279.891618) (xy 302.009811 -279.846342)
			(xy 301.998034 -279.798558) (xy 301.994074 -279.749504) (xy 301.655221 -279.749504) (xy 301.655226 -279.749758)
			(xy 301.654731 -279.774365) (xy 301.646836 -279.822942) (xy 301.631252 -279.869623) (xy 301.608381 -279.9132)
			(xy 301.578816 -279.952544) (xy 301.543323 -279.986636) (xy 301.50282 -280.014592) (xy 301.458358 -280.03569)
			(xy 301.411087 -280.049382) (xy 301.362232 -280.055314) (xy 301.313057 -280.053333) (xy 301.264838 -280.043489)
			(xy 301.218822 -280.026037) (xy 301.176201 -280.00143) (xy 301.13808 -279.970305) (xy 301.105445 -279.933468)
			(xy 301.079142 -279.891872) (xy 301.059851 -279.846596) (xy 301.048074 -279.798812) (xy 301.044114 -279.749758)
			(xy 300.705007 -279.749758) (xy 300.704517 -279.774111) (xy 300.696622 -279.822688) (xy 300.681038 -279.869369)
			(xy 300.658167 -279.912946) (xy 300.628602 -279.95229) (xy 300.593109 -279.986382) (xy 300.552606 -280.014338)
			(xy 300.508144 -280.035436) (xy 300.460873 -280.049128) (xy 300.412018 -280.05506) (xy 300.362843 -280.053079)
			(xy 300.314624 -280.043235) (xy 300.268608 -280.025783) (xy 300.225987 -280.001176) (xy 300.187866 -279.970051)
			(xy 300.155231 -279.933214) (xy 300.128928 -279.891618) (xy 300.109637 -279.846342) (xy 300.09786 -279.798558)
			(xy 300.0939 -279.749504) (xy 299.755047 -279.749504) (xy 299.755052 -279.749758) (xy 299.754557 -279.774365)
			(xy 299.746662 -279.822942) (xy 299.731078 -279.869623) (xy 299.708207 -279.9132) (xy 299.678642 -279.952544)
			(xy 299.643149 -279.986636) (xy 299.602646 -280.014592) (xy 299.558184 -280.03569) (xy 299.510913 -280.049382)
			(xy 299.462058 -280.055314) (xy 299.412883 -280.053333) (xy 299.364664 -280.043489) (xy 299.318648 -280.026037)
			(xy 299.276027 -280.00143) (xy 299.237906 -279.970305) (xy 299.205271 -279.933468) (xy 299.178968 -279.891872)
			(xy 299.159677 -279.846596) (xy 299.1479 -279.798812) (xy 299.14394 -279.749758) (xy 298.805087 -279.749758)
			(xy 298.804597 -279.774111) (xy 298.796702 -279.822688) (xy 298.781118 -279.869369) (xy 298.758247 -279.912946)
			(xy 298.728682 -279.95229) (xy 298.693189 -279.986382) (xy 298.652686 -280.014338) (xy 298.608224 -280.035436)
			(xy 298.560953 -280.049128) (xy 298.512098 -280.05506) (xy 298.462923 -280.053079) (xy 298.414704 -280.043235)
			(xy 298.368688 -280.025783) (xy 298.326067 -280.001176) (xy 298.287946 -279.970051) (xy 298.255311 -279.933214)
			(xy 298.229008 -279.891618) (xy 298.209717 -279.846342) (xy 298.19794 -279.798558) (xy 298.19398 -279.749504)
			(xy 297.855127 -279.749504) (xy 297.855132 -279.749758) (xy 297.854637 -279.774365) (xy 297.846742 -279.822942)
			(xy 297.831158 -279.869623) (xy 297.808287 -279.9132) (xy 297.778722 -279.952544) (xy 297.743229 -279.986636)
			(xy 297.702726 -280.014592) (xy 297.658264 -280.03569) (xy 297.610993 -280.049382) (xy 297.562138 -280.055314)
			(xy 297.512963 -280.053333) (xy 297.464744 -280.043489) (xy 297.418728 -280.026037) (xy 297.376107 -280.00143)
			(xy 297.337986 -279.970305) (xy 297.305351 -279.933468) (xy 297.279048 -279.891872) (xy 297.259757 -279.846596)
			(xy 297.24798 -279.798812) (xy 297.24402 -279.749758) (xy 296.905167 -279.749758) (xy 296.904677 -279.774111)
			(xy 296.896782 -279.822688) (xy 296.881198 -279.869369) (xy 296.858327 -279.912946) (xy 296.828762 -279.95229)
			(xy 296.793269 -279.986382) (xy 296.752766 -280.014338) (xy 296.708304 -280.035436) (xy 296.661033 -280.049128)
			(xy 296.612178 -280.05506) (xy 296.563003 -280.053079) (xy 296.514784 -280.043235) (xy 296.468768 -280.025783)
			(xy 296.426147 -280.001176) (xy 296.388026 -279.970051) (xy 296.355391 -279.933214) (xy 296.329088 -279.891618)
			(xy 296.309797 -279.846342) (xy 296.29802 -279.798558) (xy 296.29406 -279.749504) (xy 295.955207 -279.749504)
			(xy 295.955212 -279.749758) (xy 295.954717 -279.774365) (xy 295.946822 -279.822942) (xy 295.931238 -279.869623)
			(xy 295.908367 -279.9132) (xy 295.878802 -279.952544) (xy 295.843309 -279.986636) (xy 295.802806 -280.014592)
			(xy 295.758344 -280.03569) (xy 295.711073 -280.049382) (xy 295.662218 -280.055314) (xy 295.613043 -280.053333)
			(xy 295.564824 -280.043489) (xy 295.518808 -280.026037) (xy 295.476187 -280.00143) (xy 295.438066 -279.970305)
			(xy 295.405431 -279.933468) (xy 295.379128 -279.891872) (xy 295.359837 -279.846596) (xy 295.34806 -279.798812)
			(xy 295.3441 -279.749758) (xy 295.004993 -279.749758) (xy 295.004503 -279.774111) (xy 294.996608 -279.822688)
			(xy 294.981024 -279.869369) (xy 294.958153 -279.912946) (xy 294.928588 -279.95229) (xy 294.893095 -279.986382)
			(xy 294.852592 -280.014338) (xy 294.80813 -280.035436) (xy 294.760859 -280.049128) (xy 294.712004 -280.05506)
			(xy 294.662829 -280.053079) (xy 294.61461 -280.043235) (xy 294.568594 -280.025783) (xy 294.525973 -280.001176)
			(xy 294.487852 -279.970051) (xy 294.455217 -279.933214) (xy 294.428914 -279.891618) (xy 294.409623 -279.846342)
			(xy 294.397846 -279.798558) (xy 294.393886 -279.749504) (xy 294.055033 -279.749504) (xy 294.055038 -279.749758)
			(xy 294.054543 -279.774365) (xy 294.046648 -279.822942) (xy 294.031064 -279.869623) (xy 294.008193 -279.9132)
			(xy 293.978628 -279.952544) (xy 293.943135 -279.986636) (xy 293.902632 -280.014592) (xy 293.85817 -280.03569)
			(xy 293.810899 -280.049382) (xy 293.762044 -280.055314) (xy 293.712869 -280.053333) (xy 293.66465 -280.043489)
			(xy 293.618634 -280.026037) (xy 293.576013 -280.00143) (xy 293.537892 -279.970305) (xy 293.505257 -279.933468)
			(xy 293.478954 -279.891872) (xy 293.459663 -279.846596) (xy 293.447886 -279.798812) (xy 293.443926 -279.749758)
			(xy 293.105073 -279.749758) (xy 293.104583 -279.774111) (xy 293.096688 -279.822688) (xy 293.081104 -279.869369)
			(xy 293.058233 -279.912946) (xy 293.028668 -279.95229) (xy 292.993175 -279.986382) (xy 292.952672 -280.014338)
			(xy 292.90821 -280.035436) (xy 292.860939 -280.049128) (xy 292.812084 -280.05506) (xy 292.762909 -280.053079)
			(xy 292.71469 -280.043235) (xy 292.668674 -280.025783) (xy 292.626053 -280.001176) (xy 292.587932 -279.970051)
			(xy 292.555297 -279.933214) (xy 292.528994 -279.891618) (xy 292.509703 -279.846342) (xy 292.497926 -279.798558)
			(xy 292.493966 -279.749504) (xy 292.155113 -279.749504) (xy 292.155118 -279.749758) (xy 292.154623 -279.774365)
			(xy 292.146728 -279.822942) (xy 292.131144 -279.869623) (xy 292.108273 -279.9132) (xy 292.078708 -279.952544)
			(xy 292.043215 -279.986636) (xy 292.002712 -280.014592) (xy 291.95825 -280.03569) (xy 291.910979 -280.049382)
			(xy 291.862124 -280.055314) (xy 291.812949 -280.053333) (xy 291.76473 -280.043489) (xy 291.718714 -280.026037)
			(xy 291.676093 -280.00143) (xy 291.637972 -279.970305) (xy 291.605337 -279.933468) (xy 291.579034 -279.891872)
			(xy 291.559743 -279.846596) (xy 291.547966 -279.798812) (xy 291.544006 -279.749758) (xy 291.205153 -279.749758)
			(xy 291.204663 -279.774111) (xy 291.196768 -279.822688) (xy 291.181184 -279.869369) (xy 291.158313 -279.912946)
			(xy 291.128748 -279.95229) (xy 291.093255 -279.986382) (xy 291.052752 -280.014338) (xy 291.00829 -280.035436)
			(xy 290.961019 -280.049128) (xy 290.912164 -280.05506) (xy 290.862989 -280.053079) (xy 290.81477 -280.043235)
			(xy 290.768754 -280.025783) (xy 290.726133 -280.001176) (xy 290.688012 -279.970051) (xy 290.655377 -279.933214)
			(xy 290.629074 -279.891618) (xy 290.609783 -279.846342) (xy 290.598006 -279.798558) (xy 290.594046 -279.749504)
			(xy 290.255193 -279.749504) (xy 290.255198 -279.749758) (xy 290.254703 -279.774365) (xy 290.246808 -279.822942)
			(xy 290.231224 -279.869623) (xy 290.208353 -279.9132) (xy 290.178788 -279.952544) (xy 290.143295 -279.986636)
			(xy 290.102792 -280.014592) (xy 290.05833 -280.03569) (xy 290.011059 -280.049382) (xy 289.962204 -280.055314)
			(xy 289.913029 -280.053333) (xy 289.86481 -280.043489) (xy 289.818794 -280.026037) (xy 289.776173 -280.00143)
			(xy 289.738052 -279.970305) (xy 289.705417 -279.933468) (xy 289.679114 -279.891872) (xy 289.659823 -279.846596)
			(xy 289.648046 -279.798812) (xy 289.644086 -279.749758) (xy 289.304979 -279.749758) (xy 289.304489 -279.774111)
			(xy 289.296594 -279.822688) (xy 289.28101 -279.869369) (xy 289.258139 -279.912946) (xy 289.228574 -279.95229)
			(xy 289.193081 -279.986382) (xy 289.152578 -280.014338) (xy 289.108116 -280.035436) (xy 289.060845 -280.049128)
			(xy 289.01199 -280.05506) (xy 288.962815 -280.053079) (xy 288.914596 -280.043235) (xy 288.86858 -280.025783)
			(xy 288.825959 -280.001176) (xy 288.787838 -279.970051) (xy 288.755203 -279.933214) (xy 288.7289 -279.891618)
			(xy 288.709609 -279.846342) (xy 288.697832 -279.798558) (xy 288.693872 -279.749504) (xy 288.355019 -279.749504)
			(xy 288.355024 -279.749758) (xy 288.354529 -279.774365) (xy 288.346634 -279.822942) (xy 288.33105 -279.869623)
			(xy 288.308179 -279.9132) (xy 288.278614 -279.952544) (xy 288.243121 -279.986636) (xy 288.202618 -280.014592)
			(xy 288.158156 -280.03569) (xy 288.110885 -280.049382) (xy 288.06203 -280.055314) (xy 288.012855 -280.053333)
			(xy 287.964636 -280.043489) (xy 287.91862 -280.026037) (xy 287.875999 -280.00143) (xy 287.837878 -279.970305)
			(xy 287.805243 -279.933468) (xy 287.77894 -279.891872) (xy 287.759649 -279.846596) (xy 287.747872 -279.798812)
			(xy 287.743912 -279.749758) (xy 287.405059 -279.749758) (xy 287.404569 -279.774111) (xy 287.396674 -279.822688)
			(xy 287.38109 -279.869369) (xy 287.358219 -279.912946) (xy 287.328654 -279.95229) (xy 287.293161 -279.986382)
			(xy 287.252658 -280.014338) (xy 287.208196 -280.035436) (xy 287.160925 -280.049128) (xy 287.11207 -280.05506)
			(xy 287.062895 -280.053079) (xy 287.014676 -280.043235) (xy 286.96866 -280.025783) (xy 286.926039 -280.001176)
			(xy 286.887918 -279.970051) (xy 286.855283 -279.933214) (xy 286.82898 -279.891618) (xy 286.809689 -279.846342)
			(xy 286.797912 -279.798558) (xy 286.793952 -279.749504) (xy 286.455099 -279.749504) (xy 286.455104 -279.749758)
			(xy 286.454609 -279.774365) (xy 286.446714 -279.822942) (xy 286.43113 -279.869623) (xy 286.408259 -279.9132)
			(xy 286.378694 -279.952544) (xy 286.343201 -279.986636) (xy 286.302698 -280.014592) (xy 286.258236 -280.03569)
			(xy 286.210965 -280.049382) (xy 286.16211 -280.055314) (xy 286.112935 -280.053333) (xy 286.064716 -280.043489)
			(xy 286.0187 -280.026037) (xy 285.976079 -280.00143) (xy 285.937958 -279.970305) (xy 285.905323 -279.933468)
			(xy 285.87902 -279.891872) (xy 285.859729 -279.846596) (xy 285.847952 -279.798812) (xy 285.843992 -279.749758)
			(xy 285.505139 -279.749758) (xy 285.504649 -279.774111) (xy 285.496754 -279.822688) (xy 285.48117 -279.869369)
			(xy 285.458299 -279.912946) (xy 285.428734 -279.95229) (xy 285.393241 -279.986382) (xy 285.352738 -280.014338)
			(xy 285.308276 -280.035436) (xy 285.261005 -280.049128) (xy 285.21215 -280.05506) (xy 285.162975 -280.053079)
			(xy 285.114756 -280.043235) (xy 285.06874 -280.025783) (xy 285.026119 -280.001176) (xy 284.987998 -279.970051)
			(xy 284.955363 -279.933214) (xy 284.92906 -279.891618) (xy 284.909769 -279.846342) (xy 284.897992 -279.798558)
			(xy 284.894032 -279.749504) (xy 284.555179 -279.749504) (xy 284.555184 -279.749758) (xy 284.554689 -279.774365)
			(xy 284.546794 -279.822942) (xy 284.53121 -279.869623) (xy 284.508339 -279.9132) (xy 284.478774 -279.952544)
			(xy 284.443281 -279.986636) (xy 284.402778 -280.014592) (xy 284.358316 -280.03569) (xy 284.311045 -280.049382)
			(xy 284.26219 -280.055314) (xy 284.213015 -280.053333) (xy 284.164796 -280.043489) (xy 284.11878 -280.026037)
			(xy 284.076159 -280.00143) (xy 284.038038 -279.970305) (xy 284.005403 -279.933468) (xy 283.9791 -279.891872)
			(xy 283.959809 -279.846596) (xy 283.948032 -279.798812) (xy 283.944072 -279.749758) (xy 283.605219 -279.749758)
			(xy 283.604729 -279.774111) (xy 283.596834 -279.822688) (xy 283.58125 -279.869369) (xy 283.558379 -279.912946)
			(xy 283.528814 -279.95229) (xy 283.493321 -279.986382) (xy 283.452818 -280.014338) (xy 283.408356 -280.035436)
			(xy 283.361085 -280.049128) (xy 283.31223 -280.05506) (xy 283.263055 -280.053079) (xy 283.214836 -280.043235)
			(xy 283.16882 -280.025783) (xy 283.126199 -280.001176) (xy 283.088078 -279.970051) (xy 283.055443 -279.933214)
			(xy 283.02914 -279.891618) (xy 283.009849 -279.846342) (xy 282.998072 -279.798558) (xy 282.994112 -279.749504)
			(xy 282.655005 -279.749504) (xy 282.65501 -279.749758) (xy 282.654515 -279.774365) (xy 282.64662 -279.822942)
			(xy 282.631036 -279.869623) (xy 282.608165 -279.9132) (xy 282.5786 -279.952544) (xy 282.543107 -279.986636)
			(xy 282.502604 -280.014592) (xy 282.458142 -280.03569) (xy 282.410871 -280.049382) (xy 282.362016 -280.055314)
			(xy 282.312841 -280.053333) (xy 282.264622 -280.043489) (xy 282.218606 -280.026037) (xy 282.175985 -280.00143)
			(xy 282.137864 -279.970305) (xy 282.105229 -279.933468) (xy 282.078926 -279.891872) (xy 282.059635 -279.846596)
			(xy 282.047858 -279.798812) (xy 282.043898 -279.749758) (xy 281.705045 -279.749758) (xy 281.704555 -279.774111)
			(xy 281.69666 -279.822688) (xy 281.681076 -279.869369) (xy 281.658205 -279.912946) (xy 281.62864 -279.95229)
			(xy 281.593147 -279.986382) (xy 281.552644 -280.014338) (xy 281.508182 -280.035436) (xy 281.460911 -280.049128)
			(xy 281.412056 -280.05506) (xy 281.362881 -280.053079) (xy 281.314662 -280.043235) (xy 281.268646 -280.025783)
			(xy 281.226025 -280.001176) (xy 281.187904 -279.970051) (xy 281.155269 -279.933214) (xy 281.128966 -279.891618)
			(xy 281.109675 -279.846342) (xy 281.097898 -279.798558) (xy 281.093938 -279.749504) (xy 280.755085 -279.749504)
			(xy 280.75509 -279.749758) (xy 280.754595 -279.774365) (xy 280.7467 -279.822942) (xy 280.731116 -279.869623)
			(xy 280.708245 -279.9132) (xy 280.67868 -279.952544) (xy 280.643187 -279.986636) (xy 280.602684 -280.014592)
			(xy 280.558222 -280.03569) (xy 280.510951 -280.049382) (xy 280.462096 -280.055314) (xy 280.412921 -280.053333)
			(xy 280.364702 -280.043489) (xy 280.318686 -280.026037) (xy 280.276065 -280.00143) (xy 280.237944 -279.970305)
			(xy 280.205309 -279.933468) (xy 280.179006 -279.891872) (xy 280.159715 -279.846596) (xy 280.147938 -279.798812)
			(xy 280.143978 -279.749758) (xy 279.805125 -279.749758) (xy 279.804635 -279.774111) (xy 279.79674 -279.822688)
			(xy 279.781156 -279.869369) (xy 279.758285 -279.912946) (xy 279.72872 -279.95229) (xy 279.693227 -279.986382)
			(xy 279.652724 -280.014338) (xy 279.608262 -280.035436) (xy 279.560991 -280.049128) (xy 279.512136 -280.05506)
			(xy 279.462961 -280.053079) (xy 279.414742 -280.043235) (xy 279.368726 -280.025783) (xy 279.326105 -280.001176)
			(xy 279.287984 -279.970051) (xy 279.255349 -279.933214) (xy 279.229046 -279.891618) (xy 279.209755 -279.846342)
			(xy 279.197978 -279.798558) (xy 279.194018 -279.749504) (xy 278.855165 -279.749504) (xy 278.85517 -279.749758)
			(xy 278.854675 -279.774365) (xy 278.84678 -279.822942) (xy 278.831196 -279.869623) (xy 278.808325 -279.9132)
			(xy 278.77876 -279.952544) (xy 278.743267 -279.986636) (xy 278.702764 -280.014592) (xy 278.658302 -280.03569)
			(xy 278.611031 -280.049382) (xy 278.562176 -280.055314) (xy 278.513001 -280.053333) (xy 278.464782 -280.043489)
			(xy 278.418766 -280.026037) (xy 278.376145 -280.00143) (xy 278.338024 -279.970305) (xy 278.305389 -279.933468)
			(xy 278.279086 -279.891872) (xy 278.259795 -279.846596) (xy 278.248018 -279.798812) (xy 278.244058 -279.749758)
			(xy 277.905205 -279.749758) (xy 277.904715 -279.774111) (xy 277.89682 -279.822688) (xy 277.881236 -279.869369)
			(xy 277.858365 -279.912946) (xy 277.8288 -279.95229) (xy 277.793307 -279.986382) (xy 277.752804 -280.014338)
			(xy 277.708342 -280.035436) (xy 277.661071 -280.049128) (xy 277.612216 -280.05506) (xy 277.563041 -280.053079)
			(xy 277.514822 -280.043235) (xy 277.468806 -280.025783) (xy 277.426185 -280.001176) (xy 277.388064 -279.970051)
			(xy 277.355429 -279.933214) (xy 277.329126 -279.891618) (xy 277.309835 -279.846342) (xy 277.298058 -279.798558)
			(xy 277.294098 -279.749504) (xy 276.954991 -279.749504) (xy 276.954996 -279.749758) (xy 276.954501 -279.774365)
			(xy 276.946606 -279.822942) (xy 276.931022 -279.869623) (xy 276.908151 -279.9132) (xy 276.878586 -279.952544)
			(xy 276.843093 -279.986636) (xy 276.80259 -280.014592) (xy 276.758128 -280.03569) (xy 276.710857 -280.049382)
			(xy 276.662002 -280.055314) (xy 276.612827 -280.053333) (xy 276.564608 -280.043489) (xy 276.518592 -280.026037)
			(xy 276.475971 -280.00143) (xy 276.43785 -279.970305) (xy 276.405215 -279.933468) (xy 276.378912 -279.891872)
			(xy 276.359621 -279.846596) (xy 276.347844 -279.798812) (xy 276.343884 -279.749758) (xy 266.590526 -279.749758)
			(xy 266.590526 -280.224738) (xy 268.26897 -280.224738) (xy 268.27293 -280.175684) (xy 268.284707 -280.1279)
			(xy 268.303998 -280.082624) (xy 268.330301 -280.041028) (xy 268.362936 -280.004191) (xy 268.401057 -279.973066)
			(xy 268.443678 -279.948459) (xy 268.489694 -279.931007) (xy 268.537913 -279.921163) (xy 268.587088 -279.919182)
			(xy 268.635943 -279.925114) (xy 268.683214 -279.938806) (xy 268.727676 -279.959904) (xy 268.768179 -279.98786)
			(xy 268.803672 -280.021952) (xy 268.833237 -280.061296) (xy 268.856108 -280.104873) (xy 268.871692 -280.151554)
			(xy 268.879587 -280.200131) (xy 268.880082 -280.224738) (xy 269.21893 -280.224738) (xy 269.22289 -280.175684)
			(xy 269.234667 -280.1279) (xy 269.253958 -280.082624) (xy 269.280261 -280.041028) (xy 269.312896 -280.004191)
			(xy 269.351017 -279.973066) (xy 269.393638 -279.948459) (xy 269.439654 -279.931007) (xy 269.487873 -279.921163)
			(xy 269.537048 -279.919182) (xy 269.585903 -279.925114) (xy 269.633174 -279.938806) (xy 269.677636 -279.959904)
			(xy 269.718139 -279.98786) (xy 269.753632 -280.021952) (xy 269.783197 -280.061296) (xy 269.806068 -280.104873)
			(xy 269.821652 -280.151554) (xy 269.829547 -280.200131) (xy 269.830042 -280.224738) (xy 270.169144 -280.224738)
			(xy 270.173104 -280.175684) (xy 270.184881 -280.1279) (xy 270.204172 -280.082624) (xy 270.230475 -280.041028)
			(xy 270.26311 -280.004191) (xy 270.301231 -279.973066) (xy 270.343852 -279.948459) (xy 270.389868 -279.931007)
			(xy 270.438087 -279.921163) (xy 270.487262 -279.919182) (xy 270.536117 -279.925114) (xy 270.583388 -279.938806)
			(xy 270.62785 -279.959904) (xy 270.668353 -279.98786) (xy 270.703846 -280.021952) (xy 270.733411 -280.061296)
			(xy 270.756282 -280.104873) (xy 270.771866 -280.151554) (xy 270.779761 -280.200131) (xy 270.780256 -280.224738)
			(xy 271.119104 -280.224738) (xy 271.123064 -280.175684) (xy 271.134841 -280.1279) (xy 271.154132 -280.082624)
			(xy 271.180435 -280.041028) (xy 271.21307 -280.004191) (xy 271.251191 -279.973066) (xy 271.293812 -279.948459)
			(xy 271.339828 -279.931007) (xy 271.388047 -279.921163) (xy 271.437222 -279.919182) (xy 271.486077 -279.925114)
			(xy 271.533348 -279.938806) (xy 271.57781 -279.959904) (xy 271.618313 -279.98786) (xy 271.653806 -280.021952)
			(xy 271.683371 -280.061296) (xy 271.706242 -280.104873) (xy 271.721826 -280.151554) (xy 271.729721 -280.200131)
			(xy 271.730216 -280.224738) (xy 272.069064 -280.224738) (xy 272.073024 -280.175684) (xy 272.084801 -280.1279)
			(xy 272.104092 -280.082624) (xy 272.130395 -280.041028) (xy 272.16303 -280.004191) (xy 272.201151 -279.973066)
			(xy 272.243772 -279.948459) (xy 272.289788 -279.931007) (xy 272.338007 -279.921163) (xy 272.387182 -279.919182)
			(xy 272.436037 -279.925114) (xy 272.483308 -279.938806) (xy 272.52777 -279.959904) (xy 272.568273 -279.98786)
			(xy 272.603766 -280.021952) (xy 272.633331 -280.061296) (xy 272.656202 -280.104873) (xy 272.671786 -280.151554)
			(xy 272.679681 -280.200131) (xy 272.680176 -280.224738) (xy 273.019024 -280.224738) (xy 273.022984 -280.175684)
			(xy 273.034761 -280.1279) (xy 273.054052 -280.082624) (xy 273.080355 -280.041028) (xy 273.11299 -280.004191)
			(xy 273.151111 -279.973066) (xy 273.193732 -279.948459) (xy 273.239748 -279.931007) (xy 273.287967 -279.921163)
			(xy 273.337142 -279.919182) (xy 273.385997 -279.925114) (xy 273.433268 -279.938806) (xy 273.47773 -279.959904)
			(xy 273.518233 -279.98786) (xy 273.553726 -280.021952) (xy 273.583291 -280.061296) (xy 273.606162 -280.104873)
			(xy 273.621746 -280.151554) (xy 273.629641 -280.200131) (xy 273.630136 -280.224738) (xy 273.968984 -280.224738)
			(xy 273.972944 -280.175684) (xy 273.984721 -280.1279) (xy 274.004012 -280.082624) (xy 274.030315 -280.041028)
			(xy 274.06295 -280.004191) (xy 274.101071 -279.973066) (xy 274.143692 -279.948459) (xy 274.189708 -279.931007)
			(xy 274.237927 -279.921163) (xy 274.287102 -279.919182) (xy 274.335957 -279.925114) (xy 274.383228 -279.938806)
			(xy 274.42769 -279.959904) (xy 274.468193 -279.98786) (xy 274.503686 -280.021952) (xy 274.533251 -280.061296)
			(xy 274.556122 -280.104873) (xy 274.571706 -280.151554) (xy 274.579601 -280.200131) (xy 274.580096 -280.224738)
			(xy 274.918944 -280.224738) (xy 274.922904 -280.175684) (xy 274.934681 -280.1279) (xy 274.953972 -280.082624)
			(xy 274.980275 -280.041028) (xy 275.01291 -280.004191) (xy 275.051031 -279.973066) (xy 275.093652 -279.948459)
			(xy 275.139668 -279.931007) (xy 275.187887 -279.921163) (xy 275.237062 -279.919182) (xy 275.285917 -279.925114)
			(xy 275.333188 -279.938806) (xy 275.37765 -279.959904) (xy 275.418153 -279.98786) (xy 275.453646 -280.021952)
			(xy 275.483211 -280.061296) (xy 275.506082 -280.104873) (xy 275.521666 -280.151554) (xy 275.529561 -280.200131)
			(xy 275.530056 -280.224738) (xy 275.529561 -280.249345) (xy 275.521666 -280.297922) (xy 275.506082 -280.344603)
			(xy 275.483211 -280.38818) (xy 275.453646 -280.427524) (xy 275.418153 -280.461616) (xy 275.37765 -280.489572)
			(xy 275.333188 -280.51067) (xy 275.285917 -280.524362) (xy 275.237062 -280.530294) (xy 275.187887 -280.528313)
			(xy 275.139668 -280.518469) (xy 275.093652 -280.501017) (xy 275.051031 -280.47641) (xy 275.01291 -280.445285)
			(xy 274.980275 -280.408448) (xy 274.953972 -280.366852) (xy 274.934681 -280.321576) (xy 274.922904 -280.273792)
			(xy 274.918944 -280.224738) (xy 274.580096 -280.224738) (xy 274.579601 -280.249345) (xy 274.571706 -280.297922)
			(xy 274.556122 -280.344603) (xy 274.533251 -280.38818) (xy 274.503686 -280.427524) (xy 274.468193 -280.461616)
			(xy 274.42769 -280.489572) (xy 274.383228 -280.51067) (xy 274.335957 -280.524362) (xy 274.287102 -280.530294)
			(xy 274.237927 -280.528313) (xy 274.189708 -280.518469) (xy 274.143692 -280.501017) (xy 274.101071 -280.47641)
			(xy 274.06295 -280.445285) (xy 274.030315 -280.408448) (xy 274.004012 -280.366852) (xy 273.984721 -280.321576)
			(xy 273.972944 -280.273792) (xy 273.968984 -280.224738) (xy 273.630136 -280.224738) (xy 273.629641 -280.249345)
			(xy 273.621746 -280.297922) (xy 273.606162 -280.344603) (xy 273.583291 -280.38818) (xy 273.553726 -280.427524)
			(xy 273.518233 -280.461616) (xy 273.47773 -280.489572) (xy 273.433268 -280.51067) (xy 273.385997 -280.524362)
			(xy 273.337142 -280.530294) (xy 273.287967 -280.528313) (xy 273.239748 -280.518469) (xy 273.193732 -280.501017)
			(xy 273.151111 -280.47641) (xy 273.11299 -280.445285) (xy 273.080355 -280.408448) (xy 273.054052 -280.366852)
			(xy 273.034761 -280.321576) (xy 273.022984 -280.273792) (xy 273.019024 -280.224738) (xy 272.680176 -280.224738)
			(xy 272.679681 -280.249345) (xy 272.671786 -280.297922) (xy 272.656202 -280.344603) (xy 272.633331 -280.38818)
			(xy 272.603766 -280.427524) (xy 272.568273 -280.461616) (xy 272.52777 -280.489572) (xy 272.483308 -280.51067)
			(xy 272.436037 -280.524362) (xy 272.387182 -280.530294) (xy 272.338007 -280.528313) (xy 272.289788 -280.518469)
			(xy 272.243772 -280.501017) (xy 272.201151 -280.47641) (xy 272.16303 -280.445285) (xy 272.130395 -280.408448)
			(xy 272.104092 -280.366852) (xy 272.084801 -280.321576) (xy 272.073024 -280.273792) (xy 272.069064 -280.224738)
			(xy 271.730216 -280.224738) (xy 271.729721 -280.249345) (xy 271.721826 -280.297922) (xy 271.706242 -280.344603)
			(xy 271.683371 -280.38818) (xy 271.653806 -280.427524) (xy 271.618313 -280.461616) (xy 271.57781 -280.489572)
			(xy 271.533348 -280.51067) (xy 271.486077 -280.524362) (xy 271.437222 -280.530294) (xy 271.388047 -280.528313)
			(xy 271.339828 -280.518469) (xy 271.293812 -280.501017) (xy 271.251191 -280.47641) (xy 271.21307 -280.445285)
			(xy 271.180435 -280.408448) (xy 271.154132 -280.366852) (xy 271.134841 -280.321576) (xy 271.123064 -280.273792)
			(xy 271.119104 -280.224738) (xy 270.780256 -280.224738) (xy 270.779761 -280.249345) (xy 270.771866 -280.297922)
			(xy 270.756282 -280.344603) (xy 270.733411 -280.38818) (xy 270.703846 -280.427524) (xy 270.668353 -280.461616)
			(xy 270.62785 -280.489572) (xy 270.583388 -280.51067) (xy 270.536117 -280.524362) (xy 270.487262 -280.530294)
			(xy 270.438087 -280.528313) (xy 270.389868 -280.518469) (xy 270.343852 -280.501017) (xy 270.301231 -280.47641)
			(xy 270.26311 -280.445285) (xy 270.230475 -280.408448) (xy 270.204172 -280.366852) (xy 270.184881 -280.321576)
			(xy 270.173104 -280.273792) (xy 270.169144 -280.224738) (xy 269.830042 -280.224738) (xy 269.829547 -280.249345)
			(xy 269.821652 -280.297922) (xy 269.806068 -280.344603) (xy 269.783197 -280.38818) (xy 269.753632 -280.427524)
			(xy 269.718139 -280.461616) (xy 269.677636 -280.489572) (xy 269.633174 -280.51067) (xy 269.585903 -280.524362)
			(xy 269.537048 -280.530294) (xy 269.487873 -280.528313) (xy 269.439654 -280.518469) (xy 269.393638 -280.501017)
			(xy 269.351017 -280.47641) (xy 269.312896 -280.445285) (xy 269.280261 -280.408448) (xy 269.253958 -280.366852)
			(xy 269.234667 -280.321576) (xy 269.22289 -280.273792) (xy 269.21893 -280.224738) (xy 268.880082 -280.224738)
			(xy 268.879587 -280.249345) (xy 268.871692 -280.297922) (xy 268.856108 -280.344603) (xy 268.833237 -280.38818)
			(xy 268.803672 -280.427524) (xy 268.768179 -280.461616) (xy 268.727676 -280.489572) (xy 268.683214 -280.51067)
			(xy 268.635943 -280.524362) (xy 268.587088 -280.530294) (xy 268.537913 -280.528313) (xy 268.489694 -280.518469)
			(xy 268.443678 -280.501017) (xy 268.401057 -280.47641) (xy 268.362936 -280.445285) (xy 268.330301 -280.408448)
			(xy 268.303998 -280.366852) (xy 268.284707 -280.321576) (xy 268.27293 -280.273792) (xy 268.26897 -280.224738)
			(xy 266.590526 -280.224738) (xy 266.590526 -281.174952) (xy 268.26897 -281.174952) (xy 268.27293 -281.125898)
			(xy 268.284707 -281.078114) (xy 268.303998 -281.032838) (xy 268.330301 -280.991242) (xy 268.362936 -280.954405)
			(xy 268.401057 -280.92328) (xy 268.443678 -280.898673) (xy 268.489694 -280.881221) (xy 268.537913 -280.871377)
			(xy 268.587088 -280.869396) (xy 268.635943 -280.875328) (xy 268.683214 -280.88902) (xy 268.727676 -280.910118)
			(xy 268.768179 -280.938074) (xy 268.803672 -280.972166) (xy 268.833237 -281.01151) (xy 268.856108 -281.055087)
			(xy 268.871692 -281.101768) (xy 268.879587 -281.150345) (xy 268.880082 -281.174952) (xy 269.21893 -281.174952)
			(xy 269.22289 -281.125898) (xy 269.234667 -281.078114) (xy 269.253958 -281.032838) (xy 269.280261 -280.991242)
			(xy 269.312896 -280.954405) (xy 269.351017 -280.92328) (xy 269.393638 -280.898673) (xy 269.439654 -280.881221)
			(xy 269.487873 -280.871377) (xy 269.537048 -280.869396) (xy 269.585903 -280.875328) (xy 269.633174 -280.88902)
			(xy 269.677636 -280.910118) (xy 269.718139 -280.938074) (xy 269.753632 -280.972166) (xy 269.783197 -281.01151)
			(xy 269.806068 -281.055087) (xy 269.821652 -281.101768) (xy 269.829547 -281.150345) (xy 269.830042 -281.174952)
			(xy 270.169144 -281.174952) (xy 270.173104 -281.125898) (xy 270.184881 -281.078114) (xy 270.204172 -281.032838)
			(xy 270.230475 -280.991242) (xy 270.26311 -280.954405) (xy 270.301231 -280.92328) (xy 270.343852 -280.898673)
			(xy 270.389868 -280.881221) (xy 270.438087 -280.871377) (xy 270.487262 -280.869396) (xy 270.536117 -280.875328)
			(xy 270.583388 -280.88902) (xy 270.62785 -280.910118) (xy 270.668353 -280.938074) (xy 270.703846 -280.972166)
			(xy 270.733411 -281.01151) (xy 270.756282 -281.055087) (xy 270.771866 -281.101768) (xy 270.779761 -281.150345)
			(xy 270.780256 -281.174952) (xy 271.119104 -281.174952) (xy 271.123064 -281.125898) (xy 271.134841 -281.078114)
			(xy 271.154132 -281.032838) (xy 271.180435 -280.991242) (xy 271.21307 -280.954405) (xy 271.251191 -280.92328)
			(xy 271.293812 -280.898673) (xy 271.339828 -280.881221) (xy 271.388047 -280.871377) (xy 271.437222 -280.869396)
			(xy 271.486077 -280.875328) (xy 271.533348 -280.88902) (xy 271.57781 -280.910118) (xy 271.618313 -280.938074)
			(xy 271.653806 -280.972166) (xy 271.683371 -281.01151) (xy 271.706242 -281.055087) (xy 271.721826 -281.101768)
			(xy 271.729721 -281.150345) (xy 271.730216 -281.174952) (xy 272.069064 -281.174952) (xy 272.073024 -281.125898)
			(xy 272.084801 -281.078114) (xy 272.104092 -281.032838) (xy 272.130395 -280.991242) (xy 272.16303 -280.954405)
			(xy 272.201151 -280.92328) (xy 272.243772 -280.898673) (xy 272.289788 -280.881221) (xy 272.338007 -280.871377)
			(xy 272.387182 -280.869396) (xy 272.436037 -280.875328) (xy 272.483308 -280.88902) (xy 272.52777 -280.910118)
			(xy 272.568273 -280.938074) (xy 272.603766 -280.972166) (xy 272.633331 -281.01151) (xy 272.656202 -281.055087)
			(xy 272.671786 -281.101768) (xy 272.679681 -281.150345) (xy 272.680176 -281.174952) (xy 273.019024 -281.174952)
			(xy 273.022984 -281.125898) (xy 273.034761 -281.078114) (xy 273.054052 -281.032838) (xy 273.080355 -280.991242)
			(xy 273.11299 -280.954405) (xy 273.151111 -280.92328) (xy 273.193732 -280.898673) (xy 273.239748 -280.881221)
			(xy 273.287967 -280.871377) (xy 273.337142 -280.869396) (xy 273.385997 -280.875328) (xy 273.433268 -280.88902)
			(xy 273.47773 -280.910118) (xy 273.518233 -280.938074) (xy 273.553726 -280.972166) (xy 273.583291 -281.01151)
			(xy 273.606162 -281.055087) (xy 273.621746 -281.101768) (xy 273.629641 -281.150345) (xy 273.630136 -281.174952)
			(xy 273.968984 -281.174952) (xy 273.972944 -281.125898) (xy 273.984721 -281.078114) (xy 274.004012 -281.032838)
			(xy 274.030315 -280.991242) (xy 274.06295 -280.954405) (xy 274.101071 -280.92328) (xy 274.143692 -280.898673)
			(xy 274.189708 -280.881221) (xy 274.237927 -280.871377) (xy 274.287102 -280.869396) (xy 274.335957 -280.875328)
			(xy 274.383228 -280.88902) (xy 274.42769 -280.910118) (xy 274.468193 -280.938074) (xy 274.503686 -280.972166)
			(xy 274.533251 -281.01151) (xy 274.556122 -281.055087) (xy 274.571706 -281.101768) (xy 274.579601 -281.150345)
			(xy 274.580096 -281.174952) (xy 274.918944 -281.174952) (xy 274.922904 -281.125898) (xy 274.934681 -281.078114)
			(xy 274.953972 -281.032838) (xy 274.980275 -280.991242) (xy 275.01291 -280.954405) (xy 275.051031 -280.92328)
			(xy 275.093652 -280.898673) (xy 275.139668 -280.881221) (xy 275.187887 -280.871377) (xy 275.237062 -280.869396)
			(xy 275.285917 -280.875328) (xy 275.333188 -280.88902) (xy 275.37765 -280.910118) (xy 275.418153 -280.938074)
			(xy 275.453646 -280.972166) (xy 275.483211 -281.01151) (xy 275.506082 -281.055087) (xy 275.521666 -281.101768)
			(xy 275.529561 -281.150345) (xy 275.530056 -281.174952) (xy 275.530055 -281.175) (xy 275.868792 -281.175)
			(xy 275.872964 -281.124648) (xy 275.885367 -281.07567) (xy 275.905663 -281.029402) (xy 275.933298 -280.987105)
			(xy 275.967517 -280.949933) (xy 276.007388 -280.918901) (xy 276.051824 -280.894855) (xy 276.099611 -280.878451)
			(xy 276.149446 -280.870136) (xy 276.174708 -280.869644) (xy 276.188891 -280.869819) (xy 276.217131 -280.872492)
			(xy 276.231096 -280.874978) (xy 276.23135 -280.874978) (xy 276.24358 -280.876459) (xy 276.267069 -280.869157)
			(xy 276.276308 -280.861008) (xy 276.344634 -280.792428) (xy 276.352 -280.768806) (xy 276.349714 -280.75636)
			(xy 276.347226 -280.742332) (xy 276.344556 -280.713964) (xy 276.34438 -280.699718) (xy 276.344859 -280.674895)
			(xy 276.352888 -280.625903) (xy 276.368737 -280.578855) (xy 276.391989 -280.534992) (xy 276.422032 -280.495468)
			(xy 276.458073 -280.461325) (xy 276.499163 -280.433463) (xy 276.544219 -280.412616) (xy 276.592055 -280.399332)
			(xy 276.64141 -280.393963) (xy 276.690983 -280.39665) (xy 276.739468 -280.407321) (xy 276.785588 -280.425696)
			(xy 276.828127 -280.45129) (xy 276.865966 -280.48343) (xy 276.898106 -280.521268) (xy 276.923701 -280.563807)
			(xy 276.942077 -280.609927) (xy 276.952749 -280.658412) (xy 276.954989 -280.699718) (xy 277.294098 -280.699718)
			(xy 277.298058 -280.650664) (xy 277.309835 -280.60288) (xy 277.329126 -280.557604) (xy 277.355429 -280.516008)
			(xy 277.388064 -280.479171) (xy 277.426185 -280.448046) (xy 277.468806 -280.423439) (xy 277.514822 -280.405987)
			(xy 277.563041 -280.396143) (xy 277.612216 -280.394162) (xy 277.661071 -280.400094) (xy 277.708342 -280.413786)
			(xy 277.752804 -280.434884) (xy 277.793307 -280.46284) (xy 277.8288 -280.496932) (xy 277.858365 -280.536276)
			(xy 277.881236 -280.579853) (xy 277.89682 -280.626534) (xy 277.904715 -280.675111) (xy 277.90521 -280.699718)
			(xy 278.244058 -280.699718) (xy 278.248018 -280.650664) (xy 278.259795 -280.60288) (xy 278.279086 -280.557604)
			(xy 278.305389 -280.516008) (xy 278.338024 -280.479171) (xy 278.376145 -280.448046) (xy 278.418766 -280.423439)
			(xy 278.464782 -280.405987) (xy 278.513001 -280.396143) (xy 278.562176 -280.394162) (xy 278.611031 -280.400094)
			(xy 278.658302 -280.413786) (xy 278.702764 -280.434884) (xy 278.743267 -280.46284) (xy 278.77876 -280.496932)
			(xy 278.808325 -280.536276) (xy 278.831196 -280.579853) (xy 278.84678 -280.626534) (xy 278.854675 -280.675111)
			(xy 278.85517 -280.699718) (xy 279.194018 -280.699718) (xy 279.197978 -280.650664) (xy 279.209755 -280.60288)
			(xy 279.229046 -280.557604) (xy 279.255349 -280.516008) (xy 279.287984 -280.479171) (xy 279.326105 -280.448046)
			(xy 279.368726 -280.423439) (xy 279.414742 -280.405987) (xy 279.462961 -280.396143) (xy 279.512136 -280.394162)
			(xy 279.560991 -280.400094) (xy 279.608262 -280.413786) (xy 279.652724 -280.434884) (xy 279.693227 -280.46284)
			(xy 279.72872 -280.496932) (xy 279.758285 -280.536276) (xy 279.781156 -280.579853) (xy 279.79674 -280.626534)
			(xy 279.804635 -280.675111) (xy 279.80513 -280.699718) (xy 280.143978 -280.699718) (xy 280.147938 -280.650664)
			(xy 280.159715 -280.60288) (xy 280.179006 -280.557604) (xy 280.205309 -280.516008) (xy 280.237944 -280.479171)
			(xy 280.276065 -280.448046) (xy 280.318686 -280.423439) (xy 280.364702 -280.405987) (xy 280.412921 -280.396143)
			(xy 280.462096 -280.394162) (xy 280.510951 -280.400094) (xy 280.558222 -280.413786) (xy 280.602684 -280.434884)
			(xy 280.643187 -280.46284) (xy 280.67868 -280.496932) (xy 280.708245 -280.536276) (xy 280.731116 -280.579853)
			(xy 280.7467 -280.626534) (xy 280.754595 -280.675111) (xy 280.75509 -280.699718) (xy 281.093938 -280.699718)
			(xy 281.097898 -280.650664) (xy 281.109675 -280.60288) (xy 281.128966 -280.557604) (xy 281.155269 -280.516008)
			(xy 281.187904 -280.479171) (xy 281.226025 -280.448046) (xy 281.268646 -280.423439) (xy 281.314662 -280.405987)
			(xy 281.362881 -280.396143) (xy 281.412056 -280.394162) (xy 281.460911 -280.400094) (xy 281.508182 -280.413786)
			(xy 281.552644 -280.434884) (xy 281.593147 -280.46284) (xy 281.62864 -280.496932) (xy 281.658205 -280.536276)
			(xy 281.681076 -280.579853) (xy 281.69666 -280.626534) (xy 281.704555 -280.675111) (xy 281.70505 -280.699718)
			(xy 282.043898 -280.699718) (xy 282.047858 -280.650664) (xy 282.059635 -280.60288) (xy 282.078926 -280.557604)
			(xy 282.105229 -280.516008) (xy 282.137864 -280.479171) (xy 282.175985 -280.448046) (xy 282.218606 -280.423439)
			(xy 282.264622 -280.405987) (xy 282.312841 -280.396143) (xy 282.362016 -280.394162) (xy 282.410871 -280.400094)
			(xy 282.458142 -280.413786) (xy 282.502604 -280.434884) (xy 282.543107 -280.46284) (xy 282.5786 -280.496932)
			(xy 282.608165 -280.536276) (xy 282.631036 -280.579853) (xy 282.64662 -280.626534) (xy 282.654515 -280.675111)
			(xy 282.65501 -280.699718) (xy 282.994112 -280.699718) (xy 282.998072 -280.650664) (xy 283.009849 -280.60288)
			(xy 283.02914 -280.557604) (xy 283.055443 -280.516008) (xy 283.088078 -280.479171) (xy 283.126199 -280.448046)
			(xy 283.16882 -280.423439) (xy 283.214836 -280.405987) (xy 283.263055 -280.396143) (xy 283.31223 -280.394162)
			(xy 283.361085 -280.400094) (xy 283.408356 -280.413786) (xy 283.452818 -280.434884) (xy 283.493321 -280.46284)
			(xy 283.528814 -280.496932) (xy 283.558379 -280.536276) (xy 283.58125 -280.579853) (xy 283.596834 -280.626534)
			(xy 283.604729 -280.675111) (xy 283.605224 -280.699718) (xy 283.944072 -280.699718) (xy 283.948032 -280.650664)
			(xy 283.959809 -280.60288) (xy 283.9791 -280.557604) (xy 284.005403 -280.516008) (xy 284.038038 -280.479171)
			(xy 284.076159 -280.448046) (xy 284.11878 -280.423439) (xy 284.164796 -280.405987) (xy 284.213015 -280.396143)
			(xy 284.26219 -280.394162) (xy 284.311045 -280.400094) (xy 284.358316 -280.413786) (xy 284.402778 -280.434884)
			(xy 284.443281 -280.46284) (xy 284.478774 -280.496932) (xy 284.508339 -280.536276) (xy 284.53121 -280.579853)
			(xy 284.546794 -280.626534) (xy 284.554689 -280.675111) (xy 284.555184 -280.699718) (xy 284.894032 -280.699718)
			(xy 284.897992 -280.650664) (xy 284.909769 -280.60288) (xy 284.92906 -280.557604) (xy 284.955363 -280.516008)
			(xy 284.987998 -280.479171) (xy 285.026119 -280.448046) (xy 285.06874 -280.423439) (xy 285.114756 -280.405987)
			(xy 285.162975 -280.396143) (xy 285.21215 -280.394162) (xy 285.261005 -280.400094) (xy 285.308276 -280.413786)
			(xy 285.352738 -280.434884) (xy 285.393241 -280.46284) (xy 285.428734 -280.496932) (xy 285.458299 -280.536276)
			(xy 285.48117 -280.579853) (xy 285.496754 -280.626534) (xy 285.504649 -280.675111) (xy 285.505144 -280.699718)
			(xy 285.843992 -280.699718) (xy 285.847952 -280.650664) (xy 285.859729 -280.60288) (xy 285.87902 -280.557604)
			(xy 285.905323 -280.516008) (xy 285.937958 -280.479171) (xy 285.976079 -280.448046) (xy 286.0187 -280.423439)
			(xy 286.064716 -280.405987) (xy 286.112935 -280.396143) (xy 286.16211 -280.394162) (xy 286.210965 -280.400094)
			(xy 286.258236 -280.413786) (xy 286.302698 -280.434884) (xy 286.343201 -280.46284) (xy 286.378694 -280.496932)
			(xy 286.408259 -280.536276) (xy 286.43113 -280.579853) (xy 286.446714 -280.626534) (xy 286.454609 -280.675111)
			(xy 286.455104 -280.699718) (xy 286.793952 -280.699718) (xy 286.797912 -280.650664) (xy 286.809689 -280.60288)
			(xy 286.82898 -280.557604) (xy 286.855283 -280.516008) (xy 286.887918 -280.479171) (xy 286.926039 -280.448046)
			(xy 286.96866 -280.423439) (xy 287.014676 -280.405987) (xy 287.062895 -280.396143) (xy 287.11207 -280.394162)
			(xy 287.160925 -280.400094) (xy 287.208196 -280.413786) (xy 287.252658 -280.434884) (xy 287.293161 -280.46284)
			(xy 287.328654 -280.496932) (xy 287.358219 -280.536276) (xy 287.38109 -280.579853) (xy 287.396674 -280.626534)
			(xy 287.404569 -280.675111) (xy 287.405064 -280.699718) (xy 287.743912 -280.699718) (xy 287.747872 -280.650664)
			(xy 287.759649 -280.60288) (xy 287.77894 -280.557604) (xy 287.805243 -280.516008) (xy 287.837878 -280.479171)
			(xy 287.875999 -280.448046) (xy 287.91862 -280.423439) (xy 287.964636 -280.405987) (xy 288.012855 -280.396143)
			(xy 288.06203 -280.394162) (xy 288.110885 -280.400094) (xy 288.158156 -280.413786) (xy 288.202618 -280.434884)
			(xy 288.243121 -280.46284) (xy 288.278614 -280.496932) (xy 288.308179 -280.536276) (xy 288.33105 -280.579853)
			(xy 288.346634 -280.626534) (xy 288.354529 -280.675111) (xy 288.355024 -280.699718) (xy 288.693872 -280.699718)
			(xy 288.697832 -280.650664) (xy 288.709609 -280.60288) (xy 288.7289 -280.557604) (xy 288.755203 -280.516008)
			(xy 288.787838 -280.479171) (xy 288.825959 -280.448046) (xy 288.86858 -280.423439) (xy 288.914596 -280.405987)
			(xy 288.962815 -280.396143) (xy 289.01199 -280.394162) (xy 289.060845 -280.400094) (xy 289.108116 -280.413786)
			(xy 289.152578 -280.434884) (xy 289.193081 -280.46284) (xy 289.228574 -280.496932) (xy 289.258139 -280.536276)
			(xy 289.28101 -280.579853) (xy 289.296594 -280.626534) (xy 289.304489 -280.675111) (xy 289.304984 -280.699718)
			(xy 289.644086 -280.699718) (xy 289.648046 -280.650664) (xy 289.659823 -280.60288) (xy 289.679114 -280.557604)
			(xy 289.705417 -280.516008) (xy 289.738052 -280.479171) (xy 289.776173 -280.448046) (xy 289.818794 -280.423439)
			(xy 289.86481 -280.405987) (xy 289.913029 -280.396143) (xy 289.962204 -280.394162) (xy 290.011059 -280.400094)
			(xy 290.05833 -280.413786) (xy 290.102792 -280.434884) (xy 290.143295 -280.46284) (xy 290.178788 -280.496932)
			(xy 290.208353 -280.536276) (xy 290.231224 -280.579853) (xy 290.246808 -280.626534) (xy 290.254703 -280.675111)
			(xy 290.255198 -280.699718) (xy 290.594046 -280.699718) (xy 290.598006 -280.650664) (xy 290.609783 -280.60288)
			(xy 290.629074 -280.557604) (xy 290.655377 -280.516008) (xy 290.688012 -280.479171) (xy 290.726133 -280.448046)
			(xy 290.768754 -280.423439) (xy 290.81477 -280.405987) (xy 290.862989 -280.396143) (xy 290.912164 -280.394162)
			(xy 290.961019 -280.400094) (xy 291.00829 -280.413786) (xy 291.052752 -280.434884) (xy 291.093255 -280.46284)
			(xy 291.128748 -280.496932) (xy 291.158313 -280.536276) (xy 291.181184 -280.579853) (xy 291.196768 -280.626534)
			(xy 291.204663 -280.675111) (xy 291.205158 -280.699718) (xy 291.544006 -280.699718) (xy 291.547966 -280.650664)
			(xy 291.559743 -280.60288) (xy 291.579034 -280.557604) (xy 291.605337 -280.516008) (xy 291.637972 -280.479171)
			(xy 291.676093 -280.448046) (xy 291.718714 -280.423439) (xy 291.76473 -280.405987) (xy 291.812949 -280.396143)
			(xy 291.862124 -280.394162) (xy 291.910979 -280.400094) (xy 291.95825 -280.413786) (xy 292.002712 -280.434884)
			(xy 292.043215 -280.46284) (xy 292.078708 -280.496932) (xy 292.108273 -280.536276) (xy 292.131144 -280.579853)
			(xy 292.146728 -280.626534) (xy 292.154623 -280.675111) (xy 292.155118 -280.699718) (xy 292.493966 -280.699718)
			(xy 292.497926 -280.650664) (xy 292.509703 -280.60288) (xy 292.528994 -280.557604) (xy 292.555297 -280.516008)
			(xy 292.587932 -280.479171) (xy 292.626053 -280.448046) (xy 292.668674 -280.423439) (xy 292.71469 -280.405987)
			(xy 292.762909 -280.396143) (xy 292.812084 -280.394162) (xy 292.860939 -280.400094) (xy 292.90821 -280.413786)
			(xy 292.952672 -280.434884) (xy 292.993175 -280.46284) (xy 293.028668 -280.496932) (xy 293.058233 -280.536276)
			(xy 293.081104 -280.579853) (xy 293.096688 -280.626534) (xy 293.104583 -280.675111) (xy 293.105078 -280.699718)
			(xy 293.443926 -280.699718) (xy 293.447886 -280.650664) (xy 293.459663 -280.60288) (xy 293.478954 -280.557604)
			(xy 293.505257 -280.516008) (xy 293.537892 -280.479171) (xy 293.576013 -280.448046) (xy 293.618634 -280.423439)
			(xy 293.66465 -280.405987) (xy 293.712869 -280.396143) (xy 293.762044 -280.394162) (xy 293.810899 -280.400094)
			(xy 293.85817 -280.413786) (xy 293.902632 -280.434884) (xy 293.943135 -280.46284) (xy 293.978628 -280.496932)
			(xy 294.008193 -280.536276) (xy 294.031064 -280.579853) (xy 294.046648 -280.626534) (xy 294.054543 -280.675111)
			(xy 294.055038 -280.699718) (xy 294.393886 -280.699718) (xy 294.397846 -280.650664) (xy 294.409623 -280.60288)
			(xy 294.428914 -280.557604) (xy 294.455217 -280.516008) (xy 294.487852 -280.479171) (xy 294.525973 -280.448046)
			(xy 294.568594 -280.423439) (xy 294.61461 -280.405987) (xy 294.662829 -280.396143) (xy 294.712004 -280.394162)
			(xy 294.760859 -280.400094) (xy 294.80813 -280.413786) (xy 294.852592 -280.434884) (xy 294.893095 -280.46284)
			(xy 294.928588 -280.496932) (xy 294.958153 -280.536276) (xy 294.981024 -280.579853) (xy 294.996608 -280.626534)
			(xy 295.004503 -280.675111) (xy 295.004998 -280.699718) (xy 295.3441 -280.699718) (xy 295.34806 -280.650664)
			(xy 295.359837 -280.60288) (xy 295.379128 -280.557604) (xy 295.405431 -280.516008) (xy 295.438066 -280.479171)
			(xy 295.476187 -280.448046) (xy 295.518808 -280.423439) (xy 295.564824 -280.405987) (xy 295.613043 -280.396143)
			(xy 295.662218 -280.394162) (xy 295.711073 -280.400094) (xy 295.758344 -280.413786) (xy 295.802806 -280.434884)
			(xy 295.843309 -280.46284) (xy 295.878802 -280.496932) (xy 295.908367 -280.536276) (xy 295.931238 -280.579853)
			(xy 295.946822 -280.626534) (xy 295.954717 -280.675111) (xy 295.955212 -280.699718) (xy 296.29406 -280.699718)
			(xy 296.29802 -280.650664) (xy 296.309797 -280.60288) (xy 296.329088 -280.557604) (xy 296.355391 -280.516008)
			(xy 296.388026 -280.479171) (xy 296.426147 -280.448046) (xy 296.468768 -280.423439) (xy 296.514784 -280.405987)
			(xy 296.563003 -280.396143) (xy 296.612178 -280.394162) (xy 296.661033 -280.400094) (xy 296.708304 -280.413786)
			(xy 296.752766 -280.434884) (xy 296.793269 -280.46284) (xy 296.828762 -280.496932) (xy 296.858327 -280.536276)
			(xy 296.881198 -280.579853) (xy 296.896782 -280.626534) (xy 296.904677 -280.675111) (xy 296.905172 -280.699718)
			(xy 297.24402 -280.699718) (xy 297.24798 -280.650664) (xy 297.259757 -280.60288) (xy 297.279048 -280.557604)
			(xy 297.305351 -280.516008) (xy 297.337986 -280.479171) (xy 297.376107 -280.448046) (xy 297.418728 -280.423439)
			(xy 297.464744 -280.405987) (xy 297.512963 -280.396143) (xy 297.562138 -280.394162) (xy 297.610993 -280.400094)
			(xy 297.658264 -280.413786) (xy 297.702726 -280.434884) (xy 297.743229 -280.46284) (xy 297.778722 -280.496932)
			(xy 297.808287 -280.536276) (xy 297.831158 -280.579853) (xy 297.846742 -280.626534) (xy 297.854637 -280.675111)
			(xy 297.855132 -280.699718) (xy 298.19398 -280.699718) (xy 298.19794 -280.650664) (xy 298.209717 -280.60288)
			(xy 298.229008 -280.557604) (xy 298.255311 -280.516008) (xy 298.287946 -280.479171) (xy 298.326067 -280.448046)
			(xy 298.368688 -280.423439) (xy 298.414704 -280.405987) (xy 298.462923 -280.396143) (xy 298.512098 -280.394162)
			(xy 298.560953 -280.400094) (xy 298.608224 -280.413786) (xy 298.652686 -280.434884) (xy 298.693189 -280.46284)
			(xy 298.728682 -280.496932) (xy 298.758247 -280.536276) (xy 298.781118 -280.579853) (xy 298.796702 -280.626534)
			(xy 298.804597 -280.675111) (xy 298.805092 -280.699718) (xy 299.14394 -280.699718) (xy 299.1479 -280.650664)
			(xy 299.159677 -280.60288) (xy 299.178968 -280.557604) (xy 299.205271 -280.516008) (xy 299.237906 -280.479171)
			(xy 299.276027 -280.448046) (xy 299.318648 -280.423439) (xy 299.364664 -280.405987) (xy 299.412883 -280.396143)
			(xy 299.462058 -280.394162) (xy 299.510913 -280.400094) (xy 299.558184 -280.413786) (xy 299.602646 -280.434884)
			(xy 299.643149 -280.46284) (xy 299.678642 -280.496932) (xy 299.708207 -280.536276) (xy 299.731078 -280.579853)
			(xy 299.746662 -280.626534) (xy 299.754557 -280.675111) (xy 299.755052 -280.699718) (xy 300.0939 -280.699718)
			(xy 300.09786 -280.650664) (xy 300.109637 -280.60288) (xy 300.128928 -280.557604) (xy 300.155231 -280.516008)
			(xy 300.187866 -280.479171) (xy 300.225987 -280.448046) (xy 300.268608 -280.423439) (xy 300.314624 -280.405987)
			(xy 300.362843 -280.396143) (xy 300.412018 -280.394162) (xy 300.460873 -280.400094) (xy 300.508144 -280.413786)
			(xy 300.552606 -280.434884) (xy 300.593109 -280.46284) (xy 300.628602 -280.496932) (xy 300.658167 -280.536276)
			(xy 300.681038 -280.579853) (xy 300.696622 -280.626534) (xy 300.704517 -280.675111) (xy 300.705012 -280.699718)
			(xy 301.044114 -280.699718) (xy 301.048074 -280.650664) (xy 301.059851 -280.60288) (xy 301.079142 -280.557604)
			(xy 301.105445 -280.516008) (xy 301.13808 -280.479171) (xy 301.176201 -280.448046) (xy 301.218822 -280.423439)
			(xy 301.264838 -280.405987) (xy 301.313057 -280.396143) (xy 301.362232 -280.394162) (xy 301.411087 -280.400094)
			(xy 301.458358 -280.413786) (xy 301.50282 -280.434884) (xy 301.543323 -280.46284) (xy 301.578816 -280.496932)
			(xy 301.608381 -280.536276) (xy 301.631252 -280.579853) (xy 301.646836 -280.626534) (xy 301.654731 -280.675111)
			(xy 301.655226 -280.699718) (xy 301.994074 -280.699718) (xy 301.998034 -280.650664) (xy 302.009811 -280.60288)
			(xy 302.029102 -280.557604) (xy 302.055405 -280.516008) (xy 302.08804 -280.479171) (xy 302.126161 -280.448046)
			(xy 302.168782 -280.423439) (xy 302.214798 -280.405987) (xy 302.263017 -280.396143) (xy 302.312192 -280.394162)
			(xy 302.361047 -280.400094) (xy 302.408318 -280.413786) (xy 302.45278 -280.434884) (xy 302.493283 -280.46284)
			(xy 302.528776 -280.496932) (xy 302.558341 -280.536276) (xy 302.581212 -280.579853) (xy 302.596796 -280.626534)
			(xy 302.604691 -280.675111) (xy 302.605186 -280.699718) (xy 302.944034 -280.699718) (xy 302.947994 -280.650664)
			(xy 302.959771 -280.60288) (xy 302.979062 -280.557604) (xy 303.005365 -280.516008) (xy 303.038 -280.479171)
			(xy 303.076121 -280.448046) (xy 303.118742 -280.423439) (xy 303.164758 -280.405987) (xy 303.212977 -280.396143)
			(xy 303.262152 -280.394162) (xy 303.311007 -280.400094) (xy 303.358278 -280.413786) (xy 303.40274 -280.434884)
			(xy 303.443243 -280.46284) (xy 303.478736 -280.496932) (xy 303.508301 -280.536276) (xy 303.531172 -280.579853)
			(xy 303.546756 -280.626534) (xy 303.554651 -280.675111) (xy 303.555146 -280.699718) (xy 303.893994 -280.699718)
			(xy 303.897954 -280.650664) (xy 303.909731 -280.60288) (xy 303.929022 -280.557604) (xy 303.955325 -280.516008)
			(xy 303.98796 -280.479171) (xy 304.026081 -280.448046) (xy 304.068702 -280.423439) (xy 304.114718 -280.405987)
			(xy 304.162937 -280.396143) (xy 304.212112 -280.394162) (xy 304.260967 -280.400094) (xy 304.308238 -280.413786)
			(xy 304.3527 -280.434884) (xy 304.393203 -280.46284) (xy 304.428696 -280.496932) (xy 304.458261 -280.536276)
			(xy 304.481132 -280.579853) (xy 304.496716 -280.626534) (xy 304.504611 -280.675111) (xy 304.505106 -280.699718)
			(xy 304.843954 -280.699718) (xy 304.847914 -280.650664) (xy 304.859691 -280.60288) (xy 304.878982 -280.557604)
			(xy 304.905285 -280.516008) (xy 304.93792 -280.479171) (xy 304.976041 -280.448046) (xy 305.018662 -280.423439)
			(xy 305.064678 -280.405987) (xy 305.112897 -280.396143) (xy 305.162072 -280.394162) (xy 305.210927 -280.400094)
			(xy 305.258198 -280.413786) (xy 305.30266 -280.434884) (xy 305.343163 -280.46284) (xy 305.378656 -280.496932)
			(xy 305.408221 -280.536276) (xy 305.431092 -280.579853) (xy 305.446676 -280.626534) (xy 305.454571 -280.675111)
			(xy 305.455066 -280.699718) (xy 305.793914 -280.699718) (xy 305.797874 -280.650664) (xy 305.809651 -280.60288)
			(xy 305.828942 -280.557604) (xy 305.855245 -280.516008) (xy 305.88788 -280.479171) (xy 305.926001 -280.448046)
			(xy 305.968622 -280.423439) (xy 306.014638 -280.405987) (xy 306.062857 -280.396143) (xy 306.112032 -280.394162)
			(xy 306.160887 -280.400094) (xy 306.208158 -280.413786) (xy 306.25262 -280.434884) (xy 306.293123 -280.46284)
			(xy 306.328616 -280.496932) (xy 306.358181 -280.536276) (xy 306.381052 -280.579853) (xy 306.396636 -280.626534)
			(xy 306.404531 -280.675111) (xy 306.405026 -280.699718) (xy 306.744128 -280.699718) (xy 306.748088 -280.650664)
			(xy 306.759865 -280.60288) (xy 306.779156 -280.557604) (xy 306.805459 -280.516008) (xy 306.838094 -280.479171)
			(xy 306.876215 -280.448046) (xy 306.918836 -280.423439) (xy 306.964852 -280.405987) (xy 307.013071 -280.396143)
			(xy 307.062246 -280.394162) (xy 307.111101 -280.400094) (xy 307.158372 -280.413786) (xy 307.202834 -280.434884)
			(xy 307.243337 -280.46284) (xy 307.27883 -280.496932) (xy 307.308395 -280.536276) (xy 307.331266 -280.579853)
			(xy 307.34685 -280.626534) (xy 307.354745 -280.675111) (xy 307.35524 -280.699718) (xy 307.694088 -280.699718)
			(xy 307.698048 -280.650664) (xy 307.709825 -280.60288) (xy 307.729116 -280.557604) (xy 307.755419 -280.516008)
			(xy 307.788054 -280.479171) (xy 307.826175 -280.448046) (xy 307.868796 -280.423439) (xy 307.914812 -280.405987)
			(xy 307.963031 -280.396143) (xy 308.012206 -280.394162) (xy 308.061061 -280.400094) (xy 308.108332 -280.413786)
			(xy 308.152794 -280.434884) (xy 308.193297 -280.46284) (xy 308.22879 -280.496932) (xy 308.258355 -280.536276)
			(xy 308.281226 -280.579853) (xy 308.29681 -280.626534) (xy 308.304705 -280.675111) (xy 308.3052 -280.699718)
			(xy 308.644048 -280.699718) (xy 308.648008 -280.650664) (xy 308.659785 -280.60288) (xy 308.679076 -280.557604)
			(xy 308.705379 -280.516008) (xy 308.738014 -280.479171) (xy 308.776135 -280.448046) (xy 308.818756 -280.423439)
			(xy 308.864772 -280.405987) (xy 308.912991 -280.396143) (xy 308.962166 -280.394162) (xy 309.011021 -280.400094)
			(xy 309.058292 -280.413786) (xy 309.102754 -280.434884) (xy 309.143257 -280.46284) (xy 309.17875 -280.496932)
			(xy 309.208315 -280.536276) (xy 309.231186 -280.579853) (xy 309.24677 -280.626534) (xy 309.254665 -280.675111)
			(xy 309.25516 -280.699718) (xy 309.254665 -280.724325) (xy 309.24677 -280.772902) (xy 309.231186 -280.819583)
			(xy 309.208315 -280.86316) (xy 309.17875 -280.902504) (xy 309.143257 -280.936596) (xy 309.102754 -280.964552)
			(xy 309.058292 -280.98565) (xy 309.011021 -280.999342) (xy 308.962166 -281.005274) (xy 308.912991 -281.003293)
			(xy 308.864772 -280.993449) (xy 308.818756 -280.975997) (xy 308.776135 -280.95139) (xy 308.738014 -280.920265)
			(xy 308.705379 -280.883428) (xy 308.679076 -280.841832) (xy 308.659785 -280.796556) (xy 308.648008 -280.748772)
			(xy 308.644048 -280.699718) (xy 308.3052 -280.699718) (xy 308.304705 -280.724325) (xy 308.29681 -280.772902)
			(xy 308.281226 -280.819583) (xy 308.258355 -280.86316) (xy 308.22879 -280.902504) (xy 308.193297 -280.936596)
			(xy 308.152794 -280.964552) (xy 308.108332 -280.98565) (xy 308.061061 -280.999342) (xy 308.012206 -281.005274)
			(xy 307.963031 -281.003293) (xy 307.914812 -280.993449) (xy 307.868796 -280.975997) (xy 307.826175 -280.95139)
			(xy 307.788054 -280.920265) (xy 307.755419 -280.883428) (xy 307.729116 -280.841832) (xy 307.709825 -280.796556)
			(xy 307.698048 -280.748772) (xy 307.694088 -280.699718) (xy 307.35524 -280.699718) (xy 307.354745 -280.724325)
			(xy 307.34685 -280.772902) (xy 307.331266 -280.819583) (xy 307.308395 -280.86316) (xy 307.27883 -280.902504)
			(xy 307.243337 -280.936596) (xy 307.202834 -280.964552) (xy 307.158372 -280.98565) (xy 307.111101 -280.999342)
			(xy 307.062246 -281.005274) (xy 307.013071 -281.003293) (xy 306.964852 -280.993449) (xy 306.918836 -280.975997)
			(xy 306.876215 -280.95139) (xy 306.838094 -280.920265) (xy 306.805459 -280.883428) (xy 306.779156 -280.841832)
			(xy 306.759865 -280.796556) (xy 306.748088 -280.748772) (xy 306.744128 -280.699718) (xy 306.405026 -280.699718)
			(xy 306.404531 -280.724325) (xy 306.396636 -280.772902) (xy 306.381052 -280.819583) (xy 306.358181 -280.86316)
			(xy 306.328616 -280.902504) (xy 306.293123 -280.936596) (xy 306.25262 -280.964552) (xy 306.208158 -280.98565)
			(xy 306.160887 -280.999342) (xy 306.112032 -281.005274) (xy 306.062857 -281.003293) (xy 306.014638 -280.993449)
			(xy 305.968622 -280.975997) (xy 305.926001 -280.95139) (xy 305.88788 -280.920265) (xy 305.855245 -280.883428)
			(xy 305.828942 -280.841832) (xy 305.809651 -280.796556) (xy 305.797874 -280.748772) (xy 305.793914 -280.699718)
			(xy 305.455066 -280.699718) (xy 305.454571 -280.724325) (xy 305.446676 -280.772902) (xy 305.431092 -280.819583)
			(xy 305.408221 -280.86316) (xy 305.378656 -280.902504) (xy 305.343163 -280.936596) (xy 305.30266 -280.964552)
			(xy 305.258198 -280.98565) (xy 305.210927 -280.999342) (xy 305.162072 -281.005274) (xy 305.112897 -281.003293)
			(xy 305.064678 -280.993449) (xy 305.018662 -280.975997) (xy 304.976041 -280.95139) (xy 304.93792 -280.920265)
			(xy 304.905285 -280.883428) (xy 304.878982 -280.841832) (xy 304.859691 -280.796556) (xy 304.847914 -280.748772)
			(xy 304.843954 -280.699718) (xy 304.505106 -280.699718) (xy 304.504611 -280.724325) (xy 304.496716 -280.772902)
			(xy 304.481132 -280.819583) (xy 304.458261 -280.86316) (xy 304.428696 -280.902504) (xy 304.393203 -280.936596)
			(xy 304.3527 -280.964552) (xy 304.308238 -280.98565) (xy 304.260967 -280.999342) (xy 304.212112 -281.005274)
			(xy 304.162937 -281.003293) (xy 304.114718 -280.993449) (xy 304.068702 -280.975997) (xy 304.026081 -280.95139)
			(xy 303.98796 -280.920265) (xy 303.955325 -280.883428) (xy 303.929022 -280.841832) (xy 303.909731 -280.796556)
			(xy 303.897954 -280.748772) (xy 303.893994 -280.699718) (xy 303.555146 -280.699718) (xy 303.554651 -280.724325)
			(xy 303.546756 -280.772902) (xy 303.531172 -280.819583) (xy 303.508301 -280.86316) (xy 303.478736 -280.902504)
			(xy 303.443243 -280.936596) (xy 303.40274 -280.964552) (xy 303.358278 -280.98565) (xy 303.311007 -280.999342)
			(xy 303.262152 -281.005274) (xy 303.212977 -281.003293) (xy 303.164758 -280.993449) (xy 303.118742 -280.975997)
			(xy 303.076121 -280.95139) (xy 303.038 -280.920265) (xy 303.005365 -280.883428) (xy 302.979062 -280.841832)
			(xy 302.959771 -280.796556) (xy 302.947994 -280.748772) (xy 302.944034 -280.699718) (xy 302.605186 -280.699718)
			(xy 302.604691 -280.724325) (xy 302.596796 -280.772902) (xy 302.581212 -280.819583) (xy 302.558341 -280.86316)
			(xy 302.528776 -280.902504) (xy 302.493283 -280.936596) (xy 302.45278 -280.964552) (xy 302.408318 -280.98565)
			(xy 302.361047 -280.999342) (xy 302.312192 -281.005274) (xy 302.263017 -281.003293) (xy 302.214798 -280.993449)
			(xy 302.168782 -280.975997) (xy 302.126161 -280.95139) (xy 302.08804 -280.920265) (xy 302.055405 -280.883428)
			(xy 302.029102 -280.841832) (xy 302.009811 -280.796556) (xy 301.998034 -280.748772) (xy 301.994074 -280.699718)
			(xy 301.655226 -280.699718) (xy 301.654731 -280.724325) (xy 301.646836 -280.772902) (xy 301.631252 -280.819583)
			(xy 301.608381 -280.86316) (xy 301.578816 -280.902504) (xy 301.543323 -280.936596) (xy 301.50282 -280.964552)
			(xy 301.458358 -280.98565) (xy 301.411087 -280.999342) (xy 301.362232 -281.005274) (xy 301.313057 -281.003293)
			(xy 301.264838 -280.993449) (xy 301.218822 -280.975997) (xy 301.176201 -280.95139) (xy 301.13808 -280.920265)
			(xy 301.105445 -280.883428) (xy 301.079142 -280.841832) (xy 301.059851 -280.796556) (xy 301.048074 -280.748772)
			(xy 301.044114 -280.699718) (xy 300.705012 -280.699718) (xy 300.704517 -280.724325) (xy 300.696622 -280.772902)
			(xy 300.681038 -280.819583) (xy 300.658167 -280.86316) (xy 300.628602 -280.902504) (xy 300.593109 -280.936596)
			(xy 300.552606 -280.964552) (xy 300.508144 -280.98565) (xy 300.460873 -280.999342) (xy 300.412018 -281.005274)
			(xy 300.362843 -281.003293) (xy 300.314624 -280.993449) (xy 300.268608 -280.975997) (xy 300.225987 -280.95139)
			(xy 300.187866 -280.920265) (xy 300.155231 -280.883428) (xy 300.128928 -280.841832) (xy 300.109637 -280.796556)
			(xy 300.09786 -280.748772) (xy 300.0939 -280.699718) (xy 299.755052 -280.699718) (xy 299.754557 -280.724325)
			(xy 299.746662 -280.772902) (xy 299.731078 -280.819583) (xy 299.708207 -280.86316) (xy 299.678642 -280.902504)
			(xy 299.643149 -280.936596) (xy 299.602646 -280.964552) (xy 299.558184 -280.98565) (xy 299.510913 -280.999342)
			(xy 299.462058 -281.005274) (xy 299.412883 -281.003293) (xy 299.364664 -280.993449) (xy 299.318648 -280.975997)
			(xy 299.276027 -280.95139) (xy 299.237906 -280.920265) (xy 299.205271 -280.883428) (xy 299.178968 -280.841832)
			(xy 299.159677 -280.796556) (xy 299.1479 -280.748772) (xy 299.14394 -280.699718) (xy 298.805092 -280.699718)
			(xy 298.804597 -280.724325) (xy 298.796702 -280.772902) (xy 298.781118 -280.819583) (xy 298.758247 -280.86316)
			(xy 298.728682 -280.902504) (xy 298.693189 -280.936596) (xy 298.652686 -280.964552) (xy 298.608224 -280.98565)
			(xy 298.560953 -280.999342) (xy 298.512098 -281.005274) (xy 298.462923 -281.003293) (xy 298.414704 -280.993449)
			(xy 298.368688 -280.975997) (xy 298.326067 -280.95139) (xy 298.287946 -280.920265) (xy 298.255311 -280.883428)
			(xy 298.229008 -280.841832) (xy 298.209717 -280.796556) (xy 298.19794 -280.748772) (xy 298.19398 -280.699718)
			(xy 297.855132 -280.699718) (xy 297.854637 -280.724325) (xy 297.846742 -280.772902) (xy 297.831158 -280.819583)
			(xy 297.808287 -280.86316) (xy 297.778722 -280.902504) (xy 297.743229 -280.936596) (xy 297.702726 -280.964552)
			(xy 297.658264 -280.98565) (xy 297.610993 -280.999342) (xy 297.562138 -281.005274) (xy 297.512963 -281.003293)
			(xy 297.464744 -280.993449) (xy 297.418728 -280.975997) (xy 297.376107 -280.95139) (xy 297.337986 -280.920265)
			(xy 297.305351 -280.883428) (xy 297.279048 -280.841832) (xy 297.259757 -280.796556) (xy 297.24798 -280.748772)
			(xy 297.24402 -280.699718) (xy 296.905172 -280.699718) (xy 296.904677 -280.724325) (xy 296.896782 -280.772902)
			(xy 296.881198 -280.819583) (xy 296.858327 -280.86316) (xy 296.828762 -280.902504) (xy 296.793269 -280.936596)
			(xy 296.752766 -280.964552) (xy 296.708304 -280.98565) (xy 296.661033 -280.999342) (xy 296.612178 -281.005274)
			(xy 296.563003 -281.003293) (xy 296.514784 -280.993449) (xy 296.468768 -280.975997) (xy 296.426147 -280.95139)
			(xy 296.388026 -280.920265) (xy 296.355391 -280.883428) (xy 296.329088 -280.841832) (xy 296.309797 -280.796556)
			(xy 296.29802 -280.748772) (xy 296.29406 -280.699718) (xy 295.955212 -280.699718) (xy 295.954717 -280.724325)
			(xy 295.946822 -280.772902) (xy 295.931238 -280.819583) (xy 295.908367 -280.86316) (xy 295.878802 -280.902504)
			(xy 295.843309 -280.936596) (xy 295.802806 -280.964552) (xy 295.758344 -280.98565) (xy 295.711073 -280.999342)
			(xy 295.662218 -281.005274) (xy 295.613043 -281.003293) (xy 295.564824 -280.993449) (xy 295.518808 -280.975997)
			(xy 295.476187 -280.95139) (xy 295.438066 -280.920265) (xy 295.405431 -280.883428) (xy 295.379128 -280.841832)
			(xy 295.359837 -280.796556) (xy 295.34806 -280.748772) (xy 295.3441 -280.699718) (xy 295.004998 -280.699718)
			(xy 295.004503 -280.724325) (xy 294.996608 -280.772902) (xy 294.981024 -280.819583) (xy 294.958153 -280.86316)
			(xy 294.928588 -280.902504) (xy 294.893095 -280.936596) (xy 294.852592 -280.964552) (xy 294.80813 -280.98565)
			(xy 294.760859 -280.999342) (xy 294.712004 -281.005274) (xy 294.662829 -281.003293) (xy 294.61461 -280.993449)
			(xy 294.568594 -280.975997) (xy 294.525973 -280.95139) (xy 294.487852 -280.920265) (xy 294.455217 -280.883428)
			(xy 294.428914 -280.841832) (xy 294.409623 -280.796556) (xy 294.397846 -280.748772) (xy 294.393886 -280.699718)
			(xy 294.055038 -280.699718) (xy 294.054543 -280.724325) (xy 294.046648 -280.772902) (xy 294.031064 -280.819583)
			(xy 294.008193 -280.86316) (xy 293.978628 -280.902504) (xy 293.943135 -280.936596) (xy 293.902632 -280.964552)
			(xy 293.85817 -280.98565) (xy 293.810899 -280.999342) (xy 293.762044 -281.005274) (xy 293.712869 -281.003293)
			(xy 293.66465 -280.993449) (xy 293.618634 -280.975997) (xy 293.576013 -280.95139) (xy 293.537892 -280.920265)
			(xy 293.505257 -280.883428) (xy 293.478954 -280.841832) (xy 293.459663 -280.796556) (xy 293.447886 -280.748772)
			(xy 293.443926 -280.699718) (xy 293.105078 -280.699718) (xy 293.104583 -280.724325) (xy 293.096688 -280.772902)
			(xy 293.081104 -280.819583) (xy 293.058233 -280.86316) (xy 293.028668 -280.902504) (xy 292.993175 -280.936596)
			(xy 292.952672 -280.964552) (xy 292.90821 -280.98565) (xy 292.860939 -280.999342) (xy 292.812084 -281.005274)
			(xy 292.762909 -281.003293) (xy 292.71469 -280.993449) (xy 292.668674 -280.975997) (xy 292.626053 -280.95139)
			(xy 292.587932 -280.920265) (xy 292.555297 -280.883428) (xy 292.528994 -280.841832) (xy 292.509703 -280.796556)
			(xy 292.497926 -280.748772) (xy 292.493966 -280.699718) (xy 292.155118 -280.699718) (xy 292.154623 -280.724325)
			(xy 292.146728 -280.772902) (xy 292.131144 -280.819583) (xy 292.108273 -280.86316) (xy 292.078708 -280.902504)
			(xy 292.043215 -280.936596) (xy 292.002712 -280.964552) (xy 291.95825 -280.98565) (xy 291.910979 -280.999342)
			(xy 291.862124 -281.005274) (xy 291.812949 -281.003293) (xy 291.76473 -280.993449) (xy 291.718714 -280.975997)
			(xy 291.676093 -280.95139) (xy 291.637972 -280.920265) (xy 291.605337 -280.883428) (xy 291.579034 -280.841832)
			(xy 291.559743 -280.796556) (xy 291.547966 -280.748772) (xy 291.544006 -280.699718) (xy 291.205158 -280.699718)
			(xy 291.204663 -280.724325) (xy 291.196768 -280.772902) (xy 291.181184 -280.819583) (xy 291.158313 -280.86316)
			(xy 291.128748 -280.902504) (xy 291.093255 -280.936596) (xy 291.052752 -280.964552) (xy 291.00829 -280.98565)
			(xy 290.961019 -280.999342) (xy 290.912164 -281.005274) (xy 290.862989 -281.003293) (xy 290.81477 -280.993449)
			(xy 290.768754 -280.975997) (xy 290.726133 -280.95139) (xy 290.688012 -280.920265) (xy 290.655377 -280.883428)
			(xy 290.629074 -280.841832) (xy 290.609783 -280.796556) (xy 290.598006 -280.748772) (xy 290.594046 -280.699718)
			(xy 290.255198 -280.699718) (xy 290.254703 -280.724325) (xy 290.246808 -280.772902) (xy 290.231224 -280.819583)
			(xy 290.208353 -280.86316) (xy 290.178788 -280.902504) (xy 290.143295 -280.936596) (xy 290.102792 -280.964552)
			(xy 290.05833 -280.98565) (xy 290.011059 -280.999342) (xy 289.962204 -281.005274) (xy 289.913029 -281.003293)
			(xy 289.86481 -280.993449) (xy 289.818794 -280.975997) (xy 289.776173 -280.95139) (xy 289.738052 -280.920265)
			(xy 289.705417 -280.883428) (xy 289.679114 -280.841832) (xy 289.659823 -280.796556) (xy 289.648046 -280.748772)
			(xy 289.644086 -280.699718) (xy 289.304984 -280.699718) (xy 289.304489 -280.724325) (xy 289.296594 -280.772902)
			(xy 289.28101 -280.819583) (xy 289.258139 -280.86316) (xy 289.228574 -280.902504) (xy 289.193081 -280.936596)
			(xy 289.152578 -280.964552) (xy 289.108116 -280.98565) (xy 289.060845 -280.999342) (xy 289.01199 -281.005274)
			(xy 288.962815 -281.003293) (xy 288.914596 -280.993449) (xy 288.86858 -280.975997) (xy 288.825959 -280.95139)
			(xy 288.787838 -280.920265) (xy 288.755203 -280.883428) (xy 288.7289 -280.841832) (xy 288.709609 -280.796556)
			(xy 288.697832 -280.748772) (xy 288.693872 -280.699718) (xy 288.355024 -280.699718) (xy 288.354529 -280.724325)
			(xy 288.346634 -280.772902) (xy 288.33105 -280.819583) (xy 288.308179 -280.86316) (xy 288.278614 -280.902504)
			(xy 288.243121 -280.936596) (xy 288.202618 -280.964552) (xy 288.158156 -280.98565) (xy 288.110885 -280.999342)
			(xy 288.06203 -281.005274) (xy 288.012855 -281.003293) (xy 287.964636 -280.993449) (xy 287.91862 -280.975997)
			(xy 287.875999 -280.95139) (xy 287.837878 -280.920265) (xy 287.805243 -280.883428) (xy 287.77894 -280.841832)
			(xy 287.759649 -280.796556) (xy 287.747872 -280.748772) (xy 287.743912 -280.699718) (xy 287.405064 -280.699718)
			(xy 287.404569 -280.724325) (xy 287.396674 -280.772902) (xy 287.38109 -280.819583) (xy 287.358219 -280.86316)
			(xy 287.328654 -280.902504) (xy 287.293161 -280.936596) (xy 287.252658 -280.964552) (xy 287.208196 -280.98565)
			(xy 287.160925 -280.999342) (xy 287.11207 -281.005274) (xy 287.062895 -281.003293) (xy 287.014676 -280.993449)
			(xy 286.96866 -280.975997) (xy 286.926039 -280.95139) (xy 286.887918 -280.920265) (xy 286.855283 -280.883428)
			(xy 286.82898 -280.841832) (xy 286.809689 -280.796556) (xy 286.797912 -280.748772) (xy 286.793952 -280.699718)
			(xy 286.455104 -280.699718) (xy 286.454609 -280.724325) (xy 286.446714 -280.772902) (xy 286.43113 -280.819583)
			(xy 286.408259 -280.86316) (xy 286.378694 -280.902504) (xy 286.343201 -280.936596) (xy 286.302698 -280.964552)
			(xy 286.258236 -280.98565) (xy 286.210965 -280.999342) (xy 286.16211 -281.005274) (xy 286.112935 -281.003293)
			(xy 286.064716 -280.993449) (xy 286.0187 -280.975997) (xy 285.976079 -280.95139) (xy 285.937958 -280.920265)
			(xy 285.905323 -280.883428) (xy 285.87902 -280.841832) (xy 285.859729 -280.796556) (xy 285.847952 -280.748772)
			(xy 285.843992 -280.699718) (xy 285.505144 -280.699718) (xy 285.504649 -280.724325) (xy 285.496754 -280.772902)
			(xy 285.48117 -280.819583) (xy 285.458299 -280.86316) (xy 285.428734 -280.902504) (xy 285.393241 -280.936596)
			(xy 285.352738 -280.964552) (xy 285.308276 -280.98565) (xy 285.261005 -280.999342) (xy 285.21215 -281.005274)
			(xy 285.162975 -281.003293) (xy 285.114756 -280.993449) (xy 285.06874 -280.975997) (xy 285.026119 -280.95139)
			(xy 284.987998 -280.920265) (xy 284.955363 -280.883428) (xy 284.92906 -280.841832) (xy 284.909769 -280.796556)
			(xy 284.897992 -280.748772) (xy 284.894032 -280.699718) (xy 284.555184 -280.699718) (xy 284.554689 -280.724325)
			(xy 284.546794 -280.772902) (xy 284.53121 -280.819583) (xy 284.508339 -280.86316) (xy 284.478774 -280.902504)
			(xy 284.443281 -280.936596) (xy 284.402778 -280.964552) (xy 284.358316 -280.98565) (xy 284.311045 -280.999342)
			(xy 284.26219 -281.005274) (xy 284.213015 -281.003293) (xy 284.164796 -280.993449) (xy 284.11878 -280.975997)
			(xy 284.076159 -280.95139) (xy 284.038038 -280.920265) (xy 284.005403 -280.883428) (xy 283.9791 -280.841832)
			(xy 283.959809 -280.796556) (xy 283.948032 -280.748772) (xy 283.944072 -280.699718) (xy 283.605224 -280.699718)
			(xy 283.604729 -280.724325) (xy 283.596834 -280.772902) (xy 283.58125 -280.819583) (xy 283.558379 -280.86316)
			(xy 283.528814 -280.902504) (xy 283.493321 -280.936596) (xy 283.452818 -280.964552) (xy 283.408356 -280.98565)
			(xy 283.361085 -280.999342) (xy 283.31223 -281.005274) (xy 283.263055 -281.003293) (xy 283.214836 -280.993449)
			(xy 283.16882 -280.975997) (xy 283.126199 -280.95139) (xy 283.088078 -280.920265) (xy 283.055443 -280.883428)
			(xy 283.02914 -280.841832) (xy 283.009849 -280.796556) (xy 282.998072 -280.748772) (xy 282.994112 -280.699718)
			(xy 282.65501 -280.699718) (xy 282.654515 -280.724325) (xy 282.64662 -280.772902) (xy 282.631036 -280.819583)
			(xy 282.608165 -280.86316) (xy 282.5786 -280.902504) (xy 282.543107 -280.936596) (xy 282.502604 -280.964552)
			(xy 282.458142 -280.98565) (xy 282.410871 -280.999342) (xy 282.362016 -281.005274) (xy 282.312841 -281.003293)
			(xy 282.264622 -280.993449) (xy 282.218606 -280.975997) (xy 282.175985 -280.95139) (xy 282.137864 -280.920265)
			(xy 282.105229 -280.883428) (xy 282.078926 -280.841832) (xy 282.059635 -280.796556) (xy 282.047858 -280.748772)
			(xy 282.043898 -280.699718) (xy 281.70505 -280.699718) (xy 281.704555 -280.724325) (xy 281.69666 -280.772902)
			(xy 281.681076 -280.819583) (xy 281.658205 -280.86316) (xy 281.62864 -280.902504) (xy 281.593147 -280.936596)
			(xy 281.552644 -280.964552) (xy 281.508182 -280.98565) (xy 281.460911 -280.999342) (xy 281.412056 -281.005274)
			(xy 281.362881 -281.003293) (xy 281.314662 -280.993449) (xy 281.268646 -280.975997) (xy 281.226025 -280.95139)
			(xy 281.187904 -280.920265) (xy 281.155269 -280.883428) (xy 281.128966 -280.841832) (xy 281.109675 -280.796556)
			(xy 281.097898 -280.748772) (xy 281.093938 -280.699718) (xy 280.75509 -280.699718) (xy 280.754595 -280.724325)
			(xy 280.7467 -280.772902) (xy 280.731116 -280.819583) (xy 280.708245 -280.86316) (xy 280.67868 -280.902504)
			(xy 280.643187 -280.936596) (xy 280.602684 -280.964552) (xy 280.558222 -280.98565) (xy 280.510951 -280.999342)
			(xy 280.462096 -281.005274) (xy 280.412921 -281.003293) (xy 280.364702 -280.993449) (xy 280.318686 -280.975997)
			(xy 280.276065 -280.95139) (xy 280.237944 -280.920265) (xy 280.205309 -280.883428) (xy 280.179006 -280.841832)
			(xy 280.159715 -280.796556) (xy 280.147938 -280.748772) (xy 280.143978 -280.699718) (xy 279.80513 -280.699718)
			(xy 279.804635 -280.724325) (xy 279.79674 -280.772902) (xy 279.781156 -280.819583) (xy 279.758285 -280.86316)
			(xy 279.72872 -280.902504) (xy 279.693227 -280.936596) (xy 279.652724 -280.964552) (xy 279.608262 -280.98565)
			(xy 279.560991 -280.999342) (xy 279.512136 -281.005274) (xy 279.462961 -281.003293) (xy 279.414742 -280.993449)
			(xy 279.368726 -280.975997) (xy 279.326105 -280.95139) (xy 279.287984 -280.920265) (xy 279.255349 -280.883428)
			(xy 279.229046 -280.841832) (xy 279.209755 -280.796556) (xy 279.197978 -280.748772) (xy 279.194018 -280.699718)
			(xy 278.85517 -280.699718) (xy 278.854675 -280.724325) (xy 278.84678 -280.772902) (xy 278.831196 -280.819583)
			(xy 278.808325 -280.86316) (xy 278.77876 -280.902504) (xy 278.743267 -280.936596) (xy 278.702764 -280.964552)
			(xy 278.658302 -280.98565) (xy 278.611031 -280.999342) (xy 278.562176 -281.005274) (xy 278.513001 -281.003293)
			(xy 278.464782 -280.993449) (xy 278.418766 -280.975997) (xy 278.376145 -280.95139) (xy 278.338024 -280.920265)
			(xy 278.305389 -280.883428) (xy 278.279086 -280.841832) (xy 278.259795 -280.796556) (xy 278.248018 -280.748772)
			(xy 278.244058 -280.699718) (xy 277.90521 -280.699718) (xy 277.904715 -280.724325) (xy 277.89682 -280.772902)
			(xy 277.881236 -280.819583) (xy 277.858365 -280.86316) (xy 277.8288 -280.902504) (xy 277.793307 -280.936596)
			(xy 277.752804 -280.964552) (xy 277.708342 -280.98565) (xy 277.661071 -280.999342) (xy 277.612216 -281.005274)
			(xy 277.563041 -281.003293) (xy 277.514822 -280.993449) (xy 277.468806 -280.975997) (xy 277.426185 -280.95139)
			(xy 277.388064 -280.920265) (xy 277.355429 -280.883428) (xy 277.329126 -280.841832) (xy 277.309835 -280.796556)
			(xy 277.298058 -280.748772) (xy 277.294098 -280.699718) (xy 276.954989 -280.699718) (xy 276.955437 -280.707984)
			(xy 276.950069 -280.757339) (xy 276.936787 -280.805175) (xy 276.91594 -280.850232) (xy 276.888079 -280.891322)
			(xy 276.853937 -280.927364) (xy 276.814413 -280.957407) (xy 276.77055 -280.980661) (xy 276.723503 -280.996511)
			(xy 276.674511 -281.004541) (xy 276.649688 -281.005026) (xy 276.635505 -281.004851) (xy 276.607265 -281.002178)
			(xy 276.5933 -280.999692) (xy 276.593046 -280.999692) (xy 276.580816 -280.998216) (xy 276.557328 -281.005516)
			(xy 276.548088 -281.013662) (xy 276.479762 -281.082242) (xy 276.472396 -281.105864) (xy 276.474682 -281.11831)
			(xy 276.477166 -281.132339) (xy 276.479838 -281.160706) (xy 276.480016 -281.174952) (xy 276.479833 -281.189135)
			(xy 276.477165 -281.217375) (xy 276.474682 -281.23134) (xy 276.472396 -281.243786) (xy 276.479762 -281.267408)
			(xy 276.557232 -281.344878) (xy 276.580854 -281.352244) (xy 276.5933 -281.349958) (xy 276.607267 -281.347486)
			(xy 276.635506 -281.344811) (xy 276.649688 -281.344624) (xy 276.673682 -281.345049) (xy 276.721081 -281.352555)
			(xy 276.766721 -281.367384) (xy 276.809479 -281.389171) (xy 276.848302 -281.417379) (xy 276.882234 -281.451313)
			(xy 276.91044 -281.490138) (xy 276.932223 -281.532898) (xy 276.947049 -281.578539) (xy 276.954552 -281.625938)
			(xy 276.954996 -281.649932) (xy 276.954824 -281.664115) (xy 276.952149 -281.692355) (xy 276.949662 -281.70632)
			(xy 276.949662 -281.706574) (xy 276.948154 -281.718803) (xy 276.955472 -281.742296) (xy 276.963632 -281.751532)
			(xy 277.032212 -281.819858) (xy 277.055834 -281.827224) (xy 277.06828 -281.824938) (xy 277.08231 -281.822458)
			(xy 277.110676 -281.819783) (xy 277.124922 -281.819604) (xy 277.139105 -281.819777) (xy 277.167345 -281.822452)
			(xy 277.18131 -281.824938) (xy 277.193756 -281.827224) (xy 277.217378 -281.819858) (xy 277.294848 -281.742388)
			(xy 277.302214 -281.718766) (xy 277.299928 -281.70632) (xy 277.297445 -281.692355) (xy 277.294777 -281.664115)
			(xy 277.294594 -281.649932) (xy 277.295116 -281.624677) (xy 277.303429 -281.574855) (xy 277.31983 -281.527081)
			(xy 277.343871 -281.482658) (xy 277.374895 -281.442798) (xy 277.412057 -281.408588) (xy 277.454343 -281.380962)
			(xy 277.500599 -281.360672) (xy 277.549564 -281.348272) (xy 277.599902 -281.344101) (xy 277.65024 -281.348272)
			(xy 277.699205 -281.360672) (xy 277.745461 -281.380962) (xy 277.787747 -281.408588) (xy 277.824909 -281.442798)
			(xy 277.855933 -281.482658) (xy 277.879974 -281.527081) (xy 277.896375 -281.574855) (xy 277.904688 -281.624677)
			(xy 277.90521 -281.649932) (xy 277.905038 -281.664115) (xy 277.902363 -281.692355) (xy 277.899876 -281.70632)
			(xy 277.89759 -281.718766) (xy 277.904956 -281.742388) (xy 277.982426 -281.819858) (xy 278.006048 -281.827224)
			(xy 278.018494 -281.824938) (xy 278.032461 -281.822467) (xy 278.0607 -281.819791) (xy 278.074882 -281.819604)
			(xy 278.089065 -281.819783) (xy 278.117305 -281.822453) (xy 278.13127 -281.824938) (xy 278.143716 -281.827224)
			(xy 278.167338 -281.819858) (xy 278.244808 -281.742388) (xy 278.252174 -281.718766) (xy 278.249888 -281.70632)
			(xy 278.247404 -281.692355) (xy 278.244737 -281.664115) (xy 278.244554 -281.649932) (xy 278.245043 -281.625107)
			(xy 278.253071 -281.576111) (xy 278.26892 -281.52906) (xy 278.292173 -281.485192) (xy 278.322216 -281.445664)
			(xy 278.358259 -281.411518) (xy 278.399352 -281.383653) (xy 278.444411 -281.362804) (xy 278.49225 -281.349519)
			(xy 278.541608 -281.344149) (xy 278.591185 -281.346836) (xy 278.639674 -281.357508) (xy 278.685797 -281.375885)
			(xy 278.728339 -281.401482) (xy 278.76618 -281.433624) (xy 278.798322 -281.471466) (xy 278.823918 -281.514009)
			(xy 278.842293 -281.560132) (xy 278.852965 -281.608621) (xy 278.855202 -281.649932) (xy 279.194018 -281.649932)
			(xy 279.197978 -281.600878) (xy 279.209755 -281.553094) (xy 279.229046 -281.507818) (xy 279.255349 -281.466222)
			(xy 279.287984 -281.429385) (xy 279.326105 -281.39826) (xy 279.368726 -281.373653) (xy 279.414742 -281.356201)
			(xy 279.462961 -281.346357) (xy 279.512136 -281.344376) (xy 279.560991 -281.350308) (xy 279.608262 -281.364)
			(xy 279.652724 -281.385098) (xy 279.693227 -281.413054) (xy 279.72872 -281.447146) (xy 279.758285 -281.48649)
			(xy 279.781156 -281.530067) (xy 279.79674 -281.576748) (xy 279.804635 -281.625325) (xy 279.80513 -281.649932)
			(xy 280.143978 -281.649932) (xy 280.147938 -281.600878) (xy 280.159715 -281.553094) (xy 280.179006 -281.507818)
			(xy 280.205309 -281.466222) (xy 280.237944 -281.429385) (xy 280.276065 -281.39826) (xy 280.318686 -281.373653)
			(xy 280.364702 -281.356201) (xy 280.412921 -281.346357) (xy 280.462096 -281.344376) (xy 280.510951 -281.350308)
			(xy 280.558222 -281.364) (xy 280.602684 -281.385098) (xy 280.643187 -281.413054) (xy 280.67868 -281.447146)
			(xy 280.708245 -281.48649) (xy 280.731116 -281.530067) (xy 280.7467 -281.576748) (xy 280.754595 -281.625325)
			(xy 280.75509 -281.649932) (xy 281.093938 -281.649932) (xy 281.097898 -281.600878) (xy 281.109675 -281.553094)
			(xy 281.128966 -281.507818) (xy 281.155269 -281.466222) (xy 281.187904 -281.429385) (xy 281.226025 -281.39826)
			(xy 281.268646 -281.373653) (xy 281.314662 -281.356201) (xy 281.362881 -281.346357) (xy 281.412056 -281.344376)
			(xy 281.460911 -281.350308) (xy 281.508182 -281.364) (xy 281.552644 -281.385098) (xy 281.593147 -281.413054)
			(xy 281.62864 -281.447146) (xy 281.658205 -281.48649) (xy 281.681076 -281.530067) (xy 281.69666 -281.576748)
			(xy 281.704555 -281.625325) (xy 281.70505 -281.649932) (xy 282.043898 -281.649932) (xy 282.047858 -281.600878)
			(xy 282.059635 -281.553094) (xy 282.078926 -281.507818) (xy 282.105229 -281.466222) (xy 282.137864 -281.429385)
			(xy 282.175985 -281.39826) (xy 282.218606 -281.373653) (xy 282.264622 -281.356201) (xy 282.312841 -281.346357)
			(xy 282.362016 -281.344376) (xy 282.410871 -281.350308) (xy 282.458142 -281.364) (xy 282.502604 -281.385098)
			(xy 282.543107 -281.413054) (xy 282.5786 -281.447146) (xy 282.608165 -281.48649) (xy 282.631036 -281.530067)
			(xy 282.64662 -281.576748) (xy 282.654515 -281.625325) (xy 282.65501 -281.649932) (xy 282.994112 -281.649932)
			(xy 282.998072 -281.600878) (xy 283.009849 -281.553094) (xy 283.02914 -281.507818) (xy 283.055443 -281.466222)
			(xy 283.088078 -281.429385) (xy 283.126199 -281.39826) (xy 283.16882 -281.373653) (xy 283.214836 -281.356201)
			(xy 283.263055 -281.346357) (xy 283.31223 -281.344376) (xy 283.361085 -281.350308) (xy 283.408356 -281.364)
			(xy 283.452818 -281.385098) (xy 283.493321 -281.413054) (xy 283.528814 -281.447146) (xy 283.558379 -281.48649)
			(xy 283.58125 -281.530067) (xy 283.596834 -281.576748) (xy 283.604729 -281.625325) (xy 283.605224 -281.649932)
			(xy 283.944072 -281.649932) (xy 283.948032 -281.600878) (xy 283.959809 -281.553094) (xy 283.9791 -281.507818)
			(xy 284.005403 -281.466222) (xy 284.038038 -281.429385) (xy 284.076159 -281.39826) (xy 284.11878 -281.373653)
			(xy 284.164796 -281.356201) (xy 284.213015 -281.346357) (xy 284.26219 -281.344376) (xy 284.311045 -281.350308)
			(xy 284.358316 -281.364) (xy 284.402778 -281.385098) (xy 284.443281 -281.413054) (xy 284.478774 -281.447146)
			(xy 284.508339 -281.48649) (xy 284.53121 -281.530067) (xy 284.546794 -281.576748) (xy 284.554689 -281.625325)
			(xy 284.555184 -281.649932) (xy 284.894032 -281.649932) (xy 284.897992 -281.600878) (xy 284.909769 -281.553094)
			(xy 284.92906 -281.507818) (xy 284.955363 -281.466222) (xy 284.987998 -281.429385) (xy 285.026119 -281.39826)
			(xy 285.06874 -281.373653) (xy 285.114756 -281.356201) (xy 285.162975 -281.346357) (xy 285.21215 -281.344376)
			(xy 285.261005 -281.350308) (xy 285.308276 -281.364) (xy 285.352738 -281.385098) (xy 285.393241 -281.413054)
			(xy 285.428734 -281.447146) (xy 285.458299 -281.48649) (xy 285.48117 -281.530067) (xy 285.496754 -281.576748)
			(xy 285.504649 -281.625325) (xy 285.505144 -281.649932) (xy 285.843992 -281.649932) (xy 285.847952 -281.600878)
			(xy 285.859729 -281.553094) (xy 285.87902 -281.507818) (xy 285.905323 -281.466222) (xy 285.937958 -281.429385)
			(xy 285.976079 -281.39826) (xy 286.0187 -281.373653) (xy 286.064716 -281.356201) (xy 286.112935 -281.346357)
			(xy 286.16211 -281.344376) (xy 286.210965 -281.350308) (xy 286.258236 -281.364) (xy 286.302698 -281.385098)
			(xy 286.343201 -281.413054) (xy 286.378694 -281.447146) (xy 286.408259 -281.48649) (xy 286.43113 -281.530067)
			(xy 286.446714 -281.576748) (xy 286.454609 -281.625325) (xy 286.455104 -281.649932) (xy 286.793952 -281.649932)
			(xy 286.797912 -281.600878) (xy 286.809689 -281.553094) (xy 286.82898 -281.507818) (xy 286.855283 -281.466222)
			(xy 286.887918 -281.429385) (xy 286.926039 -281.39826) (xy 286.96866 -281.373653) (xy 287.014676 -281.356201)
			(xy 287.062895 -281.346357) (xy 287.11207 -281.344376) (xy 287.160925 -281.350308) (xy 287.208196 -281.364)
			(xy 287.252658 -281.385098) (xy 287.293161 -281.413054) (xy 287.328654 -281.447146) (xy 287.358219 -281.48649)
			(xy 287.38109 -281.530067) (xy 287.396674 -281.576748) (xy 287.404569 -281.625325) (xy 287.405064 -281.649932)
			(xy 287.743912 -281.649932) (xy 287.747872 -281.600878) (xy 287.759649 -281.553094) (xy 287.77894 -281.507818)
			(xy 287.805243 -281.466222) (xy 287.837878 -281.429385) (xy 287.875999 -281.39826) (xy 287.91862 -281.373653)
			(xy 287.964636 -281.356201) (xy 288.012855 -281.346357) (xy 288.06203 -281.344376) (xy 288.110885 -281.350308)
			(xy 288.158156 -281.364) (xy 288.202618 -281.385098) (xy 288.243121 -281.413054) (xy 288.278614 -281.447146)
			(xy 288.308179 -281.48649) (xy 288.33105 -281.530067) (xy 288.346634 -281.576748) (xy 288.354529 -281.625325)
			(xy 288.355024 -281.649932) (xy 288.694126 -281.649932) (xy 288.698086 -281.600878) (xy 288.709863 -281.553094)
			(xy 288.729154 -281.507818) (xy 288.755457 -281.466222) (xy 288.788092 -281.429385) (xy 288.826213 -281.39826)
			(xy 288.868834 -281.373653) (xy 288.91485 -281.356201) (xy 288.963069 -281.346357) (xy 289.012244 -281.344376)
			(xy 289.061099 -281.350308) (xy 289.10837 -281.364) (xy 289.152832 -281.385098) (xy 289.193335 -281.413054)
			(xy 289.228828 -281.447146) (xy 289.258393 -281.48649) (xy 289.281264 -281.530067) (xy 289.296848 -281.576748)
			(xy 289.304743 -281.625325) (xy 289.305238 -281.649932) (xy 289.644086 -281.649932) (xy 289.648046 -281.600878)
			(xy 289.659823 -281.553094) (xy 289.679114 -281.507818) (xy 289.705417 -281.466222) (xy 289.738052 -281.429385)
			(xy 289.776173 -281.39826) (xy 289.818794 -281.373653) (xy 289.86481 -281.356201) (xy 289.913029 -281.346357)
			(xy 289.962204 -281.344376) (xy 290.011059 -281.350308) (xy 290.05833 -281.364) (xy 290.102792 -281.385098)
			(xy 290.143295 -281.413054) (xy 290.178788 -281.447146) (xy 290.208353 -281.48649) (xy 290.231224 -281.530067)
			(xy 290.246808 -281.576748) (xy 290.254703 -281.625325) (xy 290.255198 -281.649932) (xy 290.594046 -281.649932)
			(xy 290.598006 -281.600878) (xy 290.609783 -281.553094) (xy 290.629074 -281.507818) (xy 290.655377 -281.466222)
			(xy 290.688012 -281.429385) (xy 290.726133 -281.39826) (xy 290.768754 -281.373653) (xy 290.81477 -281.356201)
			(xy 290.862989 -281.346357) (xy 290.912164 -281.344376) (xy 290.961019 -281.350308) (xy 291.00829 -281.364)
			(xy 291.052752 -281.385098) (xy 291.093255 -281.413054) (xy 291.128748 -281.447146) (xy 291.158313 -281.48649)
			(xy 291.181184 -281.530067) (xy 291.196768 -281.576748) (xy 291.204663 -281.625325) (xy 291.205158 -281.649932)
			(xy 291.544006 -281.649932) (xy 291.547966 -281.600878) (xy 291.559743 -281.553094) (xy 291.579034 -281.507818)
			(xy 291.605337 -281.466222) (xy 291.637972 -281.429385) (xy 291.676093 -281.39826) (xy 291.718714 -281.373653)
			(xy 291.76473 -281.356201) (xy 291.812949 -281.346357) (xy 291.862124 -281.344376) (xy 291.910979 -281.350308)
			(xy 291.95825 -281.364) (xy 292.002712 -281.385098) (xy 292.043215 -281.413054) (xy 292.078708 -281.447146)
			(xy 292.108273 -281.48649) (xy 292.131144 -281.530067) (xy 292.146728 -281.576748) (xy 292.154623 -281.625325)
			(xy 292.155118 -281.649932) (xy 292.493966 -281.649932) (xy 292.497926 -281.600878) (xy 292.509703 -281.553094)
			(xy 292.528994 -281.507818) (xy 292.555297 -281.466222) (xy 292.587932 -281.429385) (xy 292.626053 -281.39826)
			(xy 292.668674 -281.373653) (xy 292.71469 -281.356201) (xy 292.762909 -281.346357) (xy 292.812084 -281.344376)
			(xy 292.860939 -281.350308) (xy 292.90821 -281.364) (xy 292.952672 -281.385098) (xy 292.993175 -281.413054)
			(xy 293.028668 -281.447146) (xy 293.058233 -281.48649) (xy 293.081104 -281.530067) (xy 293.096688 -281.576748)
			(xy 293.104583 -281.625325) (xy 293.105078 -281.649932) (xy 293.443926 -281.649932) (xy 293.447886 -281.600878)
			(xy 293.459663 -281.553094) (xy 293.478954 -281.507818) (xy 293.505257 -281.466222) (xy 293.537892 -281.429385)
			(xy 293.576013 -281.39826) (xy 293.618634 -281.373653) (xy 293.66465 -281.356201) (xy 293.712869 -281.346357)
			(xy 293.762044 -281.344376) (xy 293.810899 -281.350308) (xy 293.85817 -281.364) (xy 293.902632 -281.385098)
			(xy 293.943135 -281.413054) (xy 293.978628 -281.447146) (xy 294.008193 -281.48649) (xy 294.031064 -281.530067)
			(xy 294.046648 -281.576748) (xy 294.054543 -281.625325) (xy 294.055038 -281.649932) (xy 294.393886 -281.649932)
			(xy 294.397846 -281.600878) (xy 294.409623 -281.553094) (xy 294.428914 -281.507818) (xy 294.455217 -281.466222)
			(xy 294.487852 -281.429385) (xy 294.525973 -281.39826) (xy 294.568594 -281.373653) (xy 294.61461 -281.356201)
			(xy 294.662829 -281.346357) (xy 294.712004 -281.344376) (xy 294.760859 -281.350308) (xy 294.80813 -281.364)
			(xy 294.852592 -281.385098) (xy 294.893095 -281.413054) (xy 294.928588 -281.447146) (xy 294.958153 -281.48649)
			(xy 294.981024 -281.530067) (xy 294.996608 -281.576748) (xy 295.004503 -281.625325) (xy 295.004998 -281.649932)
			(xy 295.3441 -281.649932) (xy 295.34806 -281.600878) (xy 295.359837 -281.553094) (xy 295.379128 -281.507818)
			(xy 295.405431 -281.466222) (xy 295.438066 -281.429385) (xy 295.476187 -281.39826) (xy 295.518808 -281.373653)
			(xy 295.564824 -281.356201) (xy 295.613043 -281.346357) (xy 295.662218 -281.344376) (xy 295.711073 -281.350308)
			(xy 295.758344 -281.364) (xy 295.802806 -281.385098) (xy 295.843309 -281.413054) (xy 295.878802 -281.447146)
			(xy 295.908367 -281.48649) (xy 295.931238 -281.530067) (xy 295.946822 -281.576748) (xy 295.954717 -281.625325)
			(xy 295.955212 -281.649932) (xy 296.29406 -281.649932) (xy 296.29802 -281.600878) (xy 296.309797 -281.553094)
			(xy 296.329088 -281.507818) (xy 296.355391 -281.466222) (xy 296.388026 -281.429385) (xy 296.426147 -281.39826)
			(xy 296.468768 -281.373653) (xy 296.514784 -281.356201) (xy 296.563003 -281.346357) (xy 296.612178 -281.344376)
			(xy 296.661033 -281.350308) (xy 296.708304 -281.364) (xy 296.752766 -281.385098) (xy 296.793269 -281.413054)
			(xy 296.828762 -281.447146) (xy 296.858327 -281.48649) (xy 296.881198 -281.530067) (xy 296.896782 -281.576748)
			(xy 296.904677 -281.625325) (xy 296.905172 -281.649932) (xy 297.24402 -281.649932) (xy 297.24798 -281.600878)
			(xy 297.259757 -281.553094) (xy 297.279048 -281.507818) (xy 297.305351 -281.466222) (xy 297.337986 -281.429385)
			(xy 297.376107 -281.39826) (xy 297.418728 -281.373653) (xy 297.464744 -281.356201) (xy 297.512963 -281.346357)
			(xy 297.562138 -281.344376) (xy 297.610993 -281.350308) (xy 297.658264 -281.364) (xy 297.702726 -281.385098)
			(xy 297.743229 -281.413054) (xy 297.778722 -281.447146) (xy 297.808287 -281.48649) (xy 297.831158 -281.530067)
			(xy 297.846742 -281.576748) (xy 297.854637 -281.625325) (xy 297.855132 -281.649932) (xy 298.19398 -281.649932)
			(xy 298.19794 -281.600878) (xy 298.209717 -281.553094) (xy 298.229008 -281.507818) (xy 298.255311 -281.466222)
			(xy 298.287946 -281.429385) (xy 298.326067 -281.39826) (xy 298.368688 -281.373653) (xy 298.414704 -281.356201)
			(xy 298.462923 -281.346357) (xy 298.512098 -281.344376) (xy 298.560953 -281.350308) (xy 298.608224 -281.364)
			(xy 298.652686 -281.385098) (xy 298.693189 -281.413054) (xy 298.728682 -281.447146) (xy 298.758247 -281.48649)
			(xy 298.781118 -281.530067) (xy 298.796702 -281.576748) (xy 298.804597 -281.625325) (xy 298.805092 -281.649932)
			(xy 299.14394 -281.649932) (xy 299.1479 -281.600878) (xy 299.159677 -281.553094) (xy 299.178968 -281.507818)
			(xy 299.205271 -281.466222) (xy 299.237906 -281.429385) (xy 299.276027 -281.39826) (xy 299.318648 -281.373653)
			(xy 299.364664 -281.356201) (xy 299.412883 -281.346357) (xy 299.462058 -281.344376) (xy 299.510913 -281.350308)
			(xy 299.558184 -281.364) (xy 299.602646 -281.385098) (xy 299.643149 -281.413054) (xy 299.678642 -281.447146)
			(xy 299.708207 -281.48649) (xy 299.731078 -281.530067) (xy 299.746662 -281.576748) (xy 299.754557 -281.625325)
			(xy 299.755052 -281.649932) (xy 300.0939 -281.649932) (xy 300.09786 -281.600878) (xy 300.109637 -281.553094)
			(xy 300.128928 -281.507818) (xy 300.155231 -281.466222) (xy 300.187866 -281.429385) (xy 300.225987 -281.39826)
			(xy 300.268608 -281.373653) (xy 300.314624 -281.356201) (xy 300.362843 -281.346357) (xy 300.412018 -281.344376)
			(xy 300.460873 -281.350308) (xy 300.508144 -281.364) (xy 300.552606 -281.385098) (xy 300.593109 -281.413054)
			(xy 300.628602 -281.447146) (xy 300.658167 -281.48649) (xy 300.681038 -281.530067) (xy 300.696622 -281.576748)
			(xy 300.704517 -281.625325) (xy 300.705012 -281.649932) (xy 301.044114 -281.649932) (xy 301.048074 -281.600878)
			(xy 301.059851 -281.553094) (xy 301.079142 -281.507818) (xy 301.105445 -281.466222) (xy 301.13808 -281.429385)
			(xy 301.176201 -281.39826) (xy 301.218822 -281.373653) (xy 301.264838 -281.356201) (xy 301.313057 -281.346357)
			(xy 301.362232 -281.344376) (xy 301.411087 -281.350308) (xy 301.458358 -281.364) (xy 301.50282 -281.385098)
			(xy 301.543323 -281.413054) (xy 301.578816 -281.447146) (xy 301.608381 -281.48649) (xy 301.631252 -281.530067)
			(xy 301.646836 -281.576748) (xy 301.654731 -281.625325) (xy 301.655226 -281.649932) (xy 301.994074 -281.649932)
			(xy 301.998034 -281.600878) (xy 302.009811 -281.553094) (xy 302.029102 -281.507818) (xy 302.055405 -281.466222)
			(xy 302.08804 -281.429385) (xy 302.126161 -281.39826) (xy 302.168782 -281.373653) (xy 302.214798 -281.356201)
			(xy 302.263017 -281.346357) (xy 302.312192 -281.344376) (xy 302.361047 -281.350308) (xy 302.408318 -281.364)
			(xy 302.45278 -281.385098) (xy 302.493283 -281.413054) (xy 302.528776 -281.447146) (xy 302.558341 -281.48649)
			(xy 302.581212 -281.530067) (xy 302.596796 -281.576748) (xy 302.604691 -281.625325) (xy 302.605186 -281.649932)
			(xy 302.944034 -281.649932) (xy 302.947994 -281.600878) (xy 302.959771 -281.553094) (xy 302.979062 -281.507818)
			(xy 303.005365 -281.466222) (xy 303.038 -281.429385) (xy 303.076121 -281.39826) (xy 303.118742 -281.373653)
			(xy 303.164758 -281.356201) (xy 303.212977 -281.346357) (xy 303.262152 -281.344376) (xy 303.311007 -281.350308)
			(xy 303.358278 -281.364) (xy 303.40274 -281.385098) (xy 303.443243 -281.413054) (xy 303.478736 -281.447146)
			(xy 303.508301 -281.48649) (xy 303.531172 -281.530067) (xy 303.546756 -281.576748) (xy 303.554651 -281.625325)
			(xy 303.555146 -281.649932) (xy 303.893994 -281.649932) (xy 303.897954 -281.600878) (xy 303.909731 -281.553094)
			(xy 303.929022 -281.507818) (xy 303.955325 -281.466222) (xy 303.98796 -281.429385) (xy 304.026081 -281.39826)
			(xy 304.068702 -281.373653) (xy 304.114718 -281.356201) (xy 304.162937 -281.346357) (xy 304.212112 -281.344376)
			(xy 304.260967 -281.350308) (xy 304.308238 -281.364) (xy 304.3527 -281.385098) (xy 304.393203 -281.413054)
			(xy 304.428696 -281.447146) (xy 304.458261 -281.48649) (xy 304.481132 -281.530067) (xy 304.496716 -281.576748)
			(xy 304.504611 -281.625325) (xy 304.505106 -281.649932) (xy 304.843954 -281.649932) (xy 304.847914 -281.600878)
			(xy 304.859691 -281.553094) (xy 304.878982 -281.507818) (xy 304.905285 -281.466222) (xy 304.93792 -281.429385)
			(xy 304.976041 -281.39826) (xy 305.018662 -281.373653) (xy 305.064678 -281.356201) (xy 305.112897 -281.346357)
			(xy 305.162072 -281.344376) (xy 305.210927 -281.350308) (xy 305.258198 -281.364) (xy 305.30266 -281.385098)
			(xy 305.343163 -281.413054) (xy 305.378656 -281.447146) (xy 305.408221 -281.48649) (xy 305.431092 -281.530067)
			(xy 305.446676 -281.576748) (xy 305.454571 -281.625325) (xy 305.455066 -281.649932) (xy 305.793914 -281.649932)
			(xy 305.797874 -281.600878) (xy 305.809651 -281.553094) (xy 305.828942 -281.507818) (xy 305.855245 -281.466222)
			(xy 305.88788 -281.429385) (xy 305.926001 -281.39826) (xy 305.968622 -281.373653) (xy 306.014638 -281.356201)
			(xy 306.062857 -281.346357) (xy 306.112032 -281.344376) (xy 306.160887 -281.350308) (xy 306.208158 -281.364)
			(xy 306.25262 -281.385098) (xy 306.293123 -281.413054) (xy 306.328616 -281.447146) (xy 306.358181 -281.48649)
			(xy 306.381052 -281.530067) (xy 306.396636 -281.576748) (xy 306.404531 -281.625325) (xy 306.405026 -281.649932)
			(xy 306.744128 -281.649932) (xy 306.748088 -281.600878) (xy 306.759865 -281.553094) (xy 306.779156 -281.507818)
			(xy 306.805459 -281.466222) (xy 306.838094 -281.429385) (xy 306.876215 -281.39826) (xy 306.918836 -281.373653)
			(xy 306.964852 -281.356201) (xy 307.013071 -281.346357) (xy 307.062246 -281.344376) (xy 307.111101 -281.350308)
			(xy 307.158372 -281.364) (xy 307.202834 -281.385098) (xy 307.243337 -281.413054) (xy 307.27883 -281.447146)
			(xy 307.308395 -281.48649) (xy 307.331266 -281.530067) (xy 307.34685 -281.576748) (xy 307.354745 -281.625325)
			(xy 307.35524 -281.649932) (xy 307.694088 -281.649932) (xy 307.698048 -281.600878) (xy 307.709825 -281.553094)
			(xy 307.729116 -281.507818) (xy 307.755419 -281.466222) (xy 307.788054 -281.429385) (xy 307.826175 -281.39826)
			(xy 307.868796 -281.373653) (xy 307.914812 -281.356201) (xy 307.963031 -281.346357) (xy 308.012206 -281.344376)
			(xy 308.061061 -281.350308) (xy 308.108332 -281.364) (xy 308.152794 -281.385098) (xy 308.193297 -281.413054)
			(xy 308.22879 -281.447146) (xy 308.258355 -281.48649) (xy 308.281226 -281.530067) (xy 308.29681 -281.576748)
			(xy 308.304705 -281.625325) (xy 308.3052 -281.649932) (xy 308.644048 -281.649932) (xy 308.648008 -281.600878)
			(xy 308.659785 -281.553094) (xy 308.679076 -281.507818) (xy 308.705379 -281.466222) (xy 308.738014 -281.429385)
			(xy 308.776135 -281.39826) (xy 308.818756 -281.373653) (xy 308.864772 -281.356201) (xy 308.912991 -281.346357)
			(xy 308.962166 -281.344376) (xy 309.011021 -281.350308) (xy 309.058292 -281.364) (xy 309.102754 -281.385098)
			(xy 309.143257 -281.413054) (xy 309.17875 -281.447146) (xy 309.208315 -281.48649) (xy 309.231186 -281.530067)
			(xy 309.24677 -281.576748) (xy 309.254665 -281.625325) (xy 309.25516 -281.649932) (xy 309.254665 -281.674539)
			(xy 309.24677 -281.723116) (xy 309.231186 -281.769797) (xy 309.208315 -281.813374) (xy 309.17875 -281.852718)
			(xy 309.143257 -281.88681) (xy 309.102754 -281.914766) (xy 309.058292 -281.935864) (xy 309.011021 -281.949556)
			(xy 308.962166 -281.955488) (xy 308.912991 -281.953507) (xy 308.864772 -281.943663) (xy 308.818756 -281.926211)
			(xy 308.776135 -281.901604) (xy 308.738014 -281.870479) (xy 308.705379 -281.833642) (xy 308.679076 -281.792046)
			(xy 308.659785 -281.74677) (xy 308.648008 -281.698986) (xy 308.644048 -281.649932) (xy 308.3052 -281.649932)
			(xy 308.304705 -281.674539) (xy 308.29681 -281.723116) (xy 308.281226 -281.769797) (xy 308.258355 -281.813374)
			(xy 308.22879 -281.852718) (xy 308.193297 -281.88681) (xy 308.152794 -281.914766) (xy 308.108332 -281.935864)
			(xy 308.061061 -281.949556) (xy 308.012206 -281.955488) (xy 307.963031 -281.953507) (xy 307.914812 -281.943663)
			(xy 307.868796 -281.926211) (xy 307.826175 -281.901604) (xy 307.788054 -281.870479) (xy 307.755419 -281.833642)
			(xy 307.729116 -281.792046) (xy 307.709825 -281.74677) (xy 307.698048 -281.698986) (xy 307.694088 -281.649932)
			(xy 307.35524 -281.649932) (xy 307.354745 -281.674539) (xy 307.34685 -281.723116) (xy 307.331266 -281.769797)
			(xy 307.308395 -281.813374) (xy 307.27883 -281.852718) (xy 307.243337 -281.88681) (xy 307.202834 -281.914766)
			(xy 307.158372 -281.935864) (xy 307.111101 -281.949556) (xy 307.062246 -281.955488) (xy 307.013071 -281.953507)
			(xy 306.964852 -281.943663) (xy 306.918836 -281.926211) (xy 306.876215 -281.901604) (xy 306.838094 -281.870479)
			(xy 306.805459 -281.833642) (xy 306.779156 -281.792046) (xy 306.759865 -281.74677) (xy 306.748088 -281.698986)
			(xy 306.744128 -281.649932) (xy 306.405026 -281.649932) (xy 306.404531 -281.674539) (xy 306.396636 -281.723116)
			(xy 306.381052 -281.769797) (xy 306.358181 -281.813374) (xy 306.328616 -281.852718) (xy 306.293123 -281.88681)
			(xy 306.25262 -281.914766) (xy 306.208158 -281.935864) (xy 306.160887 -281.949556) (xy 306.112032 -281.955488)
			(xy 306.062857 -281.953507) (xy 306.014638 -281.943663) (xy 305.968622 -281.926211) (xy 305.926001 -281.901604)
			(xy 305.88788 -281.870479) (xy 305.855245 -281.833642) (xy 305.828942 -281.792046) (xy 305.809651 -281.74677)
			(xy 305.797874 -281.698986) (xy 305.793914 -281.649932) (xy 305.455066 -281.649932) (xy 305.454571 -281.674539)
			(xy 305.446676 -281.723116) (xy 305.431092 -281.769797) (xy 305.408221 -281.813374) (xy 305.378656 -281.852718)
			(xy 305.343163 -281.88681) (xy 305.30266 -281.914766) (xy 305.258198 -281.935864) (xy 305.210927 -281.949556)
			(xy 305.162072 -281.955488) (xy 305.112897 -281.953507) (xy 305.064678 -281.943663) (xy 305.018662 -281.926211)
			(xy 304.976041 -281.901604) (xy 304.93792 -281.870479) (xy 304.905285 -281.833642) (xy 304.878982 -281.792046)
			(xy 304.859691 -281.74677) (xy 304.847914 -281.698986) (xy 304.843954 -281.649932) (xy 304.505106 -281.649932)
			(xy 304.504611 -281.674539) (xy 304.496716 -281.723116) (xy 304.481132 -281.769797) (xy 304.458261 -281.813374)
			(xy 304.428696 -281.852718) (xy 304.393203 -281.88681) (xy 304.3527 -281.914766) (xy 304.308238 -281.935864)
			(xy 304.260967 -281.949556) (xy 304.212112 -281.955488) (xy 304.162937 -281.953507) (xy 304.114718 -281.943663)
			(xy 304.068702 -281.926211) (xy 304.026081 -281.901604) (xy 303.98796 -281.870479) (xy 303.955325 -281.833642)
			(xy 303.929022 -281.792046) (xy 303.909731 -281.74677) (xy 303.897954 -281.698986) (xy 303.893994 -281.649932)
			(xy 303.555146 -281.649932) (xy 303.554651 -281.674539) (xy 303.546756 -281.723116) (xy 303.531172 -281.769797)
			(xy 303.508301 -281.813374) (xy 303.478736 -281.852718) (xy 303.443243 -281.88681) (xy 303.40274 -281.914766)
			(xy 303.358278 -281.935864) (xy 303.311007 -281.949556) (xy 303.262152 -281.955488) (xy 303.212977 -281.953507)
			(xy 303.164758 -281.943663) (xy 303.118742 -281.926211) (xy 303.076121 -281.901604) (xy 303.038 -281.870479)
			(xy 303.005365 -281.833642) (xy 302.979062 -281.792046) (xy 302.959771 -281.74677) (xy 302.947994 -281.698986)
			(xy 302.944034 -281.649932) (xy 302.605186 -281.649932) (xy 302.604691 -281.674539) (xy 302.596796 -281.723116)
			(xy 302.581212 -281.769797) (xy 302.558341 -281.813374) (xy 302.528776 -281.852718) (xy 302.493283 -281.88681)
			(xy 302.45278 -281.914766) (xy 302.408318 -281.935864) (xy 302.361047 -281.949556) (xy 302.312192 -281.955488)
			(xy 302.263017 -281.953507) (xy 302.214798 -281.943663) (xy 302.168782 -281.926211) (xy 302.126161 -281.901604)
			(xy 302.08804 -281.870479) (xy 302.055405 -281.833642) (xy 302.029102 -281.792046) (xy 302.009811 -281.74677)
			(xy 301.998034 -281.698986) (xy 301.994074 -281.649932) (xy 301.655226 -281.649932) (xy 301.654731 -281.674539)
			(xy 301.646836 -281.723116) (xy 301.631252 -281.769797) (xy 301.608381 -281.813374) (xy 301.578816 -281.852718)
			(xy 301.543323 -281.88681) (xy 301.50282 -281.914766) (xy 301.458358 -281.935864) (xy 301.411087 -281.949556)
			(xy 301.362232 -281.955488) (xy 301.313057 -281.953507) (xy 301.264838 -281.943663) (xy 301.218822 -281.926211)
			(xy 301.176201 -281.901604) (xy 301.13808 -281.870479) (xy 301.105445 -281.833642) (xy 301.079142 -281.792046)
			(xy 301.059851 -281.74677) (xy 301.048074 -281.698986) (xy 301.044114 -281.649932) (xy 300.705012 -281.649932)
			(xy 300.704517 -281.674539) (xy 300.696622 -281.723116) (xy 300.681038 -281.769797) (xy 300.658167 -281.813374)
			(xy 300.628602 -281.852718) (xy 300.593109 -281.88681) (xy 300.552606 -281.914766) (xy 300.508144 -281.935864)
			(xy 300.460873 -281.949556) (xy 300.412018 -281.955488) (xy 300.362843 -281.953507) (xy 300.314624 -281.943663)
			(xy 300.268608 -281.926211) (xy 300.225987 -281.901604) (xy 300.187866 -281.870479) (xy 300.155231 -281.833642)
			(xy 300.128928 -281.792046) (xy 300.109637 -281.74677) (xy 300.09786 -281.698986) (xy 300.0939 -281.649932)
			(xy 299.755052 -281.649932) (xy 299.754557 -281.674539) (xy 299.746662 -281.723116) (xy 299.731078 -281.769797)
			(xy 299.708207 -281.813374) (xy 299.678642 -281.852718) (xy 299.643149 -281.88681) (xy 299.602646 -281.914766)
			(xy 299.558184 -281.935864) (xy 299.510913 -281.949556) (xy 299.462058 -281.955488) (xy 299.412883 -281.953507)
			(xy 299.364664 -281.943663) (xy 299.318648 -281.926211) (xy 299.276027 -281.901604) (xy 299.237906 -281.870479)
			(xy 299.205271 -281.833642) (xy 299.178968 -281.792046) (xy 299.159677 -281.74677) (xy 299.1479 -281.698986)
			(xy 299.14394 -281.649932) (xy 298.805092 -281.649932) (xy 298.804597 -281.674539) (xy 298.796702 -281.723116)
			(xy 298.781118 -281.769797) (xy 298.758247 -281.813374) (xy 298.728682 -281.852718) (xy 298.693189 -281.88681)
			(xy 298.652686 -281.914766) (xy 298.608224 -281.935864) (xy 298.560953 -281.949556) (xy 298.512098 -281.955488)
			(xy 298.462923 -281.953507) (xy 298.414704 -281.943663) (xy 298.368688 -281.926211) (xy 298.326067 -281.901604)
			(xy 298.287946 -281.870479) (xy 298.255311 -281.833642) (xy 298.229008 -281.792046) (xy 298.209717 -281.74677)
			(xy 298.19794 -281.698986) (xy 298.19398 -281.649932) (xy 297.855132 -281.649932) (xy 297.854637 -281.674539)
			(xy 297.846742 -281.723116) (xy 297.831158 -281.769797) (xy 297.808287 -281.813374) (xy 297.778722 -281.852718)
			(xy 297.743229 -281.88681) (xy 297.702726 -281.914766) (xy 297.658264 -281.935864) (xy 297.610993 -281.949556)
			(xy 297.562138 -281.955488) (xy 297.512963 -281.953507) (xy 297.464744 -281.943663) (xy 297.418728 -281.926211)
			(xy 297.376107 -281.901604) (xy 297.337986 -281.870479) (xy 297.305351 -281.833642) (xy 297.279048 -281.792046)
			(xy 297.259757 -281.74677) (xy 297.24798 -281.698986) (xy 297.24402 -281.649932) (xy 296.905172 -281.649932)
			(xy 296.904677 -281.674539) (xy 296.896782 -281.723116) (xy 296.881198 -281.769797) (xy 296.858327 -281.813374)
			(xy 296.828762 -281.852718) (xy 296.793269 -281.88681) (xy 296.752766 -281.914766) (xy 296.708304 -281.935864)
			(xy 296.661033 -281.949556) (xy 296.612178 -281.955488) (xy 296.563003 -281.953507) (xy 296.514784 -281.943663)
			(xy 296.468768 -281.926211) (xy 296.426147 -281.901604) (xy 296.388026 -281.870479) (xy 296.355391 -281.833642)
			(xy 296.329088 -281.792046) (xy 296.309797 -281.74677) (xy 296.29802 -281.698986) (xy 296.29406 -281.649932)
			(xy 295.955212 -281.649932) (xy 295.954717 -281.674539) (xy 295.946822 -281.723116) (xy 295.931238 -281.769797)
			(xy 295.908367 -281.813374) (xy 295.878802 -281.852718) (xy 295.843309 -281.88681) (xy 295.802806 -281.914766)
			(xy 295.758344 -281.935864) (xy 295.711073 -281.949556) (xy 295.662218 -281.955488) (xy 295.613043 -281.953507)
			(xy 295.564824 -281.943663) (xy 295.518808 -281.926211) (xy 295.476187 -281.901604) (xy 295.438066 -281.870479)
			(xy 295.405431 -281.833642) (xy 295.379128 -281.792046) (xy 295.359837 -281.74677) (xy 295.34806 -281.698986)
			(xy 295.3441 -281.649932) (xy 295.004998 -281.649932) (xy 295.004503 -281.674539) (xy 294.996608 -281.723116)
			(xy 294.981024 -281.769797) (xy 294.958153 -281.813374) (xy 294.928588 -281.852718) (xy 294.893095 -281.88681)
			(xy 294.852592 -281.914766) (xy 294.80813 -281.935864) (xy 294.760859 -281.949556) (xy 294.712004 -281.955488)
			(xy 294.662829 -281.953507) (xy 294.61461 -281.943663) (xy 294.568594 -281.926211) (xy 294.525973 -281.901604)
			(xy 294.487852 -281.870479) (xy 294.455217 -281.833642) (xy 294.428914 -281.792046) (xy 294.409623 -281.74677)
			(xy 294.397846 -281.698986) (xy 294.393886 -281.649932) (xy 294.055038 -281.649932) (xy 294.054543 -281.674539)
			(xy 294.046648 -281.723116) (xy 294.031064 -281.769797) (xy 294.008193 -281.813374) (xy 293.978628 -281.852718)
			(xy 293.943135 -281.88681) (xy 293.902632 -281.914766) (xy 293.85817 -281.935864) (xy 293.810899 -281.949556)
			(xy 293.762044 -281.955488) (xy 293.712869 -281.953507) (xy 293.66465 -281.943663) (xy 293.618634 -281.926211)
			(xy 293.576013 -281.901604) (xy 293.537892 -281.870479) (xy 293.505257 -281.833642) (xy 293.478954 -281.792046)
			(xy 293.459663 -281.74677) (xy 293.447886 -281.698986) (xy 293.443926 -281.649932) (xy 293.105078 -281.649932)
			(xy 293.104583 -281.674539) (xy 293.096688 -281.723116) (xy 293.081104 -281.769797) (xy 293.058233 -281.813374)
			(xy 293.028668 -281.852718) (xy 292.993175 -281.88681) (xy 292.952672 -281.914766) (xy 292.90821 -281.935864)
			(xy 292.860939 -281.949556) (xy 292.812084 -281.955488) (xy 292.762909 -281.953507) (xy 292.71469 -281.943663)
			(xy 292.668674 -281.926211) (xy 292.626053 -281.901604) (xy 292.587932 -281.870479) (xy 292.555297 -281.833642)
			(xy 292.528994 -281.792046) (xy 292.509703 -281.74677) (xy 292.497926 -281.698986) (xy 292.493966 -281.649932)
			(xy 292.155118 -281.649932) (xy 292.154623 -281.674539) (xy 292.146728 -281.723116) (xy 292.131144 -281.769797)
			(xy 292.108273 -281.813374) (xy 292.078708 -281.852718) (xy 292.043215 -281.88681) (xy 292.002712 -281.914766)
			(xy 291.95825 -281.935864) (xy 291.910979 -281.949556) (xy 291.862124 -281.955488) (xy 291.812949 -281.953507)
			(xy 291.76473 -281.943663) (xy 291.718714 -281.926211) (xy 291.676093 -281.901604) (xy 291.637972 -281.870479)
			(xy 291.605337 -281.833642) (xy 291.579034 -281.792046) (xy 291.559743 -281.74677) (xy 291.547966 -281.698986)
			(xy 291.544006 -281.649932) (xy 291.205158 -281.649932) (xy 291.204663 -281.674539) (xy 291.196768 -281.723116)
			(xy 291.181184 -281.769797) (xy 291.158313 -281.813374) (xy 291.128748 -281.852718) (xy 291.093255 -281.88681)
			(xy 291.052752 -281.914766) (xy 291.00829 -281.935864) (xy 290.961019 -281.949556) (xy 290.912164 -281.955488)
			(xy 290.862989 -281.953507) (xy 290.81477 -281.943663) (xy 290.768754 -281.926211) (xy 290.726133 -281.901604)
			(xy 290.688012 -281.870479) (xy 290.655377 -281.833642) (xy 290.629074 -281.792046) (xy 290.609783 -281.74677)
			(xy 290.598006 -281.698986) (xy 290.594046 -281.649932) (xy 290.255198 -281.649932) (xy 290.254703 -281.674539)
			(xy 290.246808 -281.723116) (xy 290.231224 -281.769797) (xy 290.208353 -281.813374) (xy 290.178788 -281.852718)
			(xy 290.143295 -281.88681) (xy 290.102792 -281.914766) (xy 290.05833 -281.935864) (xy 290.011059 -281.949556)
			(xy 289.962204 -281.955488) (xy 289.913029 -281.953507) (xy 289.86481 -281.943663) (xy 289.818794 -281.926211)
			(xy 289.776173 -281.901604) (xy 289.738052 -281.870479) (xy 289.705417 -281.833642) (xy 289.679114 -281.792046)
			(xy 289.659823 -281.74677) (xy 289.648046 -281.698986) (xy 289.644086 -281.649932) (xy 289.305238 -281.649932)
			(xy 289.304743 -281.674539) (xy 289.296848 -281.723116) (xy 289.281264 -281.769797) (xy 289.258393 -281.813374)
			(xy 289.228828 -281.852718) (xy 289.193335 -281.88681) (xy 289.152832 -281.914766) (xy 289.10837 -281.935864)
			(xy 289.061099 -281.949556) (xy 289.012244 -281.955488) (xy 288.963069 -281.953507) (xy 288.91485 -281.943663)
			(xy 288.868834 -281.926211) (xy 288.826213 -281.901604) (xy 288.788092 -281.870479) (xy 288.755457 -281.833642)
			(xy 288.729154 -281.792046) (xy 288.709863 -281.74677) (xy 288.698086 -281.698986) (xy 288.694126 -281.649932)
			(xy 288.355024 -281.649932) (xy 288.354529 -281.674539) (xy 288.346634 -281.723116) (xy 288.33105 -281.769797)
			(xy 288.308179 -281.813374) (xy 288.278614 -281.852718) (xy 288.243121 -281.88681) (xy 288.202618 -281.914766)
			(xy 288.158156 -281.935864) (xy 288.110885 -281.949556) (xy 288.06203 -281.955488) (xy 288.012855 -281.953507)
			(xy 287.964636 -281.943663) (xy 287.91862 -281.926211) (xy 287.875999 -281.901604) (xy 287.837878 -281.870479)
			(xy 287.805243 -281.833642) (xy 287.77894 -281.792046) (xy 287.759649 -281.74677) (xy 287.747872 -281.698986)
			(xy 287.743912 -281.649932) (xy 287.405064 -281.649932) (xy 287.404569 -281.674539) (xy 287.396674 -281.723116)
			(xy 287.38109 -281.769797) (xy 287.358219 -281.813374) (xy 287.328654 -281.852718) (xy 287.293161 -281.88681)
			(xy 287.252658 -281.914766) (xy 287.208196 -281.935864) (xy 287.160925 -281.949556) (xy 287.11207 -281.955488)
			(xy 287.062895 -281.953507) (xy 287.014676 -281.943663) (xy 286.96866 -281.926211) (xy 286.926039 -281.901604)
			(xy 286.887918 -281.870479) (xy 286.855283 -281.833642) (xy 286.82898 -281.792046) (xy 286.809689 -281.74677)
			(xy 286.797912 -281.698986) (xy 286.793952 -281.649932) (xy 286.455104 -281.649932) (xy 286.454609 -281.674539)
			(xy 286.446714 -281.723116) (xy 286.43113 -281.769797) (xy 286.408259 -281.813374) (xy 286.378694 -281.852718)
			(xy 286.343201 -281.88681) (xy 286.302698 -281.914766) (xy 286.258236 -281.935864) (xy 286.210965 -281.949556)
			(xy 286.16211 -281.955488) (xy 286.112935 -281.953507) (xy 286.064716 -281.943663) (xy 286.0187 -281.926211)
			(xy 285.976079 -281.901604) (xy 285.937958 -281.870479) (xy 285.905323 -281.833642) (xy 285.87902 -281.792046)
			(xy 285.859729 -281.74677) (xy 285.847952 -281.698986) (xy 285.843992 -281.649932) (xy 285.505144 -281.649932)
			(xy 285.504649 -281.674539) (xy 285.496754 -281.723116) (xy 285.48117 -281.769797) (xy 285.458299 -281.813374)
			(xy 285.428734 -281.852718) (xy 285.393241 -281.88681) (xy 285.352738 -281.914766) (xy 285.308276 -281.935864)
			(xy 285.261005 -281.949556) (xy 285.21215 -281.955488) (xy 285.162975 -281.953507) (xy 285.114756 -281.943663)
			(xy 285.06874 -281.926211) (xy 285.026119 -281.901604) (xy 284.987998 -281.870479) (xy 284.955363 -281.833642)
			(xy 284.92906 -281.792046) (xy 284.909769 -281.74677) (xy 284.897992 -281.698986) (xy 284.894032 -281.649932)
			(xy 284.555184 -281.649932) (xy 284.554689 -281.674539) (xy 284.546794 -281.723116) (xy 284.53121 -281.769797)
			(xy 284.508339 -281.813374) (xy 284.478774 -281.852718) (xy 284.443281 -281.88681) (xy 284.402778 -281.914766)
			(xy 284.358316 -281.935864) (xy 284.311045 -281.949556) (xy 284.26219 -281.955488) (xy 284.213015 -281.953507)
			(xy 284.164796 -281.943663) (xy 284.11878 -281.926211) (xy 284.076159 -281.901604) (xy 284.038038 -281.870479)
			(xy 284.005403 -281.833642) (xy 283.9791 -281.792046) (xy 283.959809 -281.74677) (xy 283.948032 -281.698986)
			(xy 283.944072 -281.649932) (xy 283.605224 -281.649932) (xy 283.604729 -281.674539) (xy 283.596834 -281.723116)
			(xy 283.58125 -281.769797) (xy 283.558379 -281.813374) (xy 283.528814 -281.852718) (xy 283.493321 -281.88681)
			(xy 283.452818 -281.914766) (xy 283.408356 -281.935864) (xy 283.361085 -281.949556) (xy 283.31223 -281.955488)
			(xy 283.263055 -281.953507) (xy 283.214836 -281.943663) (xy 283.16882 -281.926211) (xy 283.126199 -281.901604)
			(xy 283.088078 -281.870479) (xy 283.055443 -281.833642) (xy 283.02914 -281.792046) (xy 283.009849 -281.74677)
			(xy 282.998072 -281.698986) (xy 282.994112 -281.649932) (xy 282.65501 -281.649932) (xy 282.654515 -281.674539)
			(xy 282.64662 -281.723116) (xy 282.631036 -281.769797) (xy 282.608165 -281.813374) (xy 282.5786 -281.852718)
			(xy 282.543107 -281.88681) (xy 282.502604 -281.914766) (xy 282.458142 -281.935864) (xy 282.410871 -281.949556)
			(xy 282.362016 -281.955488) (xy 282.312841 -281.953507) (xy 282.264622 -281.943663) (xy 282.218606 -281.926211)
			(xy 282.175985 -281.901604) (xy 282.137864 -281.870479) (xy 282.105229 -281.833642) (xy 282.078926 -281.792046)
			(xy 282.059635 -281.74677) (xy 282.047858 -281.698986) (xy 282.043898 -281.649932) (xy 281.70505 -281.649932)
			(xy 281.704555 -281.674539) (xy 281.69666 -281.723116) (xy 281.681076 -281.769797) (xy 281.658205 -281.813374)
			(xy 281.62864 -281.852718) (xy 281.593147 -281.88681) (xy 281.552644 -281.914766) (xy 281.508182 -281.935864)
			(xy 281.460911 -281.949556) (xy 281.412056 -281.955488) (xy 281.362881 -281.953507) (xy 281.314662 -281.943663)
			(xy 281.268646 -281.926211) (xy 281.226025 -281.901604) (xy 281.187904 -281.870479) (xy 281.155269 -281.833642)
			(xy 281.128966 -281.792046) (xy 281.109675 -281.74677) (xy 281.097898 -281.698986) (xy 281.093938 -281.649932)
			(xy 280.75509 -281.649932) (xy 280.754595 -281.674539) (xy 280.7467 -281.723116) (xy 280.731116 -281.769797)
			(xy 280.708245 -281.813374) (xy 280.67868 -281.852718) (xy 280.643187 -281.88681) (xy 280.602684 -281.914766)
			(xy 280.558222 -281.935864) (xy 280.510951 -281.949556) (xy 280.462096 -281.955488) (xy 280.412921 -281.953507)
			(xy 280.364702 -281.943663) (xy 280.318686 -281.926211) (xy 280.276065 -281.901604) (xy 280.237944 -281.870479)
			(xy 280.205309 -281.833642) (xy 280.179006 -281.792046) (xy 280.159715 -281.74677) (xy 280.147938 -281.698986)
			(xy 280.143978 -281.649932) (xy 279.80513 -281.649932) (xy 279.804635 -281.674539) (xy 279.79674 -281.723116)
			(xy 279.781156 -281.769797) (xy 279.758285 -281.813374) (xy 279.72872 -281.852718) (xy 279.693227 -281.88681)
			(xy 279.652724 -281.914766) (xy 279.608262 -281.935864) (xy 279.560991 -281.949556) (xy 279.512136 -281.955488)
			(xy 279.462961 -281.953507) (xy 279.414742 -281.943663) (xy 279.368726 -281.926211) (xy 279.326105 -281.901604)
			(xy 279.287984 -281.870479) (xy 279.255349 -281.833642) (xy 279.229046 -281.792046) (xy 279.209755 -281.74677)
			(xy 279.197978 -281.698986) (xy 279.194018 -281.649932) (xy 278.855202 -281.649932) (xy 278.85565 -281.658198)
			(xy 278.85028 -281.707556) (xy 278.836994 -281.755394) (xy 278.816144 -281.800453) (xy 278.788278 -281.841546)
			(xy 278.754131 -281.877588) (xy 278.714603 -281.907631) (xy 278.670735 -281.930882) (xy 278.623683 -281.94673)
			(xy 278.574687 -281.954757) (xy 278.549862 -281.95524) (xy 278.535679 -281.955068) (xy 278.507439 -281.952393)
			(xy 278.493474 -281.949906) (xy 278.481028 -281.94762) (xy 278.457406 -281.954986) (xy 278.379936 -282.032456)
			(xy 278.37257 -282.056078) (xy 278.374856 -282.068524) (xy 278.377331 -282.08249) (xy 278.380004 -282.11073)
			(xy 278.38019 -282.124912) (xy 278.379668 -282.150167) (xy 278.371355 -282.199989) (xy 278.354954 -282.247763)
			(xy 278.330913 -282.292186) (xy 278.299889 -282.332046) (xy 278.262727 -282.366256) (xy 278.220441 -282.393882)
			(xy 278.174185 -282.414172) (xy 278.12522 -282.426572) (xy 278.074882 -282.430743) (xy 278.024544 -282.426572)
			(xy 277.975579 -282.414172) (xy 277.929323 -282.393882) (xy 277.887037 -282.366256) (xy 277.849875 -282.332046)
			(xy 277.818851 -282.292186) (xy 277.79481 -282.247763) (xy 277.778409 -282.199989) (xy 277.770096 -282.150167)
			(xy 277.769574 -282.124912) (xy 277.769753 -282.110729) (xy 277.772423 -282.082489) (xy 277.774908 -282.068524)
			(xy 277.777194 -282.056078) (xy 277.769828 -282.032456) (xy 277.692358 -281.954986) (xy 277.668736 -281.94762)
			(xy 277.65629 -281.949906) (xy 277.642324 -281.95238) (xy 277.614084 -281.955053) (xy 277.599902 -281.95524)
			(xy 277.585719 -281.955063) (xy 277.557479 -281.952391) (xy 277.543514 -281.949906) (xy 277.531068 -281.94762)
			(xy 277.507446 -281.954986) (xy 277.429976 -282.032456) (xy 277.42261 -282.056078) (xy 277.424896 -282.068524)
			(xy 277.427372 -282.08249) (xy 277.430044 -282.110729) (xy 277.43023 -282.124912) (xy 277.429708 -282.150167)
			(xy 277.421395 -282.199989) (xy 277.404994 -282.247763) (xy 277.380953 -282.292186) (xy 277.349929 -282.332046)
			(xy 277.312767 -282.366256) (xy 277.270481 -282.393882) (xy 277.224225 -282.414172) (xy 277.17526 -282.426572)
			(xy 277.124922 -282.430743) (xy 277.074584 -282.426572) (xy 277.025619 -282.414172) (xy 276.979363 -282.393882)
			(xy 276.937077 -282.366256) (xy 276.899915 -282.332046) (xy 276.868891 -282.292186) (xy 276.84485 -282.247763)
			(xy 276.828449 -282.199989) (xy 276.820136 -282.150167) (xy 276.819614 -282.124912) (xy 276.819792 -282.110729)
			(xy 276.822463 -282.082489) (xy 276.824948 -282.068524) (xy 276.824948 -282.06827) (xy 276.826425 -282.056039)
			(xy 276.819127 -282.032551) (xy 276.810978 -282.023312) (xy 276.742398 -281.954986) (xy 276.718776 -281.94762)
			(xy 276.70633 -281.949906) (xy 276.692302 -281.952398) (xy 276.663934 -281.955065) (xy 276.649688 -281.95524)
			(xy 276.635505 -281.955064) (xy 276.607265 -281.952392) (xy 276.5933 -281.949906) (xy 276.580854 -281.94762)
			(xy 276.557232 -281.954986) (xy 276.479762 -282.032456) (xy 276.472396 -282.056078) (xy 276.474682 -282.068524)
			(xy 276.477158 -282.08249) (xy 276.47983 -282.11073) (xy 276.480016 -282.124912) (xy 276.479509 -282.149732)
			(xy 276.471476 -282.198717) (xy 276.455625 -282.245758) (xy 276.432371 -282.289614) (xy 276.402329 -282.329131)
			(xy 276.36629 -282.363266) (xy 276.325203 -282.391122) (xy 276.28015 -282.411964) (xy 276.23232 -282.425242)
			(xy 276.182971 -282.430607) (xy 276.133404 -282.427918) (xy 276.084925 -282.417245) (xy 276.038812 -282.39887)
			(xy 275.996279 -282.373277) (xy 275.958446 -282.34114) (xy 275.926311 -282.303305) (xy 275.900721 -282.26077)
			(xy 275.882349 -282.214656) (xy 275.871679 -282.166176) (xy 275.868993 -282.116609) (xy 275.874362 -282.067261)
			(xy 275.887643 -282.019431) (xy 275.908488 -281.97438) (xy 275.936346 -281.933295) (xy 275.970484 -281.897257)
			(xy 276.010003 -281.867218) (xy 276.053861 -281.843967) (xy 276.100902 -281.828119) (xy 276.149888 -281.820089)
			(xy 276.174708 -281.819604) (xy 276.188891 -281.819779) (xy 276.217131 -281.822452) (xy 276.231096 -281.824938)
			(xy 276.243542 -281.827224) (xy 276.267164 -281.819858) (xy 276.344634 -281.742388) (xy 276.352 -281.718766)
			(xy 276.349714 -281.70632) (xy 276.347231 -281.692355) (xy 276.344563 -281.664115) (xy 276.34438 -281.649932)
			(xy 276.344561 -281.635749) (xy 276.34723 -281.607509) (xy 276.349714 -281.593544) (xy 276.352 -281.581098)
			(xy 276.344634 -281.557476) (xy 276.267164 -281.480006) (xy 276.243542 -281.47264) (xy 276.231096 -281.474926)
			(xy 276.21713 -281.477399) (xy 276.18889 -281.480073) (xy 276.174708 -281.48026) (xy 276.149446 -281.479864)
			(xy 276.099611 -281.471549) (xy 276.051824 -281.455145) (xy 276.007388 -281.431099) (xy 275.967517 -281.400067)
			(xy 275.933298 -281.362895) (xy 275.905663 -281.320598) (xy 275.885367 -281.27433) (xy 275.872964 -281.225352)
			(xy 275.868792 -281.175) (xy 275.530055 -281.175) (xy 275.529561 -281.199559) (xy 275.521666 -281.248136)
			(xy 275.506082 -281.294817) (xy 275.483211 -281.338394) (xy 275.453646 -281.377738) (xy 275.418153 -281.41183)
			(xy 275.37765 -281.439786) (xy 275.333188 -281.460884) (xy 275.285917 -281.474576) (xy 275.237062 -281.480508)
			(xy 275.187887 -281.478527) (xy 275.139668 -281.468683) (xy 275.093652 -281.451231) (xy 275.051031 -281.426624)
			(xy 275.01291 -281.395499) (xy 274.980275 -281.358662) (xy 274.953972 -281.317066) (xy 274.934681 -281.27179)
			(xy 274.922904 -281.224006) (xy 274.918944 -281.174952) (xy 274.580096 -281.174952) (xy 274.579601 -281.199559)
			(xy 274.571706 -281.248136) (xy 274.556122 -281.294817) (xy 274.533251 -281.338394) (xy 274.503686 -281.377738)
			(xy 274.468193 -281.41183) (xy 274.42769 -281.439786) (xy 274.383228 -281.460884) (xy 274.335957 -281.474576)
			(xy 274.287102 -281.480508) (xy 274.237927 -281.478527) (xy 274.189708 -281.468683) (xy 274.143692 -281.451231)
			(xy 274.101071 -281.426624) (xy 274.06295 -281.395499) (xy 274.030315 -281.358662) (xy 274.004012 -281.317066)
			(xy 273.984721 -281.27179) (xy 273.972944 -281.224006) (xy 273.968984 -281.174952) (xy 273.630136 -281.174952)
			(xy 273.629641 -281.199559) (xy 273.621746 -281.248136) (xy 273.606162 -281.294817) (xy 273.583291 -281.338394)
			(xy 273.553726 -281.377738) (xy 273.518233 -281.41183) (xy 273.47773 -281.439786) (xy 273.433268 -281.460884)
			(xy 273.385997 -281.474576) (xy 273.337142 -281.480508) (xy 273.287967 -281.478527) (xy 273.239748 -281.468683)
			(xy 273.193732 -281.451231) (xy 273.151111 -281.426624) (xy 273.11299 -281.395499) (xy 273.080355 -281.358662)
			(xy 273.054052 -281.317066) (xy 273.034761 -281.27179) (xy 273.022984 -281.224006) (xy 273.019024 -281.174952)
			(xy 272.680176 -281.174952) (xy 272.679681 -281.199559) (xy 272.671786 -281.248136) (xy 272.656202 -281.294817)
			(xy 272.633331 -281.338394) (xy 272.603766 -281.377738) (xy 272.568273 -281.41183) (xy 272.52777 -281.439786)
			(xy 272.483308 -281.460884) (xy 272.436037 -281.474576) (xy 272.387182 -281.480508) (xy 272.338007 -281.478527)
			(xy 272.289788 -281.468683) (xy 272.243772 -281.451231) (xy 272.201151 -281.426624) (xy 272.16303 -281.395499)
			(xy 272.130395 -281.358662) (xy 272.104092 -281.317066) (xy 272.084801 -281.27179) (xy 272.073024 -281.224006)
			(xy 272.069064 -281.174952) (xy 271.730216 -281.174952) (xy 271.729721 -281.199559) (xy 271.721826 -281.248136)
			(xy 271.706242 -281.294817) (xy 271.683371 -281.338394) (xy 271.653806 -281.377738) (xy 271.618313 -281.41183)
			(xy 271.57781 -281.439786) (xy 271.533348 -281.460884) (xy 271.486077 -281.474576) (xy 271.437222 -281.480508)
			(xy 271.388047 -281.478527) (xy 271.339828 -281.468683) (xy 271.293812 -281.451231) (xy 271.251191 -281.426624)
			(xy 271.21307 -281.395499) (xy 271.180435 -281.358662) (xy 271.154132 -281.317066) (xy 271.134841 -281.27179)
			(xy 271.123064 -281.224006) (xy 271.119104 -281.174952) (xy 270.780256 -281.174952) (xy 270.779761 -281.199559)
			(xy 270.771866 -281.248136) (xy 270.756282 -281.294817) (xy 270.733411 -281.338394) (xy 270.703846 -281.377738)
			(xy 270.668353 -281.41183) (xy 270.62785 -281.439786) (xy 270.583388 -281.460884) (xy 270.536117 -281.474576)
			(xy 270.487262 -281.480508) (xy 270.438087 -281.478527) (xy 270.389868 -281.468683) (xy 270.343852 -281.451231)
			(xy 270.301231 -281.426624) (xy 270.26311 -281.395499) (xy 270.230475 -281.358662) (xy 270.204172 -281.317066)
			(xy 270.184881 -281.27179) (xy 270.173104 -281.224006) (xy 270.169144 -281.174952) (xy 269.830042 -281.174952)
			(xy 269.829547 -281.199559) (xy 269.821652 -281.248136) (xy 269.806068 -281.294817) (xy 269.783197 -281.338394)
			(xy 269.753632 -281.377738) (xy 269.718139 -281.41183) (xy 269.677636 -281.439786) (xy 269.633174 -281.460884)
			(xy 269.585903 -281.474576) (xy 269.537048 -281.480508) (xy 269.487873 -281.478527) (xy 269.439654 -281.468683)
			(xy 269.393638 -281.451231) (xy 269.351017 -281.426624) (xy 269.312896 -281.395499) (xy 269.280261 -281.358662)
			(xy 269.253958 -281.317066) (xy 269.234667 -281.27179) (xy 269.22289 -281.224006) (xy 269.21893 -281.174952)
			(xy 268.880082 -281.174952) (xy 268.879587 -281.199559) (xy 268.871692 -281.248136) (xy 268.856108 -281.294817)
			(xy 268.833237 -281.338394) (xy 268.803672 -281.377738) (xy 268.768179 -281.41183) (xy 268.727676 -281.439786)
			(xy 268.683214 -281.460884) (xy 268.635943 -281.474576) (xy 268.587088 -281.480508) (xy 268.537913 -281.478527)
			(xy 268.489694 -281.468683) (xy 268.443678 -281.451231) (xy 268.401057 -281.426624) (xy 268.362936 -281.395499)
			(xy 268.330301 -281.358662) (xy 268.303998 -281.317066) (xy 268.284707 -281.27179) (xy 268.27293 -281.224006)
			(xy 268.26897 -281.174952) (xy 266.590526 -281.174952) (xy 266.590526 -282.124912) (xy 268.26897 -282.124912)
			(xy 268.27293 -282.075858) (xy 268.284707 -282.028074) (xy 268.303998 -281.982798) (xy 268.330301 -281.941202)
			(xy 268.362936 -281.904365) (xy 268.401057 -281.87324) (xy 268.443678 -281.848633) (xy 268.489694 -281.831181)
			(xy 268.537913 -281.821337) (xy 268.587088 -281.819356) (xy 268.635943 -281.825288) (xy 268.683214 -281.83898)
			(xy 268.727676 -281.860078) (xy 268.768179 -281.888034) (xy 268.803672 -281.922126) (xy 268.833237 -281.96147)
			(xy 268.856108 -282.005047) (xy 268.871692 -282.051728) (xy 268.879587 -282.100305) (xy 268.880082 -282.124912)
			(xy 269.21893 -282.124912) (xy 269.22289 -282.075858) (xy 269.234667 -282.028074) (xy 269.253958 -281.982798)
			(xy 269.280261 -281.941202) (xy 269.312896 -281.904365) (xy 269.351017 -281.87324) (xy 269.393638 -281.848633)
			(xy 269.439654 -281.831181) (xy 269.487873 -281.821337) (xy 269.537048 -281.819356) (xy 269.585903 -281.825288)
			(xy 269.633174 -281.83898) (xy 269.677636 -281.860078) (xy 269.718139 -281.888034) (xy 269.753632 -281.922126)
			(xy 269.783197 -281.96147) (xy 269.806068 -282.005047) (xy 269.821652 -282.051728) (xy 269.829547 -282.100305)
			(xy 269.830042 -282.124912) (xy 270.169144 -282.124912) (xy 270.173104 -282.075858) (xy 270.184881 -282.028074)
			(xy 270.204172 -281.982798) (xy 270.230475 -281.941202) (xy 270.26311 -281.904365) (xy 270.301231 -281.87324)
			(xy 270.343852 -281.848633) (xy 270.389868 -281.831181) (xy 270.438087 -281.821337) (xy 270.487262 -281.819356)
			(xy 270.536117 -281.825288) (xy 270.583388 -281.83898) (xy 270.62785 -281.860078) (xy 270.668353 -281.888034)
			(xy 270.703846 -281.922126) (xy 270.733411 -281.96147) (xy 270.756282 -282.005047) (xy 270.771866 -282.051728)
			(xy 270.779761 -282.100305) (xy 270.780256 -282.124912) (xy 271.119104 -282.124912) (xy 271.123064 -282.075858)
			(xy 271.134841 -282.028074) (xy 271.154132 -281.982798) (xy 271.180435 -281.941202) (xy 271.21307 -281.904365)
			(xy 271.251191 -281.87324) (xy 271.293812 -281.848633) (xy 271.339828 -281.831181) (xy 271.388047 -281.821337)
			(xy 271.437222 -281.819356) (xy 271.486077 -281.825288) (xy 271.533348 -281.83898) (xy 271.57781 -281.860078)
			(xy 271.618313 -281.888034) (xy 271.653806 -281.922126) (xy 271.683371 -281.96147) (xy 271.706242 -282.005047)
			(xy 271.721826 -282.051728) (xy 271.729721 -282.100305) (xy 271.730216 -282.124912) (xy 272.069064 -282.124912)
			(xy 272.073024 -282.075858) (xy 272.084801 -282.028074) (xy 272.104092 -281.982798) (xy 272.130395 -281.941202)
			(xy 272.16303 -281.904365) (xy 272.201151 -281.87324) (xy 272.243772 -281.848633) (xy 272.289788 -281.831181)
			(xy 272.338007 -281.821337) (xy 272.387182 -281.819356) (xy 272.436037 -281.825288) (xy 272.483308 -281.83898)
			(xy 272.52777 -281.860078) (xy 272.568273 -281.888034) (xy 272.603766 -281.922126) (xy 272.633331 -281.96147)
			(xy 272.656202 -282.005047) (xy 272.671786 -282.051728) (xy 272.679681 -282.100305) (xy 272.680176 -282.124912)
			(xy 273.019024 -282.124912) (xy 273.022984 -282.075858) (xy 273.034761 -282.028074) (xy 273.054052 -281.982798)
			(xy 273.080355 -281.941202) (xy 273.11299 -281.904365) (xy 273.151111 -281.87324) (xy 273.193732 -281.848633)
			(xy 273.239748 -281.831181) (xy 273.287967 -281.821337) (xy 273.337142 -281.819356) (xy 273.385997 -281.825288)
			(xy 273.433268 -281.83898) (xy 273.47773 -281.860078) (xy 273.518233 -281.888034) (xy 273.553726 -281.922126)
			(xy 273.583291 -281.96147) (xy 273.606162 -282.005047) (xy 273.621746 -282.051728) (xy 273.629641 -282.100305)
			(xy 273.630136 -282.124912) (xy 273.968984 -282.124912) (xy 273.972944 -282.075858) (xy 273.984721 -282.028074)
			(xy 274.004012 -281.982798) (xy 274.030315 -281.941202) (xy 274.06295 -281.904365) (xy 274.101071 -281.87324)
			(xy 274.143692 -281.848633) (xy 274.189708 -281.831181) (xy 274.237927 -281.821337) (xy 274.287102 -281.819356)
			(xy 274.335957 -281.825288) (xy 274.383228 -281.83898) (xy 274.42769 -281.860078) (xy 274.468193 -281.888034)
			(xy 274.503686 -281.922126) (xy 274.533251 -281.96147) (xy 274.556122 -282.005047) (xy 274.571706 -282.051728)
			(xy 274.579601 -282.100305) (xy 274.580096 -282.124912) (xy 274.918944 -282.124912) (xy 274.922904 -282.075858)
			(xy 274.934681 -282.028074) (xy 274.953972 -281.982798) (xy 274.980275 -281.941202) (xy 275.01291 -281.904365)
			(xy 275.051031 -281.87324) (xy 275.093652 -281.848633) (xy 275.139668 -281.831181) (xy 275.187887 -281.821337)
			(xy 275.237062 -281.819356) (xy 275.285917 -281.825288) (xy 275.333188 -281.83898) (xy 275.37765 -281.860078)
			(xy 275.418153 -281.888034) (xy 275.453646 -281.922126) (xy 275.483211 -281.96147) (xy 275.506082 -282.005047)
			(xy 275.521666 -282.051728) (xy 275.529561 -282.100305) (xy 275.530056 -282.124912) (xy 275.529561 -282.149519)
			(xy 275.521666 -282.198096) (xy 275.506082 -282.244777) (xy 275.483211 -282.288354) (xy 275.453646 -282.327698)
			(xy 275.418153 -282.36179) (xy 275.37765 -282.389746) (xy 275.333188 -282.410844) (xy 275.285917 -282.424536)
			(xy 275.237062 -282.430468) (xy 275.187887 -282.428487) (xy 275.139668 -282.418643) (xy 275.093652 -282.401191)
			(xy 275.051031 -282.376584) (xy 275.01291 -282.345459) (xy 274.980275 -282.308622) (xy 274.953972 -282.267026)
			(xy 274.934681 -282.22175) (xy 274.922904 -282.173966) (xy 274.918944 -282.124912) (xy 274.580096 -282.124912)
			(xy 274.579601 -282.149519) (xy 274.571706 -282.198096) (xy 274.556122 -282.244777) (xy 274.533251 -282.288354)
			(xy 274.503686 -282.327698) (xy 274.468193 -282.36179) (xy 274.42769 -282.389746) (xy 274.383228 -282.410844)
			(xy 274.335957 -282.424536) (xy 274.287102 -282.430468) (xy 274.237927 -282.428487) (xy 274.189708 -282.418643)
			(xy 274.143692 -282.401191) (xy 274.101071 -282.376584) (xy 274.06295 -282.345459) (xy 274.030315 -282.308622)
			(xy 274.004012 -282.267026) (xy 273.984721 -282.22175) (xy 273.972944 -282.173966) (xy 273.968984 -282.124912)
			(xy 273.630136 -282.124912) (xy 273.629641 -282.149519) (xy 273.621746 -282.198096) (xy 273.606162 -282.244777)
			(xy 273.583291 -282.288354) (xy 273.553726 -282.327698) (xy 273.518233 -282.36179) (xy 273.47773 -282.389746)
			(xy 273.433268 -282.410844) (xy 273.385997 -282.424536) (xy 273.337142 -282.430468) (xy 273.287967 -282.428487)
			(xy 273.239748 -282.418643) (xy 273.193732 -282.401191) (xy 273.151111 -282.376584) (xy 273.11299 -282.345459)
			(xy 273.080355 -282.308622) (xy 273.054052 -282.267026) (xy 273.034761 -282.22175) (xy 273.022984 -282.173966)
			(xy 273.019024 -282.124912) (xy 272.680176 -282.124912) (xy 272.679681 -282.149519) (xy 272.671786 -282.198096)
			(xy 272.656202 -282.244777) (xy 272.633331 -282.288354) (xy 272.603766 -282.327698) (xy 272.568273 -282.36179)
			(xy 272.52777 -282.389746) (xy 272.483308 -282.410844) (xy 272.436037 -282.424536) (xy 272.387182 -282.430468)
			(xy 272.338007 -282.428487) (xy 272.289788 -282.418643) (xy 272.243772 -282.401191) (xy 272.201151 -282.376584)
			(xy 272.16303 -282.345459) (xy 272.130395 -282.308622) (xy 272.104092 -282.267026) (xy 272.084801 -282.22175)
			(xy 272.073024 -282.173966) (xy 272.069064 -282.124912) (xy 271.730216 -282.124912) (xy 271.729721 -282.149519)
			(xy 271.721826 -282.198096) (xy 271.706242 -282.244777) (xy 271.683371 -282.288354) (xy 271.653806 -282.327698)
			(xy 271.618313 -282.36179) (xy 271.57781 -282.389746) (xy 271.533348 -282.410844) (xy 271.486077 -282.424536)
			(xy 271.437222 -282.430468) (xy 271.388047 -282.428487) (xy 271.339828 -282.418643) (xy 271.293812 -282.401191)
			(xy 271.251191 -282.376584) (xy 271.21307 -282.345459) (xy 271.180435 -282.308622) (xy 271.154132 -282.267026)
			(xy 271.134841 -282.22175) (xy 271.123064 -282.173966) (xy 271.119104 -282.124912) (xy 270.780256 -282.124912)
			(xy 270.779761 -282.149519) (xy 270.771866 -282.198096) (xy 270.756282 -282.244777) (xy 270.733411 -282.288354)
			(xy 270.703846 -282.327698) (xy 270.668353 -282.36179) (xy 270.62785 -282.389746) (xy 270.583388 -282.410844)
			(xy 270.536117 -282.424536) (xy 270.487262 -282.430468) (xy 270.438087 -282.428487) (xy 270.389868 -282.418643)
			(xy 270.343852 -282.401191) (xy 270.301231 -282.376584) (xy 270.26311 -282.345459) (xy 270.230475 -282.308622)
			(xy 270.204172 -282.267026) (xy 270.184881 -282.22175) (xy 270.173104 -282.173966) (xy 270.169144 -282.124912)
			(xy 269.830042 -282.124912) (xy 269.829547 -282.149519) (xy 269.821652 -282.198096) (xy 269.806068 -282.244777)
			(xy 269.783197 -282.288354) (xy 269.753632 -282.327698) (xy 269.718139 -282.36179) (xy 269.677636 -282.389746)
			(xy 269.633174 -282.410844) (xy 269.585903 -282.424536) (xy 269.537048 -282.430468) (xy 269.487873 -282.428487)
			(xy 269.439654 -282.418643) (xy 269.393638 -282.401191) (xy 269.351017 -282.376584) (xy 269.312896 -282.345459)
			(xy 269.280261 -282.308622) (xy 269.253958 -282.267026) (xy 269.234667 -282.22175) (xy 269.22289 -282.173966)
			(xy 269.21893 -282.124912) (xy 268.880082 -282.124912) (xy 268.879587 -282.149519) (xy 268.871692 -282.198096)
			(xy 268.856108 -282.244777) (xy 268.833237 -282.288354) (xy 268.803672 -282.327698) (xy 268.768179 -282.36179)
			(xy 268.727676 -282.389746) (xy 268.683214 -282.410844) (xy 268.635943 -282.424536) (xy 268.587088 -282.430468)
			(xy 268.537913 -282.428487) (xy 268.489694 -282.418643) (xy 268.443678 -282.401191) (xy 268.401057 -282.376584)
			(xy 268.362936 -282.345459) (xy 268.330301 -282.308622) (xy 268.303998 -282.267026) (xy 268.284707 -282.22175)
			(xy 268.27293 -282.173966) (xy 268.26897 -282.124912) (xy 266.590526 -282.124912) (xy 266.590526 -283.074872)
			(xy 268.26897 -283.074872) (xy 268.27293 -283.025818) (xy 268.284707 -282.978034) (xy 268.303998 -282.932758)
			(xy 268.330301 -282.891162) (xy 268.362936 -282.854325) (xy 268.401057 -282.8232) (xy 268.443678 -282.798593)
			(xy 268.489694 -282.781141) (xy 268.537913 -282.771297) (xy 268.587088 -282.769316) (xy 268.635943 -282.775248)
			(xy 268.683214 -282.78894) (xy 268.727676 -282.810038) (xy 268.768179 -282.837994) (xy 268.803672 -282.872086)
			(xy 268.833237 -282.91143) (xy 268.856108 -282.955007) (xy 268.871692 -283.001688) (xy 268.879587 -283.050265)
			(xy 268.880082 -283.074872) (xy 269.21893 -283.074872) (xy 269.22289 -283.025818) (xy 269.234667 -282.978034)
			(xy 269.253958 -282.932758) (xy 269.280261 -282.891162) (xy 269.312896 -282.854325) (xy 269.351017 -282.8232)
			(xy 269.393638 -282.798593) (xy 269.439654 -282.781141) (xy 269.487873 -282.771297) (xy 269.537048 -282.769316)
			(xy 269.585903 -282.775248) (xy 269.633174 -282.78894) (xy 269.677636 -282.810038) (xy 269.718139 -282.837994)
			(xy 269.753632 -282.872086) (xy 269.783197 -282.91143) (xy 269.806068 -282.955007) (xy 269.821652 -283.001688)
			(xy 269.829547 -283.050265) (xy 269.830042 -283.074872) (xy 270.169144 -283.074872) (xy 270.173104 -283.025818)
			(xy 270.184881 -282.978034) (xy 270.204172 -282.932758) (xy 270.230475 -282.891162) (xy 270.26311 -282.854325)
			(xy 270.301231 -282.8232) (xy 270.343852 -282.798593) (xy 270.389868 -282.781141) (xy 270.438087 -282.771297)
			(xy 270.487262 -282.769316) (xy 270.536117 -282.775248) (xy 270.583388 -282.78894) (xy 270.62785 -282.810038)
			(xy 270.668353 -282.837994) (xy 270.703846 -282.872086) (xy 270.733411 -282.91143) (xy 270.756282 -282.955007)
			(xy 270.771866 -283.001688) (xy 270.779761 -283.050265) (xy 270.780256 -283.074872) (xy 271.119104 -283.074872)
			(xy 271.123064 -283.025818) (xy 271.134841 -282.978034) (xy 271.154132 -282.932758) (xy 271.180435 -282.891162)
			(xy 271.21307 -282.854325) (xy 271.251191 -282.8232) (xy 271.293812 -282.798593) (xy 271.339828 -282.781141)
			(xy 271.388047 -282.771297) (xy 271.437222 -282.769316) (xy 271.486077 -282.775248) (xy 271.533348 -282.78894)
			(xy 271.57781 -282.810038) (xy 271.618313 -282.837994) (xy 271.653806 -282.872086) (xy 271.683371 -282.91143)
			(xy 271.706242 -282.955007) (xy 271.721826 -283.001688) (xy 271.729721 -283.050265) (xy 271.730216 -283.074872)
			(xy 272.069064 -283.074872) (xy 272.073024 -283.025818) (xy 272.084801 -282.978034) (xy 272.104092 -282.932758)
			(xy 272.130395 -282.891162) (xy 272.16303 -282.854325) (xy 272.201151 -282.8232) (xy 272.243772 -282.798593)
			(xy 272.289788 -282.781141) (xy 272.338007 -282.771297) (xy 272.387182 -282.769316) (xy 272.436037 -282.775248)
			(xy 272.483308 -282.78894) (xy 272.52777 -282.810038) (xy 272.568273 -282.837994) (xy 272.603766 -282.872086)
			(xy 272.633331 -282.91143) (xy 272.656202 -282.955007) (xy 272.671786 -283.001688) (xy 272.679681 -283.050265)
			(xy 272.680176 -283.074872) (xy 273.019024 -283.074872) (xy 273.022984 -283.025818) (xy 273.034761 -282.978034)
			(xy 273.054052 -282.932758) (xy 273.080355 -282.891162) (xy 273.11299 -282.854325) (xy 273.151111 -282.8232)
			(xy 273.193732 -282.798593) (xy 273.239748 -282.781141) (xy 273.287967 -282.771297) (xy 273.337142 -282.769316)
			(xy 273.385997 -282.775248) (xy 273.433268 -282.78894) (xy 273.47773 -282.810038) (xy 273.518233 -282.837994)
			(xy 273.553726 -282.872086) (xy 273.583291 -282.91143) (xy 273.606162 -282.955007) (xy 273.621746 -283.001688)
			(xy 273.629641 -283.050265) (xy 273.630136 -283.074872) (xy 273.968984 -283.074872) (xy 273.972944 -283.025818)
			(xy 273.984721 -282.978034) (xy 274.004012 -282.932758) (xy 274.030315 -282.891162) (xy 274.06295 -282.854325)
			(xy 274.101071 -282.8232) (xy 274.143692 -282.798593) (xy 274.189708 -282.781141) (xy 274.237927 -282.771297)
			(xy 274.287102 -282.769316) (xy 274.335957 -282.775248) (xy 274.383228 -282.78894) (xy 274.42769 -282.810038)
			(xy 274.468193 -282.837994) (xy 274.503686 -282.872086) (xy 274.533251 -282.91143) (xy 274.556122 -282.955007)
			(xy 274.571706 -283.001688) (xy 274.579601 -283.050265) (xy 274.580096 -283.074872) (xy 274.918944 -283.074872)
			(xy 274.922904 -283.025818) (xy 274.934681 -282.978034) (xy 274.953972 -282.932758) (xy 274.980275 -282.891162)
			(xy 275.01291 -282.854325) (xy 275.051031 -282.8232) (xy 275.093652 -282.798593) (xy 275.139668 -282.781141)
			(xy 275.187887 -282.771297) (xy 275.237062 -282.769316) (xy 275.285917 -282.775248) (xy 275.333188 -282.78894)
			(xy 275.37765 -282.810038) (xy 275.418153 -282.837994) (xy 275.453646 -282.872086) (xy 275.483211 -282.91143)
			(xy 275.506082 -282.955007) (xy 275.521666 -283.001688) (xy 275.529561 -283.050265) (xy 275.530056 -283.074872)
			(xy 275.868904 -283.074872) (xy 275.872864 -283.025818) (xy 275.884641 -282.978034) (xy 275.903932 -282.932758)
			(xy 275.930235 -282.891162) (xy 275.96287 -282.854325) (xy 276.000991 -282.8232) (xy 276.043612 -282.798593)
			(xy 276.089628 -282.781141) (xy 276.137847 -282.771297) (xy 276.187022 -282.769316) (xy 276.235877 -282.775248)
			(xy 276.283148 -282.78894) (xy 276.32761 -282.810038) (xy 276.368113 -282.837994) (xy 276.403606 -282.872086)
			(xy 276.433171 -282.91143) (xy 276.456042 -282.955007) (xy 276.471626 -283.001688) (xy 276.479521 -283.050265)
			(xy 276.480016 -283.074872) (xy 276.819118 -283.074872) (xy 276.823078 -283.025818) (xy 276.834855 -282.978034)
			(xy 276.854146 -282.932758) (xy 276.880449 -282.891162) (xy 276.913084 -282.854325) (xy 276.951205 -282.8232)
			(xy 276.993826 -282.798593) (xy 277.039842 -282.781141) (xy 277.088061 -282.771297) (xy 277.137236 -282.769316)
			(xy 277.186091 -282.775248) (xy 277.233362 -282.78894) (xy 277.277824 -282.810038) (xy 277.318327 -282.837994)
			(xy 277.35382 -282.872086) (xy 277.383385 -282.91143) (xy 277.406256 -282.955007) (xy 277.42184 -283.001688)
			(xy 277.429735 -283.050265) (xy 277.43023 -283.074872) (xy 277.769078 -283.074872) (xy 277.773038 -283.025818)
			(xy 277.784815 -282.978034) (xy 277.804106 -282.932758) (xy 277.830409 -282.891162) (xy 277.863044 -282.854325)
			(xy 277.901165 -282.8232) (xy 277.943786 -282.798593) (xy 277.989802 -282.781141) (xy 278.038021 -282.771297)
			(xy 278.087196 -282.769316) (xy 278.136051 -282.775248) (xy 278.183322 -282.78894) (xy 278.227784 -282.810038)
			(xy 278.268287 -282.837994) (xy 278.30378 -282.872086) (xy 278.333345 -282.91143) (xy 278.356216 -282.955007)
			(xy 278.3718 -283.001688) (xy 278.379695 -283.050265) (xy 278.38019 -283.074872) (xy 278.719038 -283.074872)
			(xy 278.722998 -283.025818) (xy 278.734775 -282.978034) (xy 278.754066 -282.932758) (xy 278.780369 -282.891162)
			(xy 278.813004 -282.854325) (xy 278.851125 -282.8232) (xy 278.893746 -282.798593) (xy 278.939762 -282.781141)
			(xy 278.987981 -282.771297) (xy 279.037156 -282.769316) (xy 279.086011 -282.775248) (xy 279.133282 -282.78894)
			(xy 279.177744 -282.810038) (xy 279.218247 -282.837994) (xy 279.25374 -282.872086) (xy 279.283305 -282.91143)
			(xy 279.306176 -282.955007) (xy 279.32176 -283.001688) (xy 279.329655 -283.050265) (xy 279.33015 -283.074872)
			(xy 279.668998 -283.074872) (xy 279.672958 -283.025818) (xy 279.684735 -282.978034) (xy 279.704026 -282.932758)
			(xy 279.730329 -282.891162) (xy 279.762964 -282.854325) (xy 279.801085 -282.8232) (xy 279.843706 -282.798593)
			(xy 279.889722 -282.781141) (xy 279.937941 -282.771297) (xy 279.987116 -282.769316) (xy 280.035971 -282.775248)
			(xy 280.083242 -282.78894) (xy 280.127704 -282.810038) (xy 280.168207 -282.837994) (xy 280.2037 -282.872086)
			(xy 280.233265 -282.91143) (xy 280.256136 -282.955007) (xy 280.27172 -283.001688) (xy 280.279615 -283.050265)
			(xy 280.28011 -283.074872) (xy 280.618958 -283.074872) (xy 280.622918 -283.025818) (xy 280.634695 -282.978034)
			(xy 280.653986 -282.932758) (xy 280.680289 -282.891162) (xy 280.712924 -282.854325) (xy 280.751045 -282.8232)
			(xy 280.793666 -282.798593) (xy 280.839682 -282.781141) (xy 280.887901 -282.771297) (xy 280.937076 -282.769316)
			(xy 280.985931 -282.775248) (xy 281.033202 -282.78894) (xy 281.077664 -282.810038) (xy 281.118167 -282.837994)
			(xy 281.15366 -282.872086) (xy 281.183225 -282.91143) (xy 281.206096 -282.955007) (xy 281.22168 -283.001688)
			(xy 281.229575 -283.050265) (xy 281.23007 -283.074872) (xy 281.568918 -283.074872) (xy 281.572878 -283.025818)
			(xy 281.584655 -282.978034) (xy 281.603946 -282.932758) (xy 281.630249 -282.891162) (xy 281.662884 -282.854325)
			(xy 281.701005 -282.8232) (xy 281.743626 -282.798593) (xy 281.789642 -282.781141) (xy 281.837861 -282.771297)
			(xy 281.887036 -282.769316) (xy 281.935891 -282.775248) (xy 281.983162 -282.78894) (xy 282.027624 -282.810038)
			(xy 282.068127 -282.837994) (xy 282.10362 -282.872086) (xy 282.133185 -282.91143) (xy 282.156056 -282.955007)
			(xy 282.17164 -283.001688) (xy 282.179535 -283.050265) (xy 282.18003 -283.074872) (xy 282.519132 -283.074872)
			(xy 282.523092 -283.025818) (xy 282.534869 -282.978034) (xy 282.55416 -282.932758) (xy 282.580463 -282.891162)
			(xy 282.613098 -282.854325) (xy 282.651219 -282.8232) (xy 282.69384 -282.798593) (xy 282.739856 -282.781141)
			(xy 282.788075 -282.771297) (xy 282.83725 -282.769316) (xy 282.886105 -282.775248) (xy 282.933376 -282.78894)
			(xy 282.977838 -282.810038) (xy 283.018341 -282.837994) (xy 283.053834 -282.872086) (xy 283.083399 -282.91143)
			(xy 283.10627 -282.955007) (xy 283.121854 -283.001688) (xy 283.129749 -283.050265) (xy 283.130244 -283.074872)
			(xy 283.469092 -283.074872) (xy 283.473052 -283.025818) (xy 283.484829 -282.978034) (xy 283.50412 -282.932758)
			(xy 283.530423 -282.891162) (xy 283.563058 -282.854325) (xy 283.601179 -282.8232) (xy 283.6438 -282.798593)
			(xy 283.689816 -282.781141) (xy 283.738035 -282.771297) (xy 283.78721 -282.769316) (xy 283.836065 -282.775248)
			(xy 283.883336 -282.78894) (xy 283.927798 -282.810038) (xy 283.968301 -282.837994) (xy 284.003794 -282.872086)
			(xy 284.033359 -282.91143) (xy 284.05623 -282.955007) (xy 284.071814 -283.001688) (xy 284.079709 -283.050265)
			(xy 284.080204 -283.074872) (xy 284.419052 -283.074872) (xy 284.423012 -283.025818) (xy 284.434789 -282.978034)
			(xy 284.45408 -282.932758) (xy 284.480383 -282.891162) (xy 284.513018 -282.854325) (xy 284.551139 -282.8232)
			(xy 284.59376 -282.798593) (xy 284.639776 -282.781141) (xy 284.687995 -282.771297) (xy 284.73717 -282.769316)
			(xy 284.786025 -282.775248) (xy 284.833296 -282.78894) (xy 284.877758 -282.810038) (xy 284.918261 -282.837994)
			(xy 284.953754 -282.872086) (xy 284.983319 -282.91143) (xy 285.00619 -282.955007) (xy 285.021774 -283.001688)
			(xy 285.029669 -283.050265) (xy 285.030164 -283.074872) (xy 285.369012 -283.074872) (xy 285.372972 -283.025818)
			(xy 285.384749 -282.978034) (xy 285.40404 -282.932758) (xy 285.430343 -282.891162) (xy 285.462978 -282.854325)
			(xy 285.501099 -282.8232) (xy 285.54372 -282.798593) (xy 285.589736 -282.781141) (xy 285.637955 -282.771297)
			(xy 285.68713 -282.769316) (xy 285.735985 -282.775248) (xy 285.783256 -282.78894) (xy 285.827718 -282.810038)
			(xy 285.868221 -282.837994) (xy 285.903714 -282.872086) (xy 285.933279 -282.91143) (xy 285.95615 -282.955007)
			(xy 285.971734 -283.001688) (xy 285.979629 -283.050265) (xy 285.979958 -283.066643) (xy 286.319052 -283.066643)
			(xy 286.324416 -283.017287) (xy 286.337694 -282.969449) (xy 286.358536 -282.92439) (xy 286.386394 -282.883296)
			(xy 286.420533 -282.84725) (xy 286.460053 -282.817202) (xy 286.503915 -282.793944) (xy 286.550961 -282.778088)
			(xy 286.599953 -282.770052) (xy 286.624776 -282.769564) (xy 286.638959 -282.769744) (xy 286.667199 -282.772414)
			(xy 286.681164 -282.774898) (xy 286.69361 -282.777184) (xy 286.717232 -282.769818) (xy 286.794702 -282.692348)
			(xy 286.802068 -282.668726) (xy 286.799782 -282.65628) (xy 286.797307 -282.642314) (xy 286.794634 -282.614074)
			(xy 286.794448 -282.599892) (xy 286.79497 -282.574637) (xy 286.803283 -282.524815) (xy 286.819684 -282.477041)
			(xy 286.843725 -282.432618) (xy 286.874749 -282.392758) (xy 286.911911 -282.358548) (xy 286.954197 -282.330922)
			(xy 287.000453 -282.310632) (xy 287.049418 -282.298232) (xy 287.099756 -282.294061) (xy 287.150094 -282.298232)
			(xy 287.199059 -282.310632) (xy 287.245315 -282.330922) (xy 287.287601 -282.358548) (xy 287.324763 -282.392758)
			(xy 287.355787 -282.432618) (xy 287.379828 -282.477041) (xy 287.396229 -282.524815) (xy 287.404542 -282.574637)
			(xy 287.405064 -282.599892) (xy 306.743874 -282.599892) (xy 306.747834 -282.550838) (xy 306.759611 -282.503054)
			(xy 306.778902 -282.457778) (xy 306.805205 -282.416182) (xy 306.83784 -282.379345) (xy 306.875961 -282.34822)
			(xy 306.918582 -282.323613) (xy 306.964598 -282.306161) (xy 307.012817 -282.296317) (xy 307.061992 -282.294336)
			(xy 307.110847 -282.300268) (xy 307.158118 -282.31396) (xy 307.20258 -282.335058) (xy 307.243083 -282.363014)
			(xy 307.278576 -282.397106) (xy 307.308141 -282.43645) (xy 307.331012 -282.480027) (xy 307.346596 -282.526708)
			(xy 307.354491 -282.575285) (xy 307.354986 -282.599892) (xy 307.354491 -282.624499) (xy 307.346596 -282.673076)
			(xy 307.331012 -282.719757) (xy 307.308141 -282.763334) (xy 307.278576 -282.802678) (xy 307.243083 -282.83677)
			(xy 307.20258 -282.864726) (xy 307.158118 -282.885824) (xy 307.110847 -282.899516) (xy 307.061992 -282.905448)
			(xy 307.012817 -282.903467) (xy 306.964598 -282.893623) (xy 306.918582 -282.876171) (xy 306.875961 -282.851564)
			(xy 306.83784 -282.820439) (xy 306.805205 -282.783602) (xy 306.778902 -282.742006) (xy 306.759611 -282.69673)
			(xy 306.747834 -282.648946) (xy 306.743874 -282.599892) (xy 287.405064 -282.599892) (xy 287.404887 -282.614075)
			(xy 287.402215 -282.642315) (xy 287.39973 -282.65628) (xy 287.397444 -282.668726) (xy 287.40481 -282.692348)
			(xy 287.48228 -282.769818) (xy 287.505902 -282.777184) (xy 287.518348 -282.774898) (xy 287.532313 -282.772419)
			(xy 287.560553 -282.769749) (xy 287.574736 -282.769564) (xy 287.599554 -282.770117) (xy 287.648535 -282.778153)
			(xy 287.69557 -282.794007) (xy 287.739421 -282.817262) (xy 287.778932 -282.847304) (xy 287.813062 -282.883343)
			(xy 287.840913 -282.924429) (xy 287.861749 -282.96948) (xy 287.875023 -283.017307) (xy 287.880384 -283.066653)
			(xy 287.879937 -283.074872) (xy 288.219146 -283.074872) (xy 288.223106 -283.025818) (xy 288.234883 -282.978034)
			(xy 288.254174 -282.932758) (xy 288.280477 -282.891162) (xy 288.313112 -282.854325) (xy 288.351233 -282.8232)
			(xy 288.393854 -282.798593) (xy 288.43987 -282.781141) (xy 288.488089 -282.771297) (xy 288.537264 -282.769316)
			(xy 288.586119 -282.775248) (xy 288.63339 -282.78894) (xy 288.677852 -282.810038) (xy 288.718355 -282.837994)
			(xy 288.753848 -282.872086) (xy 288.783413 -282.91143) (xy 288.806284 -282.955007) (xy 288.821868 -283.001688)
			(xy 288.829763 -283.050265) (xy 288.830258 -283.074872) (xy 289.169106 -283.074872) (xy 289.173066 -283.025818)
			(xy 289.184843 -282.978034) (xy 289.204134 -282.932758) (xy 289.230437 -282.891162) (xy 289.263072 -282.854325)
			(xy 289.301193 -282.8232) (xy 289.343814 -282.798593) (xy 289.38983 -282.781141) (xy 289.438049 -282.771297)
			(xy 289.487224 -282.769316) (xy 289.536079 -282.775248) (xy 289.58335 -282.78894) (xy 289.627812 -282.810038)
			(xy 289.668315 -282.837994) (xy 289.703808 -282.872086) (xy 289.733373 -282.91143) (xy 289.756244 -282.955007)
			(xy 289.771828 -283.001688) (xy 289.779723 -283.050265) (xy 289.780218 -283.074872) (xy 290.119066 -283.074872)
			(xy 290.123026 -283.025818) (xy 290.134803 -282.978034) (xy 290.154094 -282.932758) (xy 290.180397 -282.891162)
			(xy 290.213032 -282.854325) (xy 290.251153 -282.8232) (xy 290.293774 -282.798593) (xy 290.33979 -282.781141)
			(xy 290.388009 -282.771297) (xy 290.437184 -282.769316) (xy 290.486039 -282.775248) (xy 290.53331 -282.78894)
			(xy 290.577772 -282.810038) (xy 290.618275 -282.837994) (xy 290.653768 -282.872086) (xy 290.683333 -282.91143)
			(xy 290.706204 -282.955007) (xy 290.721788 -283.001688) (xy 290.729683 -283.050265) (xy 290.730178 -283.074872)
			(xy 292.018986 -283.074872) (xy 292.022946 -283.025818) (xy 292.034723 -282.978034) (xy 292.054014 -282.932758)
			(xy 292.080317 -282.891162) (xy 292.112952 -282.854325) (xy 292.151073 -282.8232) (xy 292.193694 -282.798593)
			(xy 292.23971 -282.781141) (xy 292.287929 -282.771297) (xy 292.337104 -282.769316) (xy 292.385959 -282.775248)
			(xy 292.43323 -282.78894) (xy 292.477692 -282.810038) (xy 292.518195 -282.837994) (xy 292.553688 -282.872086)
			(xy 292.583253 -282.91143) (xy 292.606124 -282.955007) (xy 292.621708 -283.001688) (xy 292.629603 -283.050265)
			(xy 292.630098 -283.074872) (xy 292.968946 -283.074872) (xy 292.972906 -283.025818) (xy 292.984683 -282.978034)
			(xy 293.003974 -282.932758) (xy 293.030277 -282.891162) (xy 293.062912 -282.854325) (xy 293.101033 -282.8232)
			(xy 293.143654 -282.798593) (xy 293.18967 -282.781141) (xy 293.237889 -282.771297) (xy 293.287064 -282.769316)
			(xy 293.335919 -282.775248) (xy 293.38319 -282.78894) (xy 293.427652 -282.810038) (xy 293.468155 -282.837994)
			(xy 293.503648 -282.872086) (xy 293.533213 -282.91143) (xy 293.556084 -282.955007) (xy 293.571668 -283.001688)
			(xy 293.579563 -283.050265) (xy 293.580058 -283.074872) (xy 293.918906 -283.074872) (xy 293.922866 -283.025818)
			(xy 293.934643 -282.978034) (xy 293.953934 -282.932758) (xy 293.980237 -282.891162) (xy 294.012872 -282.854325)
			(xy 294.050993 -282.8232) (xy 294.093614 -282.798593) (xy 294.13963 -282.781141) (xy 294.187849 -282.771297)
			(xy 294.237024 -282.769316) (xy 294.285879 -282.775248) (xy 294.33315 -282.78894) (xy 294.377612 -282.810038)
			(xy 294.418115 -282.837994) (xy 294.453608 -282.872086) (xy 294.483173 -282.91143) (xy 294.506044 -282.955007)
			(xy 294.521628 -283.001688) (xy 294.529523 -283.050265) (xy 294.530018 -283.074872) (xy 294.86912 -283.074872)
			(xy 294.87308 -283.025818) (xy 294.884857 -282.978034) (xy 294.904148 -282.932758) (xy 294.930451 -282.891162)
			(xy 294.963086 -282.854325) (xy 295.001207 -282.8232) (xy 295.043828 -282.798593) (xy 295.089844 -282.781141)
			(xy 295.138063 -282.771297) (xy 295.187238 -282.769316) (xy 295.236093 -282.775248) (xy 295.283364 -282.78894)
			(xy 295.327826 -282.810038) (xy 295.368329 -282.837994) (xy 295.403822 -282.872086) (xy 295.433387 -282.91143)
			(xy 295.456258 -282.955007) (xy 295.471842 -283.001688) (xy 295.479737 -283.050265) (xy 295.480232 -283.074872)
			(xy 295.81908 -283.074872) (xy 295.82304 -283.025818) (xy 295.834817 -282.978034) (xy 295.854108 -282.932758)
			(xy 295.880411 -282.891162) (xy 295.913046 -282.854325) (xy 295.951167 -282.8232) (xy 295.993788 -282.798593)
			(xy 296.039804 -282.781141) (xy 296.088023 -282.771297) (xy 296.137198 -282.769316) (xy 296.186053 -282.775248)
			(xy 296.233324 -282.78894) (xy 296.277786 -282.810038) (xy 296.318289 -282.837994) (xy 296.353782 -282.872086)
			(xy 296.383347 -282.91143) (xy 296.406218 -282.955007) (xy 296.421802 -283.001688) (xy 296.429697 -283.050265)
			(xy 296.430192 -283.074872) (xy 296.76904 -283.074872) (xy 296.773 -283.025818) (xy 296.784777 -282.978034)
			(xy 296.804068 -282.932758) (xy 296.830371 -282.891162) (xy 296.863006 -282.854325) (xy 296.901127 -282.8232)
			(xy 296.943748 -282.798593) (xy 296.989764 -282.781141) (xy 297.037983 -282.771297) (xy 297.087158 -282.769316)
			(xy 297.136013 -282.775248) (xy 297.183284 -282.78894) (xy 297.227746 -282.810038) (xy 297.268249 -282.837994)
			(xy 297.303742 -282.872086) (xy 297.333307 -282.91143) (xy 297.356178 -282.955007) (xy 297.371762 -283.001688)
			(xy 297.379657 -283.050265) (xy 297.380152 -283.074872) (xy 297.719 -283.074872) (xy 297.72296 -283.025818)
			(xy 297.734737 -282.978034) (xy 297.754028 -282.932758) (xy 297.780331 -282.891162) (xy 297.812966 -282.854325)
			(xy 297.851087 -282.8232) (xy 297.893708 -282.798593) (xy 297.939724 -282.781141) (xy 297.987943 -282.771297)
			(xy 298.037118 -282.769316) (xy 298.085973 -282.775248) (xy 298.133244 -282.78894) (xy 298.177706 -282.810038)
			(xy 298.218209 -282.837994) (xy 298.253702 -282.872086) (xy 298.283267 -282.91143) (xy 298.306138 -282.955007)
			(xy 298.321722 -283.001688) (xy 298.329617 -283.050265) (xy 298.330112 -283.074872) (xy 298.66896 -283.074872)
			(xy 298.67292 -283.025818) (xy 298.684697 -282.978034) (xy 298.703988 -282.932758) (xy 298.730291 -282.891162)
			(xy 298.762926 -282.854325) (xy 298.801047 -282.8232) (xy 298.843668 -282.798593) (xy 298.889684 -282.781141)
			(xy 298.937903 -282.771297) (xy 298.987078 -282.769316) (xy 299.035933 -282.775248) (xy 299.083204 -282.78894)
			(xy 299.127666 -282.810038) (xy 299.168169 -282.837994) (xy 299.203662 -282.872086) (xy 299.233227 -282.91143)
			(xy 299.256098 -282.955007) (xy 299.271682 -283.001688) (xy 299.279577 -283.050265) (xy 299.280072 -283.074872)
			(xy 300.56888 -283.074872) (xy 300.57284 -283.025818) (xy 300.584617 -282.978034) (xy 300.603908 -282.932758)
			(xy 300.630211 -282.891162) (xy 300.662846 -282.854325) (xy 300.700967 -282.8232) (xy 300.743588 -282.798593)
			(xy 300.789604 -282.781141) (xy 300.837823 -282.771297) (xy 300.886998 -282.769316) (xy 300.935853 -282.775248)
			(xy 300.983124 -282.78894) (xy 301.027586 -282.810038) (xy 301.068089 -282.837994) (xy 301.103582 -282.872086)
			(xy 301.133147 -282.91143) (xy 301.156018 -282.955007) (xy 301.171602 -283.001688) (xy 301.179497 -283.050265)
			(xy 301.179992 -283.074872) (xy 301.519094 -283.074872) (xy 301.523054 -283.025818) (xy 301.534831 -282.978034)
			(xy 301.554122 -282.932758) (xy 301.580425 -282.891162) (xy 301.61306 -282.854325) (xy 301.651181 -282.8232)
			(xy 301.693802 -282.798593) (xy 301.739818 -282.781141) (xy 301.788037 -282.771297) (xy 301.837212 -282.769316)
			(xy 301.886067 -282.775248) (xy 301.933338 -282.78894) (xy 301.9778 -282.810038) (xy 302.018303 -282.837994)
			(xy 302.053796 -282.872086) (xy 302.083361 -282.91143) (xy 302.106232 -282.955007) (xy 302.121816 -283.001688)
			(xy 302.129711 -283.050265) (xy 302.130206 -283.074872) (xy 302.469054 -283.074872) (xy 302.473014 -283.025818)
			(xy 302.484791 -282.978034) (xy 302.504082 -282.932758) (xy 302.530385 -282.891162) (xy 302.56302 -282.854325)
			(xy 302.601141 -282.8232) (xy 302.643762 -282.798593) (xy 302.689778 -282.781141) (xy 302.737997 -282.771297)
			(xy 302.787172 -282.769316) (xy 302.836027 -282.775248) (xy 302.883298 -282.78894) (xy 302.92776 -282.810038)
			(xy 302.968263 -282.837994) (xy 303.003756 -282.872086) (xy 303.033321 -282.91143) (xy 303.056192 -282.955007)
			(xy 303.071776 -283.001688) (xy 303.079671 -283.050265) (xy 303.080166 -283.074872) (xy 303.419014 -283.074872)
			(xy 303.422974 -283.025818) (xy 303.434751 -282.978034) (xy 303.454042 -282.932758) (xy 303.480345 -282.891162)
			(xy 303.51298 -282.854325) (xy 303.551101 -282.8232) (xy 303.593722 -282.798593) (xy 303.639738 -282.781141)
			(xy 303.687957 -282.771297) (xy 303.737132 -282.769316) (xy 303.785987 -282.775248) (xy 303.833258 -282.78894)
			(xy 303.87772 -282.810038) (xy 303.918223 -282.837994) (xy 303.953716 -282.872086) (xy 303.983281 -282.91143)
			(xy 304.006152 -282.955007) (xy 304.021736 -283.001688) (xy 304.029631 -283.050265) (xy 304.030126 -283.074872)
			(xy 304.368974 -283.074872) (xy 304.372934 -283.025818) (xy 304.384711 -282.978034) (xy 304.404002 -282.932758)
			(xy 304.430305 -282.891162) (xy 304.46294 -282.854325) (xy 304.501061 -282.8232) (xy 304.543682 -282.798593)
			(xy 304.589698 -282.781141) (xy 304.637917 -282.771297) (xy 304.687092 -282.769316) (xy 304.735947 -282.775248)
			(xy 304.783218 -282.78894) (xy 304.82768 -282.810038) (xy 304.868183 -282.837994) (xy 304.903676 -282.872086)
			(xy 304.933241 -282.91143) (xy 304.956112 -282.955007) (xy 304.971696 -283.001688) (xy 304.979591 -283.050265)
			(xy 304.980086 -283.074872) (xy 304.979591 -283.099479) (xy 304.971696 -283.148056) (xy 304.956112 -283.194737)
			(xy 304.933241 -283.238314) (xy 304.903676 -283.277658) (xy 304.868183 -283.31175) (xy 304.82768 -283.339706)
			(xy 304.783218 -283.360804) (xy 304.735947 -283.374496) (xy 304.687092 -283.380428) (xy 304.637917 -283.378447)
			(xy 304.589698 -283.368603) (xy 304.543682 -283.351151) (xy 304.501061 -283.326544) (xy 304.46294 -283.295419)
			(xy 304.430305 -283.258582) (xy 304.404002 -283.216986) (xy 304.384711 -283.17171) (xy 304.372934 -283.123926)
			(xy 304.368974 -283.074872) (xy 304.030126 -283.074872) (xy 304.029631 -283.099479) (xy 304.021736 -283.148056)
			(xy 304.006152 -283.194737) (xy 303.983281 -283.238314) (xy 303.953716 -283.277658) (xy 303.918223 -283.31175)
			(xy 303.87772 -283.339706) (xy 303.833258 -283.360804) (xy 303.785987 -283.374496) (xy 303.737132 -283.380428)
			(xy 303.687957 -283.378447) (xy 303.639738 -283.368603) (xy 303.593722 -283.351151) (xy 303.551101 -283.326544)
			(xy 303.51298 -283.295419) (xy 303.480345 -283.258582) (xy 303.454042 -283.216986) (xy 303.434751 -283.17171)
			(xy 303.422974 -283.123926) (xy 303.419014 -283.074872) (xy 303.080166 -283.074872) (xy 303.079671 -283.099479)
			(xy 303.071776 -283.148056) (xy 303.056192 -283.194737) (xy 303.033321 -283.238314) (xy 303.003756 -283.277658)
			(xy 302.968263 -283.31175) (xy 302.92776 -283.339706) (xy 302.883298 -283.360804) (xy 302.836027 -283.374496)
			(xy 302.787172 -283.380428) (xy 302.737997 -283.378447) (xy 302.689778 -283.368603) (xy 302.643762 -283.351151)
			(xy 302.601141 -283.326544) (xy 302.56302 -283.295419) (xy 302.530385 -283.258582) (xy 302.504082 -283.216986)
			(xy 302.484791 -283.17171) (xy 302.473014 -283.123926) (xy 302.469054 -283.074872) (xy 302.130206 -283.074872)
			(xy 302.129711 -283.099479) (xy 302.121816 -283.148056) (xy 302.106232 -283.194737) (xy 302.083361 -283.238314)
			(xy 302.053796 -283.277658) (xy 302.018303 -283.31175) (xy 301.9778 -283.339706) (xy 301.933338 -283.360804)
			(xy 301.886067 -283.374496) (xy 301.837212 -283.380428) (xy 301.788037 -283.378447) (xy 301.739818 -283.368603)
			(xy 301.693802 -283.351151) (xy 301.651181 -283.326544) (xy 301.61306 -283.295419) (xy 301.580425 -283.258582)
			(xy 301.554122 -283.216986) (xy 301.534831 -283.17171) (xy 301.523054 -283.123926) (xy 301.519094 -283.074872)
			(xy 301.179992 -283.074872) (xy 301.179497 -283.099479) (xy 301.171602 -283.148056) (xy 301.156018 -283.194737)
			(xy 301.133147 -283.238314) (xy 301.103582 -283.277658) (xy 301.068089 -283.31175) (xy 301.027586 -283.339706)
			(xy 300.983124 -283.360804) (xy 300.935853 -283.374496) (xy 300.886998 -283.380428) (xy 300.837823 -283.378447)
			(xy 300.789604 -283.368603) (xy 300.743588 -283.351151) (xy 300.700967 -283.326544) (xy 300.662846 -283.295419)
			(xy 300.630211 -283.258582) (xy 300.603908 -283.216986) (xy 300.584617 -283.17171) (xy 300.57284 -283.123926)
			(xy 300.56888 -283.074872) (xy 299.280072 -283.074872) (xy 299.279577 -283.099479) (xy 299.271682 -283.148056)
			(xy 299.256098 -283.194737) (xy 299.233227 -283.238314) (xy 299.203662 -283.277658) (xy 299.168169 -283.31175)
			(xy 299.127666 -283.339706) (xy 299.083204 -283.360804) (xy 299.035933 -283.374496) (xy 298.987078 -283.380428)
			(xy 298.937903 -283.378447) (xy 298.889684 -283.368603) (xy 298.843668 -283.351151) (xy 298.801047 -283.326544)
			(xy 298.762926 -283.295419) (xy 298.730291 -283.258582) (xy 298.703988 -283.216986) (xy 298.684697 -283.17171)
			(xy 298.67292 -283.123926) (xy 298.66896 -283.074872) (xy 298.330112 -283.074872) (xy 298.329617 -283.099479)
			(xy 298.321722 -283.148056) (xy 298.306138 -283.194737) (xy 298.283267 -283.238314) (xy 298.253702 -283.277658)
			(xy 298.218209 -283.31175) (xy 298.177706 -283.339706) (xy 298.133244 -283.360804) (xy 298.085973 -283.374496)
			(xy 298.037118 -283.380428) (xy 297.987943 -283.378447) (xy 297.939724 -283.368603) (xy 297.893708 -283.351151)
			(xy 297.851087 -283.326544) (xy 297.812966 -283.295419) (xy 297.780331 -283.258582) (xy 297.754028 -283.216986)
			(xy 297.734737 -283.17171) (xy 297.72296 -283.123926) (xy 297.719 -283.074872) (xy 297.380152 -283.074872)
			(xy 297.379657 -283.099479) (xy 297.371762 -283.148056) (xy 297.356178 -283.194737) (xy 297.333307 -283.238314)
			(xy 297.303742 -283.277658) (xy 297.268249 -283.31175) (xy 297.227746 -283.339706) (xy 297.183284 -283.360804)
			(xy 297.136013 -283.374496) (xy 297.087158 -283.380428) (xy 297.037983 -283.378447) (xy 296.989764 -283.368603)
			(xy 296.943748 -283.351151) (xy 296.901127 -283.326544) (xy 296.863006 -283.295419) (xy 296.830371 -283.258582)
			(xy 296.804068 -283.216986) (xy 296.784777 -283.17171) (xy 296.773 -283.123926) (xy 296.76904 -283.074872)
			(xy 296.430192 -283.074872) (xy 296.429697 -283.099479) (xy 296.421802 -283.148056) (xy 296.406218 -283.194737)
			(xy 296.383347 -283.238314) (xy 296.353782 -283.277658) (xy 296.318289 -283.31175) (xy 296.277786 -283.339706)
			(xy 296.233324 -283.360804) (xy 296.186053 -283.374496) (xy 296.137198 -283.380428) (xy 296.088023 -283.378447)
			(xy 296.039804 -283.368603) (xy 295.993788 -283.351151) (xy 295.951167 -283.326544) (xy 295.913046 -283.295419)
			(xy 295.880411 -283.258582) (xy 295.854108 -283.216986) (xy 295.834817 -283.17171) (xy 295.82304 -283.123926)
			(xy 295.81908 -283.074872) (xy 295.480232 -283.074872) (xy 295.479737 -283.099479) (xy 295.471842 -283.148056)
			(xy 295.456258 -283.194737) (xy 295.433387 -283.238314) (xy 295.403822 -283.277658) (xy 295.368329 -283.31175)
			(xy 295.327826 -283.339706) (xy 295.283364 -283.360804) (xy 295.236093 -283.374496) (xy 295.187238 -283.380428)
			(xy 295.138063 -283.378447) (xy 295.089844 -283.368603) (xy 295.043828 -283.351151) (xy 295.001207 -283.326544)
			(xy 294.963086 -283.295419) (xy 294.930451 -283.258582) (xy 294.904148 -283.216986) (xy 294.884857 -283.17171)
			(xy 294.87308 -283.123926) (xy 294.86912 -283.074872) (xy 294.530018 -283.074872) (xy 294.529523 -283.099479)
			(xy 294.521628 -283.148056) (xy 294.506044 -283.194737) (xy 294.483173 -283.238314) (xy 294.453608 -283.277658)
			(xy 294.418115 -283.31175) (xy 294.377612 -283.339706) (xy 294.33315 -283.360804) (xy 294.285879 -283.374496)
			(xy 294.237024 -283.380428) (xy 294.187849 -283.378447) (xy 294.13963 -283.368603) (xy 294.093614 -283.351151)
			(xy 294.050993 -283.326544) (xy 294.012872 -283.295419) (xy 293.980237 -283.258582) (xy 293.953934 -283.216986)
			(xy 293.934643 -283.17171) (xy 293.922866 -283.123926) (xy 293.918906 -283.074872) (xy 293.580058 -283.074872)
			(xy 293.579563 -283.099479) (xy 293.571668 -283.148056) (xy 293.556084 -283.194737) (xy 293.533213 -283.238314)
			(xy 293.503648 -283.277658) (xy 293.468155 -283.31175) (xy 293.427652 -283.339706) (xy 293.38319 -283.360804)
			(xy 293.335919 -283.374496) (xy 293.287064 -283.380428) (xy 293.237889 -283.378447) (xy 293.18967 -283.368603)
			(xy 293.143654 -283.351151) (xy 293.101033 -283.326544) (xy 293.062912 -283.295419) (xy 293.030277 -283.258582)
			(xy 293.003974 -283.216986) (xy 292.984683 -283.17171) (xy 292.972906 -283.123926) (xy 292.968946 -283.074872)
			(xy 292.630098 -283.074872) (xy 292.629603 -283.099479) (xy 292.621708 -283.148056) (xy 292.606124 -283.194737)
			(xy 292.583253 -283.238314) (xy 292.553688 -283.277658) (xy 292.518195 -283.31175) (xy 292.477692 -283.339706)
			(xy 292.43323 -283.360804) (xy 292.385959 -283.374496) (xy 292.337104 -283.380428) (xy 292.287929 -283.378447)
			(xy 292.23971 -283.368603) (xy 292.193694 -283.351151) (xy 292.151073 -283.326544) (xy 292.112952 -283.295419)
			(xy 292.080317 -283.258582) (xy 292.054014 -283.216986) (xy 292.034723 -283.17171) (xy 292.022946 -283.123926)
			(xy 292.018986 -283.074872) (xy 290.730178 -283.074872) (xy 290.729683 -283.099479) (xy 290.721788 -283.148056)
			(xy 290.706204 -283.194737) (xy 290.683333 -283.238314) (xy 290.653768 -283.277658) (xy 290.618275 -283.31175)
			(xy 290.577772 -283.339706) (xy 290.53331 -283.360804) (xy 290.486039 -283.374496) (xy 290.437184 -283.380428)
			(xy 290.388009 -283.378447) (xy 290.33979 -283.368603) (xy 290.293774 -283.351151) (xy 290.251153 -283.326544)
			(xy 290.213032 -283.295419) (xy 290.180397 -283.258582) (xy 290.154094 -283.216986) (xy 290.134803 -283.17171)
			(xy 290.123026 -283.123926) (xy 290.119066 -283.074872) (xy 289.780218 -283.074872) (xy 289.779723 -283.099479)
			(xy 289.771828 -283.148056) (xy 289.756244 -283.194737) (xy 289.733373 -283.238314) (xy 289.703808 -283.277658)
			(xy 289.668315 -283.31175) (xy 289.627812 -283.339706) (xy 289.58335 -283.360804) (xy 289.536079 -283.374496)
			(xy 289.487224 -283.380428) (xy 289.438049 -283.378447) (xy 289.38983 -283.368603) (xy 289.343814 -283.351151)
			(xy 289.301193 -283.326544) (xy 289.263072 -283.295419) (xy 289.230437 -283.258582) (xy 289.204134 -283.216986)
			(xy 289.184843 -283.17171) (xy 289.173066 -283.123926) (xy 289.169106 -283.074872) (xy 288.830258 -283.074872)
			(xy 288.829763 -283.099479) (xy 288.821868 -283.148056) (xy 288.806284 -283.194737) (xy 288.783413 -283.238314)
			(xy 288.753848 -283.277658) (xy 288.718355 -283.31175) (xy 288.677852 -283.339706) (xy 288.63339 -283.360804)
			(xy 288.586119 -283.374496) (xy 288.537264 -283.380428) (xy 288.488089 -283.378447) (xy 288.43987 -283.368603)
			(xy 288.393854 -283.351151) (xy 288.351233 -283.326544) (xy 288.313112 -283.295419) (xy 288.280477 -283.258582)
			(xy 288.254174 -283.216986) (xy 288.234883 -283.17171) (xy 288.223106 -283.123926) (xy 288.219146 -283.074872)
			(xy 287.879937 -283.074872) (xy 287.877691 -283.116215) (xy 287.867016 -283.164689) (xy 287.848639 -283.210798)
			(xy 287.823044 -283.253325) (xy 287.790907 -283.291152) (xy 287.753073 -283.323282) (xy 287.71054 -283.348867)
			(xy 287.664428 -283.367235) (xy 287.615952 -283.3779) (xy 287.566389 -283.380582) (xy 287.517045 -283.375211)
			(xy 287.469219 -283.361927) (xy 287.424173 -283.341081) (xy 287.383093 -283.313222) (xy 287.347061 -283.279084)
			(xy 287.317027 -283.239567) (xy 287.293781 -283.195711) (xy 287.277937 -283.148672) (xy 287.269911 -283.09969)
			(xy 287.269428 -283.074872) (xy 287.2696 -283.060689) (xy 287.272275 -283.032449) (xy 287.274762 -283.018484)
			(xy 287.277048 -283.006038) (xy 287.269682 -282.982416) (xy 287.192212 -282.904946) (xy 287.16859 -282.89758)
			(xy 287.156144 -282.899866) (xy 287.142179 -282.902346) (xy 287.113939 -282.905015) (xy 287.099756 -282.9052)
			(xy 287.085573 -282.905016) (xy 287.057333 -282.902349) (xy 287.043368 -282.899866) (xy 287.030922 -282.89758)
			(xy 287.0073 -282.904946) (xy 286.92983 -282.982416) (xy 286.922464 -283.006038) (xy 286.92475 -283.018484)
			(xy 286.927234 -283.032449) (xy 286.929901 -283.060689) (xy 286.930084 -283.074872) (xy 286.929652 -283.099695)
			(xy 286.921625 -283.148688) (xy 286.905777 -283.195737) (xy 286.882526 -283.239603) (xy 286.852485 -283.279128)
			(xy 286.816445 -283.313273) (xy 286.775356 -283.341138) (xy 286.7303 -283.361988) (xy 286.682464 -283.375274)
			(xy 286.633109 -283.380646) (xy 286.583535 -283.377963) (xy 286.535049 -283.367294) (xy 286.488927 -283.348922)
			(xy 286.446385 -283.323331) (xy 286.408543 -283.291193) (xy 286.3764 -283.253358) (xy 286.350801 -283.21082)
			(xy 286.332421 -283.164701) (xy 286.321744 -283.116216) (xy 286.319052 -283.066643) (xy 285.979958 -283.066643)
			(xy 285.980124 -283.074872) (xy 285.979629 -283.099479) (xy 285.971734 -283.148056) (xy 285.95615 -283.194737)
			(xy 285.933279 -283.238314) (xy 285.903714 -283.277658) (xy 285.868221 -283.31175) (xy 285.827718 -283.339706)
			(xy 285.783256 -283.360804) (xy 285.735985 -283.374496) (xy 285.68713 -283.380428) (xy 285.637955 -283.378447)
			(xy 285.589736 -283.368603) (xy 285.54372 -283.351151) (xy 285.501099 -283.326544) (xy 285.462978 -283.295419)
			(xy 285.430343 -283.258582) (xy 285.40404 -283.216986) (xy 285.384749 -283.17171) (xy 285.372972 -283.123926)
			(xy 285.369012 -283.074872) (xy 285.030164 -283.074872) (xy 285.029669 -283.099479) (xy 285.021774 -283.148056)
			(xy 285.00619 -283.194737) (xy 284.983319 -283.238314) (xy 284.953754 -283.277658) (xy 284.918261 -283.31175)
			(xy 284.877758 -283.339706) (xy 284.833296 -283.360804) (xy 284.786025 -283.374496) (xy 284.73717 -283.380428)
			(xy 284.687995 -283.378447) (xy 284.639776 -283.368603) (xy 284.59376 -283.351151) (xy 284.551139 -283.326544)
			(xy 284.513018 -283.295419) (xy 284.480383 -283.258582) (xy 284.45408 -283.216986) (xy 284.434789 -283.17171)
			(xy 284.423012 -283.123926) (xy 284.419052 -283.074872) (xy 284.080204 -283.074872) (xy 284.079709 -283.099479)
			(xy 284.071814 -283.148056) (xy 284.05623 -283.194737) (xy 284.033359 -283.238314) (xy 284.003794 -283.277658)
			(xy 283.968301 -283.31175) (xy 283.927798 -283.339706) (xy 283.883336 -283.360804) (xy 283.836065 -283.374496)
			(xy 283.78721 -283.380428) (xy 283.738035 -283.378447) (xy 283.689816 -283.368603) (xy 283.6438 -283.351151)
			(xy 283.601179 -283.326544) (xy 283.563058 -283.295419) (xy 283.530423 -283.258582) (xy 283.50412 -283.216986)
			(xy 283.484829 -283.17171) (xy 283.473052 -283.123926) (xy 283.469092 -283.074872) (xy 283.130244 -283.074872)
			(xy 283.129749 -283.099479) (xy 283.121854 -283.148056) (xy 283.10627 -283.194737) (xy 283.083399 -283.238314)
			(xy 283.053834 -283.277658) (xy 283.018341 -283.31175) (xy 282.977838 -283.339706) (xy 282.933376 -283.360804)
			(xy 282.886105 -283.374496) (xy 282.83725 -283.380428) (xy 282.788075 -283.378447) (xy 282.739856 -283.368603)
			(xy 282.69384 -283.351151) (xy 282.651219 -283.326544) (xy 282.613098 -283.295419) (xy 282.580463 -283.258582)
			(xy 282.55416 -283.216986) (xy 282.534869 -283.17171) (xy 282.523092 -283.123926) (xy 282.519132 -283.074872)
			(xy 282.18003 -283.074872) (xy 282.179535 -283.099479) (xy 282.17164 -283.148056) (xy 282.156056 -283.194737)
			(xy 282.133185 -283.238314) (xy 282.10362 -283.277658) (xy 282.068127 -283.31175) (xy 282.027624 -283.339706)
			(xy 281.983162 -283.360804) (xy 281.935891 -283.374496) (xy 281.887036 -283.380428) (xy 281.837861 -283.378447)
			(xy 281.789642 -283.368603) (xy 281.743626 -283.351151) (xy 281.701005 -283.326544) (xy 281.662884 -283.295419)
			(xy 281.630249 -283.258582) (xy 281.603946 -283.216986) (xy 281.584655 -283.17171) (xy 281.572878 -283.123926)
			(xy 281.568918 -283.074872) (xy 281.23007 -283.074872) (xy 281.229575 -283.099479) (xy 281.22168 -283.148056)
			(xy 281.206096 -283.194737) (xy 281.183225 -283.238314) (xy 281.15366 -283.277658) (xy 281.118167 -283.31175)
			(xy 281.077664 -283.339706) (xy 281.033202 -283.360804) (xy 280.985931 -283.374496) (xy 280.937076 -283.380428)
			(xy 280.887901 -283.378447) (xy 280.839682 -283.368603) (xy 280.793666 -283.351151) (xy 280.751045 -283.326544)
			(xy 280.712924 -283.295419) (xy 280.680289 -283.258582) (xy 280.653986 -283.216986) (xy 280.634695 -283.17171)
			(xy 280.622918 -283.123926) (xy 280.618958 -283.074872) (xy 280.28011 -283.074872) (xy 280.279615 -283.099479)
			(xy 280.27172 -283.148056) (xy 280.256136 -283.194737) (xy 280.233265 -283.238314) (xy 280.2037 -283.277658)
			(xy 280.168207 -283.31175) (xy 280.127704 -283.339706) (xy 280.083242 -283.360804) (xy 280.035971 -283.374496)
			(xy 279.987116 -283.380428) (xy 279.937941 -283.378447) (xy 279.889722 -283.368603) (xy 279.843706 -283.351151)
			(xy 279.801085 -283.326544) (xy 279.762964 -283.295419) (xy 279.730329 -283.258582) (xy 279.704026 -283.216986)
			(xy 279.684735 -283.17171) (xy 279.672958 -283.123926) (xy 279.668998 -283.074872) (xy 279.33015 -283.074872)
			(xy 279.329655 -283.099479) (xy 279.32176 -283.148056) (xy 279.306176 -283.194737) (xy 279.283305 -283.238314)
			(xy 279.25374 -283.277658) (xy 279.218247 -283.31175) (xy 279.177744 -283.339706) (xy 279.133282 -283.360804)
			(xy 279.086011 -283.374496) (xy 279.037156 -283.380428) (xy 278.987981 -283.378447) (xy 278.939762 -283.368603)
			(xy 278.893746 -283.351151) (xy 278.851125 -283.326544) (xy 278.813004 -283.295419) (xy 278.780369 -283.258582)
			(xy 278.754066 -283.216986) (xy 278.734775 -283.17171) (xy 278.722998 -283.123926) (xy 278.719038 -283.074872)
			(xy 278.38019 -283.074872) (xy 278.379695 -283.099479) (xy 278.3718 -283.148056) (xy 278.356216 -283.194737)
			(xy 278.333345 -283.238314) (xy 278.30378 -283.277658) (xy 278.268287 -283.31175) (xy 278.227784 -283.339706)
			(xy 278.183322 -283.360804) (xy 278.136051 -283.374496) (xy 278.087196 -283.380428) (xy 278.038021 -283.378447)
			(xy 277.989802 -283.368603) (xy 277.943786 -283.351151) (xy 277.901165 -283.326544) (xy 277.863044 -283.295419)
			(xy 277.830409 -283.258582) (xy 277.804106 -283.216986) (xy 277.784815 -283.17171) (xy 277.773038 -283.123926)
			(xy 277.769078 -283.074872) (xy 277.43023 -283.074872) (xy 277.429735 -283.099479) (xy 277.42184 -283.148056)
			(xy 277.406256 -283.194737) (xy 277.383385 -283.238314) (xy 277.35382 -283.277658) (xy 277.318327 -283.31175)
			(xy 277.277824 -283.339706) (xy 277.233362 -283.360804) (xy 277.186091 -283.374496) (xy 277.137236 -283.380428)
			(xy 277.088061 -283.378447) (xy 277.039842 -283.368603) (xy 276.993826 -283.351151) (xy 276.951205 -283.326544)
			(xy 276.913084 -283.295419) (xy 276.880449 -283.258582) (xy 276.854146 -283.216986) (xy 276.834855 -283.17171)
			(xy 276.823078 -283.123926) (xy 276.819118 -283.074872) (xy 276.480016 -283.074872) (xy 276.479521 -283.099479)
			(xy 276.471626 -283.148056) (xy 276.456042 -283.194737) (xy 276.433171 -283.238314) (xy 276.403606 -283.277658)
			(xy 276.368113 -283.31175) (xy 276.32761 -283.339706) (xy 276.283148 -283.360804) (xy 276.235877 -283.374496)
			(xy 276.187022 -283.380428) (xy 276.137847 -283.378447) (xy 276.089628 -283.368603) (xy 276.043612 -283.351151)
			(xy 276.000991 -283.326544) (xy 275.96287 -283.295419) (xy 275.930235 -283.258582) (xy 275.903932 -283.216986)
			(xy 275.884641 -283.17171) (xy 275.872864 -283.123926) (xy 275.868904 -283.074872) (xy 275.530056 -283.074872)
			(xy 275.529561 -283.099479) (xy 275.521666 -283.148056) (xy 275.506082 -283.194737) (xy 275.483211 -283.238314)
			(xy 275.453646 -283.277658) (xy 275.418153 -283.31175) (xy 275.37765 -283.339706) (xy 275.333188 -283.360804)
			(xy 275.285917 -283.374496) (xy 275.237062 -283.380428) (xy 275.187887 -283.378447) (xy 275.139668 -283.368603)
			(xy 275.093652 -283.351151) (xy 275.051031 -283.326544) (xy 275.01291 -283.295419) (xy 274.980275 -283.258582)
			(xy 274.953972 -283.216986) (xy 274.934681 -283.17171) (xy 274.922904 -283.123926) (xy 274.918944 -283.074872)
			(xy 274.580096 -283.074872) (xy 274.579601 -283.099479) (xy 274.571706 -283.148056) (xy 274.556122 -283.194737)
			(xy 274.533251 -283.238314) (xy 274.503686 -283.277658) (xy 274.468193 -283.31175) (xy 274.42769 -283.339706)
			(xy 274.383228 -283.360804) (xy 274.335957 -283.374496) (xy 274.287102 -283.380428) (xy 274.237927 -283.378447)
			(xy 274.189708 -283.368603) (xy 274.143692 -283.351151) (xy 274.101071 -283.326544) (xy 274.06295 -283.295419)
			(xy 274.030315 -283.258582) (xy 274.004012 -283.216986) (xy 273.984721 -283.17171) (xy 273.972944 -283.123926)
			(xy 273.968984 -283.074872) (xy 273.630136 -283.074872) (xy 273.629641 -283.099479) (xy 273.621746 -283.148056)
			(xy 273.606162 -283.194737) (xy 273.583291 -283.238314) (xy 273.553726 -283.277658) (xy 273.518233 -283.31175)
			(xy 273.47773 -283.339706) (xy 273.433268 -283.360804) (xy 273.385997 -283.374496) (xy 273.337142 -283.380428)
			(xy 273.287967 -283.378447) (xy 273.239748 -283.368603) (xy 273.193732 -283.351151) (xy 273.151111 -283.326544)
			(xy 273.11299 -283.295419) (xy 273.080355 -283.258582) (xy 273.054052 -283.216986) (xy 273.034761 -283.17171)
			(xy 273.022984 -283.123926) (xy 273.019024 -283.074872) (xy 272.680176 -283.074872) (xy 272.679681 -283.099479)
			(xy 272.671786 -283.148056) (xy 272.656202 -283.194737) (xy 272.633331 -283.238314) (xy 272.603766 -283.277658)
			(xy 272.568273 -283.31175) (xy 272.52777 -283.339706) (xy 272.483308 -283.360804) (xy 272.436037 -283.374496)
			(xy 272.387182 -283.380428) (xy 272.338007 -283.378447) (xy 272.289788 -283.368603) (xy 272.243772 -283.351151)
			(xy 272.201151 -283.326544) (xy 272.16303 -283.295419) (xy 272.130395 -283.258582) (xy 272.104092 -283.216986)
			(xy 272.084801 -283.17171) (xy 272.073024 -283.123926) (xy 272.069064 -283.074872) (xy 271.730216 -283.074872)
			(xy 271.729721 -283.099479) (xy 271.721826 -283.148056) (xy 271.706242 -283.194737) (xy 271.683371 -283.238314)
			(xy 271.653806 -283.277658) (xy 271.618313 -283.31175) (xy 271.57781 -283.339706) (xy 271.533348 -283.360804)
			(xy 271.486077 -283.374496) (xy 271.437222 -283.380428) (xy 271.388047 -283.378447) (xy 271.339828 -283.368603)
			(xy 271.293812 -283.351151) (xy 271.251191 -283.326544) (xy 271.21307 -283.295419) (xy 271.180435 -283.258582)
			(xy 271.154132 -283.216986) (xy 271.134841 -283.17171) (xy 271.123064 -283.123926) (xy 271.119104 -283.074872)
			(xy 270.780256 -283.074872) (xy 270.779761 -283.099479) (xy 270.771866 -283.148056) (xy 270.756282 -283.194737)
			(xy 270.733411 -283.238314) (xy 270.703846 -283.277658) (xy 270.668353 -283.31175) (xy 270.62785 -283.339706)
			(xy 270.583388 -283.360804) (xy 270.536117 -283.374496) (xy 270.487262 -283.380428) (xy 270.438087 -283.378447)
			(xy 270.389868 -283.368603) (xy 270.343852 -283.351151) (xy 270.301231 -283.326544) (xy 270.26311 -283.295419)
			(xy 270.230475 -283.258582) (xy 270.204172 -283.216986) (xy 270.184881 -283.17171) (xy 270.173104 -283.123926)
			(xy 270.169144 -283.074872) (xy 269.830042 -283.074872) (xy 269.829547 -283.099479) (xy 269.821652 -283.148056)
			(xy 269.806068 -283.194737) (xy 269.783197 -283.238314) (xy 269.753632 -283.277658) (xy 269.718139 -283.31175)
			(xy 269.677636 -283.339706) (xy 269.633174 -283.360804) (xy 269.585903 -283.374496) (xy 269.537048 -283.380428)
			(xy 269.487873 -283.378447) (xy 269.439654 -283.368603) (xy 269.393638 -283.351151) (xy 269.351017 -283.326544)
			(xy 269.312896 -283.295419) (xy 269.280261 -283.258582) (xy 269.253958 -283.216986) (xy 269.234667 -283.17171)
			(xy 269.22289 -283.123926) (xy 269.21893 -283.074872) (xy 268.880082 -283.074872) (xy 268.879587 -283.099479)
			(xy 268.871692 -283.148056) (xy 268.856108 -283.194737) (xy 268.833237 -283.238314) (xy 268.803672 -283.277658)
			(xy 268.768179 -283.31175) (xy 268.727676 -283.339706) (xy 268.683214 -283.360804) (xy 268.635943 -283.374496)
			(xy 268.587088 -283.380428) (xy 268.537913 -283.378447) (xy 268.489694 -283.368603) (xy 268.443678 -283.351151)
			(xy 268.401057 -283.326544) (xy 268.362936 -283.295419) (xy 268.330301 -283.258582) (xy 268.303998 -283.216986)
			(xy 268.284707 -283.17171) (xy 268.27293 -283.123926) (xy 268.26897 -283.074872) (xy 266.590526 -283.074872)
			(xy 266.590526 -283.549852) (xy 305.793914 -283.549852) (xy 305.797874 -283.500798) (xy 305.809651 -283.453014)
			(xy 305.828942 -283.407738) (xy 305.855245 -283.366142) (xy 305.88788 -283.329305) (xy 305.926001 -283.29818)
			(xy 305.968622 -283.273573) (xy 306.014638 -283.256121) (xy 306.062857 -283.246277) (xy 306.112032 -283.244296)
			(xy 306.160887 -283.250228) (xy 306.208158 -283.26392) (xy 306.25262 -283.285018) (xy 306.293123 -283.312974)
			(xy 306.328616 -283.347066) (xy 306.358181 -283.38641) (xy 306.381052 -283.429987) (xy 306.396636 -283.476668)
			(xy 306.404531 -283.525245) (xy 306.405026 -283.549852) (xy 306.743874 -283.549852) (xy 306.747834 -283.500798)
			(xy 306.759611 -283.453014) (xy 306.778902 -283.407738) (xy 306.805205 -283.366142) (xy 306.83784 -283.329305)
			(xy 306.875961 -283.29818) (xy 306.918582 -283.273573) (xy 306.964598 -283.256121) (xy 307.012817 -283.246277)
			(xy 307.061992 -283.244296) (xy 307.110847 -283.250228) (xy 307.158118 -283.26392) (xy 307.20258 -283.285018)
			(xy 307.243083 -283.312974) (xy 307.278576 -283.347066) (xy 307.308141 -283.38641) (xy 307.331012 -283.429987)
			(xy 307.346596 -283.476668) (xy 307.354491 -283.525245) (xy 307.354986 -283.549852) (xy 307.694088 -283.549852)
			(xy 307.698048 -283.500798) (xy 307.709825 -283.453014) (xy 307.729116 -283.407738) (xy 307.755419 -283.366142)
			(xy 307.788054 -283.329305) (xy 307.826175 -283.29818) (xy 307.868796 -283.273573) (xy 307.914812 -283.256121)
			(xy 307.963031 -283.246277) (xy 308.012206 -283.244296) (xy 308.061061 -283.250228) (xy 308.108332 -283.26392)
			(xy 308.152794 -283.285018) (xy 308.193297 -283.312974) (xy 308.22879 -283.347066) (xy 308.258355 -283.38641)
			(xy 308.281226 -283.429987) (xy 308.29681 -283.476668) (xy 308.304705 -283.525245) (xy 308.3052 -283.549852)
			(xy 308.304705 -283.574459) (xy 308.29681 -283.623036) (xy 308.281226 -283.669717) (xy 308.258355 -283.713294)
			(xy 308.22879 -283.752638) (xy 308.193297 -283.78673) (xy 308.152794 -283.814686) (xy 308.108332 -283.835784)
			(xy 308.061061 -283.849476) (xy 308.012206 -283.855408) (xy 307.963031 -283.853427) (xy 307.914812 -283.843583)
			(xy 307.868796 -283.826131) (xy 307.826175 -283.801524) (xy 307.788054 -283.770399) (xy 307.755419 -283.733562)
			(xy 307.729116 -283.691966) (xy 307.709825 -283.64669) (xy 307.698048 -283.598906) (xy 307.694088 -283.549852)
			(xy 307.354986 -283.549852) (xy 307.354491 -283.574459) (xy 307.346596 -283.623036) (xy 307.331012 -283.669717)
			(xy 307.308141 -283.713294) (xy 307.278576 -283.752638) (xy 307.243083 -283.78673) (xy 307.20258 -283.814686)
			(xy 307.158118 -283.835784) (xy 307.110847 -283.849476) (xy 307.061992 -283.855408) (xy 307.012817 -283.853427)
			(xy 306.964598 -283.843583) (xy 306.918582 -283.826131) (xy 306.875961 -283.801524) (xy 306.83784 -283.770399)
			(xy 306.805205 -283.733562) (xy 306.778902 -283.691966) (xy 306.759611 -283.64669) (xy 306.747834 -283.598906)
			(xy 306.743874 -283.549852) (xy 306.405026 -283.549852) (xy 306.404531 -283.574459) (xy 306.396636 -283.623036)
			(xy 306.381052 -283.669717) (xy 306.358181 -283.713294) (xy 306.328616 -283.752638) (xy 306.293123 -283.78673)
			(xy 306.25262 -283.814686) (xy 306.208158 -283.835784) (xy 306.160887 -283.849476) (xy 306.112032 -283.855408)
			(xy 306.062857 -283.853427) (xy 306.014638 -283.843583) (xy 305.968622 -283.826131) (xy 305.926001 -283.801524)
			(xy 305.88788 -283.770399) (xy 305.855245 -283.733562) (xy 305.828942 -283.691966) (xy 305.809651 -283.64669)
			(xy 305.797874 -283.598906) (xy 305.793914 -283.549852) (xy 266.590526 -283.549852) (xy 266.590526 -284.024832)
			(xy 268.26897 -284.024832) (xy 268.27293 -283.975778) (xy 268.284707 -283.927994) (xy 268.303998 -283.882718)
			(xy 268.330301 -283.841122) (xy 268.362936 -283.804285) (xy 268.401057 -283.77316) (xy 268.443678 -283.748553)
			(xy 268.489694 -283.731101) (xy 268.537913 -283.721257) (xy 268.587088 -283.719276) (xy 268.635943 -283.725208)
			(xy 268.683214 -283.7389) (xy 268.727676 -283.759998) (xy 268.768179 -283.787954) (xy 268.803672 -283.822046)
			(xy 268.833237 -283.86139) (xy 268.856108 -283.904967) (xy 268.871692 -283.951648) (xy 268.879587 -284.000225)
			(xy 268.880082 -284.024832) (xy 269.21893 -284.024832) (xy 269.22289 -283.975778) (xy 269.234667 -283.927994)
			(xy 269.253958 -283.882718) (xy 269.280261 -283.841122) (xy 269.312896 -283.804285) (xy 269.351017 -283.77316)
			(xy 269.393638 -283.748553) (xy 269.439654 -283.731101) (xy 269.487873 -283.721257) (xy 269.537048 -283.719276)
			(xy 269.585903 -283.725208) (xy 269.633174 -283.7389) (xy 269.677636 -283.759998) (xy 269.718139 -283.787954)
			(xy 269.753632 -283.822046) (xy 269.783197 -283.86139) (xy 269.806068 -283.904967) (xy 269.821652 -283.951648)
			(xy 269.829547 -284.000225) (xy 269.830042 -284.024832) (xy 270.169144 -284.024832) (xy 270.173104 -283.975778)
			(xy 270.184881 -283.927994) (xy 270.204172 -283.882718) (xy 270.230475 -283.841122) (xy 270.26311 -283.804285)
			(xy 270.301231 -283.77316) (xy 270.343852 -283.748553) (xy 270.389868 -283.731101) (xy 270.438087 -283.721257)
			(xy 270.487262 -283.719276) (xy 270.536117 -283.725208) (xy 270.583388 -283.7389) (xy 270.62785 -283.759998)
			(xy 270.668353 -283.787954) (xy 270.703846 -283.822046) (xy 270.733411 -283.86139) (xy 270.756282 -283.904967)
			(xy 270.771866 -283.951648) (xy 270.779761 -284.000225) (xy 270.780256 -284.024832) (xy 271.119104 -284.024832)
			(xy 271.123064 -283.975778) (xy 271.134841 -283.927994) (xy 271.154132 -283.882718) (xy 271.180435 -283.841122)
			(xy 271.21307 -283.804285) (xy 271.251191 -283.77316) (xy 271.293812 -283.748553) (xy 271.339828 -283.731101)
			(xy 271.388047 -283.721257) (xy 271.437222 -283.719276) (xy 271.486077 -283.725208) (xy 271.533348 -283.7389)
			(xy 271.57781 -283.759998) (xy 271.618313 -283.787954) (xy 271.653806 -283.822046) (xy 271.683371 -283.86139)
			(xy 271.706242 -283.904967) (xy 271.721826 -283.951648) (xy 271.729721 -284.000225) (xy 271.730216 -284.024832)
			(xy 272.069064 -284.024832) (xy 272.073024 -283.975778) (xy 272.084801 -283.927994) (xy 272.104092 -283.882718)
			(xy 272.130395 -283.841122) (xy 272.16303 -283.804285) (xy 272.201151 -283.77316) (xy 272.243772 -283.748553)
			(xy 272.289788 -283.731101) (xy 272.338007 -283.721257) (xy 272.387182 -283.719276) (xy 272.436037 -283.725208)
			(xy 272.483308 -283.7389) (xy 272.52777 -283.759998) (xy 272.568273 -283.787954) (xy 272.603766 -283.822046)
			(xy 272.633331 -283.86139) (xy 272.656202 -283.904967) (xy 272.671786 -283.951648) (xy 272.679681 -284.000225)
			(xy 272.680176 -284.024832) (xy 273.019024 -284.024832) (xy 273.022984 -283.975778) (xy 273.034761 -283.927994)
			(xy 273.054052 -283.882718) (xy 273.080355 -283.841122) (xy 273.11299 -283.804285) (xy 273.151111 -283.77316)
			(xy 273.193732 -283.748553) (xy 273.239748 -283.731101) (xy 273.287967 -283.721257) (xy 273.337142 -283.719276)
			(xy 273.385997 -283.725208) (xy 273.433268 -283.7389) (xy 273.47773 -283.759998) (xy 273.518233 -283.787954)
			(xy 273.553726 -283.822046) (xy 273.583291 -283.86139) (xy 273.606162 -283.904967) (xy 273.621746 -283.951648)
			(xy 273.629641 -284.000225) (xy 273.630136 -284.024832) (xy 273.968984 -284.024832) (xy 273.972944 -283.975778)
			(xy 273.984721 -283.927994) (xy 274.004012 -283.882718) (xy 274.030315 -283.841122) (xy 274.06295 -283.804285)
			(xy 274.101071 -283.77316) (xy 274.143692 -283.748553) (xy 274.189708 -283.731101) (xy 274.237927 -283.721257)
			(xy 274.287102 -283.719276) (xy 274.335957 -283.725208) (xy 274.383228 -283.7389) (xy 274.42769 -283.759998)
			(xy 274.468193 -283.787954) (xy 274.503686 -283.822046) (xy 274.533251 -283.86139) (xy 274.556122 -283.904967)
			(xy 274.571706 -283.951648) (xy 274.579601 -284.000225) (xy 274.580096 -284.024832) (xy 274.918944 -284.024832)
			(xy 274.922904 -283.975778) (xy 274.934681 -283.927994) (xy 274.953972 -283.882718) (xy 274.980275 -283.841122)
			(xy 275.01291 -283.804285) (xy 275.051031 -283.77316) (xy 275.093652 -283.748553) (xy 275.139668 -283.731101)
			(xy 275.187887 -283.721257) (xy 275.237062 -283.719276) (xy 275.285917 -283.725208) (xy 275.333188 -283.7389)
			(xy 275.37765 -283.759998) (xy 275.418153 -283.787954) (xy 275.453646 -283.822046) (xy 275.483211 -283.86139)
			(xy 275.506082 -283.904967) (xy 275.521666 -283.951648) (xy 275.529561 -284.000225) (xy 275.530056 -284.024832)
			(xy 275.868904 -284.024832) (xy 275.872864 -283.975778) (xy 275.884641 -283.927994) (xy 275.903932 -283.882718)
			(xy 275.930235 -283.841122) (xy 275.96287 -283.804285) (xy 276.000991 -283.77316) (xy 276.043612 -283.748553)
			(xy 276.089628 -283.731101) (xy 276.137847 -283.721257) (xy 276.187022 -283.719276) (xy 276.235877 -283.725208)
			(xy 276.283148 -283.7389) (xy 276.32761 -283.759998) (xy 276.368113 -283.787954) (xy 276.403606 -283.822046)
			(xy 276.433171 -283.86139) (xy 276.456042 -283.904967) (xy 276.471626 -283.951648) (xy 276.479521 -284.000225)
			(xy 276.480016 -284.024832) (xy 276.819118 -284.024832) (xy 276.823078 -283.975778) (xy 276.834855 -283.927994)
			(xy 276.854146 -283.882718) (xy 276.880449 -283.841122) (xy 276.913084 -283.804285) (xy 276.951205 -283.77316)
			(xy 276.993826 -283.748553) (xy 277.039842 -283.731101) (xy 277.088061 -283.721257) (xy 277.137236 -283.719276)
			(xy 277.186091 -283.725208) (xy 277.233362 -283.7389) (xy 277.277824 -283.759998) (xy 277.318327 -283.787954)
			(xy 277.35382 -283.822046) (xy 277.383385 -283.86139) (xy 277.406256 -283.904967) (xy 277.42184 -283.951648)
			(xy 277.429735 -284.000225) (xy 277.43023 -284.024832) (xy 277.769078 -284.024832) (xy 277.773038 -283.975778)
			(xy 277.784815 -283.927994) (xy 277.804106 -283.882718) (xy 277.830409 -283.841122) (xy 277.863044 -283.804285)
			(xy 277.901165 -283.77316) (xy 277.943786 -283.748553) (xy 277.989802 -283.731101) (xy 278.038021 -283.721257)
			(xy 278.087196 -283.719276) (xy 278.136051 -283.725208) (xy 278.183322 -283.7389) (xy 278.227784 -283.759998)
			(xy 278.268287 -283.787954) (xy 278.30378 -283.822046) (xy 278.333345 -283.86139) (xy 278.356216 -283.904967)
			(xy 278.3718 -283.951648) (xy 278.379695 -284.000225) (xy 278.38019 -284.024832) (xy 278.719038 -284.024832)
			(xy 278.722998 -283.975778) (xy 278.734775 -283.927994) (xy 278.754066 -283.882718) (xy 278.780369 -283.841122)
			(xy 278.813004 -283.804285) (xy 278.851125 -283.77316) (xy 278.893746 -283.748553) (xy 278.939762 -283.731101)
			(xy 278.987981 -283.721257) (xy 279.037156 -283.719276) (xy 279.086011 -283.725208) (xy 279.133282 -283.7389)
			(xy 279.177744 -283.759998) (xy 279.218247 -283.787954) (xy 279.25374 -283.822046) (xy 279.283305 -283.86139)
			(xy 279.306176 -283.904967) (xy 279.32176 -283.951648) (xy 279.329655 -284.000225) (xy 279.33015 -284.024832)
			(xy 279.668998 -284.024832) (xy 279.672958 -283.975778) (xy 279.684735 -283.927994) (xy 279.704026 -283.882718)
			(xy 279.730329 -283.841122) (xy 279.762964 -283.804285) (xy 279.801085 -283.77316) (xy 279.843706 -283.748553)
			(xy 279.889722 -283.731101) (xy 279.937941 -283.721257) (xy 279.987116 -283.719276) (xy 280.035971 -283.725208)
			(xy 280.083242 -283.7389) (xy 280.127704 -283.759998) (xy 280.168207 -283.787954) (xy 280.2037 -283.822046)
			(xy 280.233265 -283.86139) (xy 280.256136 -283.904967) (xy 280.27172 -283.951648) (xy 280.279615 -284.000225)
			(xy 280.28011 -284.024832) (xy 280.618958 -284.024832) (xy 280.622918 -283.975778) (xy 280.634695 -283.927994)
			(xy 280.653986 -283.882718) (xy 280.680289 -283.841122) (xy 280.712924 -283.804285) (xy 280.751045 -283.77316)
			(xy 280.793666 -283.748553) (xy 280.839682 -283.731101) (xy 280.887901 -283.721257) (xy 280.937076 -283.719276)
			(xy 280.985931 -283.725208) (xy 281.033202 -283.7389) (xy 281.077664 -283.759998) (xy 281.118167 -283.787954)
			(xy 281.15366 -283.822046) (xy 281.183225 -283.86139) (xy 281.206096 -283.904967) (xy 281.22168 -283.951648)
			(xy 281.229575 -284.000225) (xy 281.23007 -284.024832) (xy 281.568918 -284.024832) (xy 281.572878 -283.975778)
			(xy 281.584655 -283.927994) (xy 281.603946 -283.882718) (xy 281.630249 -283.841122) (xy 281.662884 -283.804285)
			(xy 281.701005 -283.77316) (xy 281.743626 -283.748553) (xy 281.789642 -283.731101) (xy 281.837861 -283.721257)
			(xy 281.887036 -283.719276) (xy 281.935891 -283.725208) (xy 281.983162 -283.7389) (xy 282.027624 -283.759998)
			(xy 282.068127 -283.787954) (xy 282.10362 -283.822046) (xy 282.133185 -283.86139) (xy 282.156056 -283.904967)
			(xy 282.17164 -283.951648) (xy 282.179535 -284.000225) (xy 282.18003 -284.024832) (xy 282.519132 -284.024832)
			(xy 282.523092 -283.975778) (xy 282.534869 -283.927994) (xy 282.55416 -283.882718) (xy 282.580463 -283.841122)
			(xy 282.613098 -283.804285) (xy 282.651219 -283.77316) (xy 282.69384 -283.748553) (xy 282.739856 -283.731101)
			(xy 282.788075 -283.721257) (xy 282.83725 -283.719276) (xy 282.886105 -283.725208) (xy 282.933376 -283.7389)
			(xy 282.977838 -283.759998) (xy 283.018341 -283.787954) (xy 283.053834 -283.822046) (xy 283.083399 -283.86139)
			(xy 283.10627 -283.904967) (xy 283.121854 -283.951648) (xy 283.129749 -284.000225) (xy 283.130244 -284.024832)
			(xy 283.469092 -284.024832) (xy 283.473052 -283.975778) (xy 283.484829 -283.927994) (xy 283.50412 -283.882718)
			(xy 283.530423 -283.841122) (xy 283.563058 -283.804285) (xy 283.601179 -283.77316) (xy 283.6438 -283.748553)
			(xy 283.689816 -283.731101) (xy 283.738035 -283.721257) (xy 283.78721 -283.719276) (xy 283.836065 -283.725208)
			(xy 283.883336 -283.7389) (xy 283.927798 -283.759998) (xy 283.968301 -283.787954) (xy 284.003794 -283.822046)
			(xy 284.033359 -283.86139) (xy 284.05623 -283.904967) (xy 284.071814 -283.951648) (xy 284.079709 -284.000225)
			(xy 284.080204 -284.024832) (xy 284.419052 -284.024832) (xy 284.423012 -283.975778) (xy 284.434789 -283.927994)
			(xy 284.45408 -283.882718) (xy 284.480383 -283.841122) (xy 284.513018 -283.804285) (xy 284.551139 -283.77316)
			(xy 284.59376 -283.748553) (xy 284.639776 -283.731101) (xy 284.687995 -283.721257) (xy 284.73717 -283.719276)
			(xy 284.786025 -283.725208) (xy 284.833296 -283.7389) (xy 284.877758 -283.759998) (xy 284.918261 -283.787954)
			(xy 284.953754 -283.822046) (xy 284.983319 -283.86139) (xy 285.00619 -283.904967) (xy 285.021774 -283.951648)
			(xy 285.029669 -284.000225) (xy 285.030164 -284.024832) (xy 285.369012 -284.024832) (xy 285.372972 -283.975778)
			(xy 285.384749 -283.927994) (xy 285.40404 -283.882718) (xy 285.430343 -283.841122) (xy 285.462978 -283.804285)
			(xy 285.501099 -283.77316) (xy 285.54372 -283.748553) (xy 285.589736 -283.731101) (xy 285.637955 -283.721257)
			(xy 285.68713 -283.719276) (xy 285.735985 -283.725208) (xy 285.783256 -283.7389) (xy 285.827718 -283.759998)
			(xy 285.868221 -283.787954) (xy 285.903714 -283.822046) (xy 285.933279 -283.86139) (xy 285.95615 -283.904967)
			(xy 285.971734 -283.951648) (xy 285.979629 -284.000225) (xy 285.980124 -284.024832) (xy 286.318972 -284.024832)
			(xy 286.322932 -283.975778) (xy 286.334709 -283.927994) (xy 286.354 -283.882718) (xy 286.380303 -283.841122)
			(xy 286.412938 -283.804285) (xy 286.451059 -283.77316) (xy 286.49368 -283.748553) (xy 286.539696 -283.731101)
			(xy 286.587915 -283.721257) (xy 286.63709 -283.719276) (xy 286.685945 -283.725208) (xy 286.733216 -283.7389)
			(xy 286.777678 -283.759998) (xy 286.818181 -283.787954) (xy 286.853674 -283.822046) (xy 286.883239 -283.86139)
			(xy 286.90611 -283.904967) (xy 286.921694 -283.951648) (xy 286.929589 -284.000225) (xy 286.930084 -284.024832)
			(xy 287.268932 -284.024832) (xy 287.272892 -283.975778) (xy 287.284669 -283.927994) (xy 287.30396 -283.882718)
			(xy 287.330263 -283.841122) (xy 287.362898 -283.804285) (xy 287.401019 -283.77316) (xy 287.44364 -283.748553)
			(xy 287.489656 -283.731101) (xy 287.537875 -283.721257) (xy 287.58705 -283.719276) (xy 287.635905 -283.725208)
			(xy 287.683176 -283.7389) (xy 287.727638 -283.759998) (xy 287.768141 -283.787954) (xy 287.803634 -283.822046)
			(xy 287.833199 -283.86139) (xy 287.85607 -283.904967) (xy 287.871654 -283.951648) (xy 287.879549 -284.000225)
			(xy 287.880044 -284.024832) (xy 288.218892 -284.024832) (xy 288.222852 -283.975778) (xy 288.234629 -283.927994)
			(xy 288.25392 -283.882718) (xy 288.280223 -283.841122) (xy 288.312858 -283.804285) (xy 288.350979 -283.77316)
			(xy 288.3936 -283.748553) (xy 288.439616 -283.731101) (xy 288.487835 -283.721257) (xy 288.53701 -283.719276)
			(xy 288.585865 -283.725208) (xy 288.633136 -283.7389) (xy 288.677598 -283.759998) (xy 288.718101 -283.787954)
			(xy 288.753594 -283.822046) (xy 288.783159 -283.86139) (xy 288.80603 -283.904967) (xy 288.821614 -283.951648)
			(xy 288.829509 -284.000225) (xy 288.830004 -284.024832) (xy 289.169106 -284.024832) (xy 289.173066 -283.975778)
			(xy 289.184843 -283.927994) (xy 289.204134 -283.882718) (xy 289.230437 -283.841122) (xy 289.263072 -283.804285)
			(xy 289.301193 -283.77316) (xy 289.343814 -283.748553) (xy 289.38983 -283.731101) (xy 289.438049 -283.721257)
			(xy 289.487224 -283.719276) (xy 289.536079 -283.725208) (xy 289.58335 -283.7389) (xy 289.627812 -283.759998)
			(xy 289.668315 -283.787954) (xy 289.703808 -283.822046) (xy 289.733373 -283.86139) (xy 289.756244 -283.904967)
			(xy 289.771828 -283.951648) (xy 289.779723 -284.000225) (xy 289.780218 -284.024832) (xy 290.119066 -284.024832)
			(xy 290.123026 -283.975778) (xy 290.134803 -283.927994) (xy 290.154094 -283.882718) (xy 290.180397 -283.841122)
			(xy 290.213032 -283.804285) (xy 290.251153 -283.77316) (xy 290.293774 -283.748553) (xy 290.33979 -283.731101)
			(xy 290.388009 -283.721257) (xy 290.437184 -283.719276) (xy 290.486039 -283.725208) (xy 290.53331 -283.7389)
			(xy 290.577772 -283.759998) (xy 290.618275 -283.787954) (xy 290.653768 -283.822046) (xy 290.683333 -283.86139)
			(xy 290.706204 -283.904967) (xy 290.721788 -283.951648) (xy 290.729683 -284.000225) (xy 290.730178 -284.024832)
			(xy 292.018986 -284.024832) (xy 292.022946 -283.975778) (xy 292.034723 -283.927994) (xy 292.054014 -283.882718)
			(xy 292.080317 -283.841122) (xy 292.112952 -283.804285) (xy 292.151073 -283.77316) (xy 292.193694 -283.748553)
			(xy 292.23971 -283.731101) (xy 292.287929 -283.721257) (xy 292.337104 -283.719276) (xy 292.385959 -283.725208)
			(xy 292.43323 -283.7389) (xy 292.477692 -283.759998) (xy 292.518195 -283.787954) (xy 292.553688 -283.822046)
			(xy 292.583253 -283.86139) (xy 292.606124 -283.904967) (xy 292.621708 -283.951648) (xy 292.629603 -284.000225)
			(xy 292.630098 -284.024832) (xy 292.968946 -284.024832) (xy 292.972906 -283.975778) (xy 292.984683 -283.927994)
			(xy 293.003974 -283.882718) (xy 293.030277 -283.841122) (xy 293.062912 -283.804285) (xy 293.101033 -283.77316)
			(xy 293.143654 -283.748553) (xy 293.18967 -283.731101) (xy 293.237889 -283.721257) (xy 293.287064 -283.719276)
			(xy 293.335919 -283.725208) (xy 293.38319 -283.7389) (xy 293.427652 -283.759998) (xy 293.468155 -283.787954)
			(xy 293.503648 -283.822046) (xy 293.533213 -283.86139) (xy 293.556084 -283.904967) (xy 293.571668 -283.951648)
			(xy 293.579563 -284.000225) (xy 293.580058 -284.024832) (xy 293.918906 -284.024832) (xy 293.922866 -283.975778)
			(xy 293.934643 -283.927994) (xy 293.953934 -283.882718) (xy 293.980237 -283.841122) (xy 294.012872 -283.804285)
			(xy 294.050993 -283.77316) (xy 294.093614 -283.748553) (xy 294.13963 -283.731101) (xy 294.187849 -283.721257)
			(xy 294.237024 -283.719276) (xy 294.285879 -283.725208) (xy 294.33315 -283.7389) (xy 294.377612 -283.759998)
			(xy 294.418115 -283.787954) (xy 294.453608 -283.822046) (xy 294.483173 -283.86139) (xy 294.506044 -283.904967)
			(xy 294.521628 -283.951648) (xy 294.529523 -284.000225) (xy 294.530018 -284.024832) (xy 294.86912 -284.024832)
			(xy 294.87308 -283.975778) (xy 294.884857 -283.927994) (xy 294.904148 -283.882718) (xy 294.930451 -283.841122)
			(xy 294.963086 -283.804285) (xy 295.001207 -283.77316) (xy 295.043828 -283.748553) (xy 295.089844 -283.731101)
			(xy 295.138063 -283.721257) (xy 295.187238 -283.719276) (xy 295.236093 -283.725208) (xy 295.283364 -283.7389)
			(xy 295.327826 -283.759998) (xy 295.368329 -283.787954) (xy 295.403822 -283.822046) (xy 295.433387 -283.86139)
			(xy 295.456258 -283.904967) (xy 295.471842 -283.951648) (xy 295.479737 -284.000225) (xy 295.480232 -284.024832)
			(xy 295.81908 -284.024832) (xy 295.82304 -283.975778) (xy 295.834817 -283.927994) (xy 295.854108 -283.882718)
			(xy 295.880411 -283.841122) (xy 295.913046 -283.804285) (xy 295.951167 -283.77316) (xy 295.993788 -283.748553)
			(xy 296.039804 -283.731101) (xy 296.088023 -283.721257) (xy 296.137198 -283.719276) (xy 296.186053 -283.725208)
			(xy 296.233324 -283.7389) (xy 296.277786 -283.759998) (xy 296.318289 -283.787954) (xy 296.353782 -283.822046)
			(xy 296.383347 -283.86139) (xy 296.406218 -283.904967) (xy 296.421802 -283.951648) (xy 296.429697 -284.000225)
			(xy 296.430192 -284.024832) (xy 296.76904 -284.024832) (xy 296.773 -283.975778) (xy 296.784777 -283.927994)
			(xy 296.804068 -283.882718) (xy 296.830371 -283.841122) (xy 296.863006 -283.804285) (xy 296.901127 -283.77316)
			(xy 296.943748 -283.748553) (xy 296.989764 -283.731101) (xy 297.037983 -283.721257) (xy 297.087158 -283.719276)
			(xy 297.136013 -283.725208) (xy 297.183284 -283.7389) (xy 297.227746 -283.759998) (xy 297.268249 -283.787954)
			(xy 297.303742 -283.822046) (xy 297.333307 -283.86139) (xy 297.356178 -283.904967) (xy 297.371762 -283.951648)
			(xy 297.379657 -284.000225) (xy 297.380152 -284.024832) (xy 297.719 -284.024832) (xy 297.72296 -283.975778)
			(xy 297.734737 -283.927994) (xy 297.754028 -283.882718) (xy 297.780331 -283.841122) (xy 297.812966 -283.804285)
			(xy 297.851087 -283.77316) (xy 297.893708 -283.748553) (xy 297.939724 -283.731101) (xy 297.987943 -283.721257)
			(xy 298.037118 -283.719276) (xy 298.085973 -283.725208) (xy 298.133244 -283.7389) (xy 298.177706 -283.759998)
			(xy 298.218209 -283.787954) (xy 298.253702 -283.822046) (xy 298.283267 -283.86139) (xy 298.306138 -283.904967)
			(xy 298.321722 -283.951648) (xy 298.329617 -284.000225) (xy 298.330112 -284.024832) (xy 298.66896 -284.024832)
			(xy 298.67292 -283.975778) (xy 298.684697 -283.927994) (xy 298.703988 -283.882718) (xy 298.730291 -283.841122)
			(xy 298.762926 -283.804285) (xy 298.801047 -283.77316) (xy 298.843668 -283.748553) (xy 298.889684 -283.731101)
			(xy 298.937903 -283.721257) (xy 298.987078 -283.719276) (xy 299.035933 -283.725208) (xy 299.083204 -283.7389)
			(xy 299.127666 -283.759998) (xy 299.168169 -283.787954) (xy 299.203662 -283.822046) (xy 299.233227 -283.86139)
			(xy 299.256098 -283.904967) (xy 299.271682 -283.951648) (xy 299.279577 -284.000225) (xy 299.280072 -284.024832)
			(xy 300.56888 -284.024832) (xy 300.57284 -283.975778) (xy 300.584617 -283.927994) (xy 300.603908 -283.882718)
			(xy 300.630211 -283.841122) (xy 300.662846 -283.804285) (xy 300.700967 -283.77316) (xy 300.743588 -283.748553)
			(xy 300.789604 -283.731101) (xy 300.837823 -283.721257) (xy 300.886998 -283.719276) (xy 300.935853 -283.725208)
			(xy 300.983124 -283.7389) (xy 301.027586 -283.759998) (xy 301.068089 -283.787954) (xy 301.103582 -283.822046)
			(xy 301.133147 -283.86139) (xy 301.156018 -283.904967) (xy 301.171602 -283.951648) (xy 301.179497 -284.000225)
			(xy 301.179992 -284.024832) (xy 301.519094 -284.024832) (xy 301.523054 -283.975778) (xy 301.534831 -283.927994)
			(xy 301.554122 -283.882718) (xy 301.580425 -283.841122) (xy 301.61306 -283.804285) (xy 301.651181 -283.77316)
			(xy 301.693802 -283.748553) (xy 301.739818 -283.731101) (xy 301.788037 -283.721257) (xy 301.837212 -283.719276)
			(xy 301.886067 -283.725208) (xy 301.933338 -283.7389) (xy 301.9778 -283.759998) (xy 302.018303 -283.787954)
			(xy 302.053796 -283.822046) (xy 302.083361 -283.86139) (xy 302.106232 -283.904967) (xy 302.121816 -283.951648)
			(xy 302.129711 -284.000225) (xy 302.130206 -284.024832) (xy 302.469054 -284.024832) (xy 302.473014 -283.975778)
			(xy 302.484791 -283.927994) (xy 302.504082 -283.882718) (xy 302.530385 -283.841122) (xy 302.56302 -283.804285)
			(xy 302.601141 -283.77316) (xy 302.643762 -283.748553) (xy 302.689778 -283.731101) (xy 302.737997 -283.721257)
			(xy 302.787172 -283.719276) (xy 302.836027 -283.725208) (xy 302.883298 -283.7389) (xy 302.92776 -283.759998)
			(xy 302.968263 -283.787954) (xy 303.003756 -283.822046) (xy 303.033321 -283.86139) (xy 303.056192 -283.904967)
			(xy 303.071776 -283.951648) (xy 303.079671 -284.000225) (xy 303.080166 -284.024832) (xy 303.419014 -284.024832)
			(xy 303.422974 -283.975778) (xy 303.434751 -283.927994) (xy 303.454042 -283.882718) (xy 303.480345 -283.841122)
			(xy 303.51298 -283.804285) (xy 303.551101 -283.77316) (xy 303.593722 -283.748553) (xy 303.639738 -283.731101)
			(xy 303.687957 -283.721257) (xy 303.737132 -283.719276) (xy 303.785987 -283.725208) (xy 303.833258 -283.7389)
			(xy 303.87772 -283.759998) (xy 303.918223 -283.787954) (xy 303.953716 -283.822046) (xy 303.983281 -283.86139)
			(xy 304.006152 -283.904967) (xy 304.021736 -283.951648) (xy 304.029631 -284.000225) (xy 304.030126 -284.024832)
			(xy 304.368974 -284.024832) (xy 304.372934 -283.975778) (xy 304.384711 -283.927994) (xy 304.404002 -283.882718)
			(xy 304.430305 -283.841122) (xy 304.46294 -283.804285) (xy 304.501061 -283.77316) (xy 304.543682 -283.748553)
			(xy 304.589698 -283.731101) (xy 304.637917 -283.721257) (xy 304.687092 -283.719276) (xy 304.735947 -283.725208)
			(xy 304.783218 -283.7389) (xy 304.82768 -283.759998) (xy 304.868183 -283.787954) (xy 304.903676 -283.822046)
			(xy 304.933241 -283.86139) (xy 304.956112 -283.904967) (xy 304.971696 -283.951648) (xy 304.979591 -284.000225)
			(xy 304.980086 -284.024832) (xy 304.979591 -284.049439) (xy 304.971696 -284.098016) (xy 304.956112 -284.144697)
			(xy 304.933241 -284.188274) (xy 304.903676 -284.227618) (xy 304.868183 -284.26171) (xy 304.82768 -284.289666)
			(xy 304.783218 -284.310764) (xy 304.735947 -284.324456) (xy 304.687092 -284.330388) (xy 304.637917 -284.328407)
			(xy 304.589698 -284.318563) (xy 304.543682 -284.301111) (xy 304.501061 -284.276504) (xy 304.46294 -284.245379)
			(xy 304.430305 -284.208542) (xy 304.404002 -284.166946) (xy 304.384711 -284.12167) (xy 304.372934 -284.073886)
			(xy 304.368974 -284.024832) (xy 304.030126 -284.024832) (xy 304.029631 -284.049439) (xy 304.021736 -284.098016)
			(xy 304.006152 -284.144697) (xy 303.983281 -284.188274) (xy 303.953716 -284.227618) (xy 303.918223 -284.26171)
			(xy 303.87772 -284.289666) (xy 303.833258 -284.310764) (xy 303.785987 -284.324456) (xy 303.737132 -284.330388)
			(xy 303.687957 -284.328407) (xy 303.639738 -284.318563) (xy 303.593722 -284.301111) (xy 303.551101 -284.276504)
			(xy 303.51298 -284.245379) (xy 303.480345 -284.208542) (xy 303.454042 -284.166946) (xy 303.434751 -284.12167)
			(xy 303.422974 -284.073886) (xy 303.419014 -284.024832) (xy 303.080166 -284.024832) (xy 303.079671 -284.049439)
			(xy 303.071776 -284.098016) (xy 303.056192 -284.144697) (xy 303.033321 -284.188274) (xy 303.003756 -284.227618)
			(xy 302.968263 -284.26171) (xy 302.92776 -284.289666) (xy 302.883298 -284.310764) (xy 302.836027 -284.324456)
			(xy 302.787172 -284.330388) (xy 302.737997 -284.328407) (xy 302.689778 -284.318563) (xy 302.643762 -284.301111)
			(xy 302.601141 -284.276504) (xy 302.56302 -284.245379) (xy 302.530385 -284.208542) (xy 302.504082 -284.166946)
			(xy 302.484791 -284.12167) (xy 302.473014 -284.073886) (xy 302.469054 -284.024832) (xy 302.130206 -284.024832)
			(xy 302.129711 -284.049439) (xy 302.121816 -284.098016) (xy 302.106232 -284.144697) (xy 302.083361 -284.188274)
			(xy 302.053796 -284.227618) (xy 302.018303 -284.26171) (xy 301.9778 -284.289666) (xy 301.933338 -284.310764)
			(xy 301.886067 -284.324456) (xy 301.837212 -284.330388) (xy 301.788037 -284.328407) (xy 301.739818 -284.318563)
			(xy 301.693802 -284.301111) (xy 301.651181 -284.276504) (xy 301.61306 -284.245379) (xy 301.580425 -284.208542)
			(xy 301.554122 -284.166946) (xy 301.534831 -284.12167) (xy 301.523054 -284.073886) (xy 301.519094 -284.024832)
			(xy 301.179992 -284.024832) (xy 301.179497 -284.049439) (xy 301.171602 -284.098016) (xy 301.156018 -284.144697)
			(xy 301.133147 -284.188274) (xy 301.103582 -284.227618) (xy 301.068089 -284.26171) (xy 301.027586 -284.289666)
			(xy 300.983124 -284.310764) (xy 300.935853 -284.324456) (xy 300.886998 -284.330388) (xy 300.837823 -284.328407)
			(xy 300.789604 -284.318563) (xy 300.743588 -284.301111) (xy 300.700967 -284.276504) (xy 300.662846 -284.245379)
			(xy 300.630211 -284.208542) (xy 300.603908 -284.166946) (xy 300.584617 -284.12167) (xy 300.57284 -284.073886)
			(xy 300.56888 -284.024832) (xy 299.280072 -284.024832) (xy 299.279577 -284.049439) (xy 299.271682 -284.098016)
			(xy 299.256098 -284.144697) (xy 299.233227 -284.188274) (xy 299.203662 -284.227618) (xy 299.168169 -284.26171)
			(xy 299.127666 -284.289666) (xy 299.083204 -284.310764) (xy 299.035933 -284.324456) (xy 298.987078 -284.330388)
			(xy 298.937903 -284.328407) (xy 298.889684 -284.318563) (xy 298.843668 -284.301111) (xy 298.801047 -284.276504)
			(xy 298.762926 -284.245379) (xy 298.730291 -284.208542) (xy 298.703988 -284.166946) (xy 298.684697 -284.12167)
			(xy 298.67292 -284.073886) (xy 298.66896 -284.024832) (xy 298.330112 -284.024832) (xy 298.329617 -284.049439)
			(xy 298.321722 -284.098016) (xy 298.306138 -284.144697) (xy 298.283267 -284.188274) (xy 298.253702 -284.227618)
			(xy 298.218209 -284.26171) (xy 298.177706 -284.289666) (xy 298.133244 -284.310764) (xy 298.085973 -284.324456)
			(xy 298.037118 -284.330388) (xy 297.987943 -284.328407) (xy 297.939724 -284.318563) (xy 297.893708 -284.301111)
			(xy 297.851087 -284.276504) (xy 297.812966 -284.245379) (xy 297.780331 -284.208542) (xy 297.754028 -284.166946)
			(xy 297.734737 -284.12167) (xy 297.72296 -284.073886) (xy 297.719 -284.024832) (xy 297.380152 -284.024832)
			(xy 297.379657 -284.049439) (xy 297.371762 -284.098016) (xy 297.356178 -284.144697) (xy 297.333307 -284.188274)
			(xy 297.303742 -284.227618) (xy 297.268249 -284.26171) (xy 297.227746 -284.289666) (xy 297.183284 -284.310764)
			(xy 297.136013 -284.324456) (xy 297.087158 -284.330388) (xy 297.037983 -284.328407) (xy 296.989764 -284.318563)
			(xy 296.943748 -284.301111) (xy 296.901127 -284.276504) (xy 296.863006 -284.245379) (xy 296.830371 -284.208542)
			(xy 296.804068 -284.166946) (xy 296.784777 -284.12167) (xy 296.773 -284.073886) (xy 296.76904 -284.024832)
			(xy 296.430192 -284.024832) (xy 296.429697 -284.049439) (xy 296.421802 -284.098016) (xy 296.406218 -284.144697)
			(xy 296.383347 -284.188274) (xy 296.353782 -284.227618) (xy 296.318289 -284.26171) (xy 296.277786 -284.289666)
			(xy 296.233324 -284.310764) (xy 296.186053 -284.324456) (xy 296.137198 -284.330388) (xy 296.088023 -284.328407)
			(xy 296.039804 -284.318563) (xy 295.993788 -284.301111) (xy 295.951167 -284.276504) (xy 295.913046 -284.245379)
			(xy 295.880411 -284.208542) (xy 295.854108 -284.166946) (xy 295.834817 -284.12167) (xy 295.82304 -284.073886)
			(xy 295.81908 -284.024832) (xy 295.480232 -284.024832) (xy 295.479737 -284.049439) (xy 295.471842 -284.098016)
			(xy 295.456258 -284.144697) (xy 295.433387 -284.188274) (xy 295.403822 -284.227618) (xy 295.368329 -284.26171)
			(xy 295.327826 -284.289666) (xy 295.283364 -284.310764) (xy 295.236093 -284.324456) (xy 295.187238 -284.330388)
			(xy 295.138063 -284.328407) (xy 295.089844 -284.318563) (xy 295.043828 -284.301111) (xy 295.001207 -284.276504)
			(xy 294.963086 -284.245379) (xy 294.930451 -284.208542) (xy 294.904148 -284.166946) (xy 294.884857 -284.12167)
			(xy 294.87308 -284.073886) (xy 294.86912 -284.024832) (xy 294.530018 -284.024832) (xy 294.529523 -284.049439)
			(xy 294.521628 -284.098016) (xy 294.506044 -284.144697) (xy 294.483173 -284.188274) (xy 294.453608 -284.227618)
			(xy 294.418115 -284.26171) (xy 294.377612 -284.289666) (xy 294.33315 -284.310764) (xy 294.285879 -284.324456)
			(xy 294.237024 -284.330388) (xy 294.187849 -284.328407) (xy 294.13963 -284.318563) (xy 294.093614 -284.301111)
			(xy 294.050993 -284.276504) (xy 294.012872 -284.245379) (xy 293.980237 -284.208542) (xy 293.953934 -284.166946)
			(xy 293.934643 -284.12167) (xy 293.922866 -284.073886) (xy 293.918906 -284.024832) (xy 293.580058 -284.024832)
			(xy 293.579563 -284.049439) (xy 293.571668 -284.098016) (xy 293.556084 -284.144697) (xy 293.533213 -284.188274)
			(xy 293.503648 -284.227618) (xy 293.468155 -284.26171) (xy 293.427652 -284.289666) (xy 293.38319 -284.310764)
			(xy 293.335919 -284.324456) (xy 293.287064 -284.330388) (xy 293.237889 -284.328407) (xy 293.18967 -284.318563)
			(xy 293.143654 -284.301111) (xy 293.101033 -284.276504) (xy 293.062912 -284.245379) (xy 293.030277 -284.208542)
			(xy 293.003974 -284.166946) (xy 292.984683 -284.12167) (xy 292.972906 -284.073886) (xy 292.968946 -284.024832)
			(xy 292.630098 -284.024832) (xy 292.629603 -284.049439) (xy 292.621708 -284.098016) (xy 292.606124 -284.144697)
			(xy 292.583253 -284.188274) (xy 292.553688 -284.227618) (xy 292.518195 -284.26171) (xy 292.477692 -284.289666)
			(xy 292.43323 -284.310764) (xy 292.385959 -284.324456) (xy 292.337104 -284.330388) (xy 292.287929 -284.328407)
			(xy 292.23971 -284.318563) (xy 292.193694 -284.301111) (xy 292.151073 -284.276504) (xy 292.112952 -284.245379)
			(xy 292.080317 -284.208542) (xy 292.054014 -284.166946) (xy 292.034723 -284.12167) (xy 292.022946 -284.073886)
			(xy 292.018986 -284.024832) (xy 290.730178 -284.024832) (xy 290.729683 -284.049439) (xy 290.721788 -284.098016)
			(xy 290.706204 -284.144697) (xy 290.683333 -284.188274) (xy 290.653768 -284.227618) (xy 290.618275 -284.26171)
			(xy 290.577772 -284.289666) (xy 290.53331 -284.310764) (xy 290.486039 -284.324456) (xy 290.437184 -284.330388)
			(xy 290.388009 -284.328407) (xy 290.33979 -284.318563) (xy 290.293774 -284.301111) (xy 290.251153 -284.276504)
			(xy 290.213032 -284.245379) (xy 290.180397 -284.208542) (xy 290.154094 -284.166946) (xy 290.134803 -284.12167)
			(xy 290.123026 -284.073886) (xy 290.119066 -284.024832) (xy 289.780218 -284.024832) (xy 289.779723 -284.049439)
			(xy 289.771828 -284.098016) (xy 289.756244 -284.144697) (xy 289.733373 -284.188274) (xy 289.703808 -284.227618)
			(xy 289.668315 -284.26171) (xy 289.627812 -284.289666) (xy 289.58335 -284.310764) (xy 289.536079 -284.324456)
			(xy 289.487224 -284.330388) (xy 289.438049 -284.328407) (xy 289.38983 -284.318563) (xy 289.343814 -284.301111)
			(xy 289.301193 -284.276504) (xy 289.263072 -284.245379) (xy 289.230437 -284.208542) (xy 289.204134 -284.166946)
			(xy 289.184843 -284.12167) (xy 289.173066 -284.073886) (xy 289.169106 -284.024832) (xy 288.830004 -284.024832)
			(xy 288.829509 -284.049439) (xy 288.821614 -284.098016) (xy 288.80603 -284.144697) (xy 288.783159 -284.188274)
			(xy 288.753594 -284.227618) (xy 288.718101 -284.26171) (xy 288.677598 -284.289666) (xy 288.633136 -284.310764)
			(xy 288.585865 -284.324456) (xy 288.53701 -284.330388) (xy 288.487835 -284.328407) (xy 288.439616 -284.318563)
			(xy 288.3936 -284.301111) (xy 288.350979 -284.276504) (xy 288.312858 -284.245379) (xy 288.280223 -284.208542)
			(xy 288.25392 -284.166946) (xy 288.234629 -284.12167) (xy 288.222852 -284.073886) (xy 288.218892 -284.024832)
			(xy 287.880044 -284.024832) (xy 287.879549 -284.049439) (xy 287.871654 -284.098016) (xy 287.85607 -284.144697)
			(xy 287.833199 -284.188274) (xy 287.803634 -284.227618) (xy 287.768141 -284.26171) (xy 287.727638 -284.289666)
			(xy 287.683176 -284.310764) (xy 287.635905 -284.324456) (xy 287.58705 -284.330388) (xy 287.537875 -284.328407)
			(xy 287.489656 -284.318563) (xy 287.44364 -284.301111) (xy 287.401019 -284.276504) (xy 287.362898 -284.245379)
			(xy 287.330263 -284.208542) (xy 287.30396 -284.166946) (xy 287.284669 -284.12167) (xy 287.272892 -284.073886)
			(xy 287.268932 -284.024832) (xy 286.930084 -284.024832) (xy 286.929589 -284.049439) (xy 286.921694 -284.098016)
			(xy 286.90611 -284.144697) (xy 286.883239 -284.188274) (xy 286.853674 -284.227618) (xy 286.818181 -284.26171)
			(xy 286.777678 -284.289666) (xy 286.733216 -284.310764) (xy 286.685945 -284.324456) (xy 286.63709 -284.330388)
			(xy 286.587915 -284.328407) (xy 286.539696 -284.318563) (xy 286.49368 -284.301111) (xy 286.451059 -284.276504)
			(xy 286.412938 -284.245379) (xy 286.380303 -284.208542) (xy 286.354 -284.166946) (xy 286.334709 -284.12167)
			(xy 286.322932 -284.073886) (xy 286.318972 -284.024832) (xy 285.980124 -284.024832) (xy 285.979629 -284.049439)
			(xy 285.971734 -284.098016) (xy 285.95615 -284.144697) (xy 285.933279 -284.188274) (xy 285.903714 -284.227618)
			(xy 285.868221 -284.26171) (xy 285.827718 -284.289666) (xy 285.783256 -284.310764) (xy 285.735985 -284.324456)
			(xy 285.68713 -284.330388) (xy 285.637955 -284.328407) (xy 285.589736 -284.318563) (xy 285.54372 -284.301111)
			(xy 285.501099 -284.276504) (xy 285.462978 -284.245379) (xy 285.430343 -284.208542) (xy 285.40404 -284.166946)
			(xy 285.384749 -284.12167) (xy 285.372972 -284.073886) (xy 285.369012 -284.024832) (xy 285.030164 -284.024832)
			(xy 285.029669 -284.049439) (xy 285.021774 -284.098016) (xy 285.00619 -284.144697) (xy 284.983319 -284.188274)
			(xy 284.953754 -284.227618) (xy 284.918261 -284.26171) (xy 284.877758 -284.289666) (xy 284.833296 -284.310764)
			(xy 284.786025 -284.324456) (xy 284.73717 -284.330388) (xy 284.687995 -284.328407) (xy 284.639776 -284.318563)
			(xy 284.59376 -284.301111) (xy 284.551139 -284.276504) (xy 284.513018 -284.245379) (xy 284.480383 -284.208542)
			(xy 284.45408 -284.166946) (xy 284.434789 -284.12167) (xy 284.423012 -284.073886) (xy 284.419052 -284.024832)
			(xy 284.080204 -284.024832) (xy 284.079709 -284.049439) (xy 284.071814 -284.098016) (xy 284.05623 -284.144697)
			(xy 284.033359 -284.188274) (xy 284.003794 -284.227618) (xy 283.968301 -284.26171) (xy 283.927798 -284.289666)
			(xy 283.883336 -284.310764) (xy 283.836065 -284.324456) (xy 283.78721 -284.330388) (xy 283.738035 -284.328407)
			(xy 283.689816 -284.318563) (xy 283.6438 -284.301111) (xy 283.601179 -284.276504) (xy 283.563058 -284.245379)
			(xy 283.530423 -284.208542) (xy 283.50412 -284.166946) (xy 283.484829 -284.12167) (xy 283.473052 -284.073886)
			(xy 283.469092 -284.024832) (xy 283.130244 -284.024832) (xy 283.129749 -284.049439) (xy 283.121854 -284.098016)
			(xy 283.10627 -284.144697) (xy 283.083399 -284.188274) (xy 283.053834 -284.227618) (xy 283.018341 -284.26171)
			(xy 282.977838 -284.289666) (xy 282.933376 -284.310764) (xy 282.886105 -284.324456) (xy 282.83725 -284.330388)
			(xy 282.788075 -284.328407) (xy 282.739856 -284.318563) (xy 282.69384 -284.301111) (xy 282.651219 -284.276504)
			(xy 282.613098 -284.245379) (xy 282.580463 -284.208542) (xy 282.55416 -284.166946) (xy 282.534869 -284.12167)
			(xy 282.523092 -284.073886) (xy 282.519132 -284.024832) (xy 282.18003 -284.024832) (xy 282.179535 -284.049439)
			(xy 282.17164 -284.098016) (xy 282.156056 -284.144697) (xy 282.133185 -284.188274) (xy 282.10362 -284.227618)
			(xy 282.068127 -284.26171) (xy 282.027624 -284.289666) (xy 281.983162 -284.310764) (xy 281.935891 -284.324456)
			(xy 281.887036 -284.330388) (xy 281.837861 -284.328407) (xy 281.789642 -284.318563) (xy 281.743626 -284.301111)
			(xy 281.701005 -284.276504) (xy 281.662884 -284.245379) (xy 281.630249 -284.208542) (xy 281.603946 -284.166946)
			(xy 281.584655 -284.12167) (xy 281.572878 -284.073886) (xy 281.568918 -284.024832) (xy 281.23007 -284.024832)
			(xy 281.229575 -284.049439) (xy 281.22168 -284.098016) (xy 281.206096 -284.144697) (xy 281.183225 -284.188274)
			(xy 281.15366 -284.227618) (xy 281.118167 -284.26171) (xy 281.077664 -284.289666) (xy 281.033202 -284.310764)
			(xy 280.985931 -284.324456) (xy 280.937076 -284.330388) (xy 280.887901 -284.328407) (xy 280.839682 -284.318563)
			(xy 280.793666 -284.301111) (xy 280.751045 -284.276504) (xy 280.712924 -284.245379) (xy 280.680289 -284.208542)
			(xy 280.653986 -284.166946) (xy 280.634695 -284.12167) (xy 280.622918 -284.073886) (xy 280.618958 -284.024832)
			(xy 280.28011 -284.024832) (xy 280.279615 -284.049439) (xy 280.27172 -284.098016) (xy 280.256136 -284.144697)
			(xy 280.233265 -284.188274) (xy 280.2037 -284.227618) (xy 280.168207 -284.26171) (xy 280.127704 -284.289666)
			(xy 280.083242 -284.310764) (xy 280.035971 -284.324456) (xy 279.987116 -284.330388) (xy 279.937941 -284.328407)
			(xy 279.889722 -284.318563) (xy 279.843706 -284.301111) (xy 279.801085 -284.276504) (xy 279.762964 -284.245379)
			(xy 279.730329 -284.208542) (xy 279.704026 -284.166946) (xy 279.684735 -284.12167) (xy 279.672958 -284.073886)
			(xy 279.668998 -284.024832) (xy 279.33015 -284.024832) (xy 279.329655 -284.049439) (xy 279.32176 -284.098016)
			(xy 279.306176 -284.144697) (xy 279.283305 -284.188274) (xy 279.25374 -284.227618) (xy 279.218247 -284.26171)
			(xy 279.177744 -284.289666) (xy 279.133282 -284.310764) (xy 279.086011 -284.324456) (xy 279.037156 -284.330388)
			(xy 278.987981 -284.328407) (xy 278.939762 -284.318563) (xy 278.893746 -284.301111) (xy 278.851125 -284.276504)
			(xy 278.813004 -284.245379) (xy 278.780369 -284.208542) (xy 278.754066 -284.166946) (xy 278.734775 -284.12167)
			(xy 278.722998 -284.073886) (xy 278.719038 -284.024832) (xy 278.38019 -284.024832) (xy 278.379695 -284.049439)
			(xy 278.3718 -284.098016) (xy 278.356216 -284.144697) (xy 278.333345 -284.188274) (xy 278.30378 -284.227618)
			(xy 278.268287 -284.26171) (xy 278.227784 -284.289666) (xy 278.183322 -284.310764) (xy 278.136051 -284.324456)
			(xy 278.087196 -284.330388) (xy 278.038021 -284.328407) (xy 277.989802 -284.318563) (xy 277.943786 -284.301111)
			(xy 277.901165 -284.276504) (xy 277.863044 -284.245379) (xy 277.830409 -284.208542) (xy 277.804106 -284.166946)
			(xy 277.784815 -284.12167) (xy 277.773038 -284.073886) (xy 277.769078 -284.024832) (xy 277.43023 -284.024832)
			(xy 277.429735 -284.049439) (xy 277.42184 -284.098016) (xy 277.406256 -284.144697) (xy 277.383385 -284.188274)
			(xy 277.35382 -284.227618) (xy 277.318327 -284.26171) (xy 277.277824 -284.289666) (xy 277.233362 -284.310764)
			(xy 277.186091 -284.324456) (xy 277.137236 -284.330388) (xy 277.088061 -284.328407) (xy 277.039842 -284.318563)
			(xy 276.993826 -284.301111) (xy 276.951205 -284.276504) (xy 276.913084 -284.245379) (xy 276.880449 -284.208542)
			(xy 276.854146 -284.166946) (xy 276.834855 -284.12167) (xy 276.823078 -284.073886) (xy 276.819118 -284.024832)
			(xy 276.480016 -284.024832) (xy 276.479521 -284.049439) (xy 276.471626 -284.098016) (xy 276.456042 -284.144697)
			(xy 276.433171 -284.188274) (xy 276.403606 -284.227618) (xy 276.368113 -284.26171) (xy 276.32761 -284.289666)
			(xy 276.283148 -284.310764) (xy 276.235877 -284.324456) (xy 276.187022 -284.330388) (xy 276.137847 -284.328407)
			(xy 276.089628 -284.318563) (xy 276.043612 -284.301111) (xy 276.000991 -284.276504) (xy 275.96287 -284.245379)
			(xy 275.930235 -284.208542) (xy 275.903932 -284.166946) (xy 275.884641 -284.12167) (xy 275.872864 -284.073886)
			(xy 275.868904 -284.024832) (xy 275.530056 -284.024832) (xy 275.529561 -284.049439) (xy 275.521666 -284.098016)
			(xy 275.506082 -284.144697) (xy 275.483211 -284.188274) (xy 275.453646 -284.227618) (xy 275.418153 -284.26171)
			(xy 275.37765 -284.289666) (xy 275.333188 -284.310764) (xy 275.285917 -284.324456) (xy 275.237062 -284.330388)
			(xy 275.187887 -284.328407) (xy 275.139668 -284.318563) (xy 275.093652 -284.301111) (xy 275.051031 -284.276504)
			(xy 275.01291 -284.245379) (xy 274.980275 -284.208542) (xy 274.953972 -284.166946) (xy 274.934681 -284.12167)
			(xy 274.922904 -284.073886) (xy 274.918944 -284.024832) (xy 274.580096 -284.024832) (xy 274.579601 -284.049439)
			(xy 274.571706 -284.098016) (xy 274.556122 -284.144697) (xy 274.533251 -284.188274) (xy 274.503686 -284.227618)
			(xy 274.468193 -284.26171) (xy 274.42769 -284.289666) (xy 274.383228 -284.310764) (xy 274.335957 -284.324456)
			(xy 274.287102 -284.330388) (xy 274.237927 -284.328407) (xy 274.189708 -284.318563) (xy 274.143692 -284.301111)
			(xy 274.101071 -284.276504) (xy 274.06295 -284.245379) (xy 274.030315 -284.208542) (xy 274.004012 -284.166946)
			(xy 273.984721 -284.12167) (xy 273.972944 -284.073886) (xy 273.968984 -284.024832) (xy 273.630136 -284.024832)
			(xy 273.629641 -284.049439) (xy 273.621746 -284.098016) (xy 273.606162 -284.144697) (xy 273.583291 -284.188274)
			(xy 273.553726 -284.227618) (xy 273.518233 -284.26171) (xy 273.47773 -284.289666) (xy 273.433268 -284.310764)
			(xy 273.385997 -284.324456) (xy 273.337142 -284.330388) (xy 273.287967 -284.328407) (xy 273.239748 -284.318563)
			(xy 273.193732 -284.301111) (xy 273.151111 -284.276504) (xy 273.11299 -284.245379) (xy 273.080355 -284.208542)
			(xy 273.054052 -284.166946) (xy 273.034761 -284.12167) (xy 273.022984 -284.073886) (xy 273.019024 -284.024832)
			(xy 272.680176 -284.024832) (xy 272.679681 -284.049439) (xy 272.671786 -284.098016) (xy 272.656202 -284.144697)
			(xy 272.633331 -284.188274) (xy 272.603766 -284.227618) (xy 272.568273 -284.26171) (xy 272.52777 -284.289666)
			(xy 272.483308 -284.310764) (xy 272.436037 -284.324456) (xy 272.387182 -284.330388) (xy 272.338007 -284.328407)
			(xy 272.289788 -284.318563) (xy 272.243772 -284.301111) (xy 272.201151 -284.276504) (xy 272.16303 -284.245379)
			(xy 272.130395 -284.208542) (xy 272.104092 -284.166946) (xy 272.084801 -284.12167) (xy 272.073024 -284.073886)
			(xy 272.069064 -284.024832) (xy 271.730216 -284.024832) (xy 271.729721 -284.049439) (xy 271.721826 -284.098016)
			(xy 271.706242 -284.144697) (xy 271.683371 -284.188274) (xy 271.653806 -284.227618) (xy 271.618313 -284.26171)
			(xy 271.57781 -284.289666) (xy 271.533348 -284.310764) (xy 271.486077 -284.324456) (xy 271.437222 -284.330388)
			(xy 271.388047 -284.328407) (xy 271.339828 -284.318563) (xy 271.293812 -284.301111) (xy 271.251191 -284.276504)
			(xy 271.21307 -284.245379) (xy 271.180435 -284.208542) (xy 271.154132 -284.166946) (xy 271.134841 -284.12167)
			(xy 271.123064 -284.073886) (xy 271.119104 -284.024832) (xy 270.780256 -284.024832) (xy 270.779761 -284.049439)
			(xy 270.771866 -284.098016) (xy 270.756282 -284.144697) (xy 270.733411 -284.188274) (xy 270.703846 -284.227618)
			(xy 270.668353 -284.26171) (xy 270.62785 -284.289666) (xy 270.583388 -284.310764) (xy 270.536117 -284.324456)
			(xy 270.487262 -284.330388) (xy 270.438087 -284.328407) (xy 270.389868 -284.318563) (xy 270.343852 -284.301111)
			(xy 270.301231 -284.276504) (xy 270.26311 -284.245379) (xy 270.230475 -284.208542) (xy 270.204172 -284.166946)
			(xy 270.184881 -284.12167) (xy 270.173104 -284.073886) (xy 270.169144 -284.024832) (xy 269.830042 -284.024832)
			(xy 269.829547 -284.049439) (xy 269.821652 -284.098016) (xy 269.806068 -284.144697) (xy 269.783197 -284.188274)
			(xy 269.753632 -284.227618) (xy 269.718139 -284.26171) (xy 269.677636 -284.289666) (xy 269.633174 -284.310764)
			(xy 269.585903 -284.324456) (xy 269.537048 -284.330388) (xy 269.487873 -284.328407) (xy 269.439654 -284.318563)
			(xy 269.393638 -284.301111) (xy 269.351017 -284.276504) (xy 269.312896 -284.245379) (xy 269.280261 -284.208542)
			(xy 269.253958 -284.166946) (xy 269.234667 -284.12167) (xy 269.22289 -284.073886) (xy 269.21893 -284.024832)
			(xy 268.880082 -284.024832) (xy 268.879587 -284.049439) (xy 268.871692 -284.098016) (xy 268.856108 -284.144697)
			(xy 268.833237 -284.188274) (xy 268.803672 -284.227618) (xy 268.768179 -284.26171) (xy 268.727676 -284.289666)
			(xy 268.683214 -284.310764) (xy 268.635943 -284.324456) (xy 268.587088 -284.330388) (xy 268.537913 -284.328407)
			(xy 268.489694 -284.318563) (xy 268.443678 -284.301111) (xy 268.401057 -284.276504) (xy 268.362936 -284.245379)
			(xy 268.330301 -284.208542) (xy 268.303998 -284.166946) (xy 268.284707 -284.12167) (xy 268.27293 -284.073886)
			(xy 268.26897 -284.024832) (xy 266.590526 -284.024832) (xy 266.590526 -284.499812) (xy 305.793914 -284.499812)
			(xy 305.797874 -284.450758) (xy 305.809651 -284.402974) (xy 305.828942 -284.357698) (xy 305.855245 -284.316102)
			(xy 305.88788 -284.279265) (xy 305.926001 -284.24814) (xy 305.968622 -284.223533) (xy 306.014638 -284.206081)
			(xy 306.062857 -284.196237) (xy 306.112032 -284.194256) (xy 306.160887 -284.200188) (xy 306.208158 -284.21388)
			(xy 306.25262 -284.234978) (xy 306.293123 -284.262934) (xy 306.328616 -284.297026) (xy 306.358181 -284.33637)
			(xy 306.381052 -284.379947) (xy 306.396636 -284.426628) (xy 306.404531 -284.475205) (xy 306.405026 -284.499812)
			(xy 306.743874 -284.499812) (xy 306.747834 -284.450758) (xy 306.759611 -284.402974) (xy 306.778902 -284.357698)
			(xy 306.805205 -284.316102) (xy 306.83784 -284.279265) (xy 306.875961 -284.24814) (xy 306.918582 -284.223533)
			(xy 306.964598 -284.206081) (xy 307.012817 -284.196237) (xy 307.061992 -284.194256) (xy 307.110847 -284.200188)
			(xy 307.158118 -284.21388) (xy 307.20258 -284.234978) (xy 307.243083 -284.262934) (xy 307.278576 -284.297026)
			(xy 307.308141 -284.33637) (xy 307.331012 -284.379947) (xy 307.346596 -284.426628) (xy 307.354491 -284.475205)
			(xy 307.354986 -284.499812) (xy 307.694088 -284.499812) (xy 307.698048 -284.450758) (xy 307.709825 -284.402974)
			(xy 307.729116 -284.357698) (xy 307.755419 -284.316102) (xy 307.788054 -284.279265) (xy 307.826175 -284.24814)
			(xy 307.868796 -284.223533) (xy 307.914812 -284.206081) (xy 307.963031 -284.196237) (xy 308.012206 -284.194256)
			(xy 308.061061 -284.200188) (xy 308.108332 -284.21388) (xy 308.152794 -284.234978) (xy 308.193297 -284.262934)
			(xy 308.22879 -284.297026) (xy 308.258355 -284.33637) (xy 308.281226 -284.379947) (xy 308.29681 -284.426628)
			(xy 308.304705 -284.475205) (xy 308.3052 -284.499812) (xy 308.304705 -284.524419) (xy 308.29681 -284.572996)
			(xy 308.281226 -284.619677) (xy 308.258355 -284.663254) (xy 308.22879 -284.702598) (xy 308.193297 -284.73669)
			(xy 308.152794 -284.764646) (xy 308.108332 -284.785744) (xy 308.061061 -284.799436) (xy 308.012206 -284.805368)
			(xy 307.963031 -284.803387) (xy 307.914812 -284.793543) (xy 307.868796 -284.776091) (xy 307.826175 -284.751484)
			(xy 307.788054 -284.720359) (xy 307.755419 -284.683522) (xy 307.729116 -284.641926) (xy 307.709825 -284.59665)
			(xy 307.698048 -284.548866) (xy 307.694088 -284.499812) (xy 307.354986 -284.499812) (xy 307.354491 -284.524419)
			(xy 307.346596 -284.572996) (xy 307.331012 -284.619677) (xy 307.308141 -284.663254) (xy 307.278576 -284.702598)
			(xy 307.243083 -284.73669) (xy 307.20258 -284.764646) (xy 307.158118 -284.785744) (xy 307.110847 -284.799436)
			(xy 307.061992 -284.805368) (xy 307.012817 -284.803387) (xy 306.964598 -284.793543) (xy 306.918582 -284.776091)
			(xy 306.875961 -284.751484) (xy 306.83784 -284.720359) (xy 306.805205 -284.683522) (xy 306.778902 -284.641926)
			(xy 306.759611 -284.59665) (xy 306.747834 -284.548866) (xy 306.743874 -284.499812) (xy 306.405026 -284.499812)
			(xy 306.404531 -284.524419) (xy 306.396636 -284.572996) (xy 306.381052 -284.619677) (xy 306.358181 -284.663254)
			(xy 306.328616 -284.702598) (xy 306.293123 -284.73669) (xy 306.25262 -284.764646) (xy 306.208158 -284.785744)
			(xy 306.160887 -284.799436) (xy 306.112032 -284.805368) (xy 306.062857 -284.803387) (xy 306.014638 -284.793543)
			(xy 305.968622 -284.776091) (xy 305.926001 -284.751484) (xy 305.88788 -284.720359) (xy 305.855245 -284.683522)
			(xy 305.828942 -284.641926) (xy 305.809651 -284.59665) (xy 305.797874 -284.548866) (xy 305.793914 -284.499812)
			(xy 266.590526 -284.499812) (xy 266.590526 -284.974792) (xy 268.26897 -284.974792) (xy 268.27293 -284.925738)
			(xy 268.284707 -284.877954) (xy 268.303998 -284.832678) (xy 268.330301 -284.791082) (xy 268.362936 -284.754245)
			(xy 268.401057 -284.72312) (xy 268.443678 -284.698513) (xy 268.489694 -284.681061) (xy 268.537913 -284.671217)
			(xy 268.587088 -284.669236) (xy 268.635943 -284.675168) (xy 268.683214 -284.68886) (xy 268.727676 -284.709958)
			(xy 268.768179 -284.737914) (xy 268.803672 -284.772006) (xy 268.833237 -284.81135) (xy 268.856108 -284.854927)
			(xy 268.871692 -284.901608) (xy 268.879587 -284.950185) (xy 268.880082 -284.974792) (xy 269.21893 -284.974792)
			(xy 269.22289 -284.925738) (xy 269.234667 -284.877954) (xy 269.253958 -284.832678) (xy 269.280261 -284.791082)
			(xy 269.312896 -284.754245) (xy 269.351017 -284.72312) (xy 269.393638 -284.698513) (xy 269.439654 -284.681061)
			(xy 269.487873 -284.671217) (xy 269.537048 -284.669236) (xy 269.585903 -284.675168) (xy 269.633174 -284.68886)
			(xy 269.677636 -284.709958) (xy 269.718139 -284.737914) (xy 269.753632 -284.772006) (xy 269.783197 -284.81135)
			(xy 269.806068 -284.854927) (xy 269.821652 -284.901608) (xy 269.829547 -284.950185) (xy 269.830042 -284.974792)
			(xy 270.169144 -284.974792) (xy 270.173104 -284.925738) (xy 270.184881 -284.877954) (xy 270.204172 -284.832678)
			(xy 270.230475 -284.791082) (xy 270.26311 -284.754245) (xy 270.301231 -284.72312) (xy 270.343852 -284.698513)
			(xy 270.389868 -284.681061) (xy 270.438087 -284.671217) (xy 270.487262 -284.669236) (xy 270.536117 -284.675168)
			(xy 270.583388 -284.68886) (xy 270.62785 -284.709958) (xy 270.668353 -284.737914) (xy 270.703846 -284.772006)
			(xy 270.733411 -284.81135) (xy 270.756282 -284.854927) (xy 270.771866 -284.901608) (xy 270.779761 -284.950185)
			(xy 270.780256 -284.974792) (xy 271.119104 -284.974792) (xy 271.123064 -284.925738) (xy 271.134841 -284.877954)
			(xy 271.154132 -284.832678) (xy 271.180435 -284.791082) (xy 271.21307 -284.754245) (xy 271.251191 -284.72312)
			(xy 271.293812 -284.698513) (xy 271.339828 -284.681061) (xy 271.388047 -284.671217) (xy 271.437222 -284.669236)
			(xy 271.486077 -284.675168) (xy 271.533348 -284.68886) (xy 271.57781 -284.709958) (xy 271.618313 -284.737914)
			(xy 271.653806 -284.772006) (xy 271.683371 -284.81135) (xy 271.706242 -284.854927) (xy 271.721826 -284.901608)
			(xy 271.729721 -284.950185) (xy 271.730216 -284.974792) (xy 272.069064 -284.974792) (xy 272.073024 -284.925738)
			(xy 272.084801 -284.877954) (xy 272.104092 -284.832678) (xy 272.130395 -284.791082) (xy 272.16303 -284.754245)
			(xy 272.201151 -284.72312) (xy 272.243772 -284.698513) (xy 272.289788 -284.681061) (xy 272.338007 -284.671217)
			(xy 272.387182 -284.669236) (xy 272.436037 -284.675168) (xy 272.483308 -284.68886) (xy 272.52777 -284.709958)
			(xy 272.568273 -284.737914) (xy 272.603766 -284.772006) (xy 272.633331 -284.81135) (xy 272.656202 -284.854927)
			(xy 272.671786 -284.901608) (xy 272.679681 -284.950185) (xy 272.680176 -284.974792) (xy 273.019024 -284.974792)
			(xy 273.022984 -284.925738) (xy 273.034761 -284.877954) (xy 273.054052 -284.832678) (xy 273.080355 -284.791082)
			(xy 273.11299 -284.754245) (xy 273.151111 -284.72312) (xy 273.193732 -284.698513) (xy 273.239748 -284.681061)
			(xy 273.287967 -284.671217) (xy 273.337142 -284.669236) (xy 273.385997 -284.675168) (xy 273.433268 -284.68886)
			(xy 273.47773 -284.709958) (xy 273.518233 -284.737914) (xy 273.553726 -284.772006) (xy 273.583291 -284.81135)
			(xy 273.606162 -284.854927) (xy 273.621746 -284.901608) (xy 273.629641 -284.950185) (xy 273.630136 -284.974792)
			(xy 274.918944 -284.974792) (xy 274.922904 -284.925738) (xy 274.934681 -284.877954) (xy 274.953972 -284.832678)
			(xy 274.980275 -284.791082) (xy 275.01291 -284.754245) (xy 275.051031 -284.72312) (xy 275.093652 -284.698513)
			(xy 275.139668 -284.681061) (xy 275.187887 -284.671217) (xy 275.237062 -284.669236) (xy 275.285917 -284.675168)
			(xy 275.333188 -284.68886) (xy 275.37765 -284.709958) (xy 275.418153 -284.737914) (xy 275.453646 -284.772006)
			(xy 275.483211 -284.81135) (xy 275.506082 -284.854927) (xy 275.521666 -284.901608) (xy 275.529561 -284.950185)
			(xy 275.530056 -284.974792) (xy 276.819118 -284.974792) (xy 276.823078 -284.925738) (xy 276.834855 -284.877954)
			(xy 276.854146 -284.832678) (xy 276.880449 -284.791082) (xy 276.913084 -284.754245) (xy 276.951205 -284.72312)
			(xy 276.993826 -284.698513) (xy 277.039842 -284.681061) (xy 277.088061 -284.671217) (xy 277.137236 -284.669236)
			(xy 277.186091 -284.675168) (xy 277.233362 -284.68886) (xy 277.277824 -284.709958) (xy 277.318327 -284.737914)
			(xy 277.35382 -284.772006) (xy 277.383385 -284.81135) (xy 277.406256 -284.854927) (xy 277.42184 -284.901608)
			(xy 277.429735 -284.950185) (xy 277.43023 -284.974792) (xy 277.769078 -284.974792) (xy 277.773038 -284.925738)
			(xy 277.784815 -284.877954) (xy 277.804106 -284.832678) (xy 277.830409 -284.791082) (xy 277.863044 -284.754245)
			(xy 277.901165 -284.72312) (xy 277.943786 -284.698513) (xy 277.989802 -284.681061) (xy 278.038021 -284.671217)
			(xy 278.087196 -284.669236) (xy 278.136051 -284.675168) (xy 278.183322 -284.68886) (xy 278.227784 -284.709958)
			(xy 278.268287 -284.737914) (xy 278.30378 -284.772006) (xy 278.333345 -284.81135) (xy 278.356216 -284.854927)
			(xy 278.3718 -284.901608) (xy 278.379695 -284.950185) (xy 278.38019 -284.974792) (xy 278.719038 -284.974792)
			(xy 278.722998 -284.925738) (xy 278.734775 -284.877954) (xy 278.754066 -284.832678) (xy 278.780369 -284.791082)
			(xy 278.813004 -284.754245) (xy 278.851125 -284.72312) (xy 278.893746 -284.698513) (xy 278.939762 -284.681061)
			(xy 278.987981 -284.671217) (xy 279.037156 -284.669236) (xy 279.086011 -284.675168) (xy 279.133282 -284.68886)
			(xy 279.177744 -284.709958) (xy 279.218247 -284.737914) (xy 279.25374 -284.772006) (xy 279.283305 -284.81135)
			(xy 279.306176 -284.854927) (xy 279.32176 -284.901608) (xy 279.329655 -284.950185) (xy 279.33015 -284.974792)
			(xy 279.668998 -284.974792) (xy 279.672958 -284.925738) (xy 279.684735 -284.877954) (xy 279.704026 -284.832678)
			(xy 279.730329 -284.791082) (xy 279.762964 -284.754245) (xy 279.801085 -284.72312) (xy 279.843706 -284.698513)
			(xy 279.889722 -284.681061) (xy 279.937941 -284.671217) (xy 279.987116 -284.669236) (xy 280.035971 -284.675168)
			(xy 280.083242 -284.68886) (xy 280.127704 -284.709958) (xy 280.168207 -284.737914) (xy 280.2037 -284.772006)
			(xy 280.233265 -284.81135) (xy 280.256136 -284.854927) (xy 280.27172 -284.901608) (xy 280.279615 -284.950185)
			(xy 280.28011 -284.974792) (xy 280.618958 -284.974792) (xy 280.622918 -284.925738) (xy 280.634695 -284.877954)
			(xy 280.653986 -284.832678) (xy 280.680289 -284.791082) (xy 280.712924 -284.754245) (xy 280.751045 -284.72312)
			(xy 280.793666 -284.698513) (xy 280.839682 -284.681061) (xy 280.887901 -284.671217) (xy 280.937076 -284.669236)
			(xy 280.985931 -284.675168) (xy 281.033202 -284.68886) (xy 281.077664 -284.709958) (xy 281.118167 -284.737914)
			(xy 281.15366 -284.772006) (xy 281.183225 -284.81135) (xy 281.206096 -284.854927) (xy 281.22168 -284.901608)
			(xy 281.229575 -284.950185) (xy 281.23007 -284.974792) (xy 281.568918 -284.974792) (xy 281.572878 -284.925738)
			(xy 281.584655 -284.877954) (xy 281.603946 -284.832678) (xy 281.630249 -284.791082) (xy 281.662884 -284.754245)
			(xy 281.701005 -284.72312) (xy 281.743626 -284.698513) (xy 281.789642 -284.681061) (xy 281.837861 -284.671217)
			(xy 281.887036 -284.669236) (xy 281.935891 -284.675168) (xy 281.983162 -284.68886) (xy 282.027624 -284.709958)
			(xy 282.068127 -284.737914) (xy 282.10362 -284.772006) (xy 282.133185 -284.81135) (xy 282.156056 -284.854927)
			(xy 282.17164 -284.901608) (xy 282.179535 -284.950185) (xy 282.18003 -284.974792) (xy 282.519132 -284.974792)
			(xy 282.523092 -284.925738) (xy 282.534869 -284.877954) (xy 282.55416 -284.832678) (xy 282.580463 -284.791082)
			(xy 282.613098 -284.754245) (xy 282.651219 -284.72312) (xy 282.69384 -284.698513) (xy 282.739856 -284.681061)
			(xy 282.788075 -284.671217) (xy 282.83725 -284.669236) (xy 282.886105 -284.675168) (xy 282.933376 -284.68886)
			(xy 282.977838 -284.709958) (xy 283.018341 -284.737914) (xy 283.053834 -284.772006) (xy 283.083399 -284.81135)
			(xy 283.10627 -284.854927) (xy 283.121854 -284.901608) (xy 283.129749 -284.950185) (xy 283.130244 -284.974792)
			(xy 283.469092 -284.974792) (xy 283.473052 -284.925738) (xy 283.484829 -284.877954) (xy 283.50412 -284.832678)
			(xy 283.530423 -284.791082) (xy 283.563058 -284.754245) (xy 283.601179 -284.72312) (xy 283.6438 -284.698513)
			(xy 283.689816 -284.681061) (xy 283.738035 -284.671217) (xy 283.78721 -284.669236) (xy 283.836065 -284.675168)
			(xy 283.883336 -284.68886) (xy 283.927798 -284.709958) (xy 283.968301 -284.737914) (xy 284.003794 -284.772006)
			(xy 284.033359 -284.81135) (xy 284.05623 -284.854927) (xy 284.071814 -284.901608) (xy 284.079709 -284.950185)
			(xy 284.080204 -284.974792) (xy 284.419052 -284.974792) (xy 284.423012 -284.925738) (xy 284.434789 -284.877954)
			(xy 284.45408 -284.832678) (xy 284.480383 -284.791082) (xy 284.513018 -284.754245) (xy 284.551139 -284.72312)
			(xy 284.59376 -284.698513) (xy 284.639776 -284.681061) (xy 284.687995 -284.671217) (xy 284.73717 -284.669236)
			(xy 284.786025 -284.675168) (xy 284.833296 -284.68886) (xy 284.877758 -284.709958) (xy 284.918261 -284.737914)
			(xy 284.953754 -284.772006) (xy 284.983319 -284.81135) (xy 285.00619 -284.854927) (xy 285.021774 -284.901608)
			(xy 285.029669 -284.950185) (xy 285.030164 -284.974792) (xy 285.369012 -284.974792) (xy 285.372972 -284.925738)
			(xy 285.384749 -284.877954) (xy 285.40404 -284.832678) (xy 285.430343 -284.791082) (xy 285.462978 -284.754245)
			(xy 285.501099 -284.72312) (xy 285.54372 -284.698513) (xy 285.589736 -284.681061) (xy 285.637955 -284.671217)
			(xy 285.68713 -284.669236) (xy 285.735985 -284.675168) (xy 285.783256 -284.68886) (xy 285.827718 -284.709958)
			(xy 285.868221 -284.737914) (xy 285.903714 -284.772006) (xy 285.933279 -284.81135) (xy 285.95615 -284.854927)
			(xy 285.971734 -284.901608) (xy 285.979629 -284.950185) (xy 285.980124 -284.974792) (xy 286.318972 -284.974792)
			(xy 286.322932 -284.925738) (xy 286.334709 -284.877954) (xy 286.354 -284.832678) (xy 286.380303 -284.791082)
			(xy 286.412938 -284.754245) (xy 286.451059 -284.72312) (xy 286.49368 -284.698513) (xy 286.539696 -284.681061)
			(xy 286.587915 -284.671217) (xy 286.63709 -284.669236) (xy 286.685945 -284.675168) (xy 286.733216 -284.68886)
			(xy 286.777678 -284.709958) (xy 286.818181 -284.737914) (xy 286.853674 -284.772006) (xy 286.883239 -284.81135)
			(xy 286.90611 -284.854927) (xy 286.921694 -284.901608) (xy 286.929589 -284.950185) (xy 286.930084 -284.974792)
			(xy 287.268932 -284.974792) (xy 287.272892 -284.925738) (xy 287.284669 -284.877954) (xy 287.30396 -284.832678)
			(xy 287.330263 -284.791082) (xy 287.362898 -284.754245) (xy 287.401019 -284.72312) (xy 287.44364 -284.698513)
			(xy 287.489656 -284.681061) (xy 287.537875 -284.671217) (xy 287.58705 -284.669236) (xy 287.635905 -284.675168)
			(xy 287.683176 -284.68886) (xy 287.727638 -284.709958) (xy 287.768141 -284.737914) (xy 287.803634 -284.772006)
			(xy 287.833199 -284.81135) (xy 287.85607 -284.854927) (xy 287.871654 -284.901608) (xy 287.879549 -284.950185)
			(xy 287.880044 -284.974792) (xy 288.218892 -284.974792) (xy 288.222852 -284.925738) (xy 288.234629 -284.877954)
			(xy 288.25392 -284.832678) (xy 288.280223 -284.791082) (xy 288.312858 -284.754245) (xy 288.350979 -284.72312)
			(xy 288.3936 -284.698513) (xy 288.439616 -284.681061) (xy 288.487835 -284.671217) (xy 288.53701 -284.669236)
			(xy 288.585865 -284.675168) (xy 288.633136 -284.68886) (xy 288.677598 -284.709958) (xy 288.718101 -284.737914)
			(xy 288.753594 -284.772006) (xy 288.783159 -284.81135) (xy 288.80603 -284.854927) (xy 288.821614 -284.901608)
			(xy 288.829509 -284.950185) (xy 288.830004 -284.974792) (xy 289.169106 -284.974792) (xy 289.173066 -284.925738)
			(xy 289.184843 -284.877954) (xy 289.204134 -284.832678) (xy 289.230437 -284.791082) (xy 289.263072 -284.754245)
			(xy 289.301193 -284.72312) (xy 289.343814 -284.698513) (xy 289.38983 -284.681061) (xy 289.438049 -284.671217)
			(xy 289.487224 -284.669236) (xy 289.536079 -284.675168) (xy 289.58335 -284.68886) (xy 289.627812 -284.709958)
			(xy 289.668315 -284.737914) (xy 289.703808 -284.772006) (xy 289.733373 -284.81135) (xy 289.756244 -284.854927)
			(xy 289.771828 -284.901608) (xy 289.779723 -284.950185) (xy 289.780218 -284.974792) (xy 290.119066 -284.974792)
			(xy 290.123026 -284.925738) (xy 290.134803 -284.877954) (xy 290.154094 -284.832678) (xy 290.180397 -284.791082)
			(xy 290.213032 -284.754245) (xy 290.251153 -284.72312) (xy 290.293774 -284.698513) (xy 290.33979 -284.681061)
			(xy 290.388009 -284.671217) (xy 290.437184 -284.669236) (xy 290.486039 -284.675168) (xy 290.53331 -284.68886)
			(xy 290.577772 -284.709958) (xy 290.618275 -284.737914) (xy 290.653768 -284.772006) (xy 290.683333 -284.81135)
			(xy 290.706204 -284.854927) (xy 290.721788 -284.901608) (xy 290.729683 -284.950185) (xy 290.730178 -284.974792)
			(xy 292.018986 -284.974792) (xy 292.022946 -284.925738) (xy 292.034723 -284.877954) (xy 292.054014 -284.832678)
			(xy 292.080317 -284.791082) (xy 292.112952 -284.754245) (xy 292.151073 -284.72312) (xy 292.193694 -284.698513)
			(xy 292.23971 -284.681061) (xy 292.287929 -284.671217) (xy 292.337104 -284.669236) (xy 292.385959 -284.675168)
			(xy 292.43323 -284.68886) (xy 292.477692 -284.709958) (xy 292.518195 -284.737914) (xy 292.553688 -284.772006)
			(xy 292.583253 -284.81135) (xy 292.606124 -284.854927) (xy 292.621708 -284.901608) (xy 292.629603 -284.950185)
			(xy 292.630098 -284.974792) (xy 292.968946 -284.974792) (xy 292.972906 -284.925738) (xy 292.984683 -284.877954)
			(xy 293.003974 -284.832678) (xy 293.030277 -284.791082) (xy 293.062912 -284.754245) (xy 293.101033 -284.72312)
			(xy 293.143654 -284.698513) (xy 293.18967 -284.681061) (xy 293.237889 -284.671217) (xy 293.287064 -284.669236)
			(xy 293.335919 -284.675168) (xy 293.38319 -284.68886) (xy 293.427652 -284.709958) (xy 293.468155 -284.737914)
			(xy 293.503648 -284.772006) (xy 293.533213 -284.81135) (xy 293.556084 -284.854927) (xy 293.571668 -284.901608)
			(xy 293.579563 -284.950185) (xy 293.580058 -284.974792) (xy 293.918906 -284.974792) (xy 293.922866 -284.925738)
			(xy 293.934643 -284.877954) (xy 293.953934 -284.832678) (xy 293.980237 -284.791082) (xy 294.012872 -284.754245)
			(xy 294.050993 -284.72312) (xy 294.093614 -284.698513) (xy 294.13963 -284.681061) (xy 294.187849 -284.671217)
			(xy 294.237024 -284.669236) (xy 294.285879 -284.675168) (xy 294.33315 -284.68886) (xy 294.377612 -284.709958)
			(xy 294.418115 -284.737914) (xy 294.453608 -284.772006) (xy 294.483173 -284.81135) (xy 294.506044 -284.854927)
			(xy 294.521628 -284.901608) (xy 294.529523 -284.950185) (xy 294.530018 -284.974792) (xy 294.86912 -284.974792)
			(xy 294.87308 -284.925738) (xy 294.884857 -284.877954) (xy 294.904148 -284.832678) (xy 294.930451 -284.791082)
			(xy 294.963086 -284.754245) (xy 295.001207 -284.72312) (xy 295.043828 -284.698513) (xy 295.089844 -284.681061)
			(xy 295.138063 -284.671217) (xy 295.187238 -284.669236) (xy 295.236093 -284.675168) (xy 295.283364 -284.68886)
			(xy 295.327826 -284.709958) (xy 295.368329 -284.737914) (xy 295.403822 -284.772006) (xy 295.433387 -284.81135)
			(xy 295.456258 -284.854927) (xy 295.471842 -284.901608) (xy 295.479737 -284.950185) (xy 295.480232 -284.974792)
			(xy 295.81908 -284.974792) (xy 295.82304 -284.925738) (xy 295.834817 -284.877954) (xy 295.854108 -284.832678)
			(xy 295.880411 -284.791082) (xy 295.913046 -284.754245) (xy 295.951167 -284.72312) (xy 295.993788 -284.698513)
			(xy 296.039804 -284.681061) (xy 296.088023 -284.671217) (xy 296.137198 -284.669236) (xy 296.186053 -284.675168)
			(xy 296.233324 -284.68886) (xy 296.277786 -284.709958) (xy 296.318289 -284.737914) (xy 296.353782 -284.772006)
			(xy 296.383347 -284.81135) (xy 296.406218 -284.854927) (xy 296.421802 -284.901608) (xy 296.429697 -284.950185)
			(xy 296.430192 -284.974792) (xy 296.76904 -284.974792) (xy 296.773 -284.925738) (xy 296.784777 -284.877954)
			(xy 296.804068 -284.832678) (xy 296.830371 -284.791082) (xy 296.863006 -284.754245) (xy 296.901127 -284.72312)
			(xy 296.943748 -284.698513) (xy 296.989764 -284.681061) (xy 297.037983 -284.671217) (xy 297.087158 -284.669236)
			(xy 297.136013 -284.675168) (xy 297.183284 -284.68886) (xy 297.227746 -284.709958) (xy 297.268249 -284.737914)
			(xy 297.303742 -284.772006) (xy 297.333307 -284.81135) (xy 297.356178 -284.854927) (xy 297.371762 -284.901608)
			(xy 297.379657 -284.950185) (xy 297.380152 -284.974792) (xy 297.719 -284.974792) (xy 297.72296 -284.925738)
			(xy 297.734737 -284.877954) (xy 297.754028 -284.832678) (xy 297.780331 -284.791082) (xy 297.812966 -284.754245)
			(xy 297.851087 -284.72312) (xy 297.893708 -284.698513) (xy 297.939724 -284.681061) (xy 297.987943 -284.671217)
			(xy 298.037118 -284.669236) (xy 298.085973 -284.675168) (xy 298.133244 -284.68886) (xy 298.177706 -284.709958)
			(xy 298.218209 -284.737914) (xy 298.253702 -284.772006) (xy 298.283267 -284.81135) (xy 298.306138 -284.854927)
			(xy 298.321722 -284.901608) (xy 298.329617 -284.950185) (xy 298.330112 -284.974792) (xy 298.66896 -284.974792)
			(xy 298.67292 -284.925738) (xy 298.684697 -284.877954) (xy 298.703988 -284.832678) (xy 298.730291 -284.791082)
			(xy 298.762926 -284.754245) (xy 298.801047 -284.72312) (xy 298.843668 -284.698513) (xy 298.889684 -284.681061)
			(xy 298.937903 -284.671217) (xy 298.987078 -284.669236) (xy 299.035933 -284.675168) (xy 299.083204 -284.68886)
			(xy 299.127666 -284.709958) (xy 299.168169 -284.737914) (xy 299.203662 -284.772006) (xy 299.233227 -284.81135)
			(xy 299.256098 -284.854927) (xy 299.271682 -284.901608) (xy 299.279577 -284.950185) (xy 299.280072 -284.974792)
			(xy 299.61892 -284.974792) (xy 299.62288 -284.925738) (xy 299.634657 -284.877954) (xy 299.653948 -284.832678)
			(xy 299.680251 -284.791082) (xy 299.712886 -284.754245) (xy 299.751007 -284.72312) (xy 299.793628 -284.698513)
			(xy 299.839644 -284.681061) (xy 299.887863 -284.671217) (xy 299.937038 -284.669236) (xy 299.985893 -284.675168)
			(xy 300.033164 -284.68886) (xy 300.077626 -284.709958) (xy 300.118129 -284.737914) (xy 300.153622 -284.772006)
			(xy 300.183187 -284.81135) (xy 300.206058 -284.854927) (xy 300.221642 -284.901608) (xy 300.229537 -284.950185)
			(xy 300.230032 -284.974792) (xy 300.56888 -284.974792) (xy 300.57284 -284.925738) (xy 300.584617 -284.877954)
			(xy 300.603908 -284.832678) (xy 300.630211 -284.791082) (xy 300.662846 -284.754245) (xy 300.700967 -284.72312)
			(xy 300.743588 -284.698513) (xy 300.789604 -284.681061) (xy 300.837823 -284.671217) (xy 300.886998 -284.669236)
			(xy 300.935853 -284.675168) (xy 300.983124 -284.68886) (xy 301.027586 -284.709958) (xy 301.068089 -284.737914)
			(xy 301.103582 -284.772006) (xy 301.133147 -284.81135) (xy 301.156018 -284.854927) (xy 301.171602 -284.901608)
			(xy 301.179497 -284.950185) (xy 301.179992 -284.974792) (xy 301.519094 -284.974792) (xy 301.523054 -284.925738)
			(xy 301.534831 -284.877954) (xy 301.554122 -284.832678) (xy 301.580425 -284.791082) (xy 301.61306 -284.754245)
			(xy 301.651181 -284.72312) (xy 301.693802 -284.698513) (xy 301.739818 -284.681061) (xy 301.788037 -284.671217)
			(xy 301.837212 -284.669236) (xy 301.886067 -284.675168) (xy 301.933338 -284.68886) (xy 301.9778 -284.709958)
			(xy 302.018303 -284.737914) (xy 302.053796 -284.772006) (xy 302.083361 -284.81135) (xy 302.106232 -284.854927)
			(xy 302.121816 -284.901608) (xy 302.129711 -284.950185) (xy 302.130206 -284.974792) (xy 302.469054 -284.974792)
			(xy 302.473014 -284.925738) (xy 302.484791 -284.877954) (xy 302.504082 -284.832678) (xy 302.530385 -284.791082)
			(xy 302.56302 -284.754245) (xy 302.601141 -284.72312) (xy 302.643762 -284.698513) (xy 302.689778 -284.681061)
			(xy 302.737997 -284.671217) (xy 302.787172 -284.669236) (xy 302.836027 -284.675168) (xy 302.883298 -284.68886)
			(xy 302.92776 -284.709958) (xy 302.968263 -284.737914) (xy 303.003756 -284.772006) (xy 303.033321 -284.81135)
			(xy 303.056192 -284.854927) (xy 303.071776 -284.901608) (xy 303.079671 -284.950185) (xy 303.080166 -284.974792)
			(xy 303.079671 -284.999399) (xy 303.071776 -285.047976) (xy 303.056192 -285.094657) (xy 303.033321 -285.138234)
			(xy 303.003756 -285.177578) (xy 302.968263 -285.21167) (xy 302.92776 -285.239626) (xy 302.883298 -285.260724)
			(xy 302.836027 -285.274416) (xy 302.787172 -285.280348) (xy 302.737997 -285.278367) (xy 302.689778 -285.268523)
			(xy 302.643762 -285.251071) (xy 302.601141 -285.226464) (xy 302.56302 -285.195339) (xy 302.530385 -285.158502)
			(xy 302.504082 -285.116906) (xy 302.484791 -285.07163) (xy 302.473014 -285.023846) (xy 302.469054 -284.974792)
			(xy 302.130206 -284.974792) (xy 302.129711 -284.999399) (xy 302.121816 -285.047976) (xy 302.106232 -285.094657)
			(xy 302.083361 -285.138234) (xy 302.053796 -285.177578) (xy 302.018303 -285.21167) (xy 301.9778 -285.239626)
			(xy 301.933338 -285.260724) (xy 301.886067 -285.274416) (xy 301.837212 -285.280348) (xy 301.788037 -285.278367)
			(xy 301.739818 -285.268523) (xy 301.693802 -285.251071) (xy 301.651181 -285.226464) (xy 301.61306 -285.195339)
			(xy 301.580425 -285.158502) (xy 301.554122 -285.116906) (xy 301.534831 -285.07163) (xy 301.523054 -285.023846)
			(xy 301.519094 -284.974792) (xy 301.179992 -284.974792) (xy 301.179497 -284.999399) (xy 301.171602 -285.047976)
			(xy 301.156018 -285.094657) (xy 301.133147 -285.138234) (xy 301.103582 -285.177578) (xy 301.068089 -285.21167)
			(xy 301.027586 -285.239626) (xy 300.983124 -285.260724) (xy 300.935853 -285.274416) (xy 300.886998 -285.280348)
			(xy 300.837823 -285.278367) (xy 300.789604 -285.268523) (xy 300.743588 -285.251071) (xy 300.700967 -285.226464)
			(xy 300.662846 -285.195339) (xy 300.630211 -285.158502) (xy 300.603908 -285.116906) (xy 300.584617 -285.07163)
			(xy 300.57284 -285.023846) (xy 300.56888 -284.974792) (xy 300.230032 -284.974792) (xy 300.229537 -284.999399)
			(xy 300.221642 -285.047976) (xy 300.206058 -285.094657) (xy 300.183187 -285.138234) (xy 300.153622 -285.177578)
			(xy 300.118129 -285.21167) (xy 300.077626 -285.239626) (xy 300.033164 -285.260724) (xy 299.985893 -285.274416)
			(xy 299.937038 -285.280348) (xy 299.887863 -285.278367) (xy 299.839644 -285.268523) (xy 299.793628 -285.251071)
			(xy 299.751007 -285.226464) (xy 299.712886 -285.195339) (xy 299.680251 -285.158502) (xy 299.653948 -285.116906)
			(xy 299.634657 -285.07163) (xy 299.62288 -285.023846) (xy 299.61892 -284.974792) (xy 299.280072 -284.974792)
			(xy 299.279577 -284.999399) (xy 299.271682 -285.047976) (xy 299.256098 -285.094657) (xy 299.233227 -285.138234)
			(xy 299.203662 -285.177578) (xy 299.168169 -285.21167) (xy 299.127666 -285.239626) (xy 299.083204 -285.260724)
			(xy 299.035933 -285.274416) (xy 298.987078 -285.280348) (xy 298.937903 -285.278367) (xy 298.889684 -285.268523)
			(xy 298.843668 -285.251071) (xy 298.801047 -285.226464) (xy 298.762926 -285.195339) (xy 298.730291 -285.158502)
			(xy 298.703988 -285.116906) (xy 298.684697 -285.07163) (xy 298.67292 -285.023846) (xy 298.66896 -284.974792)
			(xy 298.330112 -284.974792) (xy 298.329617 -284.999399) (xy 298.321722 -285.047976) (xy 298.306138 -285.094657)
			(xy 298.283267 -285.138234) (xy 298.253702 -285.177578) (xy 298.218209 -285.21167) (xy 298.177706 -285.239626)
			(xy 298.133244 -285.260724) (xy 298.085973 -285.274416) (xy 298.037118 -285.280348) (xy 297.987943 -285.278367)
			(xy 297.939724 -285.268523) (xy 297.893708 -285.251071) (xy 297.851087 -285.226464) (xy 297.812966 -285.195339)
			(xy 297.780331 -285.158502) (xy 297.754028 -285.116906) (xy 297.734737 -285.07163) (xy 297.72296 -285.023846)
			(xy 297.719 -284.974792) (xy 297.380152 -284.974792) (xy 297.379657 -284.999399) (xy 297.371762 -285.047976)
			(xy 297.356178 -285.094657) (xy 297.333307 -285.138234) (xy 297.303742 -285.177578) (xy 297.268249 -285.21167)
			(xy 297.227746 -285.239626) (xy 297.183284 -285.260724) (xy 297.136013 -285.274416) (xy 297.087158 -285.280348)
			(xy 297.037983 -285.278367) (xy 296.989764 -285.268523) (xy 296.943748 -285.251071) (xy 296.901127 -285.226464)
			(xy 296.863006 -285.195339) (xy 296.830371 -285.158502) (xy 296.804068 -285.116906) (xy 296.784777 -285.07163)
			(xy 296.773 -285.023846) (xy 296.76904 -284.974792) (xy 296.430192 -284.974792) (xy 296.429697 -284.999399)
			(xy 296.421802 -285.047976) (xy 296.406218 -285.094657) (xy 296.383347 -285.138234) (xy 296.353782 -285.177578)
			(xy 296.318289 -285.21167) (xy 296.277786 -285.239626) (xy 296.233324 -285.260724) (xy 296.186053 -285.274416)
			(xy 296.137198 -285.280348) (xy 296.088023 -285.278367) (xy 296.039804 -285.268523) (xy 295.993788 -285.251071)
			(xy 295.951167 -285.226464) (xy 295.913046 -285.195339) (xy 295.880411 -285.158502) (xy 295.854108 -285.116906)
			(xy 295.834817 -285.07163) (xy 295.82304 -285.023846) (xy 295.81908 -284.974792) (xy 295.480232 -284.974792)
			(xy 295.479737 -284.999399) (xy 295.471842 -285.047976) (xy 295.456258 -285.094657) (xy 295.433387 -285.138234)
			(xy 295.403822 -285.177578) (xy 295.368329 -285.21167) (xy 295.327826 -285.239626) (xy 295.283364 -285.260724)
			(xy 295.236093 -285.274416) (xy 295.187238 -285.280348) (xy 295.138063 -285.278367) (xy 295.089844 -285.268523)
			(xy 295.043828 -285.251071) (xy 295.001207 -285.226464) (xy 294.963086 -285.195339) (xy 294.930451 -285.158502)
			(xy 294.904148 -285.116906) (xy 294.884857 -285.07163) (xy 294.87308 -285.023846) (xy 294.86912 -284.974792)
			(xy 294.530018 -284.974792) (xy 294.529523 -284.999399) (xy 294.521628 -285.047976) (xy 294.506044 -285.094657)
			(xy 294.483173 -285.138234) (xy 294.453608 -285.177578) (xy 294.418115 -285.21167) (xy 294.377612 -285.239626)
			(xy 294.33315 -285.260724) (xy 294.285879 -285.274416) (xy 294.237024 -285.280348) (xy 294.187849 -285.278367)
			(xy 294.13963 -285.268523) (xy 294.093614 -285.251071) (xy 294.050993 -285.226464) (xy 294.012872 -285.195339)
			(xy 293.980237 -285.158502) (xy 293.953934 -285.116906) (xy 293.934643 -285.07163) (xy 293.922866 -285.023846)
			(xy 293.918906 -284.974792) (xy 293.580058 -284.974792) (xy 293.579563 -284.999399) (xy 293.571668 -285.047976)
			(xy 293.556084 -285.094657) (xy 293.533213 -285.138234) (xy 293.503648 -285.177578) (xy 293.468155 -285.21167)
			(xy 293.427652 -285.239626) (xy 293.38319 -285.260724) (xy 293.335919 -285.274416) (xy 293.287064 -285.280348)
			(xy 293.237889 -285.278367) (xy 293.18967 -285.268523) (xy 293.143654 -285.251071) (xy 293.101033 -285.226464)
			(xy 293.062912 -285.195339) (xy 293.030277 -285.158502) (xy 293.003974 -285.116906) (xy 292.984683 -285.07163)
			(xy 292.972906 -285.023846) (xy 292.968946 -284.974792) (xy 292.630098 -284.974792) (xy 292.629603 -284.999399)
			(xy 292.621708 -285.047976) (xy 292.606124 -285.094657) (xy 292.583253 -285.138234) (xy 292.553688 -285.177578)
			(xy 292.518195 -285.21167) (xy 292.477692 -285.239626) (xy 292.43323 -285.260724) (xy 292.385959 -285.274416)
			(xy 292.337104 -285.280348) (xy 292.287929 -285.278367) (xy 292.23971 -285.268523) (xy 292.193694 -285.251071)
			(xy 292.151073 -285.226464) (xy 292.112952 -285.195339) (xy 292.080317 -285.158502) (xy 292.054014 -285.116906)
			(xy 292.034723 -285.07163) (xy 292.022946 -285.023846) (xy 292.018986 -284.974792) (xy 290.730178 -284.974792)
			(xy 290.729683 -284.999399) (xy 290.721788 -285.047976) (xy 290.706204 -285.094657) (xy 290.683333 -285.138234)
			(xy 290.653768 -285.177578) (xy 290.618275 -285.21167) (xy 290.577772 -285.239626) (xy 290.53331 -285.260724)
			(xy 290.486039 -285.274416) (xy 290.437184 -285.280348) (xy 290.388009 -285.278367) (xy 290.33979 -285.268523)
			(xy 290.293774 -285.251071) (xy 290.251153 -285.226464) (xy 290.213032 -285.195339) (xy 290.180397 -285.158502)
			(xy 290.154094 -285.116906) (xy 290.134803 -285.07163) (xy 290.123026 -285.023846) (xy 290.119066 -284.974792)
			(xy 289.780218 -284.974792) (xy 289.779723 -284.999399) (xy 289.771828 -285.047976) (xy 289.756244 -285.094657)
			(xy 289.733373 -285.138234) (xy 289.703808 -285.177578) (xy 289.668315 -285.21167) (xy 289.627812 -285.239626)
			(xy 289.58335 -285.260724) (xy 289.536079 -285.274416) (xy 289.487224 -285.280348) (xy 289.438049 -285.278367)
			(xy 289.38983 -285.268523) (xy 289.343814 -285.251071) (xy 289.301193 -285.226464) (xy 289.263072 -285.195339)
			(xy 289.230437 -285.158502) (xy 289.204134 -285.116906) (xy 289.184843 -285.07163) (xy 289.173066 -285.023846)
			(xy 289.169106 -284.974792) (xy 288.830004 -284.974792) (xy 288.829509 -284.999399) (xy 288.821614 -285.047976)
			(xy 288.80603 -285.094657) (xy 288.783159 -285.138234) (xy 288.753594 -285.177578) (xy 288.718101 -285.21167)
			(xy 288.677598 -285.239626) (xy 288.633136 -285.260724) (xy 288.585865 -285.274416) (xy 288.53701 -285.280348)
			(xy 288.487835 -285.278367) (xy 288.439616 -285.268523) (xy 288.3936 -285.251071) (xy 288.350979 -285.226464)
			(xy 288.312858 -285.195339) (xy 288.280223 -285.158502) (xy 288.25392 -285.116906) (xy 288.234629 -285.07163)
			(xy 288.222852 -285.023846) (xy 288.218892 -284.974792) (xy 287.880044 -284.974792) (xy 287.879549 -284.999399)
			(xy 287.871654 -285.047976) (xy 287.85607 -285.094657) (xy 287.833199 -285.138234) (xy 287.803634 -285.177578)
			(xy 287.768141 -285.21167) (xy 287.727638 -285.239626) (xy 287.683176 -285.260724) (xy 287.635905 -285.274416)
			(xy 287.58705 -285.280348) (xy 287.537875 -285.278367) (xy 287.489656 -285.268523) (xy 287.44364 -285.251071)
			(xy 287.401019 -285.226464) (xy 287.362898 -285.195339) (xy 287.330263 -285.158502) (xy 287.30396 -285.116906)
			(xy 287.284669 -285.07163) (xy 287.272892 -285.023846) (xy 287.268932 -284.974792) (xy 286.930084 -284.974792)
			(xy 286.929589 -284.999399) (xy 286.921694 -285.047976) (xy 286.90611 -285.094657) (xy 286.883239 -285.138234)
			(xy 286.853674 -285.177578) (xy 286.818181 -285.21167) (xy 286.777678 -285.239626) (xy 286.733216 -285.260724)
			(xy 286.685945 -285.274416) (xy 286.63709 -285.280348) (xy 286.587915 -285.278367) (xy 286.539696 -285.268523)
			(xy 286.49368 -285.251071) (xy 286.451059 -285.226464) (xy 286.412938 -285.195339) (xy 286.380303 -285.158502)
			(xy 286.354 -285.116906) (xy 286.334709 -285.07163) (xy 286.322932 -285.023846) (xy 286.318972 -284.974792)
			(xy 285.980124 -284.974792) (xy 285.979629 -284.999399) (xy 285.971734 -285.047976) (xy 285.95615 -285.094657)
			(xy 285.933279 -285.138234) (xy 285.903714 -285.177578) (xy 285.868221 -285.21167) (xy 285.827718 -285.239626)
			(xy 285.783256 -285.260724) (xy 285.735985 -285.274416) (xy 285.68713 -285.280348) (xy 285.637955 -285.278367)
			(xy 285.589736 -285.268523) (xy 285.54372 -285.251071) (xy 285.501099 -285.226464) (xy 285.462978 -285.195339)
			(xy 285.430343 -285.158502) (xy 285.40404 -285.116906) (xy 285.384749 -285.07163) (xy 285.372972 -285.023846)
			(xy 285.369012 -284.974792) (xy 285.030164 -284.974792) (xy 285.029669 -284.999399) (xy 285.021774 -285.047976)
			(xy 285.00619 -285.094657) (xy 284.983319 -285.138234) (xy 284.953754 -285.177578) (xy 284.918261 -285.21167)
			(xy 284.877758 -285.239626) (xy 284.833296 -285.260724) (xy 284.786025 -285.274416) (xy 284.73717 -285.280348)
			(xy 284.687995 -285.278367) (xy 284.639776 -285.268523) (xy 284.59376 -285.251071) (xy 284.551139 -285.226464)
			(xy 284.513018 -285.195339) (xy 284.480383 -285.158502) (xy 284.45408 -285.116906) (xy 284.434789 -285.07163)
			(xy 284.423012 -285.023846) (xy 284.419052 -284.974792) (xy 284.080204 -284.974792) (xy 284.079709 -284.999399)
			(xy 284.071814 -285.047976) (xy 284.05623 -285.094657) (xy 284.033359 -285.138234) (xy 284.003794 -285.177578)
			(xy 283.968301 -285.21167) (xy 283.927798 -285.239626) (xy 283.883336 -285.260724) (xy 283.836065 -285.274416)
			(xy 283.78721 -285.280348) (xy 283.738035 -285.278367) (xy 283.689816 -285.268523) (xy 283.6438 -285.251071)
			(xy 283.601179 -285.226464) (xy 283.563058 -285.195339) (xy 283.530423 -285.158502) (xy 283.50412 -285.116906)
			(xy 283.484829 -285.07163) (xy 283.473052 -285.023846) (xy 283.469092 -284.974792) (xy 283.130244 -284.974792)
			(xy 283.129749 -284.999399) (xy 283.121854 -285.047976) (xy 283.10627 -285.094657) (xy 283.083399 -285.138234)
			(xy 283.053834 -285.177578) (xy 283.018341 -285.21167) (xy 282.977838 -285.239626) (xy 282.933376 -285.260724)
			(xy 282.886105 -285.274416) (xy 282.83725 -285.280348) (xy 282.788075 -285.278367) (xy 282.739856 -285.268523)
			(xy 282.69384 -285.251071) (xy 282.651219 -285.226464) (xy 282.613098 -285.195339) (xy 282.580463 -285.158502)
			(xy 282.55416 -285.116906) (xy 282.534869 -285.07163) (xy 282.523092 -285.023846) (xy 282.519132 -284.974792)
			(xy 282.18003 -284.974792) (xy 282.179535 -284.999399) (xy 282.17164 -285.047976) (xy 282.156056 -285.094657)
			(xy 282.133185 -285.138234) (xy 282.10362 -285.177578) (xy 282.068127 -285.21167) (xy 282.027624 -285.239626)
			(xy 281.983162 -285.260724) (xy 281.935891 -285.274416) (xy 281.887036 -285.280348) (xy 281.837861 -285.278367)
			(xy 281.789642 -285.268523) (xy 281.743626 -285.251071) (xy 281.701005 -285.226464) (xy 281.662884 -285.195339)
			(xy 281.630249 -285.158502) (xy 281.603946 -285.116906) (xy 281.584655 -285.07163) (xy 281.572878 -285.023846)
			(xy 281.568918 -284.974792) (xy 281.23007 -284.974792) (xy 281.229575 -284.999399) (xy 281.22168 -285.047976)
			(xy 281.206096 -285.094657) (xy 281.183225 -285.138234) (xy 281.15366 -285.177578) (xy 281.118167 -285.21167)
			(xy 281.077664 -285.239626) (xy 281.033202 -285.260724) (xy 280.985931 -285.274416) (xy 280.937076 -285.280348)
			(xy 280.887901 -285.278367) (xy 280.839682 -285.268523) (xy 280.793666 -285.251071) (xy 280.751045 -285.226464)
			(xy 280.712924 -285.195339) (xy 280.680289 -285.158502) (xy 280.653986 -285.116906) (xy 280.634695 -285.07163)
			(xy 280.622918 -285.023846) (xy 280.618958 -284.974792) (xy 280.28011 -284.974792) (xy 280.279615 -284.999399)
			(xy 280.27172 -285.047976) (xy 280.256136 -285.094657) (xy 280.233265 -285.138234) (xy 280.2037 -285.177578)
			(xy 280.168207 -285.21167) (xy 280.127704 -285.239626) (xy 280.083242 -285.260724) (xy 280.035971 -285.274416)
			(xy 279.987116 -285.280348) (xy 279.937941 -285.278367) (xy 279.889722 -285.268523) (xy 279.843706 -285.251071)
			(xy 279.801085 -285.226464) (xy 279.762964 -285.195339) (xy 279.730329 -285.158502) (xy 279.704026 -285.116906)
			(xy 279.684735 -285.07163) (xy 279.672958 -285.023846) (xy 279.668998 -284.974792) (xy 279.33015 -284.974792)
			(xy 279.329655 -284.999399) (xy 279.32176 -285.047976) (xy 279.306176 -285.094657) (xy 279.283305 -285.138234)
			(xy 279.25374 -285.177578) (xy 279.218247 -285.21167) (xy 279.177744 -285.239626) (xy 279.133282 -285.260724)
			(xy 279.086011 -285.274416) (xy 279.037156 -285.280348) (xy 278.987981 -285.278367) (xy 278.939762 -285.268523)
			(xy 278.893746 -285.251071) (xy 278.851125 -285.226464) (xy 278.813004 -285.195339) (xy 278.780369 -285.158502)
			(xy 278.754066 -285.116906) (xy 278.734775 -285.07163) (xy 278.722998 -285.023846) (xy 278.719038 -284.974792)
			(xy 278.38019 -284.974792) (xy 278.379695 -284.999399) (xy 278.3718 -285.047976) (xy 278.356216 -285.094657)
			(xy 278.333345 -285.138234) (xy 278.30378 -285.177578) (xy 278.268287 -285.21167) (xy 278.227784 -285.239626)
			(xy 278.183322 -285.260724) (xy 278.136051 -285.274416) (xy 278.087196 -285.280348) (xy 278.038021 -285.278367)
			(xy 277.989802 -285.268523) (xy 277.943786 -285.251071) (xy 277.901165 -285.226464) (xy 277.863044 -285.195339)
			(xy 277.830409 -285.158502) (xy 277.804106 -285.116906) (xy 277.784815 -285.07163) (xy 277.773038 -285.023846)
			(xy 277.769078 -284.974792) (xy 277.43023 -284.974792) (xy 277.429735 -284.999399) (xy 277.42184 -285.047976)
			(xy 277.406256 -285.094657) (xy 277.383385 -285.138234) (xy 277.35382 -285.177578) (xy 277.318327 -285.21167)
			(xy 277.277824 -285.239626) (xy 277.233362 -285.260724) (xy 277.186091 -285.274416) (xy 277.137236 -285.280348)
			(xy 277.088061 -285.278367) (xy 277.039842 -285.268523) (xy 276.993826 -285.251071) (xy 276.951205 -285.226464)
			(xy 276.913084 -285.195339) (xy 276.880449 -285.158502) (xy 276.854146 -285.116906) (xy 276.834855 -285.07163)
			(xy 276.823078 -285.023846) (xy 276.819118 -284.974792) (xy 275.530056 -284.974792) (xy 275.529561 -284.999399)
			(xy 275.521666 -285.047976) (xy 275.506082 -285.094657) (xy 275.483211 -285.138234) (xy 275.453646 -285.177578)
			(xy 275.418153 -285.21167) (xy 275.37765 -285.239626) (xy 275.333188 -285.260724) (xy 275.285917 -285.274416)
			(xy 275.237062 -285.280348) (xy 275.187887 -285.278367) (xy 275.139668 -285.268523) (xy 275.093652 -285.251071)
			(xy 275.051031 -285.226464) (xy 275.01291 -285.195339) (xy 274.980275 -285.158502) (xy 274.953972 -285.116906)
			(xy 274.934681 -285.07163) (xy 274.922904 -285.023846) (xy 274.918944 -284.974792) (xy 273.630136 -284.974792)
			(xy 273.629641 -284.999399) (xy 273.621746 -285.047976) (xy 273.606162 -285.094657) (xy 273.583291 -285.138234)
			(xy 273.553726 -285.177578) (xy 273.518233 -285.21167) (xy 273.47773 -285.239626) (xy 273.433268 -285.260724)
			(xy 273.385997 -285.274416) (xy 273.337142 -285.280348) (xy 273.287967 -285.278367) (xy 273.239748 -285.268523)
			(xy 273.193732 -285.251071) (xy 273.151111 -285.226464) (xy 273.11299 -285.195339) (xy 273.080355 -285.158502)
			(xy 273.054052 -285.116906) (xy 273.034761 -285.07163) (xy 273.022984 -285.023846) (xy 273.019024 -284.974792)
			(xy 272.680176 -284.974792) (xy 272.679681 -284.999399) (xy 272.671786 -285.047976) (xy 272.656202 -285.094657)
			(xy 272.633331 -285.138234) (xy 272.603766 -285.177578) (xy 272.568273 -285.21167) (xy 272.52777 -285.239626)
			(xy 272.483308 -285.260724) (xy 272.436037 -285.274416) (xy 272.387182 -285.280348) (xy 272.338007 -285.278367)
			(xy 272.289788 -285.268523) (xy 272.243772 -285.251071) (xy 272.201151 -285.226464) (xy 272.16303 -285.195339)
			(xy 272.130395 -285.158502) (xy 272.104092 -285.116906) (xy 272.084801 -285.07163) (xy 272.073024 -285.023846)
			(xy 272.069064 -284.974792) (xy 271.730216 -284.974792) (xy 271.729721 -284.999399) (xy 271.721826 -285.047976)
			(xy 271.706242 -285.094657) (xy 271.683371 -285.138234) (xy 271.653806 -285.177578) (xy 271.618313 -285.21167)
			(xy 271.57781 -285.239626) (xy 271.533348 -285.260724) (xy 271.486077 -285.274416) (xy 271.437222 -285.280348)
			(xy 271.388047 -285.278367) (xy 271.339828 -285.268523) (xy 271.293812 -285.251071) (xy 271.251191 -285.226464)
			(xy 271.21307 -285.195339) (xy 271.180435 -285.158502) (xy 271.154132 -285.116906) (xy 271.134841 -285.07163)
			(xy 271.123064 -285.023846) (xy 271.119104 -284.974792) (xy 270.780256 -284.974792) (xy 270.779761 -284.999399)
			(xy 270.771866 -285.047976) (xy 270.756282 -285.094657) (xy 270.733411 -285.138234) (xy 270.703846 -285.177578)
			(xy 270.668353 -285.21167) (xy 270.62785 -285.239626) (xy 270.583388 -285.260724) (xy 270.536117 -285.274416)
			(xy 270.487262 -285.280348) (xy 270.438087 -285.278367) (xy 270.389868 -285.268523) (xy 270.343852 -285.251071)
			(xy 270.301231 -285.226464) (xy 270.26311 -285.195339) (xy 270.230475 -285.158502) (xy 270.204172 -285.116906)
			(xy 270.184881 -285.07163) (xy 270.173104 -285.023846) (xy 270.169144 -284.974792) (xy 269.830042 -284.974792)
			(xy 269.829547 -284.999399) (xy 269.821652 -285.047976) (xy 269.806068 -285.094657) (xy 269.783197 -285.138234)
			(xy 269.753632 -285.177578) (xy 269.718139 -285.21167) (xy 269.677636 -285.239626) (xy 269.633174 -285.260724)
			(xy 269.585903 -285.274416) (xy 269.537048 -285.280348) (xy 269.487873 -285.278367) (xy 269.439654 -285.268523)
			(xy 269.393638 -285.251071) (xy 269.351017 -285.226464) (xy 269.312896 -285.195339) (xy 269.280261 -285.158502)
			(xy 269.253958 -285.116906) (xy 269.234667 -285.07163) (xy 269.22289 -285.023846) (xy 269.21893 -284.974792)
			(xy 268.880082 -284.974792) (xy 268.879587 -284.999399) (xy 268.871692 -285.047976) (xy 268.856108 -285.094657)
			(xy 268.833237 -285.138234) (xy 268.803672 -285.177578) (xy 268.768179 -285.21167) (xy 268.727676 -285.239626)
			(xy 268.683214 -285.260724) (xy 268.635943 -285.274416) (xy 268.587088 -285.280348) (xy 268.537913 -285.278367)
			(xy 268.489694 -285.268523) (xy 268.443678 -285.251071) (xy 268.401057 -285.226464) (xy 268.362936 -285.195339)
			(xy 268.330301 -285.158502) (xy 268.303998 -285.116906) (xy 268.284707 -285.07163) (xy 268.27293 -285.023846)
			(xy 268.26897 -284.974792) (xy 266.590526 -284.974792) (xy 266.590526 -285.449772) (xy 305.793914 -285.449772)
			(xy 305.797874 -285.400718) (xy 305.809651 -285.352934) (xy 305.828942 -285.307658) (xy 305.855245 -285.266062)
			(xy 305.88788 -285.229225) (xy 305.926001 -285.1981) (xy 305.968622 -285.173493) (xy 306.014638 -285.156041)
			(xy 306.062857 -285.146197) (xy 306.112032 -285.144216) (xy 306.160887 -285.150148) (xy 306.208158 -285.16384)
			(xy 306.25262 -285.184938) (xy 306.293123 -285.212894) (xy 306.328616 -285.246986) (xy 306.358181 -285.28633)
			(xy 306.381052 -285.329907) (xy 306.396636 -285.376588) (xy 306.404531 -285.425165) (xy 306.405026 -285.449772)
			(xy 306.743874 -285.449772) (xy 306.747834 -285.400718) (xy 306.759611 -285.352934) (xy 306.778902 -285.307658)
			(xy 306.805205 -285.266062) (xy 306.83784 -285.229225) (xy 306.875961 -285.1981) (xy 306.918582 -285.173493)
			(xy 306.964598 -285.156041) (xy 307.012817 -285.146197) (xy 307.061992 -285.144216) (xy 307.110847 -285.150148)
			(xy 307.158118 -285.16384) (xy 307.20258 -285.184938) (xy 307.243083 -285.212894) (xy 307.278576 -285.246986)
			(xy 307.308141 -285.28633) (xy 307.331012 -285.329907) (xy 307.346596 -285.376588) (xy 307.354491 -285.425165)
			(xy 307.354986 -285.449772) (xy 307.694088 -285.449772) (xy 307.698048 -285.400718) (xy 307.709825 -285.352934)
			(xy 307.729116 -285.307658) (xy 307.755419 -285.266062) (xy 307.788054 -285.229225) (xy 307.826175 -285.1981)
			(xy 307.868796 -285.173493) (xy 307.914812 -285.156041) (xy 307.963031 -285.146197) (xy 308.012206 -285.144216)
			(xy 308.061061 -285.150148) (xy 308.108332 -285.16384) (xy 308.152794 -285.184938) (xy 308.193297 -285.212894)
			(xy 308.22879 -285.246986) (xy 308.258355 -285.28633) (xy 308.281226 -285.329907) (xy 308.29681 -285.376588)
			(xy 308.304705 -285.425165) (xy 308.3052 -285.449772) (xy 308.304705 -285.474379) (xy 308.29681 -285.522956)
			(xy 308.281226 -285.569637) (xy 308.258355 -285.613214) (xy 308.22879 -285.652558) (xy 308.193297 -285.68665)
			(xy 308.152794 -285.714606) (xy 308.108332 -285.735704) (xy 308.061061 -285.749396) (xy 308.012206 -285.755328)
			(xy 307.963031 -285.753347) (xy 307.914812 -285.743503) (xy 307.868796 -285.726051) (xy 307.826175 -285.701444)
			(xy 307.788054 -285.670319) (xy 307.755419 -285.633482) (xy 307.729116 -285.591886) (xy 307.709825 -285.54661)
			(xy 307.698048 -285.498826) (xy 307.694088 -285.449772) (xy 307.354986 -285.449772) (xy 307.354491 -285.474379)
			(xy 307.346596 -285.522956) (xy 307.331012 -285.569637) (xy 307.308141 -285.613214) (xy 307.278576 -285.652558)
			(xy 307.243083 -285.68665) (xy 307.20258 -285.714606) (xy 307.158118 -285.735704) (xy 307.110847 -285.749396)
			(xy 307.061992 -285.755328) (xy 307.012817 -285.753347) (xy 306.964598 -285.743503) (xy 306.918582 -285.726051)
			(xy 306.875961 -285.701444) (xy 306.83784 -285.670319) (xy 306.805205 -285.633482) (xy 306.778902 -285.591886)
			(xy 306.759611 -285.54661) (xy 306.747834 -285.498826) (xy 306.743874 -285.449772) (xy 306.405026 -285.449772)
			(xy 306.404531 -285.474379) (xy 306.396636 -285.522956) (xy 306.381052 -285.569637) (xy 306.358181 -285.613214)
			(xy 306.328616 -285.652558) (xy 306.293123 -285.68665) (xy 306.25262 -285.714606) (xy 306.208158 -285.735704)
			(xy 306.160887 -285.749396) (xy 306.112032 -285.755328) (xy 306.062857 -285.753347) (xy 306.014638 -285.743503)
			(xy 305.968622 -285.726051) (xy 305.926001 -285.701444) (xy 305.88788 -285.670319) (xy 305.855245 -285.633482)
			(xy 305.828942 -285.591886) (xy 305.809651 -285.54661) (xy 305.797874 -285.498826) (xy 305.793914 -285.449772)
			(xy 266.590526 -285.449772) (xy 266.590526 -285.924752) (xy 268.26897 -285.924752) (xy 268.27293 -285.875698)
			(xy 268.284707 -285.827914) (xy 268.303998 -285.782638) (xy 268.330301 -285.741042) (xy 268.362936 -285.704205)
			(xy 268.401057 -285.67308) (xy 268.443678 -285.648473) (xy 268.489694 -285.631021) (xy 268.537913 -285.621177)
			(xy 268.587088 -285.619196) (xy 268.635943 -285.625128) (xy 268.683214 -285.63882) (xy 268.727676 -285.659918)
			(xy 268.768179 -285.687874) (xy 268.803672 -285.721966) (xy 268.833237 -285.76131) (xy 268.856108 -285.804887)
			(xy 268.871692 -285.851568) (xy 268.879587 -285.900145) (xy 268.880082 -285.924752) (xy 269.21893 -285.924752)
			(xy 269.22289 -285.875698) (xy 269.234667 -285.827914) (xy 269.253958 -285.782638) (xy 269.280261 -285.741042)
			(xy 269.312896 -285.704205) (xy 269.351017 -285.67308) (xy 269.393638 -285.648473) (xy 269.439654 -285.631021)
			(xy 269.487873 -285.621177) (xy 269.537048 -285.619196) (xy 269.585903 -285.625128) (xy 269.633174 -285.63882)
			(xy 269.677636 -285.659918) (xy 269.718139 -285.687874) (xy 269.753632 -285.721966) (xy 269.783197 -285.76131)
			(xy 269.806068 -285.804887) (xy 269.821652 -285.851568) (xy 269.829547 -285.900145) (xy 269.830042 -285.924752)
			(xy 270.169144 -285.924752) (xy 270.173104 -285.875698) (xy 270.184881 -285.827914) (xy 270.204172 -285.782638)
			(xy 270.230475 -285.741042) (xy 270.26311 -285.704205) (xy 270.301231 -285.67308) (xy 270.343852 -285.648473)
			(xy 270.389868 -285.631021) (xy 270.438087 -285.621177) (xy 270.487262 -285.619196) (xy 270.536117 -285.625128)
			(xy 270.583388 -285.63882) (xy 270.62785 -285.659918) (xy 270.668353 -285.687874) (xy 270.703846 -285.721966)
			(xy 270.733411 -285.76131) (xy 270.756282 -285.804887) (xy 270.771866 -285.851568) (xy 270.779761 -285.900145)
			(xy 270.780256 -285.924752) (xy 271.119104 -285.924752) (xy 271.123064 -285.875698) (xy 271.134841 -285.827914)
			(xy 271.154132 -285.782638) (xy 271.180435 -285.741042) (xy 271.21307 -285.704205) (xy 271.251191 -285.67308)
			(xy 271.293812 -285.648473) (xy 271.339828 -285.631021) (xy 271.388047 -285.621177) (xy 271.437222 -285.619196)
			(xy 271.486077 -285.625128) (xy 271.533348 -285.63882) (xy 271.57781 -285.659918) (xy 271.618313 -285.687874)
			(xy 271.653806 -285.721966) (xy 271.683371 -285.76131) (xy 271.706242 -285.804887) (xy 271.721826 -285.851568)
			(xy 271.729721 -285.900145) (xy 271.730216 -285.924752) (xy 272.069064 -285.924752) (xy 272.073024 -285.875698)
			(xy 272.084801 -285.827914) (xy 272.104092 -285.782638) (xy 272.130395 -285.741042) (xy 272.16303 -285.704205)
			(xy 272.201151 -285.67308) (xy 272.243772 -285.648473) (xy 272.289788 -285.631021) (xy 272.338007 -285.621177)
			(xy 272.387182 -285.619196) (xy 272.436037 -285.625128) (xy 272.483308 -285.63882) (xy 272.52777 -285.659918)
			(xy 272.568273 -285.687874) (xy 272.603766 -285.721966) (xy 272.633331 -285.76131) (xy 272.656202 -285.804887)
			(xy 272.671786 -285.851568) (xy 272.679681 -285.900145) (xy 272.680176 -285.924752) (xy 273.019024 -285.924752)
			(xy 273.022984 -285.875698) (xy 273.034761 -285.827914) (xy 273.054052 -285.782638) (xy 273.080355 -285.741042)
			(xy 273.11299 -285.704205) (xy 273.151111 -285.67308) (xy 273.193732 -285.648473) (xy 273.239748 -285.631021)
			(xy 273.287967 -285.621177) (xy 273.337142 -285.619196) (xy 273.385997 -285.625128) (xy 273.433268 -285.63882)
			(xy 273.47773 -285.659918) (xy 273.518233 -285.687874) (xy 273.553726 -285.721966) (xy 273.583291 -285.76131)
			(xy 273.606162 -285.804887) (xy 273.621746 -285.851568) (xy 273.629641 -285.900145) (xy 273.630136 -285.924752)
			(xy 276.819118 -285.924752) (xy 276.823078 -285.875698) (xy 276.834855 -285.827914) (xy 276.854146 -285.782638)
			(xy 276.880449 -285.741042) (xy 276.913084 -285.704205) (xy 276.951205 -285.67308) (xy 276.993826 -285.648473)
			(xy 277.039842 -285.631021) (xy 277.088061 -285.621177) (xy 277.137236 -285.619196) (xy 277.186091 -285.625128)
			(xy 277.233362 -285.63882) (xy 277.277824 -285.659918) (xy 277.318327 -285.687874) (xy 277.35382 -285.721966)
			(xy 277.383385 -285.76131) (xy 277.406256 -285.804887) (xy 277.42184 -285.851568) (xy 277.429735 -285.900145)
			(xy 277.43023 -285.924752) (xy 277.769078 -285.924752) (xy 277.773038 -285.875698) (xy 277.784815 -285.827914)
			(xy 277.804106 -285.782638) (xy 277.830409 -285.741042) (xy 277.863044 -285.704205) (xy 277.901165 -285.67308)
			(xy 277.943786 -285.648473) (xy 277.989802 -285.631021) (xy 278.038021 -285.621177) (xy 278.087196 -285.619196)
			(xy 278.136051 -285.625128) (xy 278.183322 -285.63882) (xy 278.227784 -285.659918) (xy 278.268287 -285.687874)
			(xy 278.30378 -285.721966) (xy 278.333345 -285.76131) (xy 278.356216 -285.804887) (xy 278.3718 -285.851568)
			(xy 278.379695 -285.900145) (xy 278.38019 -285.924752) (xy 278.719038 -285.924752) (xy 278.722998 -285.875698)
			(xy 278.734775 -285.827914) (xy 278.754066 -285.782638) (xy 278.780369 -285.741042) (xy 278.813004 -285.704205)
			(xy 278.851125 -285.67308) (xy 278.893746 -285.648473) (xy 278.939762 -285.631021) (xy 278.987981 -285.621177)
			(xy 279.037156 -285.619196) (xy 279.086011 -285.625128) (xy 279.133282 -285.63882) (xy 279.177744 -285.659918)
			(xy 279.218247 -285.687874) (xy 279.25374 -285.721966) (xy 279.283305 -285.76131) (xy 279.306176 -285.804887)
			(xy 279.32176 -285.851568) (xy 279.329655 -285.900145) (xy 279.33015 -285.924752) (xy 279.668998 -285.924752)
			(xy 279.672958 -285.875698) (xy 279.684735 -285.827914) (xy 279.704026 -285.782638) (xy 279.730329 -285.741042)
			(xy 279.762964 -285.704205) (xy 279.801085 -285.67308) (xy 279.843706 -285.648473) (xy 279.889722 -285.631021)
			(xy 279.937941 -285.621177) (xy 279.987116 -285.619196) (xy 280.035971 -285.625128) (xy 280.083242 -285.63882)
			(xy 280.127704 -285.659918) (xy 280.168207 -285.687874) (xy 280.2037 -285.721966) (xy 280.233265 -285.76131)
			(xy 280.256136 -285.804887) (xy 280.27172 -285.851568) (xy 280.279615 -285.900145) (xy 280.28011 -285.924752)
			(xy 280.618958 -285.924752) (xy 280.622918 -285.875698) (xy 280.634695 -285.827914) (xy 280.653986 -285.782638)
			(xy 280.680289 -285.741042) (xy 280.712924 -285.704205) (xy 280.751045 -285.67308) (xy 280.793666 -285.648473)
			(xy 280.839682 -285.631021) (xy 280.887901 -285.621177) (xy 280.937076 -285.619196) (xy 280.985931 -285.625128)
			(xy 281.033202 -285.63882) (xy 281.077664 -285.659918) (xy 281.118167 -285.687874) (xy 281.15366 -285.721966)
			(xy 281.183225 -285.76131) (xy 281.206096 -285.804887) (xy 281.22168 -285.851568) (xy 281.229575 -285.900145)
			(xy 281.23007 -285.924752) (xy 281.568918 -285.924752) (xy 281.572878 -285.875698) (xy 281.584655 -285.827914)
			(xy 281.603946 -285.782638) (xy 281.630249 -285.741042) (xy 281.662884 -285.704205) (xy 281.701005 -285.67308)
			(xy 281.743626 -285.648473) (xy 281.789642 -285.631021) (xy 281.837861 -285.621177) (xy 281.887036 -285.619196)
			(xy 281.935891 -285.625128) (xy 281.983162 -285.63882) (xy 282.027624 -285.659918) (xy 282.068127 -285.687874)
			(xy 282.10362 -285.721966) (xy 282.133185 -285.76131) (xy 282.156056 -285.804887) (xy 282.17164 -285.851568)
			(xy 282.179535 -285.900145) (xy 282.18003 -285.924752) (xy 282.519132 -285.924752) (xy 282.523092 -285.875698)
			(xy 282.534869 -285.827914) (xy 282.55416 -285.782638) (xy 282.580463 -285.741042) (xy 282.613098 -285.704205)
			(xy 282.651219 -285.67308) (xy 282.69384 -285.648473) (xy 282.739856 -285.631021) (xy 282.788075 -285.621177)
			(xy 282.83725 -285.619196) (xy 282.886105 -285.625128) (xy 282.933376 -285.63882) (xy 282.977838 -285.659918)
			(xy 283.018341 -285.687874) (xy 283.053834 -285.721966) (xy 283.083399 -285.76131) (xy 283.10627 -285.804887)
			(xy 283.121854 -285.851568) (xy 283.129749 -285.900145) (xy 283.130244 -285.924752) (xy 283.469092 -285.924752)
			(xy 283.473052 -285.875698) (xy 283.484829 -285.827914) (xy 283.50412 -285.782638) (xy 283.530423 -285.741042)
			(xy 283.563058 -285.704205) (xy 283.601179 -285.67308) (xy 283.6438 -285.648473) (xy 283.689816 -285.631021)
			(xy 283.738035 -285.621177) (xy 283.78721 -285.619196) (xy 283.836065 -285.625128) (xy 283.883336 -285.63882)
			(xy 283.927798 -285.659918) (xy 283.968301 -285.687874) (xy 284.003794 -285.721966) (xy 284.033359 -285.76131)
			(xy 284.05623 -285.804887) (xy 284.071814 -285.851568) (xy 284.079709 -285.900145) (xy 284.080204 -285.924752)
			(xy 284.419052 -285.924752) (xy 284.423012 -285.875698) (xy 284.434789 -285.827914) (xy 284.45408 -285.782638)
			(xy 284.480383 -285.741042) (xy 284.513018 -285.704205) (xy 284.551139 -285.67308) (xy 284.59376 -285.648473)
			(xy 284.639776 -285.631021) (xy 284.687995 -285.621177) (xy 284.73717 -285.619196) (xy 284.786025 -285.625128)
			(xy 284.833296 -285.63882) (xy 284.877758 -285.659918) (xy 284.918261 -285.687874) (xy 284.953754 -285.721966)
			(xy 284.983319 -285.76131) (xy 285.00619 -285.804887) (xy 285.021774 -285.851568) (xy 285.029669 -285.900145)
			(xy 285.030164 -285.924752) (xy 285.369012 -285.924752) (xy 285.372972 -285.875698) (xy 285.384749 -285.827914)
			(xy 285.40404 -285.782638) (xy 285.430343 -285.741042) (xy 285.462978 -285.704205) (xy 285.501099 -285.67308)
			(xy 285.54372 -285.648473) (xy 285.589736 -285.631021) (xy 285.637955 -285.621177) (xy 285.68713 -285.619196)
			(xy 285.735985 -285.625128) (xy 285.783256 -285.63882) (xy 285.827718 -285.659918) (xy 285.868221 -285.687874)
			(xy 285.903714 -285.721966) (xy 285.933279 -285.76131) (xy 285.95615 -285.804887) (xy 285.971734 -285.851568)
			(xy 285.979629 -285.900145) (xy 285.980124 -285.924752) (xy 286.318972 -285.924752) (xy 286.322932 -285.875698)
			(xy 286.334709 -285.827914) (xy 286.354 -285.782638) (xy 286.380303 -285.741042) (xy 286.412938 -285.704205)
			(xy 286.451059 -285.67308) (xy 286.49368 -285.648473) (xy 286.539696 -285.631021) (xy 286.587915 -285.621177)
			(xy 286.63709 -285.619196) (xy 286.685945 -285.625128) (xy 286.733216 -285.63882) (xy 286.777678 -285.659918)
			(xy 286.818181 -285.687874) (xy 286.853674 -285.721966) (xy 286.883239 -285.76131) (xy 286.90611 -285.804887)
			(xy 286.921694 -285.851568) (xy 286.929589 -285.900145) (xy 286.930084 -285.924752) (xy 287.268932 -285.924752)
			(xy 287.272892 -285.875698) (xy 287.284669 -285.827914) (xy 287.30396 -285.782638) (xy 287.330263 -285.741042)
			(xy 287.362898 -285.704205) (xy 287.401019 -285.67308) (xy 287.44364 -285.648473) (xy 287.489656 -285.631021)
			(xy 287.537875 -285.621177) (xy 287.58705 -285.619196) (xy 287.635905 -285.625128) (xy 287.683176 -285.63882)
			(xy 287.727638 -285.659918) (xy 287.768141 -285.687874) (xy 287.803634 -285.721966) (xy 287.833199 -285.76131)
			(xy 287.85607 -285.804887) (xy 287.871654 -285.851568) (xy 287.879549 -285.900145) (xy 287.880044 -285.924752)
			(xy 288.218892 -285.924752) (xy 288.222852 -285.875698) (xy 288.234629 -285.827914) (xy 288.25392 -285.782638)
			(xy 288.280223 -285.741042) (xy 288.312858 -285.704205) (xy 288.350979 -285.67308) (xy 288.3936 -285.648473)
			(xy 288.439616 -285.631021) (xy 288.487835 -285.621177) (xy 288.53701 -285.619196) (xy 288.585865 -285.625128)
			(xy 288.633136 -285.63882) (xy 288.677598 -285.659918) (xy 288.718101 -285.687874) (xy 288.753594 -285.721966)
			(xy 288.783159 -285.76131) (xy 288.80603 -285.804887) (xy 288.821614 -285.851568) (xy 288.829509 -285.900145)
			(xy 288.830004 -285.924752) (xy 289.169106 -285.924752) (xy 289.173066 -285.875698) (xy 289.184843 -285.827914)
			(xy 289.204134 -285.782638) (xy 289.230437 -285.741042) (xy 289.263072 -285.704205) (xy 289.301193 -285.67308)
			(xy 289.343814 -285.648473) (xy 289.38983 -285.631021) (xy 289.438049 -285.621177) (xy 289.487224 -285.619196)
			(xy 289.536079 -285.625128) (xy 289.58335 -285.63882) (xy 289.627812 -285.659918) (xy 289.668315 -285.687874)
			(xy 289.703808 -285.721966) (xy 289.733373 -285.76131) (xy 289.756244 -285.804887) (xy 289.771828 -285.851568)
			(xy 289.779723 -285.900145) (xy 289.780218 -285.924752) (xy 290.119066 -285.924752) (xy 290.123026 -285.875698)
			(xy 290.134803 -285.827914) (xy 290.154094 -285.782638) (xy 290.180397 -285.741042) (xy 290.213032 -285.704205)
			(xy 290.251153 -285.67308) (xy 290.293774 -285.648473) (xy 290.33979 -285.631021) (xy 290.388009 -285.621177)
			(xy 290.437184 -285.619196) (xy 290.486039 -285.625128) (xy 290.53331 -285.63882) (xy 290.577772 -285.659918)
			(xy 290.618275 -285.687874) (xy 290.653768 -285.721966) (xy 290.683333 -285.76131) (xy 290.706204 -285.804887)
			(xy 290.721788 -285.851568) (xy 290.729683 -285.900145) (xy 290.730178 -285.924752) (xy 292.018986 -285.924752)
			(xy 292.022946 -285.875698) (xy 292.034723 -285.827914) (xy 292.054014 -285.782638) (xy 292.080317 -285.741042)
			(xy 292.112952 -285.704205) (xy 292.151073 -285.67308) (xy 292.193694 -285.648473) (xy 292.23971 -285.631021)
			(xy 292.287929 -285.621177) (xy 292.337104 -285.619196) (xy 292.385959 -285.625128) (xy 292.43323 -285.63882)
			(xy 292.477692 -285.659918) (xy 292.518195 -285.687874) (xy 292.553688 -285.721966) (xy 292.583253 -285.76131)
			(xy 292.606124 -285.804887) (xy 292.621708 -285.851568) (xy 292.629603 -285.900145) (xy 292.630098 -285.924752)
			(xy 292.968946 -285.924752) (xy 292.972906 -285.875698) (xy 292.984683 -285.827914) (xy 293.003974 -285.782638)
			(xy 293.030277 -285.741042) (xy 293.062912 -285.704205) (xy 293.101033 -285.67308) (xy 293.143654 -285.648473)
			(xy 293.18967 -285.631021) (xy 293.237889 -285.621177) (xy 293.287064 -285.619196) (xy 293.335919 -285.625128)
			(xy 293.38319 -285.63882) (xy 293.427652 -285.659918) (xy 293.468155 -285.687874) (xy 293.503648 -285.721966)
			(xy 293.533213 -285.76131) (xy 293.556084 -285.804887) (xy 293.571668 -285.851568) (xy 293.579563 -285.900145)
			(xy 293.580058 -285.924752) (xy 293.918906 -285.924752) (xy 293.922866 -285.875698) (xy 293.934643 -285.827914)
			(xy 293.953934 -285.782638) (xy 293.980237 -285.741042) (xy 294.012872 -285.704205) (xy 294.050993 -285.67308)
			(xy 294.093614 -285.648473) (xy 294.13963 -285.631021) (xy 294.187849 -285.621177) (xy 294.237024 -285.619196)
			(xy 294.285879 -285.625128) (xy 294.33315 -285.63882) (xy 294.377612 -285.659918) (xy 294.418115 -285.687874)
			(xy 294.453608 -285.721966) (xy 294.483173 -285.76131) (xy 294.506044 -285.804887) (xy 294.521628 -285.851568)
			(xy 294.529523 -285.900145) (xy 294.530018 -285.924752) (xy 294.86912 -285.924752) (xy 294.87308 -285.875698)
			(xy 294.884857 -285.827914) (xy 294.904148 -285.782638) (xy 294.930451 -285.741042) (xy 294.963086 -285.704205)
			(xy 295.001207 -285.67308) (xy 295.043828 -285.648473) (xy 295.089844 -285.631021) (xy 295.138063 -285.621177)
			(xy 295.187238 -285.619196) (xy 295.236093 -285.625128) (xy 295.283364 -285.63882) (xy 295.327826 -285.659918)
			(xy 295.368329 -285.687874) (xy 295.403822 -285.721966) (xy 295.433387 -285.76131) (xy 295.456258 -285.804887)
			(xy 295.471842 -285.851568) (xy 295.479737 -285.900145) (xy 295.480232 -285.924752) (xy 295.81908 -285.924752)
			(xy 295.82304 -285.875698) (xy 295.834817 -285.827914) (xy 295.854108 -285.782638) (xy 295.880411 -285.741042)
			(xy 295.913046 -285.704205) (xy 295.951167 -285.67308) (xy 295.993788 -285.648473) (xy 296.039804 -285.631021)
			(xy 296.088023 -285.621177) (xy 296.137198 -285.619196) (xy 296.186053 -285.625128) (xy 296.233324 -285.63882)
			(xy 296.277786 -285.659918) (xy 296.318289 -285.687874) (xy 296.353782 -285.721966) (xy 296.383347 -285.76131)
			(xy 296.406218 -285.804887) (xy 296.421802 -285.851568) (xy 296.429697 -285.900145) (xy 296.430192 -285.924752)
			(xy 296.76904 -285.924752) (xy 296.773 -285.875698) (xy 296.784777 -285.827914) (xy 296.804068 -285.782638)
			(xy 296.830371 -285.741042) (xy 296.863006 -285.704205) (xy 296.901127 -285.67308) (xy 296.943748 -285.648473)
			(xy 296.989764 -285.631021) (xy 297.037983 -285.621177) (xy 297.087158 -285.619196) (xy 297.136013 -285.625128)
			(xy 297.183284 -285.63882) (xy 297.227746 -285.659918) (xy 297.268249 -285.687874) (xy 297.303742 -285.721966)
			(xy 297.333307 -285.76131) (xy 297.356178 -285.804887) (xy 297.371762 -285.851568) (xy 297.379657 -285.900145)
			(xy 297.380152 -285.924752) (xy 297.719 -285.924752) (xy 297.72296 -285.875698) (xy 297.734737 -285.827914)
			(xy 297.754028 -285.782638) (xy 297.780331 -285.741042) (xy 297.812966 -285.704205) (xy 297.851087 -285.67308)
			(xy 297.893708 -285.648473) (xy 297.939724 -285.631021) (xy 297.987943 -285.621177) (xy 298.037118 -285.619196)
			(xy 298.085973 -285.625128) (xy 298.133244 -285.63882) (xy 298.177706 -285.659918) (xy 298.218209 -285.687874)
			(xy 298.253702 -285.721966) (xy 298.283267 -285.76131) (xy 298.306138 -285.804887) (xy 298.321722 -285.851568)
			(xy 298.329617 -285.900145) (xy 298.330112 -285.924752) (xy 298.66896 -285.924752) (xy 298.67292 -285.875698)
			(xy 298.684697 -285.827914) (xy 298.703988 -285.782638) (xy 298.730291 -285.741042) (xy 298.762926 -285.704205)
			(xy 298.801047 -285.67308) (xy 298.843668 -285.648473) (xy 298.889684 -285.631021) (xy 298.937903 -285.621177)
			(xy 298.987078 -285.619196) (xy 299.035933 -285.625128) (xy 299.083204 -285.63882) (xy 299.127666 -285.659918)
			(xy 299.168169 -285.687874) (xy 299.203662 -285.721966) (xy 299.233227 -285.76131) (xy 299.256098 -285.804887)
			(xy 299.271682 -285.851568) (xy 299.279577 -285.900145) (xy 299.280072 -285.924752) (xy 299.61892 -285.924752)
			(xy 299.62288 -285.875698) (xy 299.634657 -285.827914) (xy 299.653948 -285.782638) (xy 299.680251 -285.741042)
			(xy 299.712886 -285.704205) (xy 299.751007 -285.67308) (xy 299.793628 -285.648473) (xy 299.839644 -285.631021)
			(xy 299.887863 -285.621177) (xy 299.937038 -285.619196) (xy 299.985893 -285.625128) (xy 300.033164 -285.63882)
			(xy 300.077626 -285.659918) (xy 300.118129 -285.687874) (xy 300.153622 -285.721966) (xy 300.183187 -285.76131)
			(xy 300.206058 -285.804887) (xy 300.221642 -285.851568) (xy 300.229537 -285.900145) (xy 300.230032 -285.924752)
			(xy 300.56888 -285.924752) (xy 300.57284 -285.875698) (xy 300.584617 -285.827914) (xy 300.603908 -285.782638)
			(xy 300.630211 -285.741042) (xy 300.662846 -285.704205) (xy 300.700967 -285.67308) (xy 300.743588 -285.648473)
			(xy 300.789604 -285.631021) (xy 300.837823 -285.621177) (xy 300.886998 -285.619196) (xy 300.935853 -285.625128)
			(xy 300.983124 -285.63882) (xy 301.027586 -285.659918) (xy 301.068089 -285.687874) (xy 301.103582 -285.721966)
			(xy 301.133147 -285.76131) (xy 301.156018 -285.804887) (xy 301.171602 -285.851568) (xy 301.179497 -285.900145)
			(xy 301.179992 -285.924752) (xy 301.519094 -285.924752) (xy 301.523054 -285.875698) (xy 301.534831 -285.827914)
			(xy 301.554122 -285.782638) (xy 301.580425 -285.741042) (xy 301.61306 -285.704205) (xy 301.651181 -285.67308)
			(xy 301.693802 -285.648473) (xy 301.739818 -285.631021) (xy 301.788037 -285.621177) (xy 301.837212 -285.619196)
			(xy 301.886067 -285.625128) (xy 301.933338 -285.63882) (xy 301.9778 -285.659918) (xy 302.018303 -285.687874)
			(xy 302.053796 -285.721966) (xy 302.083361 -285.76131) (xy 302.106232 -285.804887) (xy 302.121816 -285.851568)
			(xy 302.129711 -285.900145) (xy 302.130206 -285.924752) (xy 302.469054 -285.924752) (xy 302.473014 -285.875698)
			(xy 302.484791 -285.827914) (xy 302.504082 -285.782638) (xy 302.530385 -285.741042) (xy 302.56302 -285.704205)
			(xy 302.601141 -285.67308) (xy 302.643762 -285.648473) (xy 302.689778 -285.631021) (xy 302.737997 -285.621177)
			(xy 302.787172 -285.619196) (xy 302.836027 -285.625128) (xy 302.883298 -285.63882) (xy 302.92776 -285.659918)
			(xy 302.968263 -285.687874) (xy 303.003756 -285.721966) (xy 303.033321 -285.76131) (xy 303.056192 -285.804887)
			(xy 303.071776 -285.851568) (xy 303.079671 -285.900145) (xy 303.080166 -285.924752) (xy 303.079671 -285.949359)
			(xy 303.071776 -285.997936) (xy 303.056192 -286.044617) (xy 303.033321 -286.088194) (xy 303.003756 -286.127538)
			(xy 302.968263 -286.16163) (xy 302.92776 -286.189586) (xy 302.883298 -286.210684) (xy 302.836027 -286.224376)
			(xy 302.787172 -286.230308) (xy 302.737997 -286.228327) (xy 302.689778 -286.218483) (xy 302.643762 -286.201031)
			(xy 302.601141 -286.176424) (xy 302.56302 -286.145299) (xy 302.530385 -286.108462) (xy 302.504082 -286.066866)
			(xy 302.484791 -286.02159) (xy 302.473014 -285.973806) (xy 302.469054 -285.924752) (xy 302.130206 -285.924752)
			(xy 302.129711 -285.949359) (xy 302.121816 -285.997936) (xy 302.106232 -286.044617) (xy 302.083361 -286.088194)
			(xy 302.053796 -286.127538) (xy 302.018303 -286.16163) (xy 301.9778 -286.189586) (xy 301.933338 -286.210684)
			(xy 301.886067 -286.224376) (xy 301.837212 -286.230308) (xy 301.788037 -286.228327) (xy 301.739818 -286.218483)
			(xy 301.693802 -286.201031) (xy 301.651181 -286.176424) (xy 301.61306 -286.145299) (xy 301.580425 -286.108462)
			(xy 301.554122 -286.066866) (xy 301.534831 -286.02159) (xy 301.523054 -285.973806) (xy 301.519094 -285.924752)
			(xy 301.179992 -285.924752) (xy 301.179497 -285.949359) (xy 301.171602 -285.997936) (xy 301.156018 -286.044617)
			(xy 301.133147 -286.088194) (xy 301.103582 -286.127538) (xy 301.068089 -286.16163) (xy 301.027586 -286.189586)
			(xy 300.983124 -286.210684) (xy 300.935853 -286.224376) (xy 300.886998 -286.230308) (xy 300.837823 -286.228327)
			(xy 300.789604 -286.218483) (xy 300.743588 -286.201031) (xy 300.700967 -286.176424) (xy 300.662846 -286.145299)
			(xy 300.630211 -286.108462) (xy 300.603908 -286.066866) (xy 300.584617 -286.02159) (xy 300.57284 -285.973806)
			(xy 300.56888 -285.924752) (xy 300.230032 -285.924752) (xy 300.229537 -285.949359) (xy 300.221642 -285.997936)
			(xy 300.206058 -286.044617) (xy 300.183187 -286.088194) (xy 300.153622 -286.127538) (xy 300.118129 -286.16163)
			(xy 300.077626 -286.189586) (xy 300.033164 -286.210684) (xy 299.985893 -286.224376) (xy 299.937038 -286.230308)
			(xy 299.887863 -286.228327) (xy 299.839644 -286.218483) (xy 299.793628 -286.201031) (xy 299.751007 -286.176424)
			(xy 299.712886 -286.145299) (xy 299.680251 -286.108462) (xy 299.653948 -286.066866) (xy 299.634657 -286.02159)
			(xy 299.62288 -285.973806) (xy 299.61892 -285.924752) (xy 299.280072 -285.924752) (xy 299.279577 -285.949359)
			(xy 299.271682 -285.997936) (xy 299.256098 -286.044617) (xy 299.233227 -286.088194) (xy 299.203662 -286.127538)
			(xy 299.168169 -286.16163) (xy 299.127666 -286.189586) (xy 299.083204 -286.210684) (xy 299.035933 -286.224376)
			(xy 298.987078 -286.230308) (xy 298.937903 -286.228327) (xy 298.889684 -286.218483) (xy 298.843668 -286.201031)
			(xy 298.801047 -286.176424) (xy 298.762926 -286.145299) (xy 298.730291 -286.108462) (xy 298.703988 -286.066866)
			(xy 298.684697 -286.02159) (xy 298.67292 -285.973806) (xy 298.66896 -285.924752) (xy 298.330112 -285.924752)
			(xy 298.329617 -285.949359) (xy 298.321722 -285.997936) (xy 298.306138 -286.044617) (xy 298.283267 -286.088194)
			(xy 298.253702 -286.127538) (xy 298.218209 -286.16163) (xy 298.177706 -286.189586) (xy 298.133244 -286.210684)
			(xy 298.085973 -286.224376) (xy 298.037118 -286.230308) (xy 297.987943 -286.228327) (xy 297.939724 -286.218483)
			(xy 297.893708 -286.201031) (xy 297.851087 -286.176424) (xy 297.812966 -286.145299) (xy 297.780331 -286.108462)
			(xy 297.754028 -286.066866) (xy 297.734737 -286.02159) (xy 297.72296 -285.973806) (xy 297.719 -285.924752)
			(xy 297.380152 -285.924752) (xy 297.379657 -285.949359) (xy 297.371762 -285.997936) (xy 297.356178 -286.044617)
			(xy 297.333307 -286.088194) (xy 297.303742 -286.127538) (xy 297.268249 -286.16163) (xy 297.227746 -286.189586)
			(xy 297.183284 -286.210684) (xy 297.136013 -286.224376) (xy 297.087158 -286.230308) (xy 297.037983 -286.228327)
			(xy 296.989764 -286.218483) (xy 296.943748 -286.201031) (xy 296.901127 -286.176424) (xy 296.863006 -286.145299)
			(xy 296.830371 -286.108462) (xy 296.804068 -286.066866) (xy 296.784777 -286.02159) (xy 296.773 -285.973806)
			(xy 296.76904 -285.924752) (xy 296.430192 -285.924752) (xy 296.429697 -285.949359) (xy 296.421802 -285.997936)
			(xy 296.406218 -286.044617) (xy 296.383347 -286.088194) (xy 296.353782 -286.127538) (xy 296.318289 -286.16163)
			(xy 296.277786 -286.189586) (xy 296.233324 -286.210684) (xy 296.186053 -286.224376) (xy 296.137198 -286.230308)
			(xy 296.088023 -286.228327) (xy 296.039804 -286.218483) (xy 295.993788 -286.201031) (xy 295.951167 -286.176424)
			(xy 295.913046 -286.145299) (xy 295.880411 -286.108462) (xy 295.854108 -286.066866) (xy 295.834817 -286.02159)
			(xy 295.82304 -285.973806) (xy 295.81908 -285.924752) (xy 295.480232 -285.924752) (xy 295.479737 -285.949359)
			(xy 295.471842 -285.997936) (xy 295.456258 -286.044617) (xy 295.433387 -286.088194) (xy 295.403822 -286.127538)
			(xy 295.368329 -286.16163) (xy 295.327826 -286.189586) (xy 295.283364 -286.210684) (xy 295.236093 -286.224376)
			(xy 295.187238 -286.230308) (xy 295.138063 -286.228327) (xy 295.089844 -286.218483) (xy 295.043828 -286.201031)
			(xy 295.001207 -286.176424) (xy 294.963086 -286.145299) (xy 294.930451 -286.108462) (xy 294.904148 -286.066866)
			(xy 294.884857 -286.02159) (xy 294.87308 -285.973806) (xy 294.86912 -285.924752) (xy 294.530018 -285.924752)
			(xy 294.529523 -285.949359) (xy 294.521628 -285.997936) (xy 294.506044 -286.044617) (xy 294.483173 -286.088194)
			(xy 294.453608 -286.127538) (xy 294.418115 -286.16163) (xy 294.377612 -286.189586) (xy 294.33315 -286.210684)
			(xy 294.285879 -286.224376) (xy 294.237024 -286.230308) (xy 294.187849 -286.228327) (xy 294.13963 -286.218483)
			(xy 294.093614 -286.201031) (xy 294.050993 -286.176424) (xy 294.012872 -286.145299) (xy 293.980237 -286.108462)
			(xy 293.953934 -286.066866) (xy 293.934643 -286.02159) (xy 293.922866 -285.973806) (xy 293.918906 -285.924752)
			(xy 293.580058 -285.924752) (xy 293.579563 -285.949359) (xy 293.571668 -285.997936) (xy 293.556084 -286.044617)
			(xy 293.533213 -286.088194) (xy 293.503648 -286.127538) (xy 293.468155 -286.16163) (xy 293.427652 -286.189586)
			(xy 293.38319 -286.210684) (xy 293.335919 -286.224376) (xy 293.287064 -286.230308) (xy 293.237889 -286.228327)
			(xy 293.18967 -286.218483) (xy 293.143654 -286.201031) (xy 293.101033 -286.176424) (xy 293.062912 -286.145299)
			(xy 293.030277 -286.108462) (xy 293.003974 -286.066866) (xy 292.984683 -286.02159) (xy 292.972906 -285.973806)
			(xy 292.968946 -285.924752) (xy 292.630098 -285.924752) (xy 292.629603 -285.949359) (xy 292.621708 -285.997936)
			(xy 292.606124 -286.044617) (xy 292.583253 -286.088194) (xy 292.553688 -286.127538) (xy 292.518195 -286.16163)
			(xy 292.477692 -286.189586) (xy 292.43323 -286.210684) (xy 292.385959 -286.224376) (xy 292.337104 -286.230308)
			(xy 292.287929 -286.228327) (xy 292.23971 -286.218483) (xy 292.193694 -286.201031) (xy 292.151073 -286.176424)
			(xy 292.112952 -286.145299) (xy 292.080317 -286.108462) (xy 292.054014 -286.066866) (xy 292.034723 -286.02159)
			(xy 292.022946 -285.973806) (xy 292.018986 -285.924752) (xy 290.730178 -285.924752) (xy 290.729683 -285.949359)
			(xy 290.721788 -285.997936) (xy 290.706204 -286.044617) (xy 290.683333 -286.088194) (xy 290.653768 -286.127538)
			(xy 290.618275 -286.16163) (xy 290.577772 -286.189586) (xy 290.53331 -286.210684) (xy 290.486039 -286.224376)
			(xy 290.437184 -286.230308) (xy 290.388009 -286.228327) (xy 290.33979 -286.218483) (xy 290.293774 -286.201031)
			(xy 290.251153 -286.176424) (xy 290.213032 -286.145299) (xy 290.180397 -286.108462) (xy 290.154094 -286.066866)
			(xy 290.134803 -286.02159) (xy 290.123026 -285.973806) (xy 290.119066 -285.924752) (xy 289.780218 -285.924752)
			(xy 289.779723 -285.949359) (xy 289.771828 -285.997936) (xy 289.756244 -286.044617) (xy 289.733373 -286.088194)
			(xy 289.703808 -286.127538) (xy 289.668315 -286.16163) (xy 289.627812 -286.189586) (xy 289.58335 -286.210684)
			(xy 289.536079 -286.224376) (xy 289.487224 -286.230308) (xy 289.438049 -286.228327) (xy 289.38983 -286.218483)
			(xy 289.343814 -286.201031) (xy 289.301193 -286.176424) (xy 289.263072 -286.145299) (xy 289.230437 -286.108462)
			(xy 289.204134 -286.066866) (xy 289.184843 -286.02159) (xy 289.173066 -285.973806) (xy 289.169106 -285.924752)
			(xy 288.830004 -285.924752) (xy 288.829509 -285.949359) (xy 288.821614 -285.997936) (xy 288.80603 -286.044617)
			(xy 288.783159 -286.088194) (xy 288.753594 -286.127538) (xy 288.718101 -286.16163) (xy 288.677598 -286.189586)
			(xy 288.633136 -286.210684) (xy 288.585865 -286.224376) (xy 288.53701 -286.230308) (xy 288.487835 -286.228327)
			(xy 288.439616 -286.218483) (xy 288.3936 -286.201031) (xy 288.350979 -286.176424) (xy 288.312858 -286.145299)
			(xy 288.280223 -286.108462) (xy 288.25392 -286.066866) (xy 288.234629 -286.02159) (xy 288.222852 -285.973806)
			(xy 288.218892 -285.924752) (xy 287.880044 -285.924752) (xy 287.879549 -285.949359) (xy 287.871654 -285.997936)
			(xy 287.85607 -286.044617) (xy 287.833199 -286.088194) (xy 287.803634 -286.127538) (xy 287.768141 -286.16163)
			(xy 287.727638 -286.189586) (xy 287.683176 -286.210684) (xy 287.635905 -286.224376) (xy 287.58705 -286.230308)
			(xy 287.537875 -286.228327) (xy 287.489656 -286.218483) (xy 287.44364 -286.201031) (xy 287.401019 -286.176424)
			(xy 287.362898 -286.145299) (xy 287.330263 -286.108462) (xy 287.30396 -286.066866) (xy 287.284669 -286.02159)
			(xy 287.272892 -285.973806) (xy 287.268932 -285.924752) (xy 286.930084 -285.924752) (xy 286.929589 -285.949359)
			(xy 286.921694 -285.997936) (xy 286.90611 -286.044617) (xy 286.883239 -286.088194) (xy 286.853674 -286.127538)
			(xy 286.818181 -286.16163) (xy 286.777678 -286.189586) (xy 286.733216 -286.210684) (xy 286.685945 -286.224376)
			(xy 286.63709 -286.230308) (xy 286.587915 -286.228327) (xy 286.539696 -286.218483) (xy 286.49368 -286.201031)
			(xy 286.451059 -286.176424) (xy 286.412938 -286.145299) (xy 286.380303 -286.108462) (xy 286.354 -286.066866)
			(xy 286.334709 -286.02159) (xy 286.322932 -285.973806) (xy 286.318972 -285.924752) (xy 285.980124 -285.924752)
			(xy 285.979629 -285.949359) (xy 285.971734 -285.997936) (xy 285.95615 -286.044617) (xy 285.933279 -286.088194)
			(xy 285.903714 -286.127538) (xy 285.868221 -286.16163) (xy 285.827718 -286.189586) (xy 285.783256 -286.210684)
			(xy 285.735985 -286.224376) (xy 285.68713 -286.230308) (xy 285.637955 -286.228327) (xy 285.589736 -286.218483)
			(xy 285.54372 -286.201031) (xy 285.501099 -286.176424) (xy 285.462978 -286.145299) (xy 285.430343 -286.108462)
			(xy 285.40404 -286.066866) (xy 285.384749 -286.02159) (xy 285.372972 -285.973806) (xy 285.369012 -285.924752)
			(xy 285.030164 -285.924752) (xy 285.029669 -285.949359) (xy 285.021774 -285.997936) (xy 285.00619 -286.044617)
			(xy 284.983319 -286.088194) (xy 284.953754 -286.127538) (xy 284.918261 -286.16163) (xy 284.877758 -286.189586)
			(xy 284.833296 -286.210684) (xy 284.786025 -286.224376) (xy 284.73717 -286.230308) (xy 284.687995 -286.228327)
			(xy 284.639776 -286.218483) (xy 284.59376 -286.201031) (xy 284.551139 -286.176424) (xy 284.513018 -286.145299)
			(xy 284.480383 -286.108462) (xy 284.45408 -286.066866) (xy 284.434789 -286.02159) (xy 284.423012 -285.973806)
			(xy 284.419052 -285.924752) (xy 284.080204 -285.924752) (xy 284.079709 -285.949359) (xy 284.071814 -285.997936)
			(xy 284.05623 -286.044617) (xy 284.033359 -286.088194) (xy 284.003794 -286.127538) (xy 283.968301 -286.16163)
			(xy 283.927798 -286.189586) (xy 283.883336 -286.210684) (xy 283.836065 -286.224376) (xy 283.78721 -286.230308)
			(xy 283.738035 -286.228327) (xy 283.689816 -286.218483) (xy 283.6438 -286.201031) (xy 283.601179 -286.176424)
			(xy 283.563058 -286.145299) (xy 283.530423 -286.108462) (xy 283.50412 -286.066866) (xy 283.484829 -286.02159)
			(xy 283.473052 -285.973806) (xy 283.469092 -285.924752) (xy 283.130244 -285.924752) (xy 283.129749 -285.949359)
			(xy 283.121854 -285.997936) (xy 283.10627 -286.044617) (xy 283.083399 -286.088194) (xy 283.053834 -286.127538)
			(xy 283.018341 -286.16163) (xy 282.977838 -286.189586) (xy 282.933376 -286.210684) (xy 282.886105 -286.224376)
			(xy 282.83725 -286.230308) (xy 282.788075 -286.228327) (xy 282.739856 -286.218483) (xy 282.69384 -286.201031)
			(xy 282.651219 -286.176424) (xy 282.613098 -286.145299) (xy 282.580463 -286.108462) (xy 282.55416 -286.066866)
			(xy 282.534869 -286.02159) (xy 282.523092 -285.973806) (xy 282.519132 -285.924752) (xy 282.18003 -285.924752)
			(xy 282.179535 -285.949359) (xy 282.17164 -285.997936) (xy 282.156056 -286.044617) (xy 282.133185 -286.088194)
			(xy 282.10362 -286.127538) (xy 282.068127 -286.16163) (xy 282.027624 -286.189586) (xy 281.983162 -286.210684)
			(xy 281.935891 -286.224376) (xy 281.887036 -286.230308) (xy 281.837861 -286.228327) (xy 281.789642 -286.218483)
			(xy 281.743626 -286.201031) (xy 281.701005 -286.176424) (xy 281.662884 -286.145299) (xy 281.630249 -286.108462)
			(xy 281.603946 -286.066866) (xy 281.584655 -286.02159) (xy 281.572878 -285.973806) (xy 281.568918 -285.924752)
			(xy 281.23007 -285.924752) (xy 281.229575 -285.949359) (xy 281.22168 -285.997936) (xy 281.206096 -286.044617)
			(xy 281.183225 -286.088194) (xy 281.15366 -286.127538) (xy 281.118167 -286.16163) (xy 281.077664 -286.189586)
			(xy 281.033202 -286.210684) (xy 280.985931 -286.224376) (xy 280.937076 -286.230308) (xy 280.887901 -286.228327)
			(xy 280.839682 -286.218483) (xy 280.793666 -286.201031) (xy 280.751045 -286.176424) (xy 280.712924 -286.145299)
			(xy 280.680289 -286.108462) (xy 280.653986 -286.066866) (xy 280.634695 -286.02159) (xy 280.622918 -285.973806)
			(xy 280.618958 -285.924752) (xy 280.28011 -285.924752) (xy 280.279615 -285.949359) (xy 280.27172 -285.997936)
			(xy 280.256136 -286.044617) (xy 280.233265 -286.088194) (xy 280.2037 -286.127538) (xy 280.168207 -286.16163)
			(xy 280.127704 -286.189586) (xy 280.083242 -286.210684) (xy 280.035971 -286.224376) (xy 279.987116 -286.230308)
			(xy 279.937941 -286.228327) (xy 279.889722 -286.218483) (xy 279.843706 -286.201031) (xy 279.801085 -286.176424)
			(xy 279.762964 -286.145299) (xy 279.730329 -286.108462) (xy 279.704026 -286.066866) (xy 279.684735 -286.02159)
			(xy 279.672958 -285.973806) (xy 279.668998 -285.924752) (xy 279.33015 -285.924752) (xy 279.329655 -285.949359)
			(xy 279.32176 -285.997936) (xy 279.306176 -286.044617) (xy 279.283305 -286.088194) (xy 279.25374 -286.127538)
			(xy 279.218247 -286.16163) (xy 279.177744 -286.189586) (xy 279.133282 -286.210684) (xy 279.086011 -286.224376)
			(xy 279.037156 -286.230308) (xy 278.987981 -286.228327) (xy 278.939762 -286.218483) (xy 278.893746 -286.201031)
			(xy 278.851125 -286.176424) (xy 278.813004 -286.145299) (xy 278.780369 -286.108462) (xy 278.754066 -286.066866)
			(xy 278.734775 -286.02159) (xy 278.722998 -285.973806) (xy 278.719038 -285.924752) (xy 278.38019 -285.924752)
			(xy 278.379695 -285.949359) (xy 278.3718 -285.997936) (xy 278.356216 -286.044617) (xy 278.333345 -286.088194)
			(xy 278.30378 -286.127538) (xy 278.268287 -286.16163) (xy 278.227784 -286.189586) (xy 278.183322 -286.210684)
			(xy 278.136051 -286.224376) (xy 278.087196 -286.230308) (xy 278.038021 -286.228327) (xy 277.989802 -286.218483)
			(xy 277.943786 -286.201031) (xy 277.901165 -286.176424) (xy 277.863044 -286.145299) (xy 277.830409 -286.108462)
			(xy 277.804106 -286.066866) (xy 277.784815 -286.02159) (xy 277.773038 -285.973806) (xy 277.769078 -285.924752)
			(xy 277.43023 -285.924752) (xy 277.429735 -285.949359) (xy 277.42184 -285.997936) (xy 277.406256 -286.044617)
			(xy 277.383385 -286.088194) (xy 277.35382 -286.127538) (xy 277.318327 -286.16163) (xy 277.277824 -286.189586)
			(xy 277.233362 -286.210684) (xy 277.186091 -286.224376) (xy 277.137236 -286.230308) (xy 277.088061 -286.228327)
			(xy 277.039842 -286.218483) (xy 276.993826 -286.201031) (xy 276.951205 -286.176424) (xy 276.913084 -286.145299)
			(xy 276.880449 -286.108462) (xy 276.854146 -286.066866) (xy 276.834855 -286.02159) (xy 276.823078 -285.973806)
			(xy 276.819118 -285.924752) (xy 273.630136 -285.924752) (xy 273.629641 -285.949359) (xy 273.621746 -285.997936)
			(xy 273.606162 -286.044617) (xy 273.583291 -286.088194) (xy 273.553726 -286.127538) (xy 273.518233 -286.16163)
			(xy 273.47773 -286.189586) (xy 273.433268 -286.210684) (xy 273.385997 -286.224376) (xy 273.337142 -286.230308)
			(xy 273.287967 -286.228327) (xy 273.239748 -286.218483) (xy 273.193732 -286.201031) (xy 273.151111 -286.176424)
			(xy 273.11299 -286.145299) (xy 273.080355 -286.108462) (xy 273.054052 -286.066866) (xy 273.034761 -286.02159)
			(xy 273.022984 -285.973806) (xy 273.019024 -285.924752) (xy 272.680176 -285.924752) (xy 272.679681 -285.949359)
			(xy 272.671786 -285.997936) (xy 272.656202 -286.044617) (xy 272.633331 -286.088194) (xy 272.603766 -286.127538)
			(xy 272.568273 -286.16163) (xy 272.52777 -286.189586) (xy 272.483308 -286.210684) (xy 272.436037 -286.224376)
			(xy 272.387182 -286.230308) (xy 272.338007 -286.228327) (xy 272.289788 -286.218483) (xy 272.243772 -286.201031)
			(xy 272.201151 -286.176424) (xy 272.16303 -286.145299) (xy 272.130395 -286.108462) (xy 272.104092 -286.066866)
			(xy 272.084801 -286.02159) (xy 272.073024 -285.973806) (xy 272.069064 -285.924752) (xy 271.730216 -285.924752)
			(xy 271.729721 -285.949359) (xy 271.721826 -285.997936) (xy 271.706242 -286.044617) (xy 271.683371 -286.088194)
			(xy 271.653806 -286.127538) (xy 271.618313 -286.16163) (xy 271.57781 -286.189586) (xy 271.533348 -286.210684)
			(xy 271.486077 -286.224376) (xy 271.437222 -286.230308) (xy 271.388047 -286.228327) (xy 271.339828 -286.218483)
			(xy 271.293812 -286.201031) (xy 271.251191 -286.176424) (xy 271.21307 -286.145299) (xy 271.180435 -286.108462)
			(xy 271.154132 -286.066866) (xy 271.134841 -286.02159) (xy 271.123064 -285.973806) (xy 271.119104 -285.924752)
			(xy 270.780256 -285.924752) (xy 270.779761 -285.949359) (xy 270.771866 -285.997936) (xy 270.756282 -286.044617)
			(xy 270.733411 -286.088194) (xy 270.703846 -286.127538) (xy 270.668353 -286.16163) (xy 270.62785 -286.189586)
			(xy 270.583388 -286.210684) (xy 270.536117 -286.224376) (xy 270.487262 -286.230308) (xy 270.438087 -286.228327)
			(xy 270.389868 -286.218483) (xy 270.343852 -286.201031) (xy 270.301231 -286.176424) (xy 270.26311 -286.145299)
			(xy 270.230475 -286.108462) (xy 270.204172 -286.066866) (xy 270.184881 -286.02159) (xy 270.173104 -285.973806)
			(xy 270.169144 -285.924752) (xy 269.830042 -285.924752) (xy 269.829547 -285.949359) (xy 269.821652 -285.997936)
			(xy 269.806068 -286.044617) (xy 269.783197 -286.088194) (xy 269.753632 -286.127538) (xy 269.718139 -286.16163)
			(xy 269.677636 -286.189586) (xy 269.633174 -286.210684) (xy 269.585903 -286.224376) (xy 269.537048 -286.230308)
			(xy 269.487873 -286.228327) (xy 269.439654 -286.218483) (xy 269.393638 -286.201031) (xy 269.351017 -286.176424)
			(xy 269.312896 -286.145299) (xy 269.280261 -286.108462) (xy 269.253958 -286.066866) (xy 269.234667 -286.02159)
			(xy 269.22289 -285.973806) (xy 269.21893 -285.924752) (xy 268.880082 -285.924752) (xy 268.879587 -285.949359)
			(xy 268.871692 -285.997936) (xy 268.856108 -286.044617) (xy 268.833237 -286.088194) (xy 268.803672 -286.127538)
			(xy 268.768179 -286.16163) (xy 268.727676 -286.189586) (xy 268.683214 -286.210684) (xy 268.635943 -286.224376)
			(xy 268.587088 -286.230308) (xy 268.537913 -286.228327) (xy 268.489694 -286.218483) (xy 268.443678 -286.201031)
			(xy 268.401057 -286.176424) (xy 268.362936 -286.145299) (xy 268.330301 -286.108462) (xy 268.303998 -286.066866)
			(xy 268.284707 -286.02159) (xy 268.27293 -285.973806) (xy 268.26897 -285.924752) (xy 266.590526 -285.924752)
			(xy 266.590526 -286.399732) (xy 305.793914 -286.399732) (xy 305.797874 -286.350678) (xy 305.809651 -286.302894)
			(xy 305.828942 -286.257618) (xy 305.855245 -286.216022) (xy 305.88788 -286.179185) (xy 305.926001 -286.14806)
			(xy 305.968622 -286.123453) (xy 306.014638 -286.106001) (xy 306.062857 -286.096157) (xy 306.112032 -286.094176)
			(xy 306.160887 -286.100108) (xy 306.208158 -286.1138) (xy 306.25262 -286.134898) (xy 306.293123 -286.162854)
			(xy 306.328616 -286.196946) (xy 306.358181 -286.23629) (xy 306.381052 -286.279867) (xy 306.396636 -286.326548)
			(xy 306.404531 -286.375125) (xy 306.405026 -286.399732) (xy 306.744128 -286.399732) (xy 306.748088 -286.350678)
			(xy 306.759865 -286.302894) (xy 306.779156 -286.257618) (xy 306.805459 -286.216022) (xy 306.838094 -286.179185)
			(xy 306.876215 -286.14806) (xy 306.918836 -286.123453) (xy 306.964852 -286.106001) (xy 307.013071 -286.096157)
			(xy 307.062246 -286.094176) (xy 307.111101 -286.100108) (xy 307.158372 -286.1138) (xy 307.202834 -286.134898)
			(xy 307.243337 -286.162854) (xy 307.27883 -286.196946) (xy 307.308395 -286.23629) (xy 307.331266 -286.279867)
			(xy 307.34685 -286.326548) (xy 307.354745 -286.375125) (xy 307.35524 -286.399732) (xy 307.694088 -286.399732)
			(xy 307.698048 -286.350678) (xy 307.709825 -286.302894) (xy 307.729116 -286.257618) (xy 307.755419 -286.216022)
			(xy 307.788054 -286.179185) (xy 307.826175 -286.14806) (xy 307.868796 -286.123453) (xy 307.914812 -286.106001)
			(xy 307.963031 -286.096157) (xy 308.012206 -286.094176) (xy 308.061061 -286.100108) (xy 308.108332 -286.1138)
			(xy 308.152794 -286.134898) (xy 308.193297 -286.162854) (xy 308.22879 -286.196946) (xy 308.258355 -286.23629)
			(xy 308.281226 -286.279867) (xy 308.29681 -286.326548) (xy 308.304705 -286.375125) (xy 308.3052 -286.399732)
			(xy 308.304705 -286.424339) (xy 308.29681 -286.472916) (xy 308.281226 -286.519597) (xy 308.258355 -286.563174)
			(xy 308.22879 -286.602518) (xy 308.193297 -286.63661) (xy 308.152794 -286.664566) (xy 308.108332 -286.685664)
			(xy 308.061061 -286.699356) (xy 308.012206 -286.705288) (xy 307.963031 -286.703307) (xy 307.914812 -286.693463)
			(xy 307.868796 -286.676011) (xy 307.826175 -286.651404) (xy 307.788054 -286.620279) (xy 307.755419 -286.583442)
			(xy 307.729116 -286.541846) (xy 307.709825 -286.49657) (xy 307.698048 -286.448786) (xy 307.694088 -286.399732)
			(xy 307.35524 -286.399732) (xy 307.354745 -286.424339) (xy 307.34685 -286.472916) (xy 307.331266 -286.519597)
			(xy 307.308395 -286.563174) (xy 307.27883 -286.602518) (xy 307.243337 -286.63661) (xy 307.202834 -286.664566)
			(xy 307.158372 -286.685664) (xy 307.111101 -286.699356) (xy 307.062246 -286.705288) (xy 307.013071 -286.703307)
			(xy 306.964852 -286.693463) (xy 306.918836 -286.676011) (xy 306.876215 -286.651404) (xy 306.838094 -286.620279)
			(xy 306.805459 -286.583442) (xy 306.779156 -286.541846) (xy 306.759865 -286.49657) (xy 306.748088 -286.448786)
			(xy 306.744128 -286.399732) (xy 306.405026 -286.399732) (xy 306.404531 -286.424339) (xy 306.396636 -286.472916)
			(xy 306.381052 -286.519597) (xy 306.358181 -286.563174) (xy 306.328616 -286.602518) (xy 306.293123 -286.63661)
			(xy 306.25262 -286.664566) (xy 306.208158 -286.685664) (xy 306.160887 -286.699356) (xy 306.112032 -286.705288)
			(xy 306.062857 -286.703307) (xy 306.014638 -286.693463) (xy 305.968622 -286.676011) (xy 305.926001 -286.651404)
			(xy 305.88788 -286.620279) (xy 305.855245 -286.583442) (xy 305.828942 -286.541846) (xy 305.809651 -286.49657)
			(xy 305.797874 -286.448786) (xy 305.793914 -286.399732) (xy 266.590526 -286.399732) (xy 266.590526 -286.874966)
			(xy 268.26897 -286.874966) (xy 268.27293 -286.825912) (xy 268.284707 -286.778128) (xy 268.303998 -286.732852)
			(xy 268.330301 -286.691256) (xy 268.362936 -286.654419) (xy 268.401057 -286.623294) (xy 268.443678 -286.598687)
			(xy 268.489694 -286.581235) (xy 268.537913 -286.571391) (xy 268.587088 -286.56941) (xy 268.635943 -286.575342)
			(xy 268.683214 -286.589034) (xy 268.727676 -286.610132) (xy 268.768179 -286.638088) (xy 268.803672 -286.67218)
			(xy 268.833237 -286.711524) (xy 268.856108 -286.755101) (xy 268.871692 -286.801782) (xy 268.879587 -286.850359)
			(xy 268.880082 -286.874966) (xy 269.21893 -286.874966) (xy 269.22289 -286.825912) (xy 269.234667 -286.778128)
			(xy 269.253958 -286.732852) (xy 269.280261 -286.691256) (xy 269.312896 -286.654419) (xy 269.351017 -286.623294)
			(xy 269.393638 -286.598687) (xy 269.439654 -286.581235) (xy 269.487873 -286.571391) (xy 269.537048 -286.56941)
			(xy 269.585903 -286.575342) (xy 269.633174 -286.589034) (xy 269.677636 -286.610132) (xy 269.718139 -286.638088)
			(xy 269.753632 -286.67218) (xy 269.783197 -286.711524) (xy 269.806068 -286.755101) (xy 269.821652 -286.801782)
			(xy 269.829547 -286.850359) (xy 269.830042 -286.874966) (xy 270.169144 -286.874966) (xy 270.173104 -286.825912)
			(xy 270.184881 -286.778128) (xy 270.204172 -286.732852) (xy 270.230475 -286.691256) (xy 270.26311 -286.654419)
			(xy 270.301231 -286.623294) (xy 270.343852 -286.598687) (xy 270.389868 -286.581235) (xy 270.438087 -286.571391)
			(xy 270.487262 -286.56941) (xy 270.536117 -286.575342) (xy 270.583388 -286.589034) (xy 270.62785 -286.610132)
			(xy 270.668353 -286.638088) (xy 270.703846 -286.67218) (xy 270.733411 -286.711524) (xy 270.756282 -286.755101)
			(xy 270.771866 -286.801782) (xy 270.779761 -286.850359) (xy 270.780256 -286.874966) (xy 271.119104 -286.874966)
			(xy 271.123064 -286.825912) (xy 271.134841 -286.778128) (xy 271.154132 -286.732852) (xy 271.180435 -286.691256)
			(xy 271.21307 -286.654419) (xy 271.251191 -286.623294) (xy 271.293812 -286.598687) (xy 271.339828 -286.581235)
			(xy 271.388047 -286.571391) (xy 271.437222 -286.56941) (xy 271.486077 -286.575342) (xy 271.533348 -286.589034)
			(xy 271.57781 -286.610132) (xy 271.618313 -286.638088) (xy 271.653806 -286.67218) (xy 271.683371 -286.711524)
			(xy 271.706242 -286.755101) (xy 271.721826 -286.801782) (xy 271.729721 -286.850359) (xy 271.730216 -286.874966)
			(xy 272.069064 -286.874966) (xy 272.073024 -286.825912) (xy 272.084801 -286.778128) (xy 272.104092 -286.732852)
			(xy 272.130395 -286.691256) (xy 272.16303 -286.654419) (xy 272.201151 -286.623294) (xy 272.243772 -286.598687)
			(xy 272.289788 -286.581235) (xy 272.338007 -286.571391) (xy 272.387182 -286.56941) (xy 272.436037 -286.575342)
			(xy 272.483308 -286.589034) (xy 272.52777 -286.610132) (xy 272.568273 -286.638088) (xy 272.603766 -286.67218)
			(xy 272.633331 -286.711524) (xy 272.656202 -286.755101) (xy 272.671786 -286.801782) (xy 272.679681 -286.850359)
			(xy 272.680176 -286.874966) (xy 273.019024 -286.874966) (xy 273.022984 -286.825912) (xy 273.034761 -286.778128)
			(xy 273.054052 -286.732852) (xy 273.080355 -286.691256) (xy 273.11299 -286.654419) (xy 273.151111 -286.623294)
			(xy 273.193732 -286.598687) (xy 273.239748 -286.581235) (xy 273.287967 -286.571391) (xy 273.337142 -286.56941)
			(xy 273.385997 -286.575342) (xy 273.433268 -286.589034) (xy 273.47773 -286.610132) (xy 273.518233 -286.638088)
			(xy 273.553726 -286.67218) (xy 273.583291 -286.711524) (xy 273.606162 -286.755101) (xy 273.621746 -286.801782)
			(xy 273.629641 -286.850359) (xy 273.630136 -286.874966) (xy 273.968984 -286.874966) (xy 273.972944 -286.825912)
			(xy 273.984721 -286.778128) (xy 274.004012 -286.732852) (xy 274.030315 -286.691256) (xy 274.06295 -286.654419)
			(xy 274.101071 -286.623294) (xy 274.143692 -286.598687) (xy 274.189708 -286.581235) (xy 274.237927 -286.571391)
			(xy 274.287102 -286.56941) (xy 274.335957 -286.575342) (xy 274.383228 -286.589034) (xy 274.42769 -286.610132)
			(xy 274.468193 -286.638088) (xy 274.503686 -286.67218) (xy 274.533251 -286.711524) (xy 274.556122 -286.755101)
			(xy 274.571706 -286.801782) (xy 274.579601 -286.850359) (xy 274.580091 -286.874712) (xy 274.918944 -286.874712)
			(xy 274.922904 -286.825658) (xy 274.934681 -286.777874) (xy 274.953972 -286.732598) (xy 274.980275 -286.691002)
			(xy 275.01291 -286.654165) (xy 275.051031 -286.62304) (xy 275.093652 -286.598433) (xy 275.139668 -286.580981)
			(xy 275.187887 -286.571137) (xy 275.237062 -286.569156) (xy 275.285917 -286.575088) (xy 275.333188 -286.58878)
			(xy 275.37765 -286.609878) (xy 275.418153 -286.637834) (xy 275.453646 -286.671926) (xy 275.483211 -286.71127)
			(xy 275.506082 -286.754847) (xy 275.521666 -286.801528) (xy 275.529561 -286.850105) (xy 275.530056 -286.874712)
			(xy 275.868904 -286.874712) (xy 275.872864 -286.825658) (xy 275.884641 -286.777874) (xy 275.903932 -286.732598)
			(xy 275.930235 -286.691002) (xy 275.96287 -286.654165) (xy 276.000991 -286.62304) (xy 276.043612 -286.598433)
			(xy 276.089628 -286.580981) (xy 276.137847 -286.571137) (xy 276.187022 -286.569156) (xy 276.235877 -286.575088)
			(xy 276.283148 -286.58878) (xy 276.32761 -286.609878) (xy 276.368113 -286.637834) (xy 276.403606 -286.671926)
			(xy 276.433171 -286.71127) (xy 276.456042 -286.754847) (xy 276.471626 -286.801528) (xy 276.479521 -286.850105)
			(xy 276.480016 -286.874712) (xy 276.480011 -286.874966) (xy 276.819118 -286.874966) (xy 276.823078 -286.825912)
			(xy 276.834855 -286.778128) (xy 276.854146 -286.732852) (xy 276.880449 -286.691256) (xy 276.913084 -286.654419)
			(xy 276.951205 -286.623294) (xy 276.993826 -286.598687) (xy 277.039842 -286.581235) (xy 277.088061 -286.571391)
			(xy 277.137236 -286.56941) (xy 277.186091 -286.575342) (xy 277.233362 -286.589034) (xy 277.277824 -286.610132)
			(xy 277.318327 -286.638088) (xy 277.35382 -286.67218) (xy 277.383385 -286.711524) (xy 277.406256 -286.755101)
			(xy 277.42184 -286.801782) (xy 277.429735 -286.850359) (xy 277.43023 -286.874966) (xy 277.769078 -286.874966)
			(xy 277.773038 -286.825912) (xy 277.784815 -286.778128) (xy 277.804106 -286.732852) (xy 277.830409 -286.691256)
			(xy 277.863044 -286.654419) (xy 277.901165 -286.623294) (xy 277.943786 -286.598687) (xy 277.989802 -286.581235)
			(xy 278.038021 -286.571391) (xy 278.087196 -286.56941) (xy 278.136051 -286.575342) (xy 278.183322 -286.589034)
			(xy 278.227784 -286.610132) (xy 278.268287 -286.638088) (xy 278.30378 -286.67218) (xy 278.333345 -286.711524)
			(xy 278.356216 -286.755101) (xy 278.3718 -286.801782) (xy 278.379695 -286.850359) (xy 278.38019 -286.874966)
			(xy 278.719038 -286.874966) (xy 278.722998 -286.825912) (xy 278.734775 -286.778128) (xy 278.754066 -286.732852)
			(xy 278.780369 -286.691256) (xy 278.813004 -286.654419) (xy 278.851125 -286.623294) (xy 278.893746 -286.598687)
			(xy 278.939762 -286.581235) (xy 278.987981 -286.571391) (xy 279.037156 -286.56941) (xy 279.086011 -286.575342)
			(xy 279.133282 -286.589034) (xy 279.177744 -286.610132) (xy 279.218247 -286.638088) (xy 279.25374 -286.67218)
			(xy 279.283305 -286.711524) (xy 279.306176 -286.755101) (xy 279.32176 -286.801782) (xy 279.329655 -286.850359)
			(xy 279.33015 -286.874966) (xy 279.668998 -286.874966) (xy 279.672958 -286.825912) (xy 279.684735 -286.778128)
			(xy 279.704026 -286.732852) (xy 279.730329 -286.691256) (xy 279.762964 -286.654419) (xy 279.801085 -286.623294)
			(xy 279.843706 -286.598687) (xy 279.889722 -286.581235) (xy 279.937941 -286.571391) (xy 279.987116 -286.56941)
			(xy 280.035971 -286.575342) (xy 280.083242 -286.589034) (xy 280.127704 -286.610132) (xy 280.168207 -286.638088)
			(xy 280.2037 -286.67218) (xy 280.233265 -286.711524) (xy 280.256136 -286.755101) (xy 280.27172 -286.801782)
			(xy 280.279615 -286.850359) (xy 280.28011 -286.874966) (xy 280.618958 -286.874966) (xy 280.622918 -286.825912)
			(xy 280.634695 -286.778128) (xy 280.653986 -286.732852) (xy 280.680289 -286.691256) (xy 280.712924 -286.654419)
			(xy 280.751045 -286.623294) (xy 280.793666 -286.598687) (xy 280.839682 -286.581235) (xy 280.887901 -286.571391)
			(xy 280.937076 -286.56941) (xy 280.985931 -286.575342) (xy 281.033202 -286.589034) (xy 281.077664 -286.610132)
			(xy 281.118167 -286.638088) (xy 281.15366 -286.67218) (xy 281.183225 -286.711524) (xy 281.206096 -286.755101)
			(xy 281.22168 -286.801782) (xy 281.229575 -286.850359) (xy 281.23007 -286.874966) (xy 281.568918 -286.874966)
			(xy 281.572878 -286.825912) (xy 281.584655 -286.778128) (xy 281.603946 -286.732852) (xy 281.630249 -286.691256)
			(xy 281.662884 -286.654419) (xy 281.701005 -286.623294) (xy 281.743626 -286.598687) (xy 281.789642 -286.581235)
			(xy 281.837861 -286.571391) (xy 281.887036 -286.56941) (xy 281.935891 -286.575342) (xy 281.983162 -286.589034)
			(xy 282.027624 -286.610132) (xy 282.068127 -286.638088) (xy 282.10362 -286.67218) (xy 282.133185 -286.711524)
			(xy 282.156056 -286.755101) (xy 282.17164 -286.801782) (xy 282.179535 -286.850359) (xy 282.18003 -286.874966)
			(xy 282.519132 -286.874966) (xy 282.523092 -286.825912) (xy 282.534869 -286.778128) (xy 282.55416 -286.732852)
			(xy 282.580463 -286.691256) (xy 282.613098 -286.654419) (xy 282.651219 -286.623294) (xy 282.69384 -286.598687)
			(xy 282.739856 -286.581235) (xy 282.788075 -286.571391) (xy 282.83725 -286.56941) (xy 282.886105 -286.575342)
			(xy 282.933376 -286.589034) (xy 282.977838 -286.610132) (xy 283.018341 -286.638088) (xy 283.053834 -286.67218)
			(xy 283.083399 -286.711524) (xy 283.10627 -286.755101) (xy 283.121854 -286.801782) (xy 283.129749 -286.850359)
			(xy 283.130244 -286.874966) (xy 283.469092 -286.874966) (xy 283.473052 -286.825912) (xy 283.484829 -286.778128)
			(xy 283.50412 -286.732852) (xy 283.530423 -286.691256) (xy 283.563058 -286.654419) (xy 283.601179 -286.623294)
			(xy 283.6438 -286.598687) (xy 283.689816 -286.581235) (xy 283.738035 -286.571391) (xy 283.78721 -286.56941)
			(xy 283.836065 -286.575342) (xy 283.883336 -286.589034) (xy 283.927798 -286.610132) (xy 283.968301 -286.638088)
			(xy 284.003794 -286.67218) (xy 284.033359 -286.711524) (xy 284.05623 -286.755101) (xy 284.071814 -286.801782)
			(xy 284.079709 -286.850359) (xy 284.080204 -286.874966) (xy 284.419052 -286.874966) (xy 284.423012 -286.825912)
			(xy 284.434789 -286.778128) (xy 284.45408 -286.732852) (xy 284.480383 -286.691256) (xy 284.513018 -286.654419)
			(xy 284.551139 -286.623294) (xy 284.59376 -286.598687) (xy 284.639776 -286.581235) (xy 284.687995 -286.571391)
			(xy 284.73717 -286.56941) (xy 284.786025 -286.575342) (xy 284.833296 -286.589034) (xy 284.877758 -286.610132)
			(xy 284.918261 -286.638088) (xy 284.953754 -286.67218) (xy 284.983319 -286.711524) (xy 285.00619 -286.755101)
			(xy 285.021774 -286.801782) (xy 285.029669 -286.850359) (xy 285.030164 -286.874966) (xy 285.369012 -286.874966)
			(xy 285.372972 -286.825912) (xy 285.384749 -286.778128) (xy 285.40404 -286.732852) (xy 285.430343 -286.691256)
			(xy 285.462978 -286.654419) (xy 285.501099 -286.623294) (xy 285.54372 -286.598687) (xy 285.589736 -286.581235)
			(xy 285.637955 -286.571391) (xy 285.68713 -286.56941) (xy 285.735985 -286.575342) (xy 285.783256 -286.589034)
			(xy 285.827718 -286.610132) (xy 285.868221 -286.638088) (xy 285.903714 -286.67218) (xy 285.933279 -286.711524)
			(xy 285.95615 -286.755101) (xy 285.971734 -286.801782) (xy 285.979629 -286.850359) (xy 285.980124 -286.874966)
			(xy 286.318972 -286.874966) (xy 286.322932 -286.825912) (xy 286.334709 -286.778128) (xy 286.354 -286.732852)
			(xy 286.380303 -286.691256) (xy 286.412938 -286.654419) (xy 286.451059 -286.623294) (xy 286.49368 -286.598687)
			(xy 286.539696 -286.581235) (xy 286.587915 -286.571391) (xy 286.63709 -286.56941) (xy 286.685945 -286.575342)
			(xy 286.733216 -286.589034) (xy 286.777678 -286.610132) (xy 286.818181 -286.638088) (xy 286.853674 -286.67218)
			(xy 286.883239 -286.711524) (xy 286.90611 -286.755101) (xy 286.921694 -286.801782) (xy 286.929589 -286.850359)
			(xy 286.930084 -286.874966) (xy 287.268932 -286.874966) (xy 287.272892 -286.825912) (xy 287.284669 -286.778128)
			(xy 287.30396 -286.732852) (xy 287.330263 -286.691256) (xy 287.362898 -286.654419) (xy 287.401019 -286.623294)
			(xy 287.44364 -286.598687) (xy 287.489656 -286.581235) (xy 287.537875 -286.571391) (xy 287.58705 -286.56941)
			(xy 287.635905 -286.575342) (xy 287.683176 -286.589034) (xy 287.727638 -286.610132) (xy 287.768141 -286.638088)
			(xy 287.803634 -286.67218) (xy 287.833199 -286.711524) (xy 287.85607 -286.755101) (xy 287.871654 -286.801782)
			(xy 287.879549 -286.850359) (xy 287.880044 -286.874966) (xy 288.218892 -286.874966) (xy 288.222852 -286.825912)
			(xy 288.234629 -286.778128) (xy 288.25392 -286.732852) (xy 288.280223 -286.691256) (xy 288.312858 -286.654419)
			(xy 288.350979 -286.623294) (xy 288.3936 -286.598687) (xy 288.439616 -286.581235) (xy 288.487835 -286.571391)
			(xy 288.53701 -286.56941) (xy 288.585865 -286.575342) (xy 288.633136 -286.589034) (xy 288.677598 -286.610132)
			(xy 288.718101 -286.638088) (xy 288.753594 -286.67218) (xy 288.783159 -286.711524) (xy 288.80603 -286.755101)
			(xy 288.821614 -286.801782) (xy 288.829509 -286.850359) (xy 288.830004 -286.874966) (xy 289.169106 -286.874966)
			(xy 289.173066 -286.825912) (xy 289.184843 -286.778128) (xy 289.204134 -286.732852) (xy 289.230437 -286.691256)
			(xy 289.263072 -286.654419) (xy 289.301193 -286.623294) (xy 289.343814 -286.598687) (xy 289.38983 -286.581235)
			(xy 289.438049 -286.571391) (xy 289.487224 -286.56941) (xy 289.536079 -286.575342) (xy 289.58335 -286.589034)
			(xy 289.627812 -286.610132) (xy 289.668315 -286.638088) (xy 289.703808 -286.67218) (xy 289.733373 -286.711524)
			(xy 289.756244 -286.755101) (xy 289.771828 -286.801782) (xy 289.779723 -286.850359) (xy 289.780218 -286.874966)
			(xy 290.119066 -286.874966) (xy 290.123026 -286.825912) (xy 290.134803 -286.778128) (xy 290.154094 -286.732852)
			(xy 290.180397 -286.691256) (xy 290.213032 -286.654419) (xy 290.251153 -286.623294) (xy 290.293774 -286.598687)
			(xy 290.33979 -286.581235) (xy 290.388009 -286.571391) (xy 290.437184 -286.56941) (xy 290.486039 -286.575342)
			(xy 290.53331 -286.589034) (xy 290.577772 -286.610132) (xy 290.618275 -286.638088) (xy 290.653768 -286.67218)
			(xy 290.683333 -286.711524) (xy 290.706204 -286.755101) (xy 290.721788 -286.801782) (xy 290.729683 -286.850359)
			(xy 290.730178 -286.874966) (xy 292.018986 -286.874966) (xy 292.022946 -286.825912) (xy 292.034723 -286.778128)
			(xy 292.054014 -286.732852) (xy 292.080317 -286.691256) (xy 292.112952 -286.654419) (xy 292.151073 -286.623294)
			(xy 292.193694 -286.598687) (xy 292.23971 -286.581235) (xy 292.287929 -286.571391) (xy 292.337104 -286.56941)
			(xy 292.385959 -286.575342) (xy 292.43323 -286.589034) (xy 292.477692 -286.610132) (xy 292.518195 -286.638088)
			(xy 292.553688 -286.67218) (xy 292.583253 -286.711524) (xy 292.606124 -286.755101) (xy 292.621708 -286.801782)
			(xy 292.629603 -286.850359) (xy 292.630098 -286.874966) (xy 292.968946 -286.874966) (xy 292.972906 -286.825912)
			(xy 292.984683 -286.778128) (xy 293.003974 -286.732852) (xy 293.030277 -286.691256) (xy 293.062912 -286.654419)
			(xy 293.101033 -286.623294) (xy 293.143654 -286.598687) (xy 293.18967 -286.581235) (xy 293.237889 -286.571391)
			(xy 293.287064 -286.56941) (xy 293.335919 -286.575342) (xy 293.38319 -286.589034) (xy 293.427652 -286.610132)
			(xy 293.468155 -286.638088) (xy 293.503648 -286.67218) (xy 293.533213 -286.711524) (xy 293.556084 -286.755101)
			(xy 293.571668 -286.801782) (xy 293.579563 -286.850359) (xy 293.580058 -286.874966) (xy 293.918906 -286.874966)
			(xy 293.922866 -286.825912) (xy 293.934643 -286.778128) (xy 293.953934 -286.732852) (xy 293.980237 -286.691256)
			(xy 294.012872 -286.654419) (xy 294.050993 -286.623294) (xy 294.093614 -286.598687) (xy 294.13963 -286.581235)
			(xy 294.187849 -286.571391) (xy 294.237024 -286.56941) (xy 294.285879 -286.575342) (xy 294.33315 -286.589034)
			(xy 294.377612 -286.610132) (xy 294.418115 -286.638088) (xy 294.453608 -286.67218) (xy 294.483173 -286.711524)
			(xy 294.506044 -286.755101) (xy 294.521628 -286.801782) (xy 294.529523 -286.850359) (xy 294.530018 -286.874966)
			(xy 294.86912 -286.874966) (xy 294.87308 -286.825912) (xy 294.884857 -286.778128) (xy 294.904148 -286.732852)
			(xy 294.930451 -286.691256) (xy 294.963086 -286.654419) (xy 295.001207 -286.623294) (xy 295.043828 -286.598687)
			(xy 295.089844 -286.581235) (xy 295.138063 -286.571391) (xy 295.187238 -286.56941) (xy 295.236093 -286.575342)
			(xy 295.283364 -286.589034) (xy 295.327826 -286.610132) (xy 295.368329 -286.638088) (xy 295.403822 -286.67218)
			(xy 295.433387 -286.711524) (xy 295.456258 -286.755101) (xy 295.471842 -286.801782) (xy 295.479737 -286.850359)
			(xy 295.480232 -286.874966) (xy 295.81908 -286.874966) (xy 295.82304 -286.825912) (xy 295.834817 -286.778128)
			(xy 295.854108 -286.732852) (xy 295.880411 -286.691256) (xy 295.913046 -286.654419) (xy 295.951167 -286.623294)
			(xy 295.993788 -286.598687) (xy 296.039804 -286.581235) (xy 296.088023 -286.571391) (xy 296.137198 -286.56941)
			(xy 296.186053 -286.575342) (xy 296.233324 -286.589034) (xy 296.277786 -286.610132) (xy 296.318289 -286.638088)
			(xy 296.353782 -286.67218) (xy 296.383347 -286.711524) (xy 296.406218 -286.755101) (xy 296.421802 -286.801782)
			(xy 296.429697 -286.850359) (xy 296.430192 -286.874966) (xy 296.76904 -286.874966) (xy 296.773 -286.825912)
			(xy 296.784777 -286.778128) (xy 296.804068 -286.732852) (xy 296.830371 -286.691256) (xy 296.863006 -286.654419)
			(xy 296.901127 -286.623294) (xy 296.943748 -286.598687) (xy 296.989764 -286.581235) (xy 297.037983 -286.571391)
			(xy 297.087158 -286.56941) (xy 297.136013 -286.575342) (xy 297.183284 -286.589034) (xy 297.227746 -286.610132)
			(xy 297.268249 -286.638088) (xy 297.303742 -286.67218) (xy 297.333307 -286.711524) (xy 297.356178 -286.755101)
			(xy 297.371762 -286.801782) (xy 297.379657 -286.850359) (xy 297.380152 -286.874966) (xy 297.719 -286.874966)
			(xy 297.72296 -286.825912) (xy 297.734737 -286.778128) (xy 297.754028 -286.732852) (xy 297.780331 -286.691256)
			(xy 297.812966 -286.654419) (xy 297.851087 -286.623294) (xy 297.893708 -286.598687) (xy 297.939724 -286.581235)
			(xy 297.987943 -286.571391) (xy 298.037118 -286.56941) (xy 298.085973 -286.575342) (xy 298.133244 -286.589034)
			(xy 298.177706 -286.610132) (xy 298.218209 -286.638088) (xy 298.253702 -286.67218) (xy 298.283267 -286.711524)
			(xy 298.306138 -286.755101) (xy 298.321722 -286.801782) (xy 298.329617 -286.850359) (xy 298.330112 -286.874966)
			(xy 298.66896 -286.874966) (xy 298.67292 -286.825912) (xy 298.684697 -286.778128) (xy 298.703988 -286.732852)
			(xy 298.730291 -286.691256) (xy 298.762926 -286.654419) (xy 298.801047 -286.623294) (xy 298.843668 -286.598687)
			(xy 298.889684 -286.581235) (xy 298.937903 -286.571391) (xy 298.987078 -286.56941) (xy 299.035933 -286.575342)
			(xy 299.083204 -286.589034) (xy 299.127666 -286.610132) (xy 299.168169 -286.638088) (xy 299.203662 -286.67218)
			(xy 299.233227 -286.711524) (xy 299.256098 -286.755101) (xy 299.271682 -286.801782) (xy 299.279577 -286.850359)
			(xy 299.280072 -286.874966) (xy 299.61892 -286.874966) (xy 299.62288 -286.825912) (xy 299.634657 -286.778128)
			(xy 299.653948 -286.732852) (xy 299.680251 -286.691256) (xy 299.712886 -286.654419) (xy 299.751007 -286.623294)
			(xy 299.793628 -286.598687) (xy 299.839644 -286.581235) (xy 299.887863 -286.571391) (xy 299.937038 -286.56941)
			(xy 299.985893 -286.575342) (xy 300.033164 -286.589034) (xy 300.077626 -286.610132) (xy 300.118129 -286.638088)
			(xy 300.153622 -286.67218) (xy 300.183187 -286.711524) (xy 300.206058 -286.755101) (xy 300.221642 -286.801782)
			(xy 300.229537 -286.850359) (xy 300.230032 -286.874966) (xy 300.56888 -286.874966) (xy 300.57284 -286.825912)
			(xy 300.584617 -286.778128) (xy 300.603908 -286.732852) (xy 300.630211 -286.691256) (xy 300.662846 -286.654419)
			(xy 300.700967 -286.623294) (xy 300.743588 -286.598687) (xy 300.789604 -286.581235) (xy 300.837823 -286.571391)
			(xy 300.886998 -286.56941) (xy 300.935853 -286.575342) (xy 300.983124 -286.589034) (xy 301.027586 -286.610132)
			(xy 301.068089 -286.638088) (xy 301.103582 -286.67218) (xy 301.133147 -286.711524) (xy 301.156018 -286.755101)
			(xy 301.171602 -286.801782) (xy 301.179497 -286.850359) (xy 301.179992 -286.874966) (xy 302.469054 -286.874966)
			(xy 302.473014 -286.825912) (xy 302.484791 -286.778128) (xy 302.504082 -286.732852) (xy 302.530385 -286.691256)
			(xy 302.56302 -286.654419) (xy 302.601141 -286.623294) (xy 302.643762 -286.598687) (xy 302.689778 -286.581235)
			(xy 302.737997 -286.571391) (xy 302.787172 -286.56941) (xy 302.836027 -286.575342) (xy 302.883298 -286.589034)
			(xy 302.92776 -286.610132) (xy 302.968263 -286.638088) (xy 303.003756 -286.67218) (xy 303.033321 -286.711524)
			(xy 303.056192 -286.755101) (xy 303.071776 -286.801782) (xy 303.079671 -286.850359) (xy 303.080166 -286.874966)
			(xy 303.079671 -286.899573) (xy 303.071776 -286.94815) (xy 303.056192 -286.994831) (xy 303.033321 -287.038408)
			(xy 303.003756 -287.077752) (xy 302.968263 -287.111844) (xy 302.92776 -287.1398) (xy 302.883298 -287.160898)
			(xy 302.836027 -287.17459) (xy 302.787172 -287.180522) (xy 302.737997 -287.178541) (xy 302.689778 -287.168697)
			(xy 302.643762 -287.151245) (xy 302.601141 -287.126638) (xy 302.56302 -287.095513) (xy 302.530385 -287.058676)
			(xy 302.504082 -287.01708) (xy 302.484791 -286.971804) (xy 302.473014 -286.92402) (xy 302.469054 -286.874966)
			(xy 301.179992 -286.874966) (xy 301.179497 -286.899573) (xy 301.171602 -286.94815) (xy 301.156018 -286.994831)
			(xy 301.133147 -287.038408) (xy 301.103582 -287.077752) (xy 301.068089 -287.111844) (xy 301.027586 -287.1398)
			(xy 300.983124 -287.160898) (xy 300.935853 -287.17459) (xy 300.886998 -287.180522) (xy 300.837823 -287.178541)
			(xy 300.789604 -287.168697) (xy 300.743588 -287.151245) (xy 300.700967 -287.126638) (xy 300.662846 -287.095513)
			(xy 300.630211 -287.058676) (xy 300.603908 -287.01708) (xy 300.584617 -286.971804) (xy 300.57284 -286.92402)
			(xy 300.56888 -286.874966) (xy 300.230032 -286.874966) (xy 300.229537 -286.899573) (xy 300.221642 -286.94815)
			(xy 300.206058 -286.994831) (xy 300.183187 -287.038408) (xy 300.153622 -287.077752) (xy 300.118129 -287.111844)
			(xy 300.077626 -287.1398) (xy 300.033164 -287.160898) (xy 299.985893 -287.17459) (xy 299.937038 -287.180522)
			(xy 299.887863 -287.178541) (xy 299.839644 -287.168697) (xy 299.793628 -287.151245) (xy 299.751007 -287.126638)
			(xy 299.712886 -287.095513) (xy 299.680251 -287.058676) (xy 299.653948 -287.01708) (xy 299.634657 -286.971804)
			(xy 299.62288 -286.92402) (xy 299.61892 -286.874966) (xy 299.280072 -286.874966) (xy 299.279577 -286.899573)
			(xy 299.271682 -286.94815) (xy 299.256098 -286.994831) (xy 299.233227 -287.038408) (xy 299.203662 -287.077752)
			(xy 299.168169 -287.111844) (xy 299.127666 -287.1398) (xy 299.083204 -287.160898) (xy 299.035933 -287.17459)
			(xy 298.987078 -287.180522) (xy 298.937903 -287.178541) (xy 298.889684 -287.168697) (xy 298.843668 -287.151245)
			(xy 298.801047 -287.126638) (xy 298.762926 -287.095513) (xy 298.730291 -287.058676) (xy 298.703988 -287.01708)
			(xy 298.684697 -286.971804) (xy 298.67292 -286.92402) (xy 298.66896 -286.874966) (xy 298.330112 -286.874966)
			(xy 298.329617 -286.899573) (xy 298.321722 -286.94815) (xy 298.306138 -286.994831) (xy 298.283267 -287.038408)
			(xy 298.253702 -287.077752) (xy 298.218209 -287.111844) (xy 298.177706 -287.1398) (xy 298.133244 -287.160898)
			(xy 298.085973 -287.17459) (xy 298.037118 -287.180522) (xy 297.987943 -287.178541) (xy 297.939724 -287.168697)
			(xy 297.893708 -287.151245) (xy 297.851087 -287.126638) (xy 297.812966 -287.095513) (xy 297.780331 -287.058676)
			(xy 297.754028 -287.01708) (xy 297.734737 -286.971804) (xy 297.72296 -286.92402) (xy 297.719 -286.874966)
			(xy 297.380152 -286.874966) (xy 297.379657 -286.899573) (xy 297.371762 -286.94815) (xy 297.356178 -286.994831)
			(xy 297.333307 -287.038408) (xy 297.303742 -287.077752) (xy 297.268249 -287.111844) (xy 297.227746 -287.1398)
			(xy 297.183284 -287.160898) (xy 297.136013 -287.17459) (xy 297.087158 -287.180522) (xy 297.037983 -287.178541)
			(xy 296.989764 -287.168697) (xy 296.943748 -287.151245) (xy 296.901127 -287.126638) (xy 296.863006 -287.095513)
			(xy 296.830371 -287.058676) (xy 296.804068 -287.01708) (xy 296.784777 -286.971804) (xy 296.773 -286.92402)
			(xy 296.76904 -286.874966) (xy 296.430192 -286.874966) (xy 296.429697 -286.899573) (xy 296.421802 -286.94815)
			(xy 296.406218 -286.994831) (xy 296.383347 -287.038408) (xy 296.353782 -287.077752) (xy 296.318289 -287.111844)
			(xy 296.277786 -287.1398) (xy 296.233324 -287.160898) (xy 296.186053 -287.17459) (xy 296.137198 -287.180522)
			(xy 296.088023 -287.178541) (xy 296.039804 -287.168697) (xy 295.993788 -287.151245) (xy 295.951167 -287.126638)
			(xy 295.913046 -287.095513) (xy 295.880411 -287.058676) (xy 295.854108 -287.01708) (xy 295.834817 -286.971804)
			(xy 295.82304 -286.92402) (xy 295.81908 -286.874966) (xy 295.480232 -286.874966) (xy 295.479737 -286.899573)
			(xy 295.471842 -286.94815) (xy 295.456258 -286.994831) (xy 295.433387 -287.038408) (xy 295.403822 -287.077752)
			(xy 295.368329 -287.111844) (xy 295.327826 -287.1398) (xy 295.283364 -287.160898) (xy 295.236093 -287.17459)
			(xy 295.187238 -287.180522) (xy 295.138063 -287.178541) (xy 295.089844 -287.168697) (xy 295.043828 -287.151245)
			(xy 295.001207 -287.126638) (xy 294.963086 -287.095513) (xy 294.930451 -287.058676) (xy 294.904148 -287.01708)
			(xy 294.884857 -286.971804) (xy 294.87308 -286.92402) (xy 294.86912 -286.874966) (xy 294.530018 -286.874966)
			(xy 294.529523 -286.899573) (xy 294.521628 -286.94815) (xy 294.506044 -286.994831) (xy 294.483173 -287.038408)
			(xy 294.453608 -287.077752) (xy 294.418115 -287.111844) (xy 294.377612 -287.1398) (xy 294.33315 -287.160898)
			(xy 294.285879 -287.17459) (xy 294.237024 -287.180522) (xy 294.187849 -287.178541) (xy 294.13963 -287.168697)
			(xy 294.093614 -287.151245) (xy 294.050993 -287.126638) (xy 294.012872 -287.095513) (xy 293.980237 -287.058676)
			(xy 293.953934 -287.01708) (xy 293.934643 -286.971804) (xy 293.922866 -286.92402) (xy 293.918906 -286.874966)
			(xy 293.580058 -286.874966) (xy 293.579563 -286.899573) (xy 293.571668 -286.94815) (xy 293.556084 -286.994831)
			(xy 293.533213 -287.038408) (xy 293.503648 -287.077752) (xy 293.468155 -287.111844) (xy 293.427652 -287.1398)
			(xy 293.38319 -287.160898) (xy 293.335919 -287.17459) (xy 293.287064 -287.180522) (xy 293.237889 -287.178541)
			(xy 293.18967 -287.168697) (xy 293.143654 -287.151245) (xy 293.101033 -287.126638) (xy 293.062912 -287.095513)
			(xy 293.030277 -287.058676) (xy 293.003974 -287.01708) (xy 292.984683 -286.971804) (xy 292.972906 -286.92402)
			(xy 292.968946 -286.874966) (xy 292.630098 -286.874966) (xy 292.629603 -286.899573) (xy 292.621708 -286.94815)
			(xy 292.606124 -286.994831) (xy 292.583253 -287.038408) (xy 292.553688 -287.077752) (xy 292.518195 -287.111844)
			(xy 292.477692 -287.1398) (xy 292.43323 -287.160898) (xy 292.385959 -287.17459) (xy 292.337104 -287.180522)
			(xy 292.287929 -287.178541) (xy 292.23971 -287.168697) (xy 292.193694 -287.151245) (xy 292.151073 -287.126638)
			(xy 292.112952 -287.095513) (xy 292.080317 -287.058676) (xy 292.054014 -287.01708) (xy 292.034723 -286.971804)
			(xy 292.022946 -286.92402) (xy 292.018986 -286.874966) (xy 290.730178 -286.874966) (xy 290.729683 -286.899573)
			(xy 290.721788 -286.94815) (xy 290.706204 -286.994831) (xy 290.683333 -287.038408) (xy 290.653768 -287.077752)
			(xy 290.618275 -287.111844) (xy 290.577772 -287.1398) (xy 290.53331 -287.160898) (xy 290.486039 -287.17459)
			(xy 290.437184 -287.180522) (xy 290.388009 -287.178541) (xy 290.33979 -287.168697) (xy 290.293774 -287.151245)
			(xy 290.251153 -287.126638) (xy 290.213032 -287.095513) (xy 290.180397 -287.058676) (xy 290.154094 -287.01708)
			(xy 290.134803 -286.971804) (xy 290.123026 -286.92402) (xy 290.119066 -286.874966) (xy 289.780218 -286.874966)
			(xy 289.779723 -286.899573) (xy 289.771828 -286.94815) (xy 289.756244 -286.994831) (xy 289.733373 -287.038408)
			(xy 289.703808 -287.077752) (xy 289.668315 -287.111844) (xy 289.627812 -287.1398) (xy 289.58335 -287.160898)
			(xy 289.536079 -287.17459) (xy 289.487224 -287.180522) (xy 289.438049 -287.178541) (xy 289.38983 -287.168697)
			(xy 289.343814 -287.151245) (xy 289.301193 -287.126638) (xy 289.263072 -287.095513) (xy 289.230437 -287.058676)
			(xy 289.204134 -287.01708) (xy 289.184843 -286.971804) (xy 289.173066 -286.92402) (xy 289.169106 -286.874966)
			(xy 288.830004 -286.874966) (xy 288.829509 -286.899573) (xy 288.821614 -286.94815) (xy 288.80603 -286.994831)
			(xy 288.783159 -287.038408) (xy 288.753594 -287.077752) (xy 288.718101 -287.111844) (xy 288.677598 -287.1398)
			(xy 288.633136 -287.160898) (xy 288.585865 -287.17459) (xy 288.53701 -287.180522) (xy 288.487835 -287.178541)
			(xy 288.439616 -287.168697) (xy 288.3936 -287.151245) (xy 288.350979 -287.126638) (xy 288.312858 -287.095513)
			(xy 288.280223 -287.058676) (xy 288.25392 -287.01708) (xy 288.234629 -286.971804) (xy 288.222852 -286.92402)
			(xy 288.218892 -286.874966) (xy 287.880044 -286.874966) (xy 287.879549 -286.899573) (xy 287.871654 -286.94815)
			(xy 287.85607 -286.994831) (xy 287.833199 -287.038408) (xy 287.803634 -287.077752) (xy 287.768141 -287.111844)
			(xy 287.727638 -287.1398) (xy 287.683176 -287.160898) (xy 287.635905 -287.17459) (xy 287.58705 -287.180522)
			(xy 287.537875 -287.178541) (xy 287.489656 -287.168697) (xy 287.44364 -287.151245) (xy 287.401019 -287.126638)
			(xy 287.362898 -287.095513) (xy 287.330263 -287.058676) (xy 287.30396 -287.01708) (xy 287.284669 -286.971804)
			(xy 287.272892 -286.92402) (xy 287.268932 -286.874966) (xy 286.930084 -286.874966) (xy 286.929589 -286.899573)
			(xy 286.921694 -286.94815) (xy 286.90611 -286.994831) (xy 286.883239 -287.038408) (xy 286.853674 -287.077752)
			(xy 286.818181 -287.111844) (xy 286.777678 -287.1398) (xy 286.733216 -287.160898) (xy 286.685945 -287.17459)
			(xy 286.63709 -287.180522) (xy 286.587915 -287.178541) (xy 286.539696 -287.168697) (xy 286.49368 -287.151245)
			(xy 286.451059 -287.126638) (xy 286.412938 -287.095513) (xy 286.380303 -287.058676) (xy 286.354 -287.01708)
			(xy 286.334709 -286.971804) (xy 286.322932 -286.92402) (xy 286.318972 -286.874966) (xy 285.980124 -286.874966)
			(xy 285.979629 -286.899573) (xy 285.971734 -286.94815) (xy 285.95615 -286.994831) (xy 285.933279 -287.038408)
			(xy 285.903714 -287.077752) (xy 285.868221 -287.111844) (xy 285.827718 -287.1398) (xy 285.783256 -287.160898)
			(xy 285.735985 -287.17459) (xy 285.68713 -287.180522) (xy 285.637955 -287.178541) (xy 285.589736 -287.168697)
			(xy 285.54372 -287.151245) (xy 285.501099 -287.126638) (xy 285.462978 -287.095513) (xy 285.430343 -287.058676)
			(xy 285.40404 -287.01708) (xy 285.384749 -286.971804) (xy 285.372972 -286.92402) (xy 285.369012 -286.874966)
			(xy 285.030164 -286.874966) (xy 285.029669 -286.899573) (xy 285.021774 -286.94815) (xy 285.00619 -286.994831)
			(xy 284.983319 -287.038408) (xy 284.953754 -287.077752) (xy 284.918261 -287.111844) (xy 284.877758 -287.1398)
			(xy 284.833296 -287.160898) (xy 284.786025 -287.17459) (xy 284.73717 -287.180522) (xy 284.687995 -287.178541)
			(xy 284.639776 -287.168697) (xy 284.59376 -287.151245) (xy 284.551139 -287.126638) (xy 284.513018 -287.095513)
			(xy 284.480383 -287.058676) (xy 284.45408 -287.01708) (xy 284.434789 -286.971804) (xy 284.423012 -286.92402)
			(xy 284.419052 -286.874966) (xy 284.080204 -286.874966) (xy 284.079709 -286.899573) (xy 284.071814 -286.94815)
			(xy 284.05623 -286.994831) (xy 284.033359 -287.038408) (xy 284.003794 -287.077752) (xy 283.968301 -287.111844)
			(xy 283.927798 -287.1398) (xy 283.883336 -287.160898) (xy 283.836065 -287.17459) (xy 283.78721 -287.180522)
			(xy 283.738035 -287.178541) (xy 283.689816 -287.168697) (xy 283.6438 -287.151245) (xy 283.601179 -287.126638)
			(xy 283.563058 -287.095513) (xy 283.530423 -287.058676) (xy 283.50412 -287.01708) (xy 283.484829 -286.971804)
			(xy 283.473052 -286.92402) (xy 283.469092 -286.874966) (xy 283.130244 -286.874966) (xy 283.129749 -286.899573)
			(xy 283.121854 -286.94815) (xy 283.10627 -286.994831) (xy 283.083399 -287.038408) (xy 283.053834 -287.077752)
			(xy 283.018341 -287.111844) (xy 282.977838 -287.1398) (xy 282.933376 -287.160898) (xy 282.886105 -287.17459)
			(xy 282.83725 -287.180522) (xy 282.788075 -287.178541) (xy 282.739856 -287.168697) (xy 282.69384 -287.151245)
			(xy 282.651219 -287.126638) (xy 282.613098 -287.095513) (xy 282.580463 -287.058676) (xy 282.55416 -287.01708)
			(xy 282.534869 -286.971804) (xy 282.523092 -286.92402) (xy 282.519132 -286.874966) (xy 282.18003 -286.874966)
			(xy 282.179535 -286.899573) (xy 282.17164 -286.94815) (xy 282.156056 -286.994831) (xy 282.133185 -287.038408)
			(xy 282.10362 -287.077752) (xy 282.068127 -287.111844) (xy 282.027624 -287.1398) (xy 281.983162 -287.160898)
			(xy 281.935891 -287.17459) (xy 281.887036 -287.180522) (xy 281.837861 -287.178541) (xy 281.789642 -287.168697)
			(xy 281.743626 -287.151245) (xy 281.701005 -287.126638) (xy 281.662884 -287.095513) (xy 281.630249 -287.058676)
			(xy 281.603946 -287.01708) (xy 281.584655 -286.971804) (xy 281.572878 -286.92402) (xy 281.568918 -286.874966)
			(xy 281.23007 -286.874966) (xy 281.229575 -286.899573) (xy 281.22168 -286.94815) (xy 281.206096 -286.994831)
			(xy 281.183225 -287.038408) (xy 281.15366 -287.077752) (xy 281.118167 -287.111844) (xy 281.077664 -287.1398)
			(xy 281.033202 -287.160898) (xy 280.985931 -287.17459) (xy 280.937076 -287.180522) (xy 280.887901 -287.178541)
			(xy 280.839682 -287.168697) (xy 280.793666 -287.151245) (xy 280.751045 -287.126638) (xy 280.712924 -287.095513)
			(xy 280.680289 -287.058676) (xy 280.653986 -287.01708) (xy 280.634695 -286.971804) (xy 280.622918 -286.92402)
			(xy 280.618958 -286.874966) (xy 280.28011 -286.874966) (xy 280.279615 -286.899573) (xy 280.27172 -286.94815)
			(xy 280.256136 -286.994831) (xy 280.233265 -287.038408) (xy 280.2037 -287.077752) (xy 280.168207 -287.111844)
			(xy 280.127704 -287.1398) (xy 280.083242 -287.160898) (xy 280.035971 -287.17459) (xy 279.987116 -287.180522)
			(xy 279.937941 -287.178541) (xy 279.889722 -287.168697) (xy 279.843706 -287.151245) (xy 279.801085 -287.126638)
			(xy 279.762964 -287.095513) (xy 279.730329 -287.058676) (xy 279.704026 -287.01708) (xy 279.684735 -286.971804)
			(xy 279.672958 -286.92402) (xy 279.668998 -286.874966) (xy 279.33015 -286.874966) (xy 279.329655 -286.899573)
			(xy 279.32176 -286.94815) (xy 279.306176 -286.994831) (xy 279.283305 -287.038408) (xy 279.25374 -287.077752)
			(xy 279.218247 -287.111844) (xy 279.177744 -287.1398) (xy 279.133282 -287.160898) (xy 279.086011 -287.17459)
			(xy 279.037156 -287.180522) (xy 278.987981 -287.178541) (xy 278.939762 -287.168697) (xy 278.893746 -287.151245)
			(xy 278.851125 -287.126638) (xy 278.813004 -287.095513) (xy 278.780369 -287.058676) (xy 278.754066 -287.01708)
			(xy 278.734775 -286.971804) (xy 278.722998 -286.92402) (xy 278.719038 -286.874966) (xy 278.38019 -286.874966)
			(xy 278.379695 -286.899573) (xy 278.3718 -286.94815) (xy 278.356216 -286.994831) (xy 278.333345 -287.038408)
			(xy 278.30378 -287.077752) (xy 278.268287 -287.111844) (xy 278.227784 -287.1398) (xy 278.183322 -287.160898)
			(xy 278.136051 -287.17459) (xy 278.087196 -287.180522) (xy 278.038021 -287.178541) (xy 277.989802 -287.168697)
			(xy 277.943786 -287.151245) (xy 277.901165 -287.126638) (xy 277.863044 -287.095513) (xy 277.830409 -287.058676)
			(xy 277.804106 -287.01708) (xy 277.784815 -286.971804) (xy 277.773038 -286.92402) (xy 277.769078 -286.874966)
			(xy 277.43023 -286.874966) (xy 277.429735 -286.899573) (xy 277.42184 -286.94815) (xy 277.406256 -286.994831)
			(xy 277.383385 -287.038408) (xy 277.35382 -287.077752) (xy 277.318327 -287.111844) (xy 277.277824 -287.1398)
			(xy 277.233362 -287.160898) (xy 277.186091 -287.17459) (xy 277.137236 -287.180522) (xy 277.088061 -287.178541)
			(xy 277.039842 -287.168697) (xy 276.993826 -287.151245) (xy 276.951205 -287.126638) (xy 276.913084 -287.095513)
			(xy 276.880449 -287.058676) (xy 276.854146 -287.01708) (xy 276.834855 -286.971804) (xy 276.823078 -286.92402)
			(xy 276.819118 -286.874966) (xy 276.480011 -286.874966) (xy 276.479521 -286.899319) (xy 276.471626 -286.947896)
			(xy 276.456042 -286.994577) (xy 276.433171 -287.038154) (xy 276.403606 -287.077498) (xy 276.368113 -287.11159)
			(xy 276.32761 -287.139546) (xy 276.283148 -287.160644) (xy 276.235877 -287.174336) (xy 276.187022 -287.180268)
			(xy 276.137847 -287.178287) (xy 276.089628 -287.168443) (xy 276.043612 -287.150991) (xy 276.000991 -287.126384)
			(xy 275.96287 -287.095259) (xy 275.930235 -287.058422) (xy 275.903932 -287.016826) (xy 275.884641 -286.97155)
			(xy 275.872864 -286.923766) (xy 275.868904 -286.874712) (xy 275.530056 -286.874712) (xy 275.529561 -286.899319)
			(xy 275.521666 -286.947896) (xy 275.506082 -286.994577) (xy 275.483211 -287.038154) (xy 275.453646 -287.077498)
			(xy 275.418153 -287.11159) (xy 275.37765 -287.139546) (xy 275.333188 -287.160644) (xy 275.285917 -287.174336)
			(xy 275.237062 -287.180268) (xy 275.187887 -287.178287) (xy 275.139668 -287.168443) (xy 275.093652 -287.150991)
			(xy 275.051031 -287.126384) (xy 275.01291 -287.095259) (xy 274.980275 -287.058422) (xy 274.953972 -287.016826)
			(xy 274.934681 -286.97155) (xy 274.922904 -286.923766) (xy 274.918944 -286.874712) (xy 274.580091 -286.874712)
			(xy 274.580096 -286.874966) (xy 274.579601 -286.899573) (xy 274.571706 -286.94815) (xy 274.556122 -286.994831)
			(xy 274.533251 -287.038408) (xy 274.503686 -287.077752) (xy 274.468193 -287.111844) (xy 274.42769 -287.1398)
			(xy 274.383228 -287.160898) (xy 274.335957 -287.17459) (xy 274.287102 -287.180522) (xy 274.237927 -287.178541)
			(xy 274.189708 -287.168697) (xy 274.143692 -287.151245) (xy 274.101071 -287.126638) (xy 274.06295 -287.095513)
			(xy 274.030315 -287.058676) (xy 274.004012 -287.01708) (xy 273.984721 -286.971804) (xy 273.972944 -286.92402)
			(xy 273.968984 -286.874966) (xy 273.630136 -286.874966) (xy 273.629641 -286.899573) (xy 273.621746 -286.94815)
			(xy 273.606162 -286.994831) (xy 273.583291 -287.038408) (xy 273.553726 -287.077752) (xy 273.518233 -287.111844)
			(xy 273.47773 -287.1398) (xy 273.433268 -287.160898) (xy 273.385997 -287.17459) (xy 273.337142 -287.180522)
			(xy 273.287967 -287.178541) (xy 273.239748 -287.168697) (xy 273.193732 -287.151245) (xy 273.151111 -287.126638)
			(xy 273.11299 -287.095513) (xy 273.080355 -287.058676) (xy 273.054052 -287.01708) (xy 273.034761 -286.971804)
			(xy 273.022984 -286.92402) (xy 273.019024 -286.874966) (xy 272.680176 -286.874966) (xy 272.679681 -286.899573)
			(xy 272.671786 -286.94815) (xy 272.656202 -286.994831) (xy 272.633331 -287.038408) (xy 272.603766 -287.077752)
			(xy 272.568273 -287.111844) (xy 272.52777 -287.1398) (xy 272.483308 -287.160898) (xy 272.436037 -287.17459)
			(xy 272.387182 -287.180522) (xy 272.338007 -287.178541) (xy 272.289788 -287.168697) (xy 272.243772 -287.151245)
			(xy 272.201151 -287.126638) (xy 272.16303 -287.095513) (xy 272.130395 -287.058676) (xy 272.104092 -287.01708)
			(xy 272.084801 -286.971804) (xy 272.073024 -286.92402) (xy 272.069064 -286.874966) (xy 271.730216 -286.874966)
			(xy 271.729721 -286.899573) (xy 271.721826 -286.94815) (xy 271.706242 -286.994831) (xy 271.683371 -287.038408)
			(xy 271.653806 -287.077752) (xy 271.618313 -287.111844) (xy 271.57781 -287.1398) (xy 271.533348 -287.160898)
			(xy 271.486077 -287.17459) (xy 271.437222 -287.180522) (xy 271.388047 -287.178541) (xy 271.339828 -287.168697)
			(xy 271.293812 -287.151245) (xy 271.251191 -287.126638) (xy 271.21307 -287.095513) (xy 271.180435 -287.058676)
			(xy 271.154132 -287.01708) (xy 271.134841 -286.971804) (xy 271.123064 -286.92402) (xy 271.119104 -286.874966)
			(xy 270.780256 -286.874966) (xy 270.779761 -286.899573) (xy 270.771866 -286.94815) (xy 270.756282 -286.994831)
			(xy 270.733411 -287.038408) (xy 270.703846 -287.077752) (xy 270.668353 -287.111844) (xy 270.62785 -287.1398)
			(xy 270.583388 -287.160898) (xy 270.536117 -287.17459) (xy 270.487262 -287.180522) (xy 270.438087 -287.178541)
			(xy 270.389868 -287.168697) (xy 270.343852 -287.151245) (xy 270.301231 -287.126638) (xy 270.26311 -287.095513)
			(xy 270.230475 -287.058676) (xy 270.204172 -287.01708) (xy 270.184881 -286.971804) (xy 270.173104 -286.92402)
			(xy 270.169144 -286.874966) (xy 269.830042 -286.874966) (xy 269.829547 -286.899573) (xy 269.821652 -286.94815)
			(xy 269.806068 -286.994831) (xy 269.783197 -287.038408) (xy 269.753632 -287.077752) (xy 269.718139 -287.111844)
			(xy 269.677636 -287.1398) (xy 269.633174 -287.160898) (xy 269.585903 -287.17459) (xy 269.537048 -287.180522)
			(xy 269.487873 -287.178541) (xy 269.439654 -287.168697) (xy 269.393638 -287.151245) (xy 269.351017 -287.126638)
			(xy 269.312896 -287.095513) (xy 269.280261 -287.058676) (xy 269.253958 -287.01708) (xy 269.234667 -286.971804)
			(xy 269.22289 -286.92402) (xy 269.21893 -286.874966) (xy 268.880082 -286.874966) (xy 268.879587 -286.899573)
			(xy 268.871692 -286.94815) (xy 268.856108 -286.994831) (xy 268.833237 -287.038408) (xy 268.803672 -287.077752)
			(xy 268.768179 -287.111844) (xy 268.727676 -287.1398) (xy 268.683214 -287.160898) (xy 268.635943 -287.17459)
			(xy 268.587088 -287.180522) (xy 268.537913 -287.178541) (xy 268.489694 -287.168697) (xy 268.443678 -287.151245)
			(xy 268.401057 -287.126638) (xy 268.362936 -287.095513) (xy 268.330301 -287.058676) (xy 268.303998 -287.01708)
			(xy 268.284707 -286.971804) (xy 268.27293 -286.92402) (xy 268.26897 -286.874966) (xy 266.590526 -286.874966)
			(xy 266.590526 -287.349946) (xy 305.793914 -287.349946) (xy 305.797874 -287.300892) (xy 305.809651 -287.253108)
			(xy 305.828942 -287.207832) (xy 305.855245 -287.166236) (xy 305.88788 -287.129399) (xy 305.926001 -287.098274)
			(xy 305.968622 -287.073667) (xy 306.014638 -287.056215) (xy 306.062857 -287.046371) (xy 306.112032 -287.04439)
			(xy 306.160887 -287.050322) (xy 306.208158 -287.064014) (xy 306.25262 -287.085112) (xy 306.293123 -287.113068)
			(xy 306.328616 -287.14716) (xy 306.358181 -287.186504) (xy 306.381052 -287.230081) (xy 306.396636 -287.276762)
			(xy 306.404531 -287.325339) (xy 306.405026 -287.349946) (xy 306.743874 -287.349946) (xy 306.747834 -287.300892)
			(xy 306.759611 -287.253108) (xy 306.778902 -287.207832) (xy 306.805205 -287.166236) (xy 306.83784 -287.129399)
			(xy 306.875961 -287.098274) (xy 306.918582 -287.073667) (xy 306.964598 -287.056215) (xy 307.012817 -287.046371)
			(xy 307.061992 -287.04439) (xy 307.110847 -287.050322) (xy 307.158118 -287.064014) (xy 307.20258 -287.085112)
			(xy 307.243083 -287.113068) (xy 307.278576 -287.14716) (xy 307.308141 -287.186504) (xy 307.331012 -287.230081)
			(xy 307.346596 -287.276762) (xy 307.354491 -287.325339) (xy 307.354986 -287.349946) (xy 307.694088 -287.349946)
			(xy 307.698048 -287.300892) (xy 307.709825 -287.253108) (xy 307.729116 -287.207832) (xy 307.755419 -287.166236)
			(xy 307.788054 -287.129399) (xy 307.826175 -287.098274) (xy 307.868796 -287.073667) (xy 307.914812 -287.056215)
			(xy 307.963031 -287.046371) (xy 308.012206 -287.04439) (xy 308.061061 -287.050322) (xy 308.108332 -287.064014)
			(xy 308.152794 -287.085112) (xy 308.193297 -287.113068) (xy 308.22879 -287.14716) (xy 308.258355 -287.186504)
			(xy 308.281226 -287.230081) (xy 308.29681 -287.276762) (xy 308.304705 -287.325339) (xy 308.3052 -287.349946)
			(xy 308.304705 -287.374553) (xy 308.29681 -287.42313) (xy 308.281226 -287.469811) (xy 308.258355 -287.513388)
			(xy 308.22879 -287.552732) (xy 308.193297 -287.586824) (xy 308.152794 -287.61478) (xy 308.108332 -287.635878)
			(xy 308.061061 -287.64957) (xy 308.012206 -287.655502) (xy 307.963031 -287.653521) (xy 307.914812 -287.643677)
			(xy 307.868796 -287.626225) (xy 307.826175 -287.601618) (xy 307.788054 -287.570493) (xy 307.755419 -287.533656)
			(xy 307.729116 -287.49206) (xy 307.709825 -287.446784) (xy 307.698048 -287.399) (xy 307.694088 -287.349946)
			(xy 307.354986 -287.349946) (xy 307.354491 -287.374553) (xy 307.346596 -287.42313) (xy 307.331012 -287.469811)
			(xy 307.308141 -287.513388) (xy 307.278576 -287.552732) (xy 307.243083 -287.586824) (xy 307.20258 -287.61478)
			(xy 307.158118 -287.635878) (xy 307.110847 -287.64957) (xy 307.061992 -287.655502) (xy 307.012817 -287.653521)
			(xy 306.964598 -287.643677) (xy 306.918582 -287.626225) (xy 306.875961 -287.601618) (xy 306.83784 -287.570493)
			(xy 306.805205 -287.533656) (xy 306.778902 -287.49206) (xy 306.759611 -287.446784) (xy 306.747834 -287.399)
			(xy 306.743874 -287.349946) (xy 306.405026 -287.349946) (xy 306.404531 -287.374553) (xy 306.396636 -287.42313)
			(xy 306.381052 -287.469811) (xy 306.358181 -287.513388) (xy 306.328616 -287.552732) (xy 306.293123 -287.586824)
			(xy 306.25262 -287.61478) (xy 306.208158 -287.635878) (xy 306.160887 -287.64957) (xy 306.112032 -287.655502)
			(xy 306.062857 -287.653521) (xy 306.014638 -287.643677) (xy 305.968622 -287.626225) (xy 305.926001 -287.601618)
			(xy 305.88788 -287.570493) (xy 305.855245 -287.533656) (xy 305.828942 -287.49206) (xy 305.809651 -287.446784)
			(xy 305.797874 -287.399) (xy 305.793914 -287.349946) (xy 266.590526 -287.349946) (xy 266.590526 -287.824926)
			(xy 268.26897 -287.824926) (xy 268.27293 -287.775872) (xy 268.284707 -287.728088) (xy 268.303998 -287.682812)
			(xy 268.330301 -287.641216) (xy 268.362936 -287.604379) (xy 268.401057 -287.573254) (xy 268.443678 -287.548647)
			(xy 268.489694 -287.531195) (xy 268.537913 -287.521351) (xy 268.587088 -287.51937) (xy 268.635943 -287.525302)
			(xy 268.683214 -287.538994) (xy 268.727676 -287.560092) (xy 268.768179 -287.588048) (xy 268.803672 -287.62214)
			(xy 268.833237 -287.661484) (xy 268.856108 -287.705061) (xy 268.871692 -287.751742) (xy 268.879587 -287.800319)
			(xy 268.880082 -287.824926) (xy 269.21893 -287.824926) (xy 269.22289 -287.775872) (xy 269.234667 -287.728088)
			(xy 269.253958 -287.682812) (xy 269.280261 -287.641216) (xy 269.312896 -287.604379) (xy 269.351017 -287.573254)
			(xy 269.393638 -287.548647) (xy 269.439654 -287.531195) (xy 269.487873 -287.521351) (xy 269.537048 -287.51937)
			(xy 269.585903 -287.525302) (xy 269.633174 -287.538994) (xy 269.677636 -287.560092) (xy 269.718139 -287.588048)
			(xy 269.753632 -287.62214) (xy 269.783197 -287.661484) (xy 269.806068 -287.705061) (xy 269.821652 -287.751742)
			(xy 269.829547 -287.800319) (xy 269.830042 -287.824926) (xy 270.169144 -287.824926) (xy 270.173104 -287.775872)
			(xy 270.184881 -287.728088) (xy 270.204172 -287.682812) (xy 270.230475 -287.641216) (xy 270.26311 -287.604379)
			(xy 270.301231 -287.573254) (xy 270.343852 -287.548647) (xy 270.389868 -287.531195) (xy 270.438087 -287.521351)
			(xy 270.487262 -287.51937) (xy 270.536117 -287.525302) (xy 270.583388 -287.538994) (xy 270.62785 -287.560092)
			(xy 270.668353 -287.588048) (xy 270.703846 -287.62214) (xy 270.733411 -287.661484) (xy 270.756282 -287.705061)
			(xy 270.771866 -287.751742) (xy 270.779761 -287.800319) (xy 270.780256 -287.824926) (xy 273.019024 -287.824926)
			(xy 273.022984 -287.775872) (xy 273.034761 -287.728088) (xy 273.054052 -287.682812) (xy 273.080355 -287.641216)
			(xy 273.11299 -287.604379) (xy 273.151111 -287.573254) (xy 273.193732 -287.548647) (xy 273.239748 -287.531195)
			(xy 273.287967 -287.521351) (xy 273.337142 -287.51937) (xy 273.385997 -287.525302) (xy 273.433268 -287.538994)
			(xy 273.47773 -287.560092) (xy 273.518233 -287.588048) (xy 273.553726 -287.62214) (xy 273.583291 -287.661484)
			(xy 273.606162 -287.705061) (xy 273.621746 -287.751742) (xy 273.629641 -287.800319) (xy 273.630136 -287.824926)
			(xy 276.819118 -287.824926) (xy 276.823078 -287.775872) (xy 276.834855 -287.728088) (xy 276.854146 -287.682812)
			(xy 276.880449 -287.641216) (xy 276.913084 -287.604379) (xy 276.951205 -287.573254) (xy 276.993826 -287.548647)
			(xy 277.039842 -287.531195) (xy 277.088061 -287.521351) (xy 277.137236 -287.51937) (xy 277.186091 -287.525302)
			(xy 277.233362 -287.538994) (xy 277.277824 -287.560092) (xy 277.318327 -287.588048) (xy 277.35382 -287.62214)
			(xy 277.383385 -287.661484) (xy 277.406256 -287.705061) (xy 277.42184 -287.751742) (xy 277.429735 -287.800319)
			(xy 277.43023 -287.824926) (xy 277.769078 -287.824926) (xy 277.773038 -287.775872) (xy 277.784815 -287.728088)
			(xy 277.804106 -287.682812) (xy 277.830409 -287.641216) (xy 277.863044 -287.604379) (xy 277.901165 -287.573254)
			(xy 277.943786 -287.548647) (xy 277.989802 -287.531195) (xy 278.038021 -287.521351) (xy 278.087196 -287.51937)
			(xy 278.136051 -287.525302) (xy 278.183322 -287.538994) (xy 278.227784 -287.560092) (xy 278.268287 -287.588048)
			(xy 278.30378 -287.62214) (xy 278.333345 -287.661484) (xy 278.356216 -287.705061) (xy 278.3718 -287.751742)
			(xy 278.379695 -287.800319) (xy 278.38019 -287.824926) (xy 278.719038 -287.824926) (xy 278.722998 -287.775872)
			(xy 278.734775 -287.728088) (xy 278.754066 -287.682812) (xy 278.780369 -287.641216) (xy 278.813004 -287.604379)
			(xy 278.851125 -287.573254) (xy 278.893746 -287.548647) (xy 278.939762 -287.531195) (xy 278.987981 -287.521351)
			(xy 279.037156 -287.51937) (xy 279.086011 -287.525302) (xy 279.133282 -287.538994) (xy 279.177744 -287.560092)
			(xy 279.218247 -287.588048) (xy 279.25374 -287.62214) (xy 279.283305 -287.661484) (xy 279.306176 -287.705061)
			(xy 279.32176 -287.751742) (xy 279.329655 -287.800319) (xy 279.33015 -287.824926) (xy 279.668998 -287.824926)
			(xy 279.672958 -287.775872) (xy 279.684735 -287.728088) (xy 279.704026 -287.682812) (xy 279.730329 -287.641216)
			(xy 279.762964 -287.604379) (xy 279.801085 -287.573254) (xy 279.843706 -287.548647) (xy 279.889722 -287.531195)
			(xy 279.937941 -287.521351) (xy 279.987116 -287.51937) (xy 280.035971 -287.525302) (xy 280.083242 -287.538994)
			(xy 280.127704 -287.560092) (xy 280.168207 -287.588048) (xy 280.2037 -287.62214) (xy 280.233265 -287.661484)
			(xy 280.256136 -287.705061) (xy 280.27172 -287.751742) (xy 280.279615 -287.800319) (xy 280.28011 -287.824926)
			(xy 280.618958 -287.824926) (xy 280.622918 -287.775872) (xy 280.634695 -287.728088) (xy 280.653986 -287.682812)
			(xy 280.680289 -287.641216) (xy 280.712924 -287.604379) (xy 280.751045 -287.573254) (xy 280.793666 -287.548647)
			(xy 280.839682 -287.531195) (xy 280.887901 -287.521351) (xy 280.937076 -287.51937) (xy 280.985931 -287.525302)
			(xy 281.033202 -287.538994) (xy 281.077664 -287.560092) (xy 281.118167 -287.588048) (xy 281.15366 -287.62214)
			(xy 281.183225 -287.661484) (xy 281.206096 -287.705061) (xy 281.22168 -287.751742) (xy 281.229575 -287.800319)
			(xy 281.23007 -287.824926) (xy 281.568918 -287.824926) (xy 281.572878 -287.775872) (xy 281.584655 -287.728088)
			(xy 281.603946 -287.682812) (xy 281.630249 -287.641216) (xy 281.662884 -287.604379) (xy 281.701005 -287.573254)
			(xy 281.743626 -287.548647) (xy 281.789642 -287.531195) (xy 281.837861 -287.521351) (xy 281.887036 -287.51937)
			(xy 281.935891 -287.525302) (xy 281.983162 -287.538994) (xy 282.027624 -287.560092) (xy 282.068127 -287.588048)
			(xy 282.10362 -287.62214) (xy 282.133185 -287.661484) (xy 282.156056 -287.705061) (xy 282.17164 -287.751742)
			(xy 282.179535 -287.800319) (xy 282.18003 -287.824926) (xy 282.179535 -287.849533) (xy 282.17164 -287.89811)
			(xy 282.156056 -287.944791) (xy 282.133185 -287.988368) (xy 282.10362 -288.027712) (xy 282.068127 -288.061804)
			(xy 282.027624 -288.08976) (xy 281.983162 -288.110858) (xy 281.935891 -288.12455) (xy 281.887036 -288.130482)
			(xy 281.837861 -288.128501) (xy 281.789642 -288.118657) (xy 281.743626 -288.101205) (xy 281.701005 -288.076598)
			(xy 281.662884 -288.045473) (xy 281.630249 -288.008636) (xy 281.603946 -287.96704) (xy 281.584655 -287.921764)
			(xy 281.572878 -287.87398) (xy 281.568918 -287.824926) (xy 281.23007 -287.824926) (xy 281.229575 -287.849533)
			(xy 281.22168 -287.89811) (xy 281.206096 -287.944791) (xy 281.183225 -287.988368) (xy 281.15366 -288.027712)
			(xy 281.118167 -288.061804) (xy 281.077664 -288.08976) (xy 281.033202 -288.110858) (xy 280.985931 -288.12455)
			(xy 280.937076 -288.130482) (xy 280.887901 -288.128501) (xy 280.839682 -288.118657) (xy 280.793666 -288.101205)
			(xy 280.751045 -288.076598) (xy 280.712924 -288.045473) (xy 280.680289 -288.008636) (xy 280.653986 -287.96704)
			(xy 280.634695 -287.921764) (xy 280.622918 -287.87398) (xy 280.618958 -287.824926) (xy 280.28011 -287.824926)
			(xy 280.279615 -287.849533) (xy 280.27172 -287.89811) (xy 280.256136 -287.944791) (xy 280.233265 -287.988368)
			(xy 280.2037 -288.027712) (xy 280.168207 -288.061804) (xy 280.127704 -288.08976) (xy 280.083242 -288.110858)
			(xy 280.035971 -288.12455) (xy 279.987116 -288.130482) (xy 279.937941 -288.128501) (xy 279.889722 -288.118657)
			(xy 279.843706 -288.101205) (xy 279.801085 -288.076598) (xy 279.762964 -288.045473) (xy 279.730329 -288.008636)
			(xy 279.704026 -287.96704) (xy 279.684735 -287.921764) (xy 279.672958 -287.87398) (xy 279.668998 -287.824926)
			(xy 279.33015 -287.824926) (xy 279.329655 -287.849533) (xy 279.32176 -287.89811) (xy 279.306176 -287.944791)
			(xy 279.283305 -287.988368) (xy 279.25374 -288.027712) (xy 279.218247 -288.061804) (xy 279.177744 -288.08976)
			(xy 279.133282 -288.110858) (xy 279.086011 -288.12455) (xy 279.037156 -288.130482) (xy 278.987981 -288.128501)
			(xy 278.939762 -288.118657) (xy 278.893746 -288.101205) (xy 278.851125 -288.076598) (xy 278.813004 -288.045473)
			(xy 278.780369 -288.008636) (xy 278.754066 -287.96704) (xy 278.734775 -287.921764) (xy 278.722998 -287.87398)
			(xy 278.719038 -287.824926) (xy 278.38019 -287.824926) (xy 278.379695 -287.849533) (xy 278.3718 -287.89811)
			(xy 278.356216 -287.944791) (xy 278.333345 -287.988368) (xy 278.30378 -288.027712) (xy 278.268287 -288.061804)
			(xy 278.227784 -288.08976) (xy 278.183322 -288.110858) (xy 278.136051 -288.12455) (xy 278.087196 -288.130482)
			(xy 278.038021 -288.128501) (xy 277.989802 -288.118657) (xy 277.943786 -288.101205) (xy 277.901165 -288.076598)
			(xy 277.863044 -288.045473) (xy 277.830409 -288.008636) (xy 277.804106 -287.96704) (xy 277.784815 -287.921764)
			(xy 277.773038 -287.87398) (xy 277.769078 -287.824926) (xy 277.43023 -287.824926) (xy 277.429735 -287.849533)
			(xy 277.42184 -287.89811) (xy 277.406256 -287.944791) (xy 277.383385 -287.988368) (xy 277.35382 -288.027712)
			(xy 277.318327 -288.061804) (xy 277.277824 -288.08976) (xy 277.233362 -288.110858) (xy 277.186091 -288.12455)
			(xy 277.137236 -288.130482) (xy 277.088061 -288.128501) (xy 277.039842 -288.118657) (xy 276.993826 -288.101205)
			(xy 276.951205 -288.076598) (xy 276.913084 -288.045473) (xy 276.880449 -288.008636) (xy 276.854146 -287.96704)
			(xy 276.834855 -287.921764) (xy 276.823078 -287.87398) (xy 276.819118 -287.824926) (xy 273.630136 -287.824926)
			(xy 273.629641 -287.849533) (xy 273.621746 -287.89811) (xy 273.606162 -287.944791) (xy 273.583291 -287.988368)
			(xy 273.553726 -288.027712) (xy 273.518233 -288.061804) (xy 273.47773 -288.08976) (xy 273.433268 -288.110858)
			(xy 273.385997 -288.12455) (xy 273.337142 -288.130482) (xy 273.287967 -288.128501) (xy 273.239748 -288.118657)
			(xy 273.193732 -288.101205) (xy 273.151111 -288.076598) (xy 273.11299 -288.045473) (xy 273.080355 -288.008636)
			(xy 273.054052 -287.96704) (xy 273.034761 -287.921764) (xy 273.022984 -287.87398) (xy 273.019024 -287.824926)
			(xy 270.780256 -287.824926) (xy 270.779761 -287.849533) (xy 270.771866 -287.89811) (xy 270.756282 -287.944791)
			(xy 270.733411 -287.988368) (xy 270.703846 -288.027712) (xy 270.668353 -288.061804) (xy 270.62785 -288.08976)
			(xy 270.583388 -288.110858) (xy 270.536117 -288.12455) (xy 270.487262 -288.130482) (xy 270.438087 -288.128501)
			(xy 270.389868 -288.118657) (xy 270.343852 -288.101205) (xy 270.301231 -288.076598) (xy 270.26311 -288.045473)
			(xy 270.230475 -288.008636) (xy 270.204172 -287.96704) (xy 270.184881 -287.921764) (xy 270.173104 -287.87398)
			(xy 270.169144 -287.824926) (xy 269.830042 -287.824926) (xy 269.829547 -287.849533) (xy 269.821652 -287.89811)
			(xy 269.806068 -287.944791) (xy 269.783197 -287.988368) (xy 269.753632 -288.027712) (xy 269.718139 -288.061804)
			(xy 269.677636 -288.08976) (xy 269.633174 -288.110858) (xy 269.585903 -288.12455) (xy 269.537048 -288.130482)
			(xy 269.487873 -288.128501) (xy 269.439654 -288.118657) (xy 269.393638 -288.101205) (xy 269.351017 -288.076598)
			(xy 269.312896 -288.045473) (xy 269.280261 -288.008636) (xy 269.253958 -287.96704) (xy 269.234667 -287.921764)
			(xy 269.22289 -287.87398) (xy 269.21893 -287.824926) (xy 268.880082 -287.824926) (xy 268.879587 -287.849533)
			(xy 268.871692 -287.89811) (xy 268.856108 -287.944791) (xy 268.833237 -287.988368) (xy 268.803672 -288.027712)
			(xy 268.768179 -288.061804) (xy 268.727676 -288.08976) (xy 268.683214 -288.110858) (xy 268.635943 -288.12455)
			(xy 268.587088 -288.130482) (xy 268.537913 -288.128501) (xy 268.489694 -288.118657) (xy 268.443678 -288.101205)
			(xy 268.401057 -288.076598) (xy 268.362936 -288.045473) (xy 268.330301 -288.008636) (xy 268.303998 -287.96704)
			(xy 268.284707 -287.921764) (xy 268.27293 -287.87398) (xy 268.26897 -287.824926) (xy 266.590526 -287.824926)
			(xy 266.590526 -288.774886) (xy 268.26897 -288.774886) (xy 268.27293 -288.725832) (xy 268.284707 -288.678048)
			(xy 268.303998 -288.632772) (xy 268.330301 -288.591176) (xy 268.362936 -288.554339) (xy 268.401057 -288.523214)
			(xy 268.443678 -288.498607) (xy 268.489694 -288.481155) (xy 268.537913 -288.471311) (xy 268.587088 -288.46933)
			(xy 268.635943 -288.475262) (xy 268.683214 -288.488954) (xy 268.727676 -288.510052) (xy 268.768179 -288.538008)
			(xy 268.803672 -288.5721) (xy 268.833237 -288.611444) (xy 268.856108 -288.655021) (xy 268.871692 -288.701702)
			(xy 268.879587 -288.750279) (xy 268.880082 -288.774886) (xy 269.21893 -288.774886) (xy 269.22289 -288.725832)
			(xy 269.234667 -288.678048) (xy 269.253958 -288.632772) (xy 269.280261 -288.591176) (xy 269.312896 -288.554339)
			(xy 269.351017 -288.523214) (xy 269.393638 -288.498607) (xy 269.439654 -288.481155) (xy 269.487873 -288.471311)
			(xy 269.537048 -288.46933) (xy 269.585903 -288.475262) (xy 269.633174 -288.488954) (xy 269.677636 -288.510052)
			(xy 269.718139 -288.538008) (xy 269.753632 -288.5721) (xy 269.783197 -288.611444) (xy 269.806068 -288.655021)
			(xy 269.821652 -288.701702) (xy 269.829547 -288.750279) (xy 269.830042 -288.774886) (xy 270.169144 -288.774886)
			(xy 270.173104 -288.725832) (xy 270.184881 -288.678048) (xy 270.204172 -288.632772) (xy 270.230475 -288.591176)
			(xy 270.26311 -288.554339) (xy 270.301231 -288.523214) (xy 270.343852 -288.498607) (xy 270.389868 -288.481155)
			(xy 270.438087 -288.471311) (xy 270.487262 -288.46933) (xy 270.536117 -288.475262) (xy 270.583388 -288.488954)
			(xy 270.62785 -288.510052) (xy 270.668353 -288.538008) (xy 270.703846 -288.5721) (xy 270.733411 -288.611444)
			(xy 270.756282 -288.655021) (xy 270.771866 -288.701702) (xy 270.779761 -288.750279) (xy 270.780256 -288.774886)
			(xy 270.779761 -288.799493) (xy 270.771866 -288.84807) (xy 270.756282 -288.894751) (xy 270.733411 -288.938328)
			(xy 270.703846 -288.977672) (xy 270.668353 -289.011764) (xy 270.62785 -289.03972) (xy 270.583388 -289.060818)
			(xy 270.536117 -289.07451) (xy 270.487262 -289.080442) (xy 270.438087 -289.078461) (xy 270.389868 -289.068617)
			(xy 270.343852 -289.051165) (xy 270.301231 -289.026558) (xy 270.26311 -288.995433) (xy 270.230475 -288.958596)
			(xy 270.204172 -288.917) (xy 270.184881 -288.871724) (xy 270.173104 -288.82394) (xy 270.169144 -288.774886)
			(xy 269.830042 -288.774886) (xy 269.829547 -288.799493) (xy 269.821652 -288.84807) (xy 269.806068 -288.894751)
			(xy 269.783197 -288.938328) (xy 269.753632 -288.977672) (xy 269.718139 -289.011764) (xy 269.677636 -289.03972)
			(xy 269.633174 -289.060818) (xy 269.585903 -289.07451) (xy 269.537048 -289.080442) (xy 269.487873 -289.078461)
			(xy 269.439654 -289.068617) (xy 269.393638 -289.051165) (xy 269.351017 -289.026558) (xy 269.312896 -288.995433)
			(xy 269.280261 -288.958596) (xy 269.253958 -288.917) (xy 269.234667 -288.871724) (xy 269.22289 -288.82394)
			(xy 269.21893 -288.774886) (xy 268.880082 -288.774886) (xy 268.879587 -288.799493) (xy 268.871692 -288.84807)
			(xy 268.856108 -288.894751) (xy 268.833237 -288.938328) (xy 268.803672 -288.977672) (xy 268.768179 -289.011764)
			(xy 268.727676 -289.03972) (xy 268.683214 -289.060818) (xy 268.635943 -289.07451) (xy 268.587088 -289.080442)
			(xy 268.537913 -289.078461) (xy 268.489694 -289.068617) (xy 268.443678 -289.051165) (xy 268.401057 -289.026558)
			(xy 268.362936 -288.995433) (xy 268.330301 -288.958596) (xy 268.303998 -288.917) (xy 268.284707 -288.871724)
			(xy 268.27293 -288.82394) (xy 268.26897 -288.774886) (xy 266.590526 -288.774886) (xy 266.590526 -289.724846)
			(xy 268.26897 -289.724846) (xy 268.27293 -289.675792) (xy 268.284707 -289.628008) (xy 268.303998 -289.582732)
			(xy 268.330301 -289.541136) (xy 268.362936 -289.504299) (xy 268.401057 -289.473174) (xy 268.443678 -289.448567)
			(xy 268.489694 -289.431115) (xy 268.537913 -289.421271) (xy 268.587088 -289.41929) (xy 268.635943 -289.425222)
			(xy 268.683214 -289.438914) (xy 268.727676 -289.460012) (xy 268.768179 -289.487968) (xy 268.803672 -289.52206)
			(xy 268.833237 -289.561404) (xy 268.856108 -289.604981) (xy 268.871692 -289.651662) (xy 268.879587 -289.700239)
			(xy 268.880082 -289.724846) (xy 269.21893 -289.724846) (xy 269.22289 -289.675792) (xy 269.234667 -289.628008)
			(xy 269.253958 -289.582732) (xy 269.280261 -289.541136) (xy 269.312896 -289.504299) (xy 269.351017 -289.473174)
			(xy 269.393638 -289.448567) (xy 269.439654 -289.431115) (xy 269.487873 -289.421271) (xy 269.537048 -289.41929)
			(xy 269.585903 -289.425222) (xy 269.633174 -289.438914) (xy 269.677636 -289.460012) (xy 269.718139 -289.487968)
			(xy 269.753632 -289.52206) (xy 269.783197 -289.561404) (xy 269.806068 -289.604981) (xy 269.821652 -289.651662)
			(xy 269.829547 -289.700239) (xy 269.830042 -289.724846) (xy 270.169144 -289.724846) (xy 270.173104 -289.675792)
			(xy 270.184881 -289.628008) (xy 270.204172 -289.582732) (xy 270.230475 -289.541136) (xy 270.26311 -289.504299)
			(xy 270.301231 -289.473174) (xy 270.343852 -289.448567) (xy 270.389868 -289.431115) (xy 270.438087 -289.421271)
			(xy 270.487262 -289.41929) (xy 270.536117 -289.425222) (xy 270.583388 -289.438914) (xy 270.62785 -289.460012)
			(xy 270.668353 -289.487968) (xy 270.703846 -289.52206) (xy 270.733411 -289.561404) (xy 270.756282 -289.604981)
			(xy 270.771866 -289.651662) (xy 270.779761 -289.700239) (xy 270.780256 -289.724846) (xy 271.119104 -289.724846)
			(xy 271.123064 -289.675792) (xy 271.134841 -289.628008) (xy 271.154132 -289.582732) (xy 271.180435 -289.541136)
			(xy 271.21307 -289.504299) (xy 271.251191 -289.473174) (xy 271.293812 -289.448567) (xy 271.339828 -289.431115)
			(xy 271.388047 -289.421271) (xy 271.437222 -289.41929) (xy 271.486077 -289.425222) (xy 271.533348 -289.438914)
			(xy 271.57781 -289.460012) (xy 271.618313 -289.487968) (xy 271.653806 -289.52206) (xy 271.683371 -289.561404)
			(xy 271.706242 -289.604981) (xy 271.721826 -289.651662) (xy 271.729721 -289.700239) (xy 271.730216 -289.724846)
			(xy 272.069064 -289.724846) (xy 272.073024 -289.675792) (xy 272.084801 -289.628008) (xy 272.104092 -289.582732)
			(xy 272.130395 -289.541136) (xy 272.16303 -289.504299) (xy 272.201151 -289.473174) (xy 272.243772 -289.448567)
			(xy 272.289788 -289.431115) (xy 272.338007 -289.421271) (xy 272.387182 -289.41929) (xy 272.436037 -289.425222)
			(xy 272.483308 -289.438914) (xy 272.52777 -289.460012) (xy 272.568273 -289.487968) (xy 272.603766 -289.52206)
			(xy 272.633331 -289.561404) (xy 272.656202 -289.604981) (xy 272.671786 -289.651662) (xy 272.679681 -289.700239)
			(xy 272.680176 -289.724846) (xy 273.019024 -289.724846) (xy 273.022984 -289.675792) (xy 273.034761 -289.628008)
			(xy 273.054052 -289.582732) (xy 273.080355 -289.541136) (xy 273.11299 -289.504299) (xy 273.151111 -289.473174)
			(xy 273.193732 -289.448567) (xy 273.239748 -289.431115) (xy 273.287967 -289.421271) (xy 273.337142 -289.41929)
			(xy 273.385997 -289.425222) (xy 273.433268 -289.438914) (xy 273.47773 -289.460012) (xy 273.518233 -289.487968)
			(xy 273.553726 -289.52206) (xy 273.583291 -289.561404) (xy 273.606162 -289.604981) (xy 273.621746 -289.651662)
			(xy 273.629641 -289.700239) (xy 273.630136 -289.724846) (xy 273.968984 -289.724846) (xy 273.972944 -289.675792)
			(xy 273.984721 -289.628008) (xy 274.004012 -289.582732) (xy 274.030315 -289.541136) (xy 274.06295 -289.504299)
			(xy 274.101071 -289.473174) (xy 274.143692 -289.448567) (xy 274.189708 -289.431115) (xy 274.237927 -289.421271)
			(xy 274.287102 -289.41929) (xy 274.335957 -289.425222) (xy 274.383228 -289.438914) (xy 274.42769 -289.460012)
			(xy 274.468193 -289.487968) (xy 274.503686 -289.52206) (xy 274.533251 -289.561404) (xy 274.556122 -289.604981)
			(xy 274.571706 -289.651662) (xy 274.579601 -289.700239) (xy 274.580096 -289.724846) (xy 274.579601 -289.749453)
			(xy 274.571706 -289.79803) (xy 274.556122 -289.844711) (xy 274.533251 -289.888288) (xy 274.503686 -289.927632)
			(xy 274.468193 -289.961724) (xy 274.42769 -289.98968) (xy 274.383228 -290.010778) (xy 274.335957 -290.02447)
			(xy 274.287102 -290.030402) (xy 274.237927 -290.028421) (xy 274.189708 -290.018577) (xy 274.143692 -290.001125)
			(xy 274.101071 -289.976518) (xy 274.06295 -289.945393) (xy 274.030315 -289.908556) (xy 274.004012 -289.86696)
			(xy 273.984721 -289.821684) (xy 273.972944 -289.7739) (xy 273.968984 -289.724846) (xy 273.630136 -289.724846)
			(xy 273.629641 -289.749453) (xy 273.621746 -289.79803) (xy 273.606162 -289.844711) (xy 273.583291 -289.888288)
			(xy 273.553726 -289.927632) (xy 273.518233 -289.961724) (xy 273.47773 -289.98968) (xy 273.433268 -290.010778)
			(xy 273.385997 -290.02447) (xy 273.337142 -290.030402) (xy 273.287967 -290.028421) (xy 273.239748 -290.018577)
			(xy 273.193732 -290.001125) (xy 273.151111 -289.976518) (xy 273.11299 -289.945393) (xy 273.080355 -289.908556)
			(xy 273.054052 -289.86696) (xy 273.034761 -289.821684) (xy 273.022984 -289.7739) (xy 273.019024 -289.724846)
			(xy 272.680176 -289.724846) (xy 272.679681 -289.749453) (xy 272.671786 -289.79803) (xy 272.656202 -289.844711)
			(xy 272.633331 -289.888288) (xy 272.603766 -289.927632) (xy 272.568273 -289.961724) (xy 272.52777 -289.98968)
			(xy 272.483308 -290.010778) (xy 272.436037 -290.02447) (xy 272.387182 -290.030402) (xy 272.338007 -290.028421)
			(xy 272.289788 -290.018577) (xy 272.243772 -290.001125) (xy 272.201151 -289.976518) (xy 272.16303 -289.945393)
			(xy 272.130395 -289.908556) (xy 272.104092 -289.86696) (xy 272.084801 -289.821684) (xy 272.073024 -289.7739)
			(xy 272.069064 -289.724846) (xy 271.730216 -289.724846) (xy 271.729721 -289.749453) (xy 271.721826 -289.79803)
			(xy 271.706242 -289.844711) (xy 271.683371 -289.888288) (xy 271.653806 -289.927632) (xy 271.618313 -289.961724)
			(xy 271.57781 -289.98968) (xy 271.533348 -290.010778) (xy 271.486077 -290.02447) (xy 271.437222 -290.030402)
			(xy 271.388047 -290.028421) (xy 271.339828 -290.018577) (xy 271.293812 -290.001125) (xy 271.251191 -289.976518)
			(xy 271.21307 -289.945393) (xy 271.180435 -289.908556) (xy 271.154132 -289.86696) (xy 271.134841 -289.821684)
			(xy 271.123064 -289.7739) (xy 271.119104 -289.724846) (xy 270.780256 -289.724846) (xy 270.779761 -289.749453)
			(xy 270.771866 -289.79803) (xy 270.756282 -289.844711) (xy 270.733411 -289.888288) (xy 270.703846 -289.927632)
			(xy 270.668353 -289.961724) (xy 270.62785 -289.98968) (xy 270.583388 -290.010778) (xy 270.536117 -290.02447)
			(xy 270.487262 -290.030402) (xy 270.438087 -290.028421) (xy 270.389868 -290.018577) (xy 270.343852 -290.001125)
			(xy 270.301231 -289.976518) (xy 270.26311 -289.945393) (xy 270.230475 -289.908556) (xy 270.204172 -289.86696)
			(xy 270.184881 -289.821684) (xy 270.173104 -289.7739) (xy 270.169144 -289.724846) (xy 269.830042 -289.724846)
			(xy 269.829547 -289.749453) (xy 269.821652 -289.79803) (xy 269.806068 -289.844711) (xy 269.783197 -289.888288)
			(xy 269.753632 -289.927632) (xy 269.718139 -289.961724) (xy 269.677636 -289.98968) (xy 269.633174 -290.010778)
			(xy 269.585903 -290.02447) (xy 269.537048 -290.030402) (xy 269.487873 -290.028421) (xy 269.439654 -290.018577)
			(xy 269.393638 -290.001125) (xy 269.351017 -289.976518) (xy 269.312896 -289.945393) (xy 269.280261 -289.908556)
			(xy 269.253958 -289.86696) (xy 269.234667 -289.821684) (xy 269.22289 -289.7739) (xy 269.21893 -289.724846)
			(xy 268.880082 -289.724846) (xy 268.879587 -289.749453) (xy 268.871692 -289.79803) (xy 268.856108 -289.844711)
			(xy 268.833237 -289.888288) (xy 268.803672 -289.927632) (xy 268.768179 -289.961724) (xy 268.727676 -289.98968)
			(xy 268.683214 -290.010778) (xy 268.635943 -290.02447) (xy 268.587088 -290.030402) (xy 268.537913 -290.028421)
			(xy 268.489694 -290.018577) (xy 268.443678 -290.001125) (xy 268.401057 -289.976518) (xy 268.362936 -289.945393)
			(xy 268.330301 -289.908556) (xy 268.303998 -289.86696) (xy 268.284707 -289.821684) (xy 268.27293 -289.7739)
			(xy 268.26897 -289.724846) (xy 266.590526 -289.724846) (xy 266.590526 -290.674806) (xy 268.26897 -290.674806)
			(xy 268.27293 -290.625752) (xy 268.284707 -290.577968) (xy 268.303998 -290.532692) (xy 268.330301 -290.491096)
			(xy 268.362936 -290.454259) (xy 268.401057 -290.423134) (xy 268.443678 -290.398527) (xy 268.489694 -290.381075)
			(xy 268.537913 -290.371231) (xy 268.587088 -290.36925) (xy 268.635943 -290.375182) (xy 268.683214 -290.388874)
			(xy 268.727676 -290.409972) (xy 268.768179 -290.437928) (xy 268.803672 -290.47202) (xy 268.833237 -290.511364)
			(xy 268.856108 -290.554941) (xy 268.871692 -290.601622) (xy 268.879587 -290.650199) (xy 268.880082 -290.674806)
			(xy 269.21893 -290.674806) (xy 269.22289 -290.625752) (xy 269.234667 -290.577968) (xy 269.253958 -290.532692)
			(xy 269.280261 -290.491096) (xy 269.312896 -290.454259) (xy 269.351017 -290.423134) (xy 269.393638 -290.398527)
			(xy 269.439654 -290.381075) (xy 269.487873 -290.371231) (xy 269.537048 -290.36925) (xy 269.585903 -290.375182)
			(xy 269.633174 -290.388874) (xy 269.677636 -290.409972) (xy 269.718139 -290.437928) (xy 269.753632 -290.47202)
			(xy 269.783197 -290.511364) (xy 269.806068 -290.554941) (xy 269.821652 -290.601622) (xy 269.829547 -290.650199)
			(xy 269.830042 -290.674806) (xy 270.169144 -290.674806) (xy 270.173104 -290.625752) (xy 270.184881 -290.577968)
			(xy 270.204172 -290.532692) (xy 270.230475 -290.491096) (xy 270.26311 -290.454259) (xy 270.301231 -290.423134)
			(xy 270.343852 -290.398527) (xy 270.389868 -290.381075) (xy 270.438087 -290.371231) (xy 270.487262 -290.36925)
			(xy 270.536117 -290.375182) (xy 270.583388 -290.388874) (xy 270.62785 -290.409972) (xy 270.668353 -290.437928)
			(xy 270.703846 -290.47202) (xy 270.733411 -290.511364) (xy 270.756282 -290.554941) (xy 270.771866 -290.601622)
			(xy 270.779761 -290.650199) (xy 270.780256 -290.674806) (xy 273.019024 -290.674806) (xy 273.022984 -290.625752)
			(xy 273.034761 -290.577968) (xy 273.054052 -290.532692) (xy 273.080355 -290.491096) (xy 273.11299 -290.454259)
			(xy 273.151111 -290.423134) (xy 273.193732 -290.398527) (xy 273.239748 -290.381075) (xy 273.287967 -290.371231)
			(xy 273.337142 -290.36925) (xy 273.385997 -290.375182) (xy 273.433268 -290.388874) (xy 273.47773 -290.409972)
			(xy 273.518233 -290.437928) (xy 273.553726 -290.47202) (xy 273.583291 -290.511364) (xy 273.606162 -290.554941)
			(xy 273.621746 -290.601622) (xy 273.629641 -290.650199) (xy 273.630136 -290.674806) (xy 273.968984 -290.674806)
			(xy 273.972944 -290.625752) (xy 273.984721 -290.577968) (xy 274.004012 -290.532692) (xy 274.030315 -290.491096)
			(xy 274.06295 -290.454259) (xy 274.101071 -290.423134) (xy 274.143692 -290.398527) (xy 274.189708 -290.381075)
			(xy 274.237927 -290.371231) (xy 274.287102 -290.36925) (xy 274.335957 -290.375182) (xy 274.383228 -290.388874)
			(xy 274.42769 -290.409972) (xy 274.468193 -290.437928) (xy 274.503686 -290.47202) (xy 274.533251 -290.511364)
			(xy 274.556122 -290.554941) (xy 274.571706 -290.601622) (xy 274.579601 -290.650199) (xy 274.580096 -290.674806)
			(xy 274.579601 -290.699413) (xy 274.571706 -290.74799) (xy 274.556122 -290.794671) (xy 274.533251 -290.838248)
			(xy 274.503686 -290.877592) (xy 274.468193 -290.911684) (xy 274.42769 -290.93964) (xy 274.383228 -290.960738)
			(xy 274.335957 -290.97443) (xy 274.287102 -290.980362) (xy 274.237927 -290.978381) (xy 274.189708 -290.968537)
			(xy 274.143692 -290.951085) (xy 274.101071 -290.926478) (xy 274.06295 -290.895353) (xy 274.030315 -290.858516)
			(xy 274.004012 -290.81692) (xy 273.984721 -290.771644) (xy 273.972944 -290.72386) (xy 273.968984 -290.674806)
			(xy 273.630136 -290.674806) (xy 273.629641 -290.699413) (xy 273.621746 -290.74799) (xy 273.606162 -290.794671)
			(xy 273.583291 -290.838248) (xy 273.553726 -290.877592) (xy 273.518233 -290.911684) (xy 273.47773 -290.93964)
			(xy 273.433268 -290.960738) (xy 273.385997 -290.97443) (xy 273.337142 -290.980362) (xy 273.287967 -290.978381)
			(xy 273.239748 -290.968537) (xy 273.193732 -290.951085) (xy 273.151111 -290.926478) (xy 273.11299 -290.895353)
			(xy 273.080355 -290.858516) (xy 273.054052 -290.81692) (xy 273.034761 -290.771644) (xy 273.022984 -290.72386)
			(xy 273.019024 -290.674806) (xy 270.780256 -290.674806) (xy 270.779761 -290.699413) (xy 270.771866 -290.74799)
			(xy 270.756282 -290.794671) (xy 270.733411 -290.838248) (xy 270.703846 -290.877592) (xy 270.668353 -290.911684)
			(xy 270.62785 -290.93964) (xy 270.583388 -290.960738) (xy 270.536117 -290.97443) (xy 270.487262 -290.980362)
			(xy 270.438087 -290.978381) (xy 270.389868 -290.968537) (xy 270.343852 -290.951085) (xy 270.301231 -290.926478)
			(xy 270.26311 -290.895353) (xy 270.230475 -290.858516) (xy 270.204172 -290.81692) (xy 270.184881 -290.771644)
			(xy 270.173104 -290.72386) (xy 270.169144 -290.674806) (xy 269.830042 -290.674806) (xy 269.829547 -290.699413)
			(xy 269.821652 -290.74799) (xy 269.806068 -290.794671) (xy 269.783197 -290.838248) (xy 269.753632 -290.877592)
			(xy 269.718139 -290.911684) (xy 269.677636 -290.93964) (xy 269.633174 -290.960738) (xy 269.585903 -290.97443)
			(xy 269.537048 -290.980362) (xy 269.487873 -290.978381) (xy 269.439654 -290.968537) (xy 269.393638 -290.951085)
			(xy 269.351017 -290.926478) (xy 269.312896 -290.895353) (xy 269.280261 -290.858516) (xy 269.253958 -290.81692)
			(xy 269.234667 -290.771644) (xy 269.22289 -290.72386) (xy 269.21893 -290.674806) (xy 268.880082 -290.674806)
			(xy 268.879587 -290.699413) (xy 268.871692 -290.74799) (xy 268.856108 -290.794671) (xy 268.833237 -290.838248)
			(xy 268.803672 -290.877592) (xy 268.768179 -290.911684) (xy 268.727676 -290.93964) (xy 268.683214 -290.960738)
			(xy 268.635943 -290.97443) (xy 268.587088 -290.980362) (xy 268.537913 -290.978381) (xy 268.489694 -290.968537)
			(xy 268.443678 -290.951085) (xy 268.401057 -290.926478) (xy 268.362936 -290.895353) (xy 268.330301 -290.858516)
			(xy 268.303998 -290.81692) (xy 268.284707 -290.771644) (xy 268.27293 -290.72386) (xy 268.26897 -290.674806)
			(xy 266.590526 -290.674806) (xy 266.590526 -291.624766) (xy 268.26897 -291.624766) (xy 268.27293 -291.575712)
			(xy 268.284707 -291.527928) (xy 268.303998 -291.482652) (xy 268.330301 -291.441056) (xy 268.362936 -291.404219)
			(xy 268.401057 -291.373094) (xy 268.443678 -291.348487) (xy 268.489694 -291.331035) (xy 268.537913 -291.321191)
			(xy 268.587088 -291.31921) (xy 268.635943 -291.325142) (xy 268.683214 -291.338834) (xy 268.727676 -291.359932)
			(xy 268.768179 -291.387888) (xy 268.803672 -291.42198) (xy 268.833237 -291.461324) (xy 268.856108 -291.504901)
			(xy 268.871692 -291.551582) (xy 268.879587 -291.600159) (xy 268.880082 -291.624766) (xy 269.21893 -291.624766)
			(xy 269.22289 -291.575712) (xy 269.234667 -291.527928) (xy 269.253958 -291.482652) (xy 269.280261 -291.441056)
			(xy 269.312896 -291.404219) (xy 269.351017 -291.373094) (xy 269.393638 -291.348487) (xy 269.439654 -291.331035)
			(xy 269.487873 -291.321191) (xy 269.537048 -291.31921) (xy 269.585903 -291.325142) (xy 269.633174 -291.338834)
			(xy 269.677636 -291.359932) (xy 269.718139 -291.387888) (xy 269.753632 -291.42198) (xy 269.783197 -291.461324)
			(xy 269.806068 -291.504901) (xy 269.821652 -291.551582) (xy 269.829547 -291.600159) (xy 269.830042 -291.624766)
			(xy 270.169144 -291.624766) (xy 270.173104 -291.575712) (xy 270.184881 -291.527928) (xy 270.204172 -291.482652)
			(xy 270.230475 -291.441056) (xy 270.26311 -291.404219) (xy 270.301231 -291.373094) (xy 270.343852 -291.348487)
			(xy 270.389868 -291.331035) (xy 270.438087 -291.321191) (xy 270.487262 -291.31921) (xy 270.536117 -291.325142)
			(xy 270.583388 -291.338834) (xy 270.62785 -291.359932) (xy 270.668353 -291.387888) (xy 270.703846 -291.42198)
			(xy 270.733411 -291.461324) (xy 270.756282 -291.504901) (xy 270.771866 -291.551582) (xy 270.779761 -291.600159)
			(xy 270.780256 -291.624766) (xy 273.019024 -291.624766) (xy 273.022984 -291.575712) (xy 273.034761 -291.527928)
			(xy 273.054052 -291.482652) (xy 273.080355 -291.441056) (xy 273.11299 -291.404219) (xy 273.151111 -291.373094)
			(xy 273.193732 -291.348487) (xy 273.239748 -291.331035) (xy 273.287967 -291.321191) (xy 273.337142 -291.31921)
			(xy 273.385997 -291.325142) (xy 273.433268 -291.338834) (xy 273.47773 -291.359932) (xy 273.518233 -291.387888)
			(xy 273.553726 -291.42198) (xy 273.583291 -291.461324) (xy 273.606162 -291.504901) (xy 273.621746 -291.551582)
			(xy 273.629641 -291.600159) (xy 273.630136 -291.624766) (xy 273.968984 -291.624766) (xy 273.972944 -291.575712)
			(xy 273.984721 -291.527928) (xy 274.004012 -291.482652) (xy 274.030315 -291.441056) (xy 274.06295 -291.404219)
			(xy 274.101071 -291.373094) (xy 274.143692 -291.348487) (xy 274.189708 -291.331035) (xy 274.237927 -291.321191)
			(xy 274.287102 -291.31921) (xy 274.335957 -291.325142) (xy 274.383228 -291.338834) (xy 274.42769 -291.359932)
			(xy 274.468193 -291.387888) (xy 274.503686 -291.42198) (xy 274.533251 -291.461324) (xy 274.556122 -291.504901)
			(xy 274.571706 -291.551582) (xy 274.579601 -291.600159) (xy 274.580096 -291.624766) (xy 274.579601 -291.649373)
			(xy 274.571706 -291.69795) (xy 274.556122 -291.744631) (xy 274.533251 -291.788208) (xy 274.503686 -291.827552)
			(xy 274.468193 -291.861644) (xy 274.42769 -291.8896) (xy 274.383228 -291.910698) (xy 274.335957 -291.92439)
			(xy 274.287102 -291.930322) (xy 274.237927 -291.928341) (xy 274.189708 -291.918497) (xy 274.143692 -291.901045)
			(xy 274.101071 -291.876438) (xy 274.06295 -291.845313) (xy 274.030315 -291.808476) (xy 274.004012 -291.76688)
			(xy 273.984721 -291.721604) (xy 273.972944 -291.67382) (xy 273.968984 -291.624766) (xy 273.630136 -291.624766)
			(xy 273.629641 -291.649373) (xy 273.621746 -291.69795) (xy 273.606162 -291.744631) (xy 273.583291 -291.788208)
			(xy 273.553726 -291.827552) (xy 273.518233 -291.861644) (xy 273.47773 -291.8896) (xy 273.433268 -291.910698)
			(xy 273.385997 -291.92439) (xy 273.337142 -291.930322) (xy 273.287967 -291.928341) (xy 273.239748 -291.918497)
			(xy 273.193732 -291.901045) (xy 273.151111 -291.876438) (xy 273.11299 -291.845313) (xy 273.080355 -291.808476)
			(xy 273.054052 -291.76688) (xy 273.034761 -291.721604) (xy 273.022984 -291.67382) (xy 273.019024 -291.624766)
			(xy 270.780256 -291.624766) (xy 270.779761 -291.649373) (xy 270.771866 -291.69795) (xy 270.756282 -291.744631)
			(xy 270.733411 -291.788208) (xy 270.703846 -291.827552) (xy 270.668353 -291.861644) (xy 270.62785 -291.8896)
			(xy 270.583388 -291.910698) (xy 270.536117 -291.92439) (xy 270.487262 -291.930322) (xy 270.438087 -291.928341)
			(xy 270.389868 -291.918497) (xy 270.343852 -291.901045) (xy 270.301231 -291.876438) (xy 270.26311 -291.845313)
			(xy 270.230475 -291.808476) (xy 270.204172 -291.76688) (xy 270.184881 -291.721604) (xy 270.173104 -291.67382)
			(xy 270.169144 -291.624766) (xy 269.830042 -291.624766) (xy 269.829547 -291.649373) (xy 269.821652 -291.69795)
			(xy 269.806068 -291.744631) (xy 269.783197 -291.788208) (xy 269.753632 -291.827552) (xy 269.718139 -291.861644)
			(xy 269.677636 -291.8896) (xy 269.633174 -291.910698) (xy 269.585903 -291.92439) (xy 269.537048 -291.930322)
			(xy 269.487873 -291.928341) (xy 269.439654 -291.918497) (xy 269.393638 -291.901045) (xy 269.351017 -291.876438)
			(xy 269.312896 -291.845313) (xy 269.280261 -291.808476) (xy 269.253958 -291.76688) (xy 269.234667 -291.721604)
			(xy 269.22289 -291.67382) (xy 269.21893 -291.624766) (xy 268.880082 -291.624766) (xy 268.879587 -291.649373)
			(xy 268.871692 -291.69795) (xy 268.856108 -291.744631) (xy 268.833237 -291.788208) (xy 268.803672 -291.827552)
			(xy 268.768179 -291.861644) (xy 268.727676 -291.8896) (xy 268.683214 -291.910698) (xy 268.635943 -291.92439)
			(xy 268.587088 -291.930322) (xy 268.537913 -291.928341) (xy 268.489694 -291.918497) (xy 268.443678 -291.901045)
			(xy 268.401057 -291.876438) (xy 268.362936 -291.845313) (xy 268.330301 -291.808476) (xy 268.303998 -291.76688)
			(xy 268.284707 -291.721604) (xy 268.27293 -291.67382) (xy 268.26897 -291.624766) (xy 266.590526 -291.624766)
			(xy 266.590526 -292.57498) (xy 268.26897 -292.57498) (xy 268.27293 -292.525926) (xy 268.284707 -292.478142)
			(xy 268.303998 -292.432866) (xy 268.330301 -292.39127) (xy 268.362936 -292.354433) (xy 268.401057 -292.323308)
			(xy 268.443678 -292.298701) (xy 268.489694 -292.281249) (xy 268.537913 -292.271405) (xy 268.587088 -292.269424)
			(xy 268.635943 -292.275356) (xy 268.683214 -292.289048) (xy 268.727676 -292.310146) (xy 268.768179 -292.338102)
			(xy 268.803672 -292.372194) (xy 268.833237 -292.411538) (xy 268.856108 -292.455115) (xy 268.871692 -292.501796)
			(xy 268.879587 -292.550373) (xy 268.880082 -292.57498) (xy 269.21893 -292.57498) (xy 269.22289 -292.525926)
			(xy 269.234667 -292.478142) (xy 269.253958 -292.432866) (xy 269.280261 -292.39127) (xy 269.312896 -292.354433)
			(xy 269.351017 -292.323308) (xy 269.393638 -292.298701) (xy 269.439654 -292.281249) (xy 269.487873 -292.271405)
			(xy 269.537048 -292.269424) (xy 269.585903 -292.275356) (xy 269.633174 -292.289048) (xy 269.677636 -292.310146)
			(xy 269.718139 -292.338102) (xy 269.753632 -292.372194) (xy 269.783197 -292.411538) (xy 269.806068 -292.455115)
			(xy 269.821652 -292.501796) (xy 269.829547 -292.550373) (xy 269.830042 -292.57498) (xy 270.169144 -292.57498)
			(xy 270.173104 -292.525926) (xy 270.184881 -292.478142) (xy 270.204172 -292.432866) (xy 270.230475 -292.39127)
			(xy 270.26311 -292.354433) (xy 270.301231 -292.323308) (xy 270.343852 -292.298701) (xy 270.389868 -292.281249)
			(xy 270.438087 -292.271405) (xy 270.487262 -292.269424) (xy 270.536117 -292.275356) (xy 270.583388 -292.289048)
			(xy 270.62785 -292.310146) (xy 270.668353 -292.338102) (xy 270.703846 -292.372194) (xy 270.733411 -292.411538)
			(xy 270.756282 -292.455115) (xy 270.771866 -292.501796) (xy 270.779761 -292.550373) (xy 270.780251 -292.574726)
			(xy 271.119104 -292.574726) (xy 271.123064 -292.525672) (xy 271.134841 -292.477888) (xy 271.154132 -292.432612)
			(xy 271.180435 -292.391016) (xy 271.21307 -292.354179) (xy 271.251191 -292.323054) (xy 271.293812 -292.298447)
			(xy 271.339828 -292.280995) (xy 271.388047 -292.271151) (xy 271.437222 -292.26917) (xy 271.486077 -292.275102)
			(xy 271.533348 -292.288794) (xy 271.57781 -292.309892) (xy 271.618313 -292.337848) (xy 271.653806 -292.37194)
			(xy 271.683371 -292.411284) (xy 271.706242 -292.454861) (xy 271.721826 -292.501542) (xy 271.729721 -292.550119)
			(xy 271.730216 -292.574726) (xy 272.069064 -292.574726) (xy 272.073024 -292.525672) (xy 272.084801 -292.477888)
			(xy 272.104092 -292.432612) (xy 272.130395 -292.391016) (xy 272.16303 -292.354179) (xy 272.201151 -292.323054)
			(xy 272.243772 -292.298447) (xy 272.289788 -292.280995) (xy 272.338007 -292.271151) (xy 272.387182 -292.26917)
			(xy 272.436037 -292.275102) (xy 272.483308 -292.288794) (xy 272.52777 -292.309892) (xy 272.568273 -292.337848)
			(xy 272.603766 -292.37194) (xy 272.633331 -292.411284) (xy 272.656202 -292.454861) (xy 272.671786 -292.501542)
			(xy 272.679681 -292.550119) (xy 272.680176 -292.574726) (xy 272.680171 -292.57498) (xy 273.019024 -292.57498)
			(xy 273.022984 -292.525926) (xy 273.034761 -292.478142) (xy 273.054052 -292.432866) (xy 273.080355 -292.39127)
			(xy 273.11299 -292.354433) (xy 273.151111 -292.323308) (xy 273.193732 -292.298701) (xy 273.239748 -292.281249)
			(xy 273.287967 -292.271405) (xy 273.337142 -292.269424) (xy 273.385997 -292.275356) (xy 273.433268 -292.289048)
			(xy 273.47773 -292.310146) (xy 273.518233 -292.338102) (xy 273.553726 -292.372194) (xy 273.583291 -292.411538)
			(xy 273.606162 -292.455115) (xy 273.621746 -292.501796) (xy 273.629641 -292.550373) (xy 273.630136 -292.57498)
			(xy 273.629641 -292.599587) (xy 273.629309 -292.601629) (xy 273.919178 -292.601629) (xy 273.919178 -292.548331)
			(xy 273.927121 -292.495627) (xy 273.942831 -292.444697) (xy 273.965957 -292.396676) (xy 273.995981 -292.352639)
			(xy 274.032233 -292.313568) (xy 274.073904 -292.280337) (xy 274.120062 -292.253688) (xy 274.169676 -292.234216)
			(xy 274.221638 -292.222356) (xy 274.274788 -292.218373) (xy 274.327938 -292.222356) (xy 274.3799 -292.234216)
			(xy 274.429514 -292.253688) (xy 274.475672 -292.280337) (xy 274.517343 -292.313568) (xy 274.553595 -292.352639)
			(xy 274.583619 -292.396676) (xy 274.606745 -292.444697) (xy 274.622455 -292.495627) (xy 274.630398 -292.548331)
			(xy 274.630896 -292.57498) (xy 274.630398 -292.601629) (xy 274.622455 -292.654333) (xy 274.606745 -292.705263)
			(xy 274.583619 -292.753284) (xy 274.553595 -292.797321) (xy 274.517343 -292.836392) (xy 274.475672 -292.869623)
			(xy 274.429514 -292.896272) (xy 274.3799 -292.915744) (xy 274.327938 -292.927604) (xy 274.274788 -292.931588)
			(xy 274.221638 -292.927604) (xy 274.169676 -292.915744) (xy 274.120062 -292.896272) (xy 274.073904 -292.869623)
			(xy 274.032233 -292.836392) (xy 273.995981 -292.797321) (xy 273.965957 -292.753284) (xy 273.942831 -292.705263)
			(xy 273.927121 -292.654333) (xy 273.919178 -292.601629) (xy 273.629309 -292.601629) (xy 273.621746 -292.648164)
			(xy 273.606162 -292.694845) (xy 273.583291 -292.738422) (xy 273.553726 -292.777766) (xy 273.518233 -292.811858)
			(xy 273.47773 -292.839814) (xy 273.433268 -292.860912) (xy 273.385997 -292.874604) (xy 273.337142 -292.880536)
			(xy 273.287967 -292.878555) (xy 273.239748 -292.868711) (xy 273.193732 -292.851259) (xy 273.151111 -292.826652)
			(xy 273.11299 -292.795527) (xy 273.080355 -292.75869) (xy 273.054052 -292.717094) (xy 273.034761 -292.671818)
			(xy 273.022984 -292.624034) (xy 273.019024 -292.57498) (xy 272.680171 -292.57498) (xy 272.679681 -292.599333)
			(xy 272.671786 -292.64791) (xy 272.656202 -292.694591) (xy 272.633331 -292.738168) (xy 272.603766 -292.777512)
			(xy 272.568273 -292.811604) (xy 272.52777 -292.83956) (xy 272.483308 -292.860658) (xy 272.436037 -292.87435)
			(xy 272.387182 -292.880282) (xy 272.338007 -292.878301) (xy 272.289788 -292.868457) (xy 272.243772 -292.851005)
			(xy 272.201151 -292.826398) (xy 272.16303 -292.795273) (xy 272.130395 -292.758436) (xy 272.104092 -292.71684)
			(xy 272.084801 -292.671564) (xy 272.073024 -292.62378) (xy 272.069064 -292.574726) (xy 271.730216 -292.574726)
			(xy 271.729721 -292.599333) (xy 271.721826 -292.64791) (xy 271.706242 -292.694591) (xy 271.683371 -292.738168)
			(xy 271.653806 -292.777512) (xy 271.618313 -292.811604) (xy 271.57781 -292.83956) (xy 271.533348 -292.860658)
			(xy 271.486077 -292.87435) (xy 271.437222 -292.880282) (xy 271.388047 -292.878301) (xy 271.339828 -292.868457)
			(xy 271.293812 -292.851005) (xy 271.251191 -292.826398) (xy 271.21307 -292.795273) (xy 271.180435 -292.758436)
			(xy 271.154132 -292.71684) (xy 271.134841 -292.671564) (xy 271.123064 -292.62378) (xy 271.119104 -292.574726)
			(xy 270.780251 -292.574726) (xy 270.780256 -292.57498) (xy 270.779761 -292.599587) (xy 270.771866 -292.648164)
			(xy 270.756282 -292.694845) (xy 270.733411 -292.738422) (xy 270.703846 -292.777766) (xy 270.668353 -292.811858)
			(xy 270.62785 -292.839814) (xy 270.583388 -292.860912) (xy 270.536117 -292.874604) (xy 270.487262 -292.880536)
			(xy 270.438087 -292.878555) (xy 270.389868 -292.868711) (xy 270.343852 -292.851259) (xy 270.301231 -292.826652)
			(xy 270.26311 -292.795527) (xy 270.230475 -292.75869) (xy 270.204172 -292.717094) (xy 270.184881 -292.671818)
			(xy 270.173104 -292.624034) (xy 270.169144 -292.57498) (xy 269.830042 -292.57498) (xy 269.829547 -292.599587)
			(xy 269.821652 -292.648164) (xy 269.806068 -292.694845) (xy 269.783197 -292.738422) (xy 269.753632 -292.777766)
			(xy 269.718139 -292.811858) (xy 269.677636 -292.839814) (xy 269.633174 -292.860912) (xy 269.585903 -292.874604)
			(xy 269.537048 -292.880536) (xy 269.487873 -292.878555) (xy 269.439654 -292.868711) (xy 269.393638 -292.851259)
			(xy 269.351017 -292.826652) (xy 269.312896 -292.795527) (xy 269.280261 -292.75869) (xy 269.253958 -292.717094)
			(xy 269.234667 -292.671818) (xy 269.22289 -292.624034) (xy 269.21893 -292.57498) (xy 268.880082 -292.57498)
			(xy 268.879587 -292.599587) (xy 268.871692 -292.648164) (xy 268.856108 -292.694845) (xy 268.833237 -292.738422)
			(xy 268.803672 -292.777766) (xy 268.768179 -292.811858) (xy 268.727676 -292.839814) (xy 268.683214 -292.860912)
			(xy 268.635943 -292.874604) (xy 268.587088 -292.880536) (xy 268.537913 -292.878555) (xy 268.489694 -292.868711)
			(xy 268.443678 -292.851259) (xy 268.401057 -292.826652) (xy 268.362936 -292.795527) (xy 268.330301 -292.75869)
			(xy 268.303998 -292.717094) (xy 268.284707 -292.671818) (xy 268.27293 -292.624034) (xy 268.26897 -292.57498)
			(xy 266.590526 -292.57498) (xy 266.590526 -293.52494) (xy 270.169144 -293.52494) (xy 270.173104 -293.475886)
			(xy 270.184881 -293.428102) (xy 270.204172 -293.382826) (xy 270.230475 -293.34123) (xy 270.26311 -293.304393)
			(xy 270.301231 -293.273268) (xy 270.343852 -293.248661) (xy 270.389868 -293.231209) (xy 270.438087 -293.221365)
			(xy 270.487262 -293.219384) (xy 270.536117 -293.225316) (xy 270.583388 -293.239008) (xy 270.62785 -293.260106)
			(xy 270.668353 -293.288062) (xy 270.703846 -293.322154) (xy 270.733411 -293.361498) (xy 270.756282 -293.405075)
			(xy 270.771866 -293.451756) (xy 270.779761 -293.500333) (xy 270.780256 -293.52494) (xy 271.119104 -293.52494)
			(xy 271.123064 -293.475886) (xy 271.134841 -293.428102) (xy 271.154132 -293.382826) (xy 271.180435 -293.34123)
			(xy 271.21307 -293.304393) (xy 271.251191 -293.273268) (xy 271.293812 -293.248661) (xy 271.339828 -293.231209)
			(xy 271.388047 -293.221365) (xy 271.437222 -293.219384) (xy 271.486077 -293.225316) (xy 271.533348 -293.239008)
			(xy 271.57781 -293.260106) (xy 271.618313 -293.288062) (xy 271.653806 -293.322154) (xy 271.683371 -293.361498)
			(xy 271.706242 -293.405075) (xy 271.721826 -293.451756) (xy 271.729721 -293.500333) (xy 271.730216 -293.52494)
			(xy 272.069064 -293.52494) (xy 272.073024 -293.475886) (xy 272.084801 -293.428102) (xy 272.104092 -293.382826)
			(xy 272.130395 -293.34123) (xy 272.16303 -293.304393) (xy 272.201151 -293.273268) (xy 272.243772 -293.248661)
			(xy 272.289788 -293.231209) (xy 272.338007 -293.221365) (xy 272.387182 -293.219384) (xy 272.436037 -293.225316)
			(xy 272.483308 -293.239008) (xy 272.52777 -293.260106) (xy 272.568273 -293.288062) (xy 272.603766 -293.322154)
			(xy 272.633331 -293.361498) (xy 272.656202 -293.405075) (xy 272.671786 -293.451756) (xy 272.679681 -293.500333)
			(xy 272.680176 -293.52494) (xy 273.019024 -293.52494) (xy 273.022984 -293.475886) (xy 273.034761 -293.428102)
			(xy 273.054052 -293.382826) (xy 273.080355 -293.34123) (xy 273.11299 -293.304393) (xy 273.151111 -293.273268)
			(xy 273.193732 -293.248661) (xy 273.239748 -293.231209) (xy 273.287967 -293.221365) (xy 273.337142 -293.219384)
			(xy 273.385997 -293.225316) (xy 273.433268 -293.239008) (xy 273.47773 -293.260106) (xy 273.518233 -293.288062)
			(xy 273.553726 -293.322154) (xy 273.583291 -293.361498) (xy 273.606162 -293.405075) (xy 273.621746 -293.451756)
			(xy 273.629641 -293.500333) (xy 273.630136 -293.52494) (xy 273.968984 -293.52494) (xy 273.972944 -293.475886)
			(xy 273.984721 -293.428102) (xy 274.004012 -293.382826) (xy 274.030315 -293.34123) (xy 274.06295 -293.304393)
			(xy 274.101071 -293.273268) (xy 274.143692 -293.248661) (xy 274.189708 -293.231209) (xy 274.237927 -293.221365)
			(xy 274.287102 -293.219384) (xy 274.335957 -293.225316) (xy 274.383228 -293.239008) (xy 274.42769 -293.260106)
			(xy 274.468193 -293.288062) (xy 274.503686 -293.322154) (xy 274.533251 -293.361498) (xy 274.556122 -293.405075)
			(xy 274.571706 -293.451756) (xy 274.579601 -293.500333) (xy 274.580096 -293.524923) (xy 274.867746 -293.524923)
			(xy 274.871602 -293.472579) (xy 274.883091 -293.421365) (xy 274.901967 -293.37239) (xy 274.92782 -293.326713)
			(xy 274.960092 -293.28532) (xy 274.998084 -293.249108) (xy 275.019262 -293.233602) (xy 275.028833 -293.226019)
			(xy 275.040094 -293.204389) (xy 275.040852 -293.1922) (xy 275.040852 -292.930834) (xy 275.041088 -292.913355)
			(xy 275.044911 -292.878606) (xy 275.048472 -292.861492) (xy 275.050108 -292.852274) (xy 275.047343 -292.833772)
			(xy 275.038143 -292.817482) (xy 275.0312 -292.8112) (xy 275.012487 -292.795275) (xy 274.979954 -292.758452)
			(xy 274.953737 -292.716896) (xy 274.934513 -292.671677) (xy 274.922777 -292.623964) (xy 274.918832 -292.574987)
			(xy 274.922781 -292.526011) (xy 274.934521 -292.478299) (xy 274.953749 -292.433082) (xy 274.97997 -292.391528)
			(xy 275.012506 -292.354708) (xy 275.0312 -292.33876) (xy 275.038198 -292.332525) (xy 275.047421 -292.316225)
			(xy 275.050134 -292.297694) (xy 275.048472 -292.288468) (xy 275.044909 -292.271355) (xy 275.041095 -292.236605)
			(xy 275.040852 -292.219126) (xy 275.040852 -291.98062) (xy 275.041102 -291.963141) (xy 275.044916 -291.928393)
			(xy 275.048472 -291.911278) (xy 275.050039 -291.902051) (xy 275.047302 -291.883559) (xy 275.038131 -291.867271)
			(xy 275.0312 -291.860986) (xy 275.012473 -291.845076) (xy 274.97994 -291.808252) (xy 274.953724 -291.766693)
			(xy 274.9345 -291.721472) (xy 274.922765 -291.673757) (xy 274.918821 -291.624778) (xy 274.922772 -291.5758)
			(xy 274.934513 -291.528087) (xy 274.953744 -291.482869) (xy 274.979966 -291.441314) (xy 275.012505 -291.404494)
			(xy 275.0312 -291.388546) (xy 275.038144 -291.382259) (xy 275.04738 -291.365985) (xy 275.050118 -291.347474)
			(xy 275.048472 -291.338254) (xy 275.044922 -291.321138) (xy 275.041099 -291.28639) (xy 275.040852 -291.268912)
			(xy 275.040852 -291.03066) (xy 275.041092 -291.013181) (xy 275.044913 -290.978432) (xy 275.048472 -290.961318)
			(xy 275.050087 -290.952097) (xy 275.047331 -290.933598) (xy 275.03814 -290.917309) (xy 275.0312 -290.911026)
			(xy 275.012513 -290.895071) (xy 274.97998 -290.858253) (xy 274.953763 -290.816701) (xy 274.934537 -290.771487)
			(xy 274.922799 -290.723777) (xy 274.918852 -290.674804) (xy 274.922798 -290.62583) (xy 274.934535 -290.578121)
			(xy 274.953759 -290.532906) (xy 274.979976 -290.491353) (xy 275.012508 -290.454534) (xy 275.0312 -290.438586)
			(xy 275.038182 -290.432335) (xy 275.047408 -290.416043) (xy 275.050129 -290.397518) (xy 275.048472 -290.388294)
			(xy 275.044913 -290.37118) (xy 275.041096 -290.336431) (xy 275.040852 -290.318952) (xy 275.040852 -290.192206)
			(xy 275.040997 -290.187113) (xy 275.043045 -290.177133) (xy 275.044916 -290.172394) (xy 275.052028 -290.155122)
			(xy 275.05393 -290.150392) (xy 275.055978 -290.140407) (xy 275.056092 -290.13531) (xy 275.056092 -290.005008)
			(xy 275.055519 -289.99344) (xy 275.045327 -289.972669) (xy 275.036534 -289.96513) (xy 275.018633 -289.950575)
			(xy 274.986993 -289.916997) (xy 274.960768 -289.879039) (xy 274.940557 -289.837566) (xy 274.926818 -289.793523)
			(xy 274.919866 -289.747914) (xy 274.91944 -289.724846) (xy 274.919947 -289.700042) (xy 274.927954 -289.651084)
			(xy 274.943766 -289.604063) (xy 274.966966 -289.560214) (xy 274.996946 -289.520689) (xy 275.032917 -289.486527)
			(xy 275.073934 -289.458625) (xy 275.096224 -289.447732) (xy 275.10458 -289.443493) (xy 275.117663 -289.430101)
			(xy 275.125007 -289.41288) (xy 275.125688 -289.403536) (xy 275.126944 -289.379455) (xy 275.135808 -289.332057)
			(xy 275.151649 -289.286514) (xy 275.17411 -289.243845) (xy 275.20269 -289.205008) (xy 275.219414 -289.187636)
			(xy 275.224494 -289.182556) (xy 275.239226 -289.168586) (xy 275.24456 -289.163506) (xy 275.250406 -289.156033)
			(xy 275.256684 -289.138146) (xy 275.256035 -289.119201) (xy 275.248546 -289.101786) (xy 275.235241 -289.088283)
			(xy 275.21794 -289.080537) (xy 275.208492 -289.079686) (xy 275.182807 -289.077741) (xy 275.132561 -289.066428)
			(xy 275.084928 -289.04684) (xy 275.041259 -289.019534) (xy 275.002793 -288.985284) (xy 274.970624 -288.945063)
			(xy 274.945662 -288.900013) (xy 274.928618 -288.851411) (xy 274.919974 -288.800638) (xy 274.91944 -288.774886)
			(xy 274.919962 -288.749631) (xy 274.928275 -288.699809) (xy 274.944676 -288.652035) (xy 274.968717 -288.607612)
			(xy 274.999741 -288.567752) (xy 275.036903 -288.533542) (xy 275.079189 -288.505916) (xy 275.125445 -288.485626)
			(xy 275.17441 -288.473226) (xy 275.224748 -288.469055) (xy 275.275086 -288.473226) (xy 275.324051 -288.485626)
			(xy 275.370307 -288.505916) (xy 275.412593 -288.533542) (xy 275.449755 -288.567752) (xy 275.480779 -288.607612)
			(xy 275.50482 -288.652035) (xy 275.521221 -288.699809) (xy 275.529534 -288.749631) (xy 275.530056 -288.774886)
			(xy 275.529431 -288.802726) (xy 275.519349 -288.857487) (xy 275.499533 -288.909522) (xy 275.485606 -288.933636)
			(xy 275.481228 -288.941507) (xy 275.477684 -288.95915) (xy 275.480497 -288.976923) (xy 275.48459 -288.984944)
			(xy 275.528024 -289.06216) (xy 275.532673 -289.06986) (xy 275.546352 -289.08153) (xy 275.563229 -289.087729)
			(xy 275.57222 -289.088068) (xy 275.833078 -289.088068) (xy 275.861506 -289.088727) (xy 275.917462 -289.098822)
			(xy 275.94433 -289.108134) (xy 275.95428 -289.111322) (xy 275.975124 -289.110283) (xy 275.993832 -289.101034)
			(xy 276.007312 -289.085102) (xy 276.013337 -289.06512) (xy 276.010911 -289.044392) (xy 276.000434 -289.026342)
			(xy 275.992336 -289.019742) (xy 275.9736 -289.005237) (xy 275.94043 -288.971404) (xy 275.912884 -288.932853)
			(xy 275.891626 -288.890509) (xy 275.877164 -288.845389) (xy 275.869846 -288.798576) (xy 275.8694 -288.774886)
			(xy 275.869922 -288.749631) (xy 275.878235 -288.699809) (xy 275.894636 -288.652035) (xy 275.918677 -288.607612)
			(xy 275.949701 -288.567752) (xy 275.986863 -288.533542) (xy 276.029149 -288.505916) (xy 276.075405 -288.485626)
			(xy 276.12437 -288.473226) (xy 276.174708 -288.469055) (xy 276.225046 -288.473226) (xy 276.274011 -288.485626)
			(xy 276.320267 -288.505916) (xy 276.362553 -288.533542) (xy 276.399715 -288.567752) (xy 276.430739 -288.607612)
			(xy 276.45478 -288.652035) (xy 276.471181 -288.699809) (xy 276.479494 -288.749631) (xy 276.480016 -288.774886)
			(xy 276.479557 -288.798576) (xy 276.47224 -288.845386) (xy 276.457779 -288.890505) (xy 276.436522 -288.932848)
			(xy 276.408979 -288.971399) (xy 276.375811 -289.005232) (xy 276.35708 -289.019742) (xy 276.348934 -289.026273)
			(xy 276.338491 -289.04434) (xy 276.336089 -289.065069) (xy 276.342123 -289.085045) (xy 276.355598 -289.100977)
			(xy 276.374296 -289.110243) (xy 276.395136 -289.111314) (xy 276.405086 -289.108134) (xy 276.431952 -289.098814)
			(xy 276.487909 -289.08872) (xy 276.516338 -289.088068) (xy 276.783292 -289.088068) (xy 276.81172 -289.088723)
			(xy 276.867676 -289.09882) (xy 276.894544 -289.108134) (xy 276.90449 -289.111332) (xy 276.925333 -289.110289)
			(xy 276.94404 -289.101037) (xy 276.95752 -289.085105) (xy 276.963545 -289.065124) (xy 276.961121 -289.044395)
			(xy 276.950647 -289.026344) (xy 276.94255 -289.019742) (xy 276.923817 -289.005233) (xy 276.890646 -288.971402)
			(xy 276.8631 -288.932851) (xy 276.84184 -288.890508) (xy 276.827378 -288.845388) (xy 276.82006 -288.798576)
			(xy 276.819614 -288.774886) (xy 276.820136 -288.749631) (xy 276.828449 -288.699809) (xy 276.84485 -288.652035)
			(xy 276.868891 -288.607612) (xy 276.899915 -288.567752) (xy 276.937077 -288.533542) (xy 276.979363 -288.505916)
			(xy 277.025619 -288.485626) (xy 277.074584 -288.473226) (xy 277.124922 -288.469055) (xy 277.17526 -288.473226)
			(xy 277.224225 -288.485626) (xy 277.270481 -288.505916) (xy 277.312767 -288.533542) (xy 277.349929 -288.567752)
			(xy 277.380953 -288.607612) (xy 277.404994 -288.652035) (xy 277.421395 -288.699809) (xy 277.429708 -288.749631)
			(xy 277.43023 -288.774886) (xy 277.429766 -288.798575) (xy 277.422449 -288.845386) (xy 277.407989 -288.890504)
			(xy 277.386733 -288.932847) (xy 277.359191 -288.971398) (xy 277.326024 -289.005231) (xy 277.307294 -289.019742)
			(xy 277.299217 -289.026338) (xy 277.288809 -289.044385) (xy 277.286421 -289.065082) (xy 277.292447 -289.085025)
			(xy 277.305896 -289.100937) (xy 277.324556 -289.110201) (xy 277.345361 -289.111294) (xy 277.3553 -289.108134)
			(xy 277.382165 -289.098811) (xy 277.438123 -289.088718) (xy 277.466552 -289.088068) (xy 277.733252 -289.088068)
			(xy 277.76168 -289.088734) (xy 277.817636 -289.098824) (xy 277.844504 -289.108134) (xy 277.854461 -289.111303)
			(xy 277.875305 -289.110272) (xy 277.894016 -289.101027) (xy 277.907498 -289.085096) (xy 277.913522 -289.065114)
			(xy 277.911093 -289.044386) (xy 277.900611 -289.026339) (xy 277.89251 -289.019742) (xy 277.873768 -289.005244)
			(xy 277.8406 -288.971409) (xy 277.813056 -288.932856) (xy 277.791798 -288.890511) (xy 277.777337 -288.84539)
			(xy 277.77002 -288.798577) (xy 277.769574 -288.774886) (xy 277.770096 -288.749631) (xy 277.778409 -288.699809)
			(xy 277.79481 -288.652035) (xy 277.818851 -288.607612) (xy 277.849875 -288.567752) (xy 277.887037 -288.533542)
			(xy 277.929323 -288.505916) (xy 277.975579 -288.485626) (xy 278.024544 -288.473226) (xy 278.074882 -288.469055)
			(xy 278.12522 -288.473226) (xy 278.174185 -288.485626) (xy 278.220441 -288.505916) (xy 278.262727 -288.533542)
			(xy 278.299889 -288.567752) (xy 278.330913 -288.607612) (xy 278.354954 -288.652035) (xy 278.371355 -288.699809)
			(xy 278.379668 -288.749631) (xy 278.38019 -288.774886) (xy 278.379742 -288.798576) (xy 278.372424 -288.845388)
			(xy 278.357962 -288.890507) (xy 278.336703 -288.93285) (xy 278.309157 -288.971401) (xy 278.275987 -289.005233)
			(xy 278.257254 -289.019742) (xy 278.249129 -289.026293) (xy 278.238696 -289.044354) (xy 278.236299 -289.065073)
			(xy 278.24233 -289.085039) (xy 278.255797 -289.100965) (xy 278.274484 -289.11023) (xy 278.295313 -289.111308)
			(xy 278.30526 -289.108134) (xy 278.332128 -289.098821) (xy 278.388083 -289.088722) (xy 278.416512 -289.088068)
			(xy 278.683212 -289.088068) (xy 278.711641 -289.088718) (xy 278.767597 -289.098819) (xy 278.794464 -289.108134)
			(xy 278.804404 -289.111347) (xy 278.825248 -289.110298) (xy 278.843953 -289.101043) (xy 278.857432 -289.08511)
			(xy 278.863457 -289.065128) (xy 278.861035 -289.044399) (xy 278.850565 -289.026346) (xy 278.84247 -289.019742)
			(xy 278.82372 -289.005255) (xy 278.790553 -288.971416) (xy 278.763012 -288.93286) (xy 278.741756 -288.890513)
			(xy 278.727296 -288.845391) (xy 278.71998 -288.798577) (xy 278.719534 -288.774886) (xy 278.720056 -288.749631)
			(xy 278.728369 -288.699809) (xy 278.74477 -288.652035) (xy 278.768811 -288.607612) (xy 278.799835 -288.567752)
			(xy 278.836997 -288.533542) (xy 278.879283 -288.505916) (xy 278.925539 -288.485626) (xy 278.974504 -288.473226)
			(xy 279.024842 -288.469055) (xy 279.07518 -288.473226) (xy 279.124145 -288.485626) (xy 279.170401 -288.505916)
			(xy 279.212687 -288.533542) (xy 279.249849 -288.567752) (xy 279.280873 -288.607612) (xy 279.304914 -288.652035)
			(xy 279.321315 -288.699809) (xy 279.329628 -288.749631) (xy 279.33015 -288.774886) (xy 279.329718 -288.798577)
			(xy 279.322399 -288.84539) (xy 279.307935 -288.890511) (xy 279.286673 -288.932854) (xy 279.259123 -288.971404)
			(xy 279.225949 -289.005234) (xy 279.207214 -289.019742) (xy 279.199121 -289.026323) (xy 279.188705 -289.044375)
			(xy 279.186314 -289.065079) (xy 279.192341 -289.085029) (xy 279.205796 -289.100946) (xy 279.224466 -289.11021)
			(xy 279.245279 -289.111299) (xy 279.25522 -289.108134) (xy 279.282083 -289.098806) (xy 279.338042 -289.088717)
			(xy 279.366472 -289.088068) (xy 279.633172 -289.088068) (xy 279.6616 -289.088729) (xy 279.717556 -289.098822)
			(xy 279.744424 -289.108134) (xy 279.754375 -289.111318) (xy 279.775219 -289.110281) (xy 279.793928 -289.101032)
			(xy 279.807409 -289.0851) (xy 279.813434 -289.065119) (xy 279.811007 -289.044391) (xy 279.800529 -289.026342)
			(xy 279.79243 -289.019742) (xy 279.773693 -289.005239) (xy 279.740523 -288.971405) (xy 279.712978 -288.932853)
			(xy 279.691719 -288.890509) (xy 279.677258 -288.845389) (xy 279.66994 -288.798577) (xy 279.669494 -288.774886)
			(xy 279.670016 -288.749631) (xy 279.678329 -288.699809) (xy 279.69473 -288.652035) (xy 279.718771 -288.607612)
			(xy 279.749795 -288.567752) (xy 279.786957 -288.533542) (xy 279.829243 -288.505916) (xy 279.875499 -288.485626)
			(xy 279.924464 -288.473226) (xy 279.974802 -288.469055) (xy 280.02514 -288.473226) (xy 280.074105 -288.485626)
			(xy 280.120361 -288.505916) (xy 280.162647 -288.533542) (xy 280.199809 -288.567752) (xy 280.230833 -288.607612)
			(xy 280.254874 -288.652035) (xy 280.271275 -288.699809) (xy 280.279588 -288.749631) (xy 280.28011 -288.774886)
			(xy 280.279654 -288.798576) (xy 280.272336 -288.845387) (xy 280.257875 -288.890506) (xy 280.236618 -288.932849)
			(xy 280.209074 -288.971399) (xy 280.175905 -289.005232) (xy 280.157174 -289.019742) (xy 280.149033 -289.026278)
			(xy 280.138593 -289.044343) (xy 280.136191 -289.065069) (xy 280.142224 -289.085043) (xy 280.155698 -289.100975)
			(xy 280.174393 -289.11024) (xy 280.195231 -289.111312) (xy 280.20518 -289.108134) (xy 280.232047 -289.098816)
			(xy 280.288003 -289.08872) (xy 280.316432 -289.088068) (xy 280.583132 -289.088068) (xy 280.608697 -289.088602)
			(xy 280.659166 -289.096804) (xy 280.707703 -289.112884) (xy 280.753085 -289.136439) (xy 280.794171 -289.166875)
			(xy 280.829927 -289.203426) (xy 280.859451 -289.245172) (xy 280.871168 -289.2679) (xy 280.885646 -289.297364)
			(xy 280.910284 -289.312604) (xy 280.924762 -289.312604) (xy 280.934182 -289.312189) (xy 280.951742 -289.305363)
			(xy 280.965651 -289.292655) (xy 280.970228 -289.28441) (xy 280.978356 -289.2679) (xy 280.990011 -289.245254)
			(xy 281.019396 -289.203659) (xy 281.05498 -289.167224) (xy 281.09587 -289.136865) (xy 281.141041 -289.113342)
			(xy 281.165046 -289.104832) (xy 281.176222 -289.101022) (xy 281.493214 -288.78403) (xy 281.499865 -288.777924)
			(xy 281.516254 -288.770378) (xy 281.525218 -288.769298) (xy 281.52725 -288.769298) (xy 281.538582 -288.767972)
			(xy 281.558349 -288.756619) (xy 281.571232 -288.737813) (xy 281.573478 -288.726626) (xy 281.577691 -288.703089)
			(xy 281.59253 -288.657635) (xy 281.614278 -288.615052) (xy 281.642402 -288.576383) (xy 281.676215 -288.542575)
			(xy 281.714887 -288.514456) (xy 281.757473 -288.492714) (xy 281.802929 -288.477881) (xy 281.826462 -288.473642)
			(xy 281.837577 -288.47127) (xy 281.856246 -288.458343) (xy 281.867602 -288.43868) (xy 281.869134 -288.427414)
			(xy 281.869134 -288.425382) (xy 281.870193 -288.416411) (xy 281.877735 -288.400011) (xy 281.883866 -288.393378)
			(xy 282.055062 -288.222182) (xy 282.073252 -288.204636) (xy 282.114126 -288.174915) (xy 282.159148 -288.151958)
			(xy 282.207209 -288.136331) (xy 282.257123 -288.12842) (xy 282.282392 -288.127948) (xy 282.491434 -288.127948)
			(xy 282.512182 -288.128276) (xy 282.553333 -288.133631) (xy 282.573476 -288.138616) (xy 282.57627 -288.139124)
			(xy 282.585629 -288.140736) (xy 282.604333 -288.13747) (xy 282.620571 -288.127628) (xy 282.632121 -288.112559)
			(xy 282.637404 -288.094322) (xy 282.635698 -288.075411) (xy 282.627236 -288.058414) (xy 282.620466 -288.051748)
			(xy 282.601846 -288.034205) (xy 282.570101 -287.994093) (xy 282.545481 -287.949254) (xy 282.528674 -287.900941)
			(xy 282.520149 -287.850503) (xy 282.519628 -287.824926) (xy 282.52015 -287.799671) (xy 282.528463 -287.749849)
			(xy 282.544864 -287.702075) (xy 282.568905 -287.657652) (xy 282.599929 -287.617792) (xy 282.637091 -287.583582)
			(xy 282.679377 -287.555956) (xy 282.725633 -287.535666) (xy 282.774598 -287.523266) (xy 282.824936 -287.519095)
			(xy 282.875274 -287.523266) (xy 282.924239 -287.535666) (xy 282.970495 -287.555956) (xy 283.012781 -287.583582)
			(xy 283.049943 -287.617792) (xy 283.080967 -287.657652) (xy 283.105008 -287.702075) (xy 283.121409 -287.749849)
			(xy 283.129722 -287.799671) (xy 283.130244 -287.824926) (xy 283.129703 -287.850503) (xy 283.121183 -287.900941)
			(xy 283.104383 -287.949257) (xy 283.079775 -287.994102) (xy 283.048043 -288.034224) (xy 283.029406 -288.051748)
			(xy 283.022596 -288.05838) (xy 283.0141 -288.075372) (xy 283.012377 -288.094292) (xy 283.017663 -288.112539)
			(xy 283.029233 -288.127608) (xy 283.045496 -288.137428) (xy 283.064218 -288.14065) (xy 283.073602 -288.139124)
			(xy 283.076396 -288.138616) (xy 283.096539 -288.133627) (xy 283.137689 -288.128274) (xy 283.158438 -288.127948)
			(xy 283.441394 -288.127948) (xy 283.462142 -288.128284) (xy 283.503292 -288.133634) (xy 283.523436 -288.138616)
			(xy 283.52623 -288.139124) (xy 283.535595 -288.140709) (xy 283.554301 -288.137453) (xy 283.570542 -288.127618)
			(xy 283.582095 -288.112551) (xy 283.587378 -288.094314) (xy 283.585668 -288.075404) (xy 283.5772 -288.058411)
			(xy 283.570426 -288.051748) (xy 283.551798 -288.034213) (xy 283.520056 -287.994098) (xy 283.495438 -287.949257)
			(xy 283.478632 -287.900942) (xy 283.470108 -287.850503) (xy 283.469588 -287.824926) (xy 283.47011 -287.799671)
			(xy 283.478423 -287.749849) (xy 283.494824 -287.702075) (xy 283.518865 -287.657652) (xy 283.549889 -287.617792)
			(xy 283.587051 -287.583582) (xy 283.629337 -287.555956) (xy 283.675593 -287.535666) (xy 283.724558 -287.523266)
			(xy 283.774896 -287.519095) (xy 283.825234 -287.523266) (xy 283.874199 -287.535666) (xy 283.920455 -287.555956)
			(xy 283.962741 -287.583582) (xy 283.999903 -287.617792) (xy 284.030927 -287.657652) (xy 284.054968 -287.702075)
			(xy 284.071369 -287.749849) (xy 284.079682 -287.799671) (xy 284.080204 -287.824926) (xy 284.079676 -287.850503)
			(xy 284.071154 -287.900943) (xy 284.054353 -287.94926) (xy 284.029741 -287.994105) (xy 283.998005 -288.034225)
			(xy 283.979366 -288.051748) (xy 283.972587 -288.058404) (xy 283.964104 -288.075389) (xy 283.962386 -288.094296)
			(xy 283.967668 -288.112531) (xy 283.979227 -288.127592) (xy 283.995475 -288.137412) (xy 284.014184 -288.140643)
			(xy 284.023562 -288.139124) (xy 284.026356 -288.138616) (xy 284.046496 -288.133616) (xy 284.087649 -288.12827)
			(xy 284.108398 -288.127948) (xy 284.391354 -288.127948) (xy 284.412102 -288.128292) (xy 284.453252 -288.133636)
			(xy 284.473396 -288.138616) (xy 284.47619 -288.139124) (xy 284.485561 -288.140681) (xy 284.504268 -288.137436)
			(xy 284.520512 -288.127608) (xy 284.532068 -288.112543) (xy 284.537351 -288.094306) (xy 284.535638 -288.075397)
			(xy 284.527163 -288.058407) (xy 284.520386 -288.051748) (xy 284.50177 -288.034201) (xy 284.470024 -287.994091)
			(xy 284.445402 -287.949253) (xy 284.428594 -287.90094) (xy 284.420069 -287.850502) (xy 284.419548 -287.824926)
			(xy 284.42007 -287.799671) (xy 284.428383 -287.749849) (xy 284.444784 -287.702075) (xy 284.468825 -287.657652)
			(xy 284.499849 -287.617792) (xy 284.537011 -287.583582) (xy 284.579297 -287.555956) (xy 284.625553 -287.535666)
			(xy 284.674518 -287.523266) (xy 284.724856 -287.519095) (xy 284.775194 -287.523266) (xy 284.824159 -287.535666)
			(xy 284.870415 -287.555956) (xy 284.912701 -287.583582) (xy 284.949863 -287.617792) (xy 284.980887 -287.657652)
			(xy 285.004928 -287.702075) (xy 285.021329 -287.749849) (xy 285.029642 -287.799671) (xy 285.030164 -287.824926)
			(xy 285.029617 -287.850502) (xy 285.021097 -287.90094) (xy 285.004299 -287.949256) (xy 284.979692 -287.994101)
			(xy 284.947962 -288.034224) (xy 284.929326 -288.051748) (xy 284.9225 -288.058367) (xy 284.913998 -288.075364)
			(xy 284.912272 -288.094289) (xy 284.91756 -288.112543) (xy 284.929135 -288.127616) (xy 284.945406 -288.137437)
			(xy 284.964136 -288.140655) (xy 284.973522 -288.139124) (xy 284.976316 -288.138616) (xy 284.996458 -288.133624)
			(xy 285.037609 -288.128273) (xy 285.058358 -288.127948) (xy 285.341314 -288.127948) (xy 285.362062 -288.12828)
			(xy 285.403212 -288.133633) (xy 285.423356 -288.138616) (xy 285.42615 -288.139124) (xy 285.435512 -288.140723)
			(xy 285.454217 -288.137461) (xy 285.470456 -288.127623) (xy 285.482008 -288.112555) (xy 285.487291 -288.094318)
			(xy 285.485583 -288.075408) (xy 285.477118 -288.058413) (xy 285.470346 -288.051748) (xy 285.451722 -288.034209)
			(xy 285.419978 -287.994096) (xy 285.395359 -287.949256) (xy 285.378553 -287.900941) (xy 285.370028 -287.850503)
			(xy 285.369508 -287.824926) (xy 285.37003 -287.799671) (xy 285.378343 -287.749849) (xy 285.394744 -287.702075)
			(xy 285.418785 -287.657652) (xy 285.449809 -287.617792) (xy 285.486971 -287.583582) (xy 285.529257 -287.555956)
			(xy 285.575513 -287.535666) (xy 285.624478 -287.523266) (xy 285.674816 -287.519095) (xy 285.725154 -287.523266)
			(xy 285.774119 -287.535666) (xy 285.820375 -287.555956) (xy 285.862661 -287.583582) (xy 285.899823 -287.617792)
			(xy 285.930847 -287.657652) (xy 285.954888 -287.702075) (xy 285.971289 -287.749849) (xy 285.979602 -287.799671)
			(xy 285.980124 -287.824926) (xy 285.97959 -287.850503) (xy 285.971069 -287.900942) (xy 285.954268 -287.949259)
			(xy 285.929658 -287.994103) (xy 285.897924 -288.034225) (xy 285.879286 -288.051748) (xy 285.872491 -288.058392)
			(xy 285.864002 -288.07538) (xy 285.862281 -288.094294) (xy 285.867566 -288.112535) (xy 285.87913 -288.1276)
			(xy 285.895386 -288.13742) (xy 285.914101 -288.140647) (xy 285.923482 -288.139124) (xy 285.926276 -288.138616)
			(xy 285.94642 -288.133631) (xy 285.98757 -288.128275) (xy 286.008318 -288.127948) (xy 286.291274 -288.127948)
			(xy 286.312022 -288.128288) (xy 286.353172 -288.133635) (xy 286.373316 -288.138616) (xy 286.37611 -288.139124)
			(xy 286.385478 -288.140695) (xy 286.404184 -288.137444) (xy 286.420427 -288.127613) (xy 286.431981 -288.112547)
			(xy 286.437264 -288.09431) (xy 286.435553 -288.075401) (xy 286.427081 -288.058409) (xy 286.420306 -288.051748)
			(xy 286.401674 -288.034217) (xy 286.369933 -287.9941) (xy 286.345317 -287.949258) (xy 286.328512 -287.900943)
			(xy 286.319988 -287.850503) (xy 286.319468 -287.824926) (xy 286.31999 -287.799671) (xy 286.328303 -287.749849)
			(xy 286.344704 -287.702075) (xy 286.368745 -287.657652) (xy 286.399769 -287.617792) (xy 286.436931 -287.583582)
			(xy 286.479217 -287.555956) (xy 286.525473 -287.535666) (xy 286.574438 -287.523266) (xy 286.624776 -287.519095)
			(xy 286.675114 -287.523266) (xy 286.724079 -287.535666) (xy 286.770335 -287.555956) (xy 286.812621 -287.583582)
			(xy 286.849783 -287.617792) (xy 286.880807 -287.657652) (xy 286.904848 -287.702075) (xy 286.921249 -287.749849)
			(xy 286.929562 -287.799671) (xy 286.930084 -287.824926) (xy 286.929563 -287.850504) (xy 286.92104 -287.900944)
			(xy 286.904238 -287.949261) (xy 286.879624 -287.994106) (xy 286.847887 -288.034226) (xy 286.829246 -288.051748)
			(xy 286.822404 -288.058354) (xy 286.813896 -288.075355) (xy 286.812168 -288.094287) (xy 286.817458 -288.112547)
			(xy 286.829038 -288.127624) (xy 286.845316 -288.137445) (xy 286.864053 -288.140658) (xy 286.873442 -288.139124)
			(xy 286.876236 -288.138616) (xy 286.896377 -288.13362) (xy 286.937529 -288.128271) (xy 286.958278 -288.127948)
			(xy 287.241234 -288.127948) (xy 287.261982 -288.128276) (xy 287.303133 -288.133631) (xy 287.323276 -288.138616)
			(xy 287.32607 -288.139124) (xy 287.335429 -288.140736) (xy 287.354133 -288.13747) (xy 287.370371 -288.127628)
			(xy 287.381921 -288.112559) (xy 287.387204 -288.094322) (xy 287.385498 -288.075411) (xy 287.377036 -288.058414)
			(xy 287.370266 -288.051748) (xy 287.351646 -288.034205) (xy 287.319901 -287.994093) (xy 287.295281 -287.949254)
			(xy 287.278474 -287.900941) (xy 287.269949 -287.850503) (xy 287.269428 -287.824926) (xy 287.26995 -287.799671)
			(xy 287.278263 -287.749849) (xy 287.294664 -287.702075) (xy 287.318705 -287.657652) (xy 287.349729 -287.617792)
			(xy 287.386891 -287.583582) (xy 287.429177 -287.555956) (xy 287.475433 -287.535666) (xy 287.524398 -287.523266)
			(xy 287.574736 -287.519095) (xy 287.625074 -287.523266) (xy 287.674039 -287.535666) (xy 287.720295 -287.555956)
			(xy 287.762581 -287.583582) (xy 287.799743 -287.617792) (xy 287.830767 -287.657652) (xy 287.854808 -287.702075)
			(xy 287.871209 -287.749849) (xy 287.879522 -287.799671) (xy 287.880044 -287.824926) (xy 287.879503 -287.850503)
			(xy 287.870983 -287.900941) (xy 287.854183 -287.949257) (xy 287.829575 -287.994102) (xy 287.797843 -288.034224)
			(xy 287.779206 -288.051748) (xy 287.772396 -288.05838) (xy 287.7639 -288.075372) (xy 287.762177 -288.094292)
			(xy 287.767463 -288.112539) (xy 287.779033 -288.127608) (xy 287.795296 -288.137428) (xy 287.814018 -288.14065)
			(xy 287.823402 -288.139124) (xy 287.826196 -288.138616) (xy 287.846339 -288.133627) (xy 287.887489 -288.128274)
			(xy 287.908238 -288.127948) (xy 288.191194 -288.127948) (xy 288.211942 -288.128284) (xy 288.253092 -288.133634)
			(xy 288.273236 -288.138616) (xy 288.27603 -288.139124) (xy 288.285395 -288.140709) (xy 288.304101 -288.137453)
			(xy 288.320342 -288.127618) (xy 288.331895 -288.112551) (xy 288.337178 -288.094314) (xy 288.335468 -288.075404)
			(xy 288.327 -288.058411) (xy 288.320226 -288.051748) (xy 288.301598 -288.034213) (xy 288.269856 -287.994098)
			(xy 288.245238 -287.949257) (xy 288.228432 -287.900942) (xy 288.219908 -287.850503) (xy 288.219388 -287.824926)
			(xy 288.21991 -287.799671) (xy 288.228223 -287.749849) (xy 288.244624 -287.702075) (xy 288.268665 -287.657652)
			(xy 288.299689 -287.617792) (xy 288.336851 -287.583582) (xy 288.379137 -287.555956) (xy 288.425393 -287.535666)
			(xy 288.474358 -287.523266) (xy 288.524696 -287.519095) (xy 288.575034 -287.523266) (xy 288.623999 -287.535666)
			(xy 288.670255 -287.555956) (xy 288.712541 -287.583582) (xy 288.749703 -287.617792) (xy 288.780727 -287.657652)
			(xy 288.804768 -287.702075) (xy 288.821169 -287.749849) (xy 288.829482 -287.799671) (xy 288.830004 -287.824926)
			(xy 288.829476 -287.850503) (xy 288.820954 -287.900943) (xy 288.804153 -287.94926) (xy 288.779541 -287.994105)
			(xy 288.747805 -288.034225) (xy 288.729166 -288.051748) (xy 288.722387 -288.058404) (xy 288.713904 -288.075389)
			(xy 288.712186 -288.094296) (xy 288.717468 -288.112531) (xy 288.729027 -288.127592) (xy 288.745275 -288.137412)
			(xy 288.763984 -288.140643) (xy 288.773362 -288.139124) (xy 288.776156 -288.138616) (xy 288.796296 -288.133616)
			(xy 288.837449 -288.12827) (xy 288.858198 -288.127948) (xy 289.141408 -288.127948) (xy 289.162156 -288.128281)
			(xy 289.203306 -288.133633) (xy 289.22345 -288.138616) (xy 289.226244 -288.139124) (xy 289.235607 -288.140719)
			(xy 289.254312 -288.137459) (xy 289.270552 -288.127622) (xy 289.282104 -288.112554) (xy 289.287387 -288.094317)
			(xy 289.285679 -288.075407) (xy 289.277212 -288.058412) (xy 289.27044 -288.051748) (xy 289.251815 -288.03421)
			(xy 289.220072 -287.994096) (xy 289.195453 -287.949256) (xy 289.178647 -287.900942) (xy 289.170122 -287.850503)
			(xy 289.169602 -287.824926) (xy 289.170124 -287.799671) (xy 289.178437 -287.749849) (xy 289.194838 -287.702075)
			(xy 289.218879 -287.657652) (xy 289.249903 -287.617792) (xy 289.287065 -287.583582) (xy 289.329351 -287.555956)
			(xy 289.375607 -287.535666) (xy 289.424572 -287.523266) (xy 289.47491 -287.519095) (xy 289.525248 -287.523266)
			(xy 289.574213 -287.535666) (xy 289.620469 -287.555956) (xy 289.662755 -287.583582) (xy 289.699917 -287.617792)
			(xy 289.730941 -287.657652) (xy 289.753836 -287.699958) (xy 290.143958 -287.699958) (xy 290.147918 -287.650904)
			(xy 290.159695 -287.60312) (xy 290.178986 -287.557844) (xy 290.205289 -287.516248) (xy 290.237924 -287.479411)
			(xy 290.276045 -287.448286) (xy 290.318666 -287.423679) (xy 290.364682 -287.406227) (xy 290.412901 -287.396383)
			(xy 290.462076 -287.394402) (xy 290.510931 -287.400334) (xy 290.558202 -287.414026) (xy 290.602664 -287.435124)
			(xy 290.643167 -287.46308) (xy 290.67866 -287.497172) (xy 290.708225 -287.536516) (xy 290.731096 -287.580093)
			(xy 290.74668 -287.626774) (xy 290.754575 -287.675351) (xy 290.75507 -287.699958) (xy 290.754575 -287.724565)
			(xy 290.74668 -287.773142) (xy 290.731096 -287.819823) (xy 290.708225 -287.8634) (xy 290.67866 -287.902744)
			(xy 290.643167 -287.936836) (xy 290.602664 -287.964792) (xy 290.558202 -287.98589) (xy 290.510931 -287.999582)
			(xy 290.462076 -288.005514) (xy 290.412901 -288.003533) (xy 290.364682 -287.993689) (xy 290.318666 -287.976237)
			(xy 290.276045 -287.95163) (xy 290.237924 -287.920505) (xy 290.205289 -287.883668) (xy 290.178986 -287.842072)
			(xy 290.159695 -287.796796) (xy 290.147918 -287.749012) (xy 290.143958 -287.699958) (xy 289.753836 -287.699958)
			(xy 289.754982 -287.702075) (xy 289.771383 -287.749849) (xy 289.779696 -287.799671) (xy 289.780218 -287.824926)
			(xy 289.779686 -287.850503) (xy 289.771164 -287.900943) (xy 289.754364 -287.949259) (xy 289.729753 -287.994104)
			(xy 289.698019 -288.034225) (xy 289.67938 -288.051748) (xy 289.67259 -288.058396) (xy 289.664102 -288.075383)
			(xy 289.662383 -288.094294) (xy 289.667667 -288.112534) (xy 289.679229 -288.127598) (xy 289.695483 -288.137418)
			(xy 289.714196 -288.140645) (xy 289.723576 -288.139124) (xy 289.72637 -288.138616) (xy 289.74651 -288.133614)
			(xy 289.787663 -288.128269) (xy 289.808412 -288.127948) (xy 290.091114 -288.127948) (xy 290.115469 -288.128421)
			(xy 290.16362 -288.135787) (xy 290.210108 -288.150335) (xy 290.253869 -288.171731) (xy 290.293901 -288.199484)
			(xy 290.329286 -288.23296) (xy 290.344606 -288.2519) (xy 290.35222 -288.2607) (xy 290.373115 -288.270888)
			(xy 290.384738 -288.271458) (xy 290.465002 -288.271458) (xy 290.476634 -288.27092) (xy 290.497545 -288.260732)
			(xy 290.505134 -288.2519) (xy 290.520466 -288.232967) (xy 290.555836 -288.199471) (xy 290.595861 -288.171702)
			(xy 290.639621 -288.150299) (xy 290.686113 -288.135753) (xy 290.734269 -288.128397) (xy 290.758626 -288.127948)
			(xy 291.991034 -288.127948) (xy 292.012878 -288.12871) (xy 292.022784 -288.128456) (xy 292.032668 -288.126645)
			(xy 292.050064 -288.116636) (xy 292.062307 -288.100734) (xy 292.067535 -288.081357) (xy 292.064952 -288.061454)
			(xy 292.060376 -288.05251) (xy 292.047561 -288.029174) (xy 292.029354 -287.979149) (xy 292.020084 -287.926727)
			(xy 292.019482 -287.90011) (xy 292.019482 -287.899856) (xy 292.020004 -287.874601) (xy 292.028317 -287.824779)
			(xy 292.044718 -287.777005) (xy 292.068759 -287.732582) (xy 292.099783 -287.692722) (xy 292.136945 -287.658512)
			(xy 292.179231 -287.630886) (xy 292.225487 -287.610596) (xy 292.274452 -287.598196) (xy 292.32479 -287.594025)
			(xy 292.375128 -287.598196) (xy 292.424093 -287.610596) (xy 292.470349 -287.630886) (xy 292.512635 -287.658512)
			(xy 292.549797 -287.692722) (xy 292.580821 -287.732582) (xy 292.604862 -287.777005) (xy 292.621263 -287.824779)
			(xy 292.629576 -287.874601) (xy 292.630098 -287.899856) (xy 292.630098 -287.90011) (xy 292.629544 -287.926732)
			(xy 292.620286 -287.979164) (xy 292.602055 -288.029189) (xy 292.589204 -288.05251) (xy 292.584483 -288.061422)
			(xy 292.581803 -288.081397) (xy 292.587023 -288.100863) (xy 292.599338 -288.116816) (xy 292.616848 -288.126794)
			(xy 292.626796 -288.128456) (xy 292.636702 -288.12871) (xy 292.658546 -288.127948) (xy 292.941248 -288.127948)
			(xy 292.961996 -288.128274) (xy 293.003147 -288.133631) (xy 293.02329 -288.138616) (xy 293.026084 -288.139124)
			(xy 293.035456 -288.140677) (xy 293.054163 -288.137434) (xy 293.070408 -288.127606) (xy 293.081964 -288.112542)
			(xy 293.087247 -288.094305) (xy 293.085533 -288.075396) (xy 293.077057 -288.058407) (xy 293.07028 -288.051748)
			(xy 293.051663 -288.034202) (xy 293.019917 -287.994091) (xy 292.995296 -287.949253) (xy 292.978488 -287.90094)
			(xy 292.969963 -287.850503) (xy 292.969442 -287.824926) (xy 292.969964 -287.799671) (xy 292.978277 -287.749849)
			(xy 292.994678 -287.702075) (xy 293.018719 -287.657652) (xy 293.049743 -287.617792) (xy 293.086905 -287.583582)
			(xy 293.129191 -287.555956) (xy 293.175447 -287.535666) (xy 293.224412 -287.523266) (xy 293.27475 -287.519095)
			(xy 293.325088 -287.523266) (xy 293.374053 -287.535666) (xy 293.420309 -287.555956) (xy 293.462595 -287.583582)
			(xy 293.499757 -287.617792) (xy 293.530781 -287.657652) (xy 293.554822 -287.702075) (xy 293.571223 -287.749849)
			(xy 293.579536 -287.799671) (xy 293.580058 -287.824926) (xy 293.579513 -287.850502) (xy 293.570993 -287.900941)
			(xy 293.554194 -287.949256) (xy 293.529587 -287.994101) (xy 293.497857 -288.034224) (xy 293.47922 -288.051748)
			(xy 293.472399 -288.058371) (xy 293.463899 -288.075366) (xy 293.462174 -288.09429) (xy 293.467462 -288.112542)
			(xy 293.479035 -288.127614) (xy 293.495303 -288.137434) (xy 293.51403 -288.140653) (xy 293.523416 -288.139124)
			(xy 293.52621 -288.138616) (xy 293.546352 -288.133625) (xy 293.587503 -288.128273) (xy 293.608252 -288.127948)
			(xy 293.891208 -288.127948) (xy 293.911956 -288.128281) (xy 293.953106 -288.133633) (xy 293.97325 -288.138616)
			(xy 293.976044 -288.139124) (xy 293.985407 -288.140719) (xy 294.004112 -288.137459) (xy 294.020352 -288.127622)
			(xy 294.031904 -288.112554) (xy 294.037187 -288.094317) (xy 294.035479 -288.075407) (xy 294.027012 -288.058412)
			(xy 294.02024 -288.051748) (xy 294.001615 -288.03421) (xy 293.969872 -287.994096) (xy 293.945253 -287.949256)
			(xy 293.928447 -287.900942) (xy 293.919922 -287.850503) (xy 293.919402 -287.824926) (xy 293.919924 -287.799671)
			(xy 293.928237 -287.749849) (xy 293.944638 -287.702075) (xy 293.968679 -287.657652) (xy 293.999703 -287.617792)
			(xy 294.036865 -287.583582) (xy 294.079151 -287.555956) (xy 294.125407 -287.535666) (xy 294.174372 -287.523266)
			(xy 294.22471 -287.519095) (xy 294.275048 -287.523266) (xy 294.324013 -287.535666) (xy 294.370269 -287.555956)
			(xy 294.412555 -287.583582) (xy 294.449717 -287.617792) (xy 294.480741 -287.657652) (xy 294.504782 -287.702075)
			(xy 294.521183 -287.749849) (xy 294.529496 -287.799671) (xy 294.530018 -287.824926) (xy 294.529486 -287.850503)
			(xy 294.520964 -287.900943) (xy 294.504164 -287.949259) (xy 294.479553 -287.994104) (xy 294.447819 -288.034225)
			(xy 294.42918 -288.051748) (xy 294.42239 -288.058396) (xy 294.413902 -288.075383) (xy 294.412183 -288.094294)
			(xy 294.417467 -288.112534) (xy 294.429029 -288.127598) (xy 294.445283 -288.137418) (xy 294.463996 -288.140645)
			(xy 294.473376 -288.139124) (xy 294.47617 -288.138616) (xy 294.49631 -288.133614) (xy 294.537463 -288.128269)
			(xy 294.558212 -288.127948) (xy 294.841422 -288.127948) (xy 294.86217 -288.128279) (xy 294.90332 -288.133632)
			(xy 294.923464 -288.138616) (xy 294.926258 -288.139124) (xy 294.935619 -288.140728) (xy 294.954323 -288.137465)
			(xy 294.970562 -288.127625) (xy 294.982113 -288.112556) (xy 294.987396 -288.094319) (xy 294.985689 -288.075409)
			(xy 294.977225 -288.058413) (xy 294.970454 -288.051748) (xy 294.951832 -288.034207) (xy 294.920088 -287.994094)
			(xy 294.895468 -287.949255) (xy 294.878662 -287.900941) (xy 294.870137 -287.850503) (xy 294.869616 -287.824926)
			(xy 294.870138 -287.799671) (xy 294.878451 -287.749849) (xy 294.894852 -287.702075) (xy 294.918893 -287.657652)
			(xy 294.949917 -287.617792) (xy 294.987079 -287.583582) (xy 295.029365 -287.555956) (xy 295.075621 -287.535666)
			(xy 295.124586 -287.523266) (xy 295.174924 -287.519095) (xy 295.225262 -287.523266) (xy 295.274227 -287.535666)
			(xy 295.320483 -287.555956) (xy 295.362769 -287.583582) (xy 295.399931 -287.617792) (xy 295.430955 -287.657652)
			(xy 295.454996 -287.702075) (xy 295.471397 -287.749849) (xy 295.47971 -287.799671) (xy 295.480232 -287.824926)
			(xy 295.479695 -287.850503) (xy 295.471174 -287.900942) (xy 295.454374 -287.949258) (xy 295.429765 -287.994103)
			(xy 295.398032 -288.034225) (xy 295.379394 -288.051748) (xy 295.372593 -288.058387) (xy 295.364101 -288.075377)
			(xy 295.36238 -288.094293) (xy 295.367665 -288.112537) (xy 295.379231 -288.127603) (xy 295.39549 -288.137423)
			(xy 295.414208 -288.140648) (xy 295.42359 -288.139124) (xy 295.426384 -288.138616) (xy 295.446527 -288.13363)
			(xy 295.487677 -288.128275) (xy 295.508426 -288.127948) (xy 295.791382 -288.127948) (xy 295.81213 -288.128286)
			(xy 295.85328 -288.133635) (xy 295.873424 -288.138616) (xy 295.876218 -288.139124) (xy 295.885585 -288.1407)
			(xy 295.904291 -288.137448) (xy 295.920533 -288.127615) (xy 295.932086 -288.112548) (xy 295.93737 -288.094312)
			(xy 295.935659 -288.075402) (xy 295.927188 -288.05841) (xy 295.920414 -288.051748) (xy 295.901784 -288.034215)
			(xy 295.870042 -287.994099) (xy 295.845425 -287.949258) (xy 295.82862 -287.900943) (xy 295.820096 -287.850503)
			(xy 295.819576 -287.824926) (xy 295.820098 -287.799671) (xy 295.828411 -287.749849) (xy 295.844812 -287.702075)
			(xy 295.868853 -287.657652) (xy 295.899877 -287.617792) (xy 295.937039 -287.583582) (xy 295.979325 -287.555956)
			(xy 296.025581 -287.535666) (xy 296.074546 -287.523266) (xy 296.124884 -287.519095) (xy 296.175222 -287.523266)
			(xy 296.224187 -287.535666) (xy 296.270443 -287.555956) (xy 296.312729 -287.583582) (xy 296.349891 -287.617792)
			(xy 296.380915 -287.657652) (xy 296.404956 -287.702075) (xy 296.421357 -287.749849) (xy 296.42967 -287.799671)
			(xy 296.430192 -287.824926) (xy 296.429668 -287.850504) (xy 296.421146 -287.900944) (xy 296.404344 -287.949261)
			(xy 296.379731 -287.994106) (xy 296.347994 -288.034226) (xy 296.329354 -288.051748) (xy 296.322584 -288.058412)
			(xy 296.314105 -288.075394) (xy 296.312388 -288.094297) (xy 296.31767 -288.112529) (xy 296.329225 -288.127588)
			(xy 296.345469 -288.137407) (xy 296.364173 -288.140641) (xy 296.37355 -288.139124) (xy 296.376344 -288.138616)
			(xy 296.396485 -288.133618) (xy 296.437637 -288.128271) (xy 296.458386 -288.127948) (xy 296.741342 -288.127948)
			(xy 296.76209 -288.128275) (xy 296.803241 -288.133631) (xy 296.823384 -288.138616) (xy 296.826178 -288.139124)
			(xy 296.835551 -288.140673) (xy 296.854258 -288.137431) (xy 296.870504 -288.127605) (xy 296.88206 -288.11254)
			(xy 296.887343 -288.094304) (xy 296.885629 -288.075395) (xy 296.877152 -288.058406) (xy 296.870374 -288.051748)
			(xy 296.851756 -288.034203) (xy 296.82001 -287.994092) (xy 296.79539 -287.949254) (xy 296.778582 -287.90094)
			(xy 296.770057 -287.850503) (xy 296.769536 -287.824926) (xy 296.770058 -287.799671) (xy 296.778371 -287.749849)
			(xy 296.794772 -287.702075) (xy 296.818813 -287.657652) (xy 296.849837 -287.617792) (xy 296.886999 -287.583582)
			(xy 296.929285 -287.555956) (xy 296.975541 -287.535666) (xy 297.024506 -287.523266) (xy 297.074844 -287.519095)
			(xy 297.125182 -287.523266) (xy 297.174147 -287.535666) (xy 297.220403 -287.555956) (xy 297.262689 -287.583582)
			(xy 297.299851 -287.617792) (xy 297.330875 -287.657652) (xy 297.354916 -287.702075) (xy 297.371317 -287.749849)
			(xy 297.37963 -287.799671) (xy 297.380152 -287.824926) (xy 297.379609 -287.850502) (xy 297.371088 -287.900941)
			(xy 297.35429 -287.949257) (xy 297.329681 -287.994102) (xy 297.297951 -288.034224) (xy 297.279314 -288.051748)
			(xy 297.272497 -288.058375) (xy 297.263999 -288.075369) (xy 297.262275 -288.094291) (xy 297.267562 -288.112541)
			(xy 297.279134 -288.127611) (xy 297.2954 -288.137431) (xy 297.314125 -288.140652) (xy 297.32351 -288.139124)
			(xy 297.326304 -288.138616) (xy 297.346446 -288.133626) (xy 297.387597 -288.128273) (xy 297.408346 -288.127948)
			(xy 297.691302 -288.127948) (xy 297.71205 -288.128282) (xy 297.7532 -288.133633) (xy 297.773344 -288.138616)
			(xy 297.776138 -288.139124) (xy 297.785502 -288.140715) (xy 297.804207 -288.137456) (xy 297.820447 -288.12762)
			(xy 297.832 -288.112552) (xy 297.837283 -288.094315) (xy 297.835574 -288.075406) (xy 297.827107 -288.058411)
			(xy 297.820334 -288.051748) (xy 297.801708 -288.034211) (xy 297.769965 -287.994097) (xy 297.745347 -287.949256)
			(xy 297.728541 -287.900942) (xy 297.720016 -287.850503) (xy 297.719496 -287.824926) (xy 297.720018 -287.799671)
			(xy 297.728331 -287.749849) (xy 297.744732 -287.702075) (xy 297.768773 -287.657652) (xy 297.799797 -287.617792)
			(xy 297.836959 -287.583582) (xy 297.879245 -287.555956) (xy 297.925501 -287.535666) (xy 297.974466 -287.523266)
			(xy 298.024804 -287.519095) (xy 298.075142 -287.523266) (xy 298.124107 -287.535666) (xy 298.170363 -287.555956)
			(xy 298.212649 -287.583582) (xy 298.249811 -287.617792) (xy 298.280835 -287.657652) (xy 298.304876 -287.702075)
			(xy 298.321277 -287.749849) (xy 298.32959 -287.799671) (xy 298.330112 -287.824926) (xy 298.329582 -287.850503)
			(xy 298.32106 -287.900943) (xy 298.304259 -287.949259) (xy 298.279648 -287.994104) (xy 298.247913 -288.034225)
			(xy 298.229274 -288.051748) (xy 298.222489 -288.058399) (xy 298.214003 -288.075385) (xy 298.212284 -288.094295)
			(xy 298.217567 -288.112533) (xy 298.229128 -288.127595) (xy 298.245379 -288.137415) (xy 298.264091 -288.140644)
			(xy 298.27347 -288.139124) (xy 298.276264 -288.138616) (xy 298.296404 -288.133615) (xy 298.337557 -288.12827)
			(xy 298.358306 -288.127948) (xy 298.641262 -288.127948) (xy 298.66201 -288.12829) (xy 298.70316 -288.133636)
			(xy 298.723304 -288.138616) (xy 298.726098 -288.139124) (xy 298.735468 -288.140687) (xy 298.754174 -288.137439)
			(xy 298.770418 -288.12761) (xy 298.781973 -288.112544) (xy 298.787257 -288.094308) (xy 298.785544 -288.075399)
			(xy 298.77707 -288.058408) (xy 298.770294 -288.051748) (xy 298.751679 -288.034199) (xy 298.719933 -287.99409)
			(xy 298.695311 -287.949252) (xy 298.678502 -287.90094) (xy 298.669977 -287.850502) (xy 298.669456 -287.824926)
			(xy 298.669978 -287.799671) (xy 298.678291 -287.749849) (xy 298.694692 -287.702075) (xy 298.718733 -287.657652)
			(xy 298.749757 -287.617792) (xy 298.786919 -287.583582) (xy 298.829205 -287.555956) (xy 298.875461 -287.535666)
			(xy 298.924426 -287.523266) (xy 298.974764 -287.519095) (xy 299.025102 -287.523266) (xy 299.074067 -287.535666)
			(xy 299.120323 -287.555956) (xy 299.162609 -287.583582) (xy 299.199771 -287.617792) (xy 299.230795 -287.657652)
			(xy 299.254836 -287.702075) (xy 299.271237 -287.749849) (xy 299.27955 -287.799671) (xy 299.280072 -287.824926)
			(xy 299.279522 -287.850502) (xy 299.271002 -287.90094) (xy 299.254205 -287.949255) (xy 299.229598 -287.9941)
			(xy 299.19787 -288.034223) (xy 299.179234 -288.051748) (xy 299.172401 -288.058362) (xy 299.163897 -288.07536)
			(xy 299.162171 -288.094289) (xy 299.167459 -288.112545) (xy 299.179036 -288.127619) (xy 299.19531 -288.13744)
			(xy 299.214043 -288.140656) (xy 299.22343 -288.139124) (xy 299.226224 -288.138616) (xy 299.246366 -288.133622)
			(xy 299.287517 -288.128272) (xy 299.308266 -288.127948) (xy 299.591222 -288.127948) (xy 299.61197 -288.128279)
			(xy 299.65312 -288.133632) (xy 299.673264 -288.138616) (xy 299.676058 -288.139124) (xy 299.685419 -288.140728)
			(xy 299.704123 -288.137465) (xy 299.720362 -288.127625) (xy 299.731913 -288.112556) (xy 299.737196 -288.094319)
			(xy 299.735489 -288.075409) (xy 299.727025 -288.058413) (xy 299.720254 -288.051748) (xy 299.701632 -288.034207)
			(xy 299.669888 -287.994094) (xy 299.645268 -287.949255) (xy 299.628462 -287.900941) (xy 299.619937 -287.850503)
			(xy 299.619416 -287.824926) (xy 299.619938 -287.799671) (xy 299.628251 -287.749849) (xy 299.644652 -287.702075)
			(xy 299.668693 -287.657652) (xy 299.699717 -287.617792) (xy 299.736879 -287.583582) (xy 299.779165 -287.555956)
			(xy 299.825421 -287.535666) (xy 299.874386 -287.523266) (xy 299.924724 -287.519095) (xy 299.975062 -287.523266)
			(xy 300.024027 -287.535666) (xy 300.070283 -287.555956) (xy 300.112569 -287.583582) (xy 300.149731 -287.617792)
			(xy 300.180755 -287.657652) (xy 300.204796 -287.702075) (xy 300.221197 -287.749849) (xy 300.22951 -287.799671)
			(xy 300.230032 -287.824926) (xy 300.229495 -287.850503) (xy 300.220974 -287.900942) (xy 300.204174 -287.949258)
			(xy 300.179565 -287.994103) (xy 300.147832 -288.034225) (xy 300.129194 -288.051748) (xy 300.122393 -288.058387)
			(xy 300.113901 -288.075377) (xy 300.11218 -288.094293) (xy 300.117465 -288.112537) (xy 300.129031 -288.127603)
			(xy 300.14529 -288.137423) (xy 300.164008 -288.140648) (xy 300.17339 -288.139124) (xy 300.176184 -288.138616)
			(xy 300.196327 -288.13363) (xy 300.237477 -288.128275) (xy 300.258226 -288.127948) (xy 300.541182 -288.127948)
			(xy 300.56193 -288.128286) (xy 300.60308 -288.133635) (xy 300.623224 -288.138616) (xy 300.632718 -288.140795)
			(xy 300.652044 -288.138446) (xy 300.669105 -288.129067) (xy 300.681445 -288.114008) (xy 300.687288 -288.095436)
			(xy 300.685793 -288.076025) (xy 300.677175 -288.058567) (xy 300.670214 -288.051748) (xy 300.651584 -288.034215)
			(xy 300.619842 -287.994099) (xy 300.595225 -287.949258) (xy 300.57842 -287.900943) (xy 300.569896 -287.850503)
			(xy 300.569376 -287.824926) (xy 300.569898 -287.799671) (xy 300.578211 -287.749849) (xy 300.594612 -287.702075)
			(xy 300.618653 -287.657652) (xy 300.649677 -287.617792) (xy 300.686839 -287.583582) (xy 300.729125 -287.555956)
			(xy 300.775381 -287.535666) (xy 300.824346 -287.523266) (xy 300.874684 -287.519095) (xy 300.925022 -287.523266)
			(xy 300.973987 -287.535666) (xy 301.020243 -287.555956) (xy 301.062529 -287.583582) (xy 301.099691 -287.617792)
			(xy 301.130715 -287.657652) (xy 301.154756 -287.702075) (xy 301.171157 -287.749849) (xy 301.17947 -287.799671)
			(xy 301.179992 -287.824926) (xy 302.469054 -287.824926) (xy 302.473014 -287.775872) (xy 302.484791 -287.728088)
			(xy 302.504082 -287.682812) (xy 302.530385 -287.641216) (xy 302.56302 -287.604379) (xy 302.601141 -287.573254)
			(xy 302.643762 -287.548647) (xy 302.689778 -287.531195) (xy 302.737997 -287.521351) (xy 302.787172 -287.51937)
			(xy 302.836027 -287.525302) (xy 302.883298 -287.538994) (xy 302.92776 -287.560092) (xy 302.968263 -287.588048)
			(xy 303.003756 -287.62214) (xy 303.033321 -287.661484) (xy 303.056192 -287.705061) (xy 303.071776 -287.751742)
			(xy 303.079671 -287.800319) (xy 303.080166 -287.824926) (xy 303.079671 -287.849533) (xy 303.071776 -287.89811)
			(xy 303.056192 -287.944791) (xy 303.033321 -287.988368) (xy 303.003756 -288.027712) (xy 302.968263 -288.061804)
			(xy 302.92776 -288.08976) (xy 302.883298 -288.110858) (xy 302.836027 -288.12455) (xy 302.787172 -288.130482)
			(xy 302.737997 -288.128501) (xy 302.689778 -288.118657) (xy 302.643762 -288.101205) (xy 302.601141 -288.076598)
			(xy 302.56302 -288.045473) (xy 302.530385 -288.008636) (xy 302.504082 -287.96704) (xy 302.484791 -287.921764)
			(xy 302.473014 -287.87398) (xy 302.469054 -287.824926) (xy 301.179992 -287.824926) (xy 301.179468 -287.850504)
			(xy 301.170946 -287.900944) (xy 301.154144 -287.949261) (xy 301.129531 -287.994106) (xy 301.097794 -288.034226)
			(xy 301.079154 -288.051748) (xy 301.072231 -288.058555) (xy 301.063719 -288.075991) (xy 301.062282 -288.09534)
			(xy 301.068126 -288.113841) (xy 301.080416 -288.128855) (xy 301.097398 -288.138239) (xy 301.116649 -288.140653)
			(xy 301.126144 -288.138616) (xy 301.146285 -288.133618) (xy 301.187437 -288.128271) (xy 301.208186 -288.127948)
			(xy 302.245522 -288.127948) (xy 302.250412 -288.128097) (xy 302.260004 -288.130008) (xy 302.264572 -288.131758)
			(xy 302.366172 -288.172652) (xy 302.371138 -288.174778) (xy 302.380103 -288.1808) (xy 302.383952 -288.18459)
			(xy 302.42129 -288.223452) (xy 302.421798 -288.22396) (xy 302.50603 -288.308192) (xy 305.793963 -288.308192)
			(xy 305.79665 -288.25862) (xy 305.80732 -288.210135) (xy 305.825695 -288.164015) (xy 305.851289 -288.121475)
			(xy 305.883428 -288.083636) (xy 305.921265 -288.051496) (xy 305.963804 -288.0259) (xy 306.009923 -288.007524)
			(xy 306.058408 -287.996851) (xy 306.10798 -287.994163) (xy 306.157335 -287.99953) (xy 306.205171 -288.012812)
			(xy 306.250228 -288.033658) (xy 306.291319 -288.061518) (xy 306.327361 -288.095659) (xy 306.357405 -288.135182)
			(xy 306.380658 -288.179045) (xy 306.39651 -288.226092) (xy 306.404541 -288.275083) (xy 306.405026 -288.299906)
			(xy 306.40485 -288.314089) (xy 306.402177 -288.342329) (xy 306.399692 -288.356294) (xy 306.397406 -288.36874)
			(xy 306.404772 -288.392362) (xy 306.482242 -288.469832) (xy 306.505864 -288.477198) (xy 306.51831 -288.474912)
			(xy 306.532276 -288.472438) (xy 306.560516 -288.469765) (xy 306.574698 -288.469578) (xy 306.588945 -288.469746)
			(xy 306.617313 -288.472414) (xy 306.63134 -288.474912) (xy 306.643786 -288.477198) (xy 306.667408 -288.469832)
			(xy 306.735988 -288.401506) (xy 306.744154 -288.392276) (xy 306.751457 -288.36878) (xy 306.749958 -288.356548)
			(xy 306.749958 -288.35604) (xy 306.74749 -288.342137) (xy 306.744822 -288.314025) (xy 306.744624 -288.299906)
			(xy 306.745071 -288.275085) (xy 306.753101 -288.226097) (xy 306.768951 -288.179053) (xy 306.792202 -288.135194)
			(xy 306.822243 -288.095673) (xy 306.858282 -288.061533) (xy 306.899368 -288.033674) (xy 306.944421 -288.012828)
			(xy 306.992253 -287.999545) (xy 307.041604 -287.994176) (xy 307.091173 -287.996861) (xy 307.139654 -288.00753)
			(xy 307.185772 -288.025901) (xy 307.228309 -288.051492) (xy 307.266146 -288.083627) (xy 307.298286 -288.12146)
			(xy 307.323882 -288.163994) (xy 307.342259 -288.210109) (xy 307.352934 -288.25859) (xy 307.355177 -288.299906)
			(xy 307.694088 -288.299906) (xy 307.698048 -288.250852) (xy 307.709825 -288.203068) (xy 307.729116 -288.157792)
			(xy 307.755419 -288.116196) (xy 307.788054 -288.079359) (xy 307.826175 -288.048234) (xy 307.868796 -288.023627)
			(xy 307.914812 -288.006175) (xy 307.963031 -287.996331) (xy 308.012206 -287.99435) (xy 308.061061 -288.000282)
			(xy 308.108332 -288.013974) (xy 308.152794 -288.035072) (xy 308.193297 -288.063028) (xy 308.22879 -288.09712)
			(xy 308.258355 -288.136464) (xy 308.281226 -288.180041) (xy 308.29681 -288.226722) (xy 308.304705 -288.275299)
			(xy 308.3052 -288.299906) (xy 308.304705 -288.324513) (xy 308.29681 -288.37309) (xy 308.281226 -288.419771)
			(xy 308.258355 -288.463348) (xy 308.22879 -288.502692) (xy 308.193297 -288.536784) (xy 308.152794 -288.56474)
			(xy 308.108332 -288.585838) (xy 308.061061 -288.59953) (xy 308.012206 -288.605462) (xy 307.963031 -288.603481)
			(xy 307.914812 -288.593637) (xy 307.868796 -288.576185) (xy 307.826175 -288.551578) (xy 307.788054 -288.520453)
			(xy 307.755419 -288.483616) (xy 307.729116 -288.44202) (xy 307.709825 -288.396744) (xy 307.698048 -288.34896)
			(xy 307.694088 -288.299906) (xy 307.355177 -288.299906) (xy 307.355625 -288.308158) (xy 307.350262 -288.35751)
			(xy 307.336985 -288.405343) (xy 307.316145 -288.450398) (xy 307.28829 -288.491489) (xy 307.254155 -288.527532)
			(xy 307.214638 -288.557577) (xy 307.170781 -288.580834) (xy 307.12374 -288.596689) (xy 307.074753 -288.604726)
			(xy 307.049932 -288.605214) (xy 307.035685 -288.605049) (xy 307.007318 -288.602375) (xy 306.99329 -288.59988)
			(xy 306.980844 -288.597594) (xy 306.957222 -288.60496) (xy 306.888642 -288.673286) (xy 306.880484 -288.682522)
			(xy 306.873175 -288.706013) (xy 306.874672 -288.718244) (xy 306.874672 -288.718752) (xy 306.877139 -288.732655)
			(xy 306.879808 -288.760767) (xy 306.880006 -288.774886) (xy 306.879484 -288.800141) (xy 306.871171 -288.849963)
			(xy 306.85477 -288.897737) (xy 306.830729 -288.94216) (xy 306.799705 -288.98202) (xy 306.762543 -289.01623)
			(xy 306.720257 -289.043856) (xy 306.674001 -289.064146) (xy 306.625036 -289.076546) (xy 306.574698 -289.080717)
			(xy 306.52436 -289.076546) (xy 306.475395 -289.064146) (xy 306.429139 -289.043856) (xy 306.386853 -289.01623)
			(xy 306.349691 -288.98202) (xy 306.318667 -288.94216) (xy 306.294626 -288.897737) (xy 306.278225 -288.849963)
			(xy 306.269912 -288.800141) (xy 306.26939 -288.774886) (xy 306.269565 -288.760703) (xy 306.272238 -288.732463)
			(xy 306.274724 -288.718498) (xy 306.27701 -288.706052) (xy 306.269644 -288.68243) (xy 306.192174 -288.60496)
			(xy 306.168552 -288.597594) (xy 306.156106 -288.59988) (xy 306.142139 -288.602352) (xy 306.1139 -288.605027)
			(xy 306.099718 -288.605214) (xy 306.074895 -288.604741) (xy 306.025903 -288.596713) (xy 305.978856 -288.580863)
			(xy 305.934992 -288.557611) (xy 305.895468 -288.527569) (xy 305.861326 -288.491528) (xy 305.833463 -288.450438)
			(xy 305.812616 -288.405382) (xy 305.799333 -288.357547) (xy 305.793963 -288.308192) (xy 302.50603 -288.308192)
			(xy 302.636682 -288.438844) (xy 302.65624 -288.46018) (xy 302.662576 -288.467044) (xy 302.67887 -288.476142)
			(xy 302.697336 -288.478833) (xy 302.706532 -288.477198) (xy 302.723322 -288.47362) (xy 302.757439 -288.469798)
			(xy 302.774604 -288.469578) (xy 302.774858 -288.469578) (xy 302.798849 -288.470077) (xy 302.846242 -288.477577)
			(xy 302.891878 -288.492399) (xy 302.934633 -288.514178) (xy 302.973454 -288.542377) (xy 303.007386 -288.576303)
			(xy 303.035593 -288.615119) (xy 303.05738 -288.65787) (xy 303.07221 -288.703503) (xy 303.079719 -288.750895)
			(xy 303.080166 -288.774886) (xy 303.419014 -288.774886) (xy 303.422974 -288.725832) (xy 303.434751 -288.678048)
			(xy 303.454042 -288.632772) (xy 303.480345 -288.591176) (xy 303.51298 -288.554339) (xy 303.551101 -288.523214)
			(xy 303.593722 -288.498607) (xy 303.639738 -288.481155) (xy 303.687957 -288.471311) (xy 303.737132 -288.46933)
			(xy 303.785987 -288.475262) (xy 303.833258 -288.488954) (xy 303.87772 -288.510052) (xy 303.918223 -288.538008)
			(xy 303.953716 -288.5721) (xy 303.983281 -288.611444) (xy 304.006152 -288.655021) (xy 304.021736 -288.701702)
			(xy 304.029631 -288.750279) (xy 304.030126 -288.774886) (xy 304.368974 -288.774886) (xy 304.372934 -288.725832)
			(xy 304.384711 -288.678048) (xy 304.404002 -288.632772) (xy 304.430305 -288.591176) (xy 304.46294 -288.554339)
			(xy 304.501061 -288.523214) (xy 304.543682 -288.498607) (xy 304.589698 -288.481155) (xy 304.637917 -288.471311)
			(xy 304.687092 -288.46933) (xy 304.735947 -288.475262) (xy 304.783218 -288.488954) (xy 304.82768 -288.510052)
			(xy 304.868183 -288.538008) (xy 304.903676 -288.5721) (xy 304.933241 -288.611444) (xy 304.956112 -288.655021)
			(xy 304.971696 -288.701702) (xy 304.979591 -288.750279) (xy 304.980086 -288.774886) (xy 304.979591 -288.799493)
			(xy 304.971696 -288.84807) (xy 304.956112 -288.894751) (xy 304.933241 -288.938328) (xy 304.903676 -288.977672)
			(xy 304.868183 -289.011764) (xy 304.82768 -289.03972) (xy 304.783218 -289.060818) (xy 304.735947 -289.07451)
			(xy 304.687092 -289.080442) (xy 304.637917 -289.078461) (xy 304.589698 -289.068617) (xy 304.543682 -289.051165)
			(xy 304.501061 -289.026558) (xy 304.46294 -288.995433) (xy 304.430305 -288.958596) (xy 304.404002 -288.917)
			(xy 304.384711 -288.871724) (xy 304.372934 -288.82394) (xy 304.368974 -288.774886) (xy 304.030126 -288.774886)
			(xy 304.029631 -288.799493) (xy 304.021736 -288.84807) (xy 304.006152 -288.894751) (xy 303.983281 -288.938328)
			(xy 303.953716 -288.977672) (xy 303.918223 -289.011764) (xy 303.87772 -289.03972) (xy 303.833258 -289.060818)
			(xy 303.785987 -289.07451) (xy 303.737132 -289.080442) (xy 303.687957 -289.078461) (xy 303.639738 -289.068617)
			(xy 303.593722 -289.051165) (xy 303.551101 -289.026558) (xy 303.51298 -288.995433) (xy 303.480345 -288.958596)
			(xy 303.454042 -288.917) (xy 303.434751 -288.871724) (xy 303.422974 -288.82394) (xy 303.419014 -288.774886)
			(xy 303.080166 -288.774886) (xy 303.07971 -288.797812) (xy 303.072775 -288.843139) (xy 303.059162 -288.886926)
			(xy 303.039176 -288.928195) (xy 303.026572 -288.947352) (xy 303.020667 -288.957002) (xy 303.017031 -288.979298)
			(xy 303.02333 -289.000992) (xy 303.030382 -289.009836) (xy 303.03724 -289.017202) (xy 303.043059 -289.02441)
			(xy 303.049581 -289.041729) (xy 303.04994 -289.050984) (xy 303.04994 -289.448748) (xy 303.049557 -289.457999)
			(xy 303.043046 -289.475317) (xy 303.03724 -289.48253) (xy 303.030382 -289.489896) (xy 303.023387 -289.498767)
			(xy 303.017136 -289.520447) (xy 303.020704 -289.542727) (xy 303.026572 -289.55238) (xy 303.040965 -289.57428)
			(xy 303.062745 -289.621944) (xy 303.076071 -289.672626) (xy 303.080552 -289.724838) (xy 303.080551 -289.724846)
			(xy 303.419014 -289.724846) (xy 303.422974 -289.675792) (xy 303.434751 -289.628008) (xy 303.454042 -289.582732)
			(xy 303.480345 -289.541136) (xy 303.51298 -289.504299) (xy 303.551101 -289.473174) (xy 303.593722 -289.448567)
			(xy 303.639738 -289.431115) (xy 303.687957 -289.421271) (xy 303.737132 -289.41929) (xy 303.785987 -289.425222)
			(xy 303.833258 -289.438914) (xy 303.87772 -289.460012) (xy 303.918223 -289.487968) (xy 303.953716 -289.52206)
			(xy 303.983281 -289.561404) (xy 304.006152 -289.604981) (xy 304.021736 -289.651662) (xy 304.029631 -289.700239)
			(xy 304.030126 -289.724846) (xy 304.368974 -289.724846) (xy 304.372934 -289.675792) (xy 304.384711 -289.628008)
			(xy 304.404002 -289.582732) (xy 304.430305 -289.541136) (xy 304.46294 -289.504299) (xy 304.501061 -289.473174)
			(xy 304.543682 -289.448567) (xy 304.589698 -289.431115) (xy 304.637917 -289.421271) (xy 304.687092 -289.41929)
			(xy 304.735947 -289.425222) (xy 304.783218 -289.438914) (xy 304.82768 -289.460012) (xy 304.868183 -289.487968)
			(xy 304.903676 -289.52206) (xy 304.933241 -289.561404) (xy 304.956112 -289.604981) (xy 304.971696 -289.651662)
			(xy 304.979591 -289.700239) (xy 304.980086 -289.724846) (xy 305.318934 -289.724846) (xy 305.322894 -289.675792)
			(xy 305.334671 -289.628008) (xy 305.353962 -289.582732) (xy 305.380265 -289.541136) (xy 305.4129 -289.504299)
			(xy 305.451021 -289.473174) (xy 305.493642 -289.448567) (xy 305.539658 -289.431115) (xy 305.587877 -289.421271)
			(xy 305.637052 -289.41929) (xy 305.685907 -289.425222) (xy 305.733178 -289.438914) (xy 305.77764 -289.460012)
			(xy 305.818143 -289.487968) (xy 305.853636 -289.52206) (xy 305.883201 -289.561404) (xy 305.906072 -289.604981)
			(xy 305.921656 -289.651662) (xy 305.929551 -289.700239) (xy 305.930046 -289.724846) (xy 306.269148 -289.724846)
			(xy 306.273108 -289.675792) (xy 306.284885 -289.628008) (xy 306.304176 -289.582732) (xy 306.330479 -289.541136)
			(xy 306.363114 -289.504299) (xy 306.401235 -289.473174) (xy 306.443856 -289.448567) (xy 306.489872 -289.431115)
			(xy 306.538091 -289.421271) (xy 306.587266 -289.41929) (xy 306.636121 -289.425222) (xy 306.683392 -289.438914)
			(xy 306.727854 -289.460012) (xy 306.768357 -289.487968) (xy 306.80385 -289.52206) (xy 306.833415 -289.561404)
			(xy 306.856286 -289.604981) (xy 306.87187 -289.651662) (xy 306.879765 -289.700239) (xy 306.88026 -289.724846)
			(xy 308.169068 -289.724846) (xy 308.173028 -289.675792) (xy 308.184805 -289.628008) (xy 308.204096 -289.582732)
			(xy 308.230399 -289.541136) (xy 308.263034 -289.504299) (xy 308.301155 -289.473174) (xy 308.343776 -289.448567)
			(xy 308.389792 -289.431115) (xy 308.438011 -289.421271) (xy 308.487186 -289.41929) (xy 308.536041 -289.425222)
			(xy 308.583312 -289.438914) (xy 308.627774 -289.460012) (xy 308.668277 -289.487968) (xy 308.70377 -289.52206)
			(xy 308.733335 -289.561404) (xy 308.756206 -289.604981) (xy 308.77179 -289.651662) (xy 308.779685 -289.700239)
			(xy 308.78018 -289.724846) (xy 309.119028 -289.724846) (xy 309.122988 -289.675792) (xy 309.134765 -289.628008)
			(xy 309.154056 -289.582732) (xy 309.180359 -289.541136) (xy 309.212994 -289.504299) (xy 309.251115 -289.473174)
			(xy 309.293736 -289.448567) (xy 309.339752 -289.431115) (xy 309.387971 -289.421271) (xy 309.437146 -289.41929)
			(xy 309.486001 -289.425222) (xy 309.533272 -289.438914) (xy 309.577734 -289.460012) (xy 309.618237 -289.487968)
			(xy 309.65373 -289.52206) (xy 309.683295 -289.561404) (xy 309.706166 -289.604981) (xy 309.72175 -289.651662)
			(xy 309.729645 -289.700239) (xy 309.73014 -289.724846) (xy 310.068988 -289.724846) (xy 310.072948 -289.675792)
			(xy 310.084725 -289.628008) (xy 310.104016 -289.582732) (xy 310.130319 -289.541136) (xy 310.162954 -289.504299)
			(xy 310.201075 -289.473174) (xy 310.243696 -289.448567) (xy 310.289712 -289.431115) (xy 310.337931 -289.421271)
			(xy 310.387106 -289.41929) (xy 310.435961 -289.425222) (xy 310.483232 -289.438914) (xy 310.527694 -289.460012)
			(xy 310.568197 -289.487968) (xy 310.60369 -289.52206) (xy 310.633255 -289.561404) (xy 310.656126 -289.604981)
			(xy 310.67171 -289.651662) (xy 310.679605 -289.700239) (xy 310.6801 -289.724846) (xy 311.018948 -289.724846)
			(xy 311.022908 -289.675792) (xy 311.034685 -289.628008) (xy 311.053976 -289.582732) (xy 311.080279 -289.541136)
			(xy 311.112914 -289.504299) (xy 311.151035 -289.473174) (xy 311.193656 -289.448567) (xy 311.239672 -289.431115)
			(xy 311.287891 -289.421271) (xy 311.337066 -289.41929) (xy 311.385921 -289.425222) (xy 311.433192 -289.438914)
			(xy 311.477654 -289.460012) (xy 311.518157 -289.487968) (xy 311.55365 -289.52206) (xy 311.583215 -289.561404)
			(xy 311.606086 -289.604981) (xy 311.62167 -289.651662) (xy 311.629565 -289.700239) (xy 311.63006 -289.724846)
			(xy 311.968908 -289.724846) (xy 311.972868 -289.675792) (xy 311.984645 -289.628008) (xy 312.003936 -289.582732)
			(xy 312.030239 -289.541136) (xy 312.062874 -289.504299) (xy 312.100995 -289.473174) (xy 312.143616 -289.448567)
			(xy 312.189632 -289.431115) (xy 312.237851 -289.421271) (xy 312.287026 -289.41929) (xy 312.335881 -289.425222)
			(xy 312.383152 -289.438914) (xy 312.427614 -289.460012) (xy 312.468117 -289.487968) (xy 312.50361 -289.52206)
			(xy 312.533175 -289.561404) (xy 312.556046 -289.604981) (xy 312.57163 -289.651662) (xy 312.579525 -289.700239)
			(xy 312.58002 -289.724846) (xy 312.919122 -289.724846) (xy 312.923082 -289.675792) (xy 312.934859 -289.628008)
			(xy 312.95415 -289.582732) (xy 312.980453 -289.541136) (xy 313.013088 -289.504299) (xy 313.051209 -289.473174)
			(xy 313.09383 -289.448567) (xy 313.139846 -289.431115) (xy 313.188065 -289.421271) (xy 313.23724 -289.41929)
			(xy 313.286095 -289.425222) (xy 313.333366 -289.438914) (xy 313.377828 -289.460012) (xy 313.418331 -289.487968)
			(xy 313.453824 -289.52206) (xy 313.483389 -289.561404) (xy 313.50626 -289.604981) (xy 313.521844 -289.651662)
			(xy 313.529739 -289.700239) (xy 313.530234 -289.724846) (xy 313.869082 -289.724846) (xy 313.873042 -289.675792)
			(xy 313.884819 -289.628008) (xy 313.90411 -289.582732) (xy 313.930413 -289.541136) (xy 313.963048 -289.504299)
			(xy 314.001169 -289.473174) (xy 314.04379 -289.448567) (xy 314.089806 -289.431115) (xy 314.138025 -289.421271)
			(xy 314.1872 -289.41929) (xy 314.236055 -289.425222) (xy 314.283326 -289.438914) (xy 314.327788 -289.460012)
			(xy 314.368291 -289.487968) (xy 314.403784 -289.52206) (xy 314.433349 -289.561404) (xy 314.45622 -289.604981)
			(xy 314.471804 -289.651662) (xy 314.479699 -289.700239) (xy 314.480194 -289.724846) (xy 314.479699 -289.749453)
			(xy 314.471804 -289.79803) (xy 314.45622 -289.844711) (xy 314.433349 -289.888288) (xy 314.403784 -289.927632)
			(xy 314.368291 -289.961724) (xy 314.327788 -289.98968) (xy 314.283326 -290.010778) (xy 314.236055 -290.02447)
			(xy 314.1872 -290.030402) (xy 314.138025 -290.028421) (xy 314.089806 -290.018577) (xy 314.04379 -290.001125)
			(xy 314.001169 -289.976518) (xy 313.963048 -289.945393) (xy 313.930413 -289.908556) (xy 313.90411 -289.86696)
			(xy 313.884819 -289.821684) (xy 313.873042 -289.7739) (xy 313.869082 -289.724846) (xy 313.530234 -289.724846)
			(xy 313.529739 -289.749453) (xy 313.521844 -289.79803) (xy 313.50626 -289.844711) (xy 313.483389 -289.888288)
			(xy 313.453824 -289.927632) (xy 313.418331 -289.961724) (xy 313.377828 -289.98968) (xy 313.333366 -290.010778)
			(xy 313.286095 -290.02447) (xy 313.23724 -290.030402) (xy 313.188065 -290.028421) (xy 313.139846 -290.018577)
			(xy 313.09383 -290.001125) (xy 313.051209 -289.976518) (xy 313.013088 -289.945393) (xy 312.980453 -289.908556)
			(xy 312.95415 -289.86696) (xy 312.934859 -289.821684) (xy 312.923082 -289.7739) (xy 312.919122 -289.724846)
			(xy 312.58002 -289.724846) (xy 312.579525 -289.749453) (xy 312.57163 -289.79803) (xy 312.556046 -289.844711)
			(xy 312.533175 -289.888288) (xy 312.50361 -289.927632) (xy 312.468117 -289.961724) (xy 312.427614 -289.98968)
			(xy 312.383152 -290.010778) (xy 312.335881 -290.02447) (xy 312.287026 -290.030402) (xy 312.237851 -290.028421)
			(xy 312.189632 -290.018577) (xy 312.143616 -290.001125) (xy 312.100995 -289.976518) (xy 312.062874 -289.945393)
			(xy 312.030239 -289.908556) (xy 312.003936 -289.86696) (xy 311.984645 -289.821684) (xy 311.972868 -289.7739)
			(xy 311.968908 -289.724846) (xy 311.63006 -289.724846) (xy 311.629565 -289.749453) (xy 311.62167 -289.79803)
			(xy 311.606086 -289.844711) (xy 311.583215 -289.888288) (xy 311.55365 -289.927632) (xy 311.518157 -289.961724)
			(xy 311.477654 -289.98968) (xy 311.433192 -290.010778) (xy 311.385921 -290.02447) (xy 311.337066 -290.030402)
			(xy 311.287891 -290.028421) (xy 311.239672 -290.018577) (xy 311.193656 -290.001125) (xy 311.151035 -289.976518)
			(xy 311.112914 -289.945393) (xy 311.080279 -289.908556) (xy 311.053976 -289.86696) (xy 311.034685 -289.821684)
			(xy 311.022908 -289.7739) (xy 311.018948 -289.724846) (xy 310.6801 -289.724846) (xy 310.679605 -289.749453)
			(xy 310.67171 -289.79803) (xy 310.656126 -289.844711) (xy 310.633255 -289.888288) (xy 310.60369 -289.927632)
			(xy 310.568197 -289.961724) (xy 310.527694 -289.98968) (xy 310.483232 -290.010778) (xy 310.435961 -290.02447)
			(xy 310.387106 -290.030402) (xy 310.337931 -290.028421) (xy 310.289712 -290.018577) (xy 310.243696 -290.001125)
			(xy 310.201075 -289.976518) (xy 310.162954 -289.945393) (xy 310.130319 -289.908556) (xy 310.104016 -289.86696)
			(xy 310.084725 -289.821684) (xy 310.072948 -289.7739) (xy 310.068988 -289.724846) (xy 309.73014 -289.724846)
			(xy 309.729645 -289.749453) (xy 309.72175 -289.79803) (xy 309.706166 -289.844711) (xy 309.683295 -289.888288)
			(xy 309.65373 -289.927632) (xy 309.618237 -289.961724) (xy 309.577734 -289.98968) (xy 309.533272 -290.010778)
			(xy 309.486001 -290.02447) (xy 309.437146 -290.030402) (xy 309.387971 -290.028421) (xy 309.339752 -290.018577)
			(xy 309.293736 -290.001125) (xy 309.251115 -289.976518) (xy 309.212994 -289.945393) (xy 309.180359 -289.908556)
			(xy 309.154056 -289.86696) (xy 309.134765 -289.821684) (xy 309.122988 -289.7739) (xy 309.119028 -289.724846)
			(xy 308.78018 -289.724846) (xy 308.779685 -289.749453) (xy 308.77179 -289.79803) (xy 308.756206 -289.844711)
			(xy 308.733335 -289.888288) (xy 308.70377 -289.927632) (xy 308.668277 -289.961724) (xy 308.627774 -289.98968)
			(xy 308.583312 -290.010778) (xy 308.536041 -290.02447) (xy 308.487186 -290.030402) (xy 308.438011 -290.028421)
			(xy 308.389792 -290.018577) (xy 308.343776 -290.001125) (xy 308.301155 -289.976518) (xy 308.263034 -289.945393)
			(xy 308.230399 -289.908556) (xy 308.204096 -289.86696) (xy 308.184805 -289.821684) (xy 308.173028 -289.7739)
			(xy 308.169068 -289.724846) (xy 306.88026 -289.724846) (xy 306.879765 -289.749453) (xy 306.87187 -289.79803)
			(xy 306.856286 -289.844711) (xy 306.833415 -289.888288) (xy 306.80385 -289.927632) (xy 306.768357 -289.961724)
			(xy 306.727854 -289.98968) (xy 306.683392 -290.010778) (xy 306.636121 -290.02447) (xy 306.587266 -290.030402)
			(xy 306.538091 -290.028421) (xy 306.489872 -290.018577) (xy 306.443856 -290.001125) (xy 306.401235 -289.976518)
			(xy 306.363114 -289.945393) (xy 306.330479 -289.908556) (xy 306.304176 -289.86696) (xy 306.284885 -289.821684)
			(xy 306.273108 -289.7739) (xy 306.269148 -289.724846) (xy 305.930046 -289.724846) (xy 305.929551 -289.749453)
			(xy 305.921656 -289.79803) (xy 305.906072 -289.844711) (xy 305.883201 -289.888288) (xy 305.853636 -289.927632)
			(xy 305.818143 -289.961724) (xy 305.77764 -289.98968) (xy 305.733178 -290.010778) (xy 305.685907 -290.02447)
			(xy 305.637052 -290.030402) (xy 305.587877 -290.028421) (xy 305.539658 -290.018577) (xy 305.493642 -290.001125)
			(xy 305.451021 -289.976518) (xy 305.4129 -289.945393) (xy 305.380265 -289.908556) (xy 305.353962 -289.86696)
			(xy 305.334671 -289.821684) (xy 305.322894 -289.7739) (xy 305.318934 -289.724846) (xy 304.980086 -289.724846)
			(xy 304.979591 -289.749453) (xy 304.971696 -289.79803) (xy 304.956112 -289.844711) (xy 304.933241 -289.888288)
			(xy 304.903676 -289.927632) (xy 304.868183 -289.961724) (xy 304.82768 -289.98968) (xy 304.783218 -290.010778)
			(xy 304.735947 -290.02447) (xy 304.687092 -290.030402) (xy 304.637917 -290.028421) (xy 304.589698 -290.018577)
			(xy 304.543682 -290.001125) (xy 304.501061 -289.976518) (xy 304.46294 -289.945393) (xy 304.430305 -289.908556)
			(xy 304.404002 -289.86696) (xy 304.384711 -289.821684) (xy 304.372934 -289.7739) (xy 304.368974 -289.724846)
			(xy 304.030126 -289.724846) (xy 304.029631 -289.749453) (xy 304.021736 -289.79803) (xy 304.006152 -289.844711)
			(xy 303.983281 -289.888288) (xy 303.953716 -289.927632) (xy 303.918223 -289.961724) (xy 303.87772 -289.98968)
			(xy 303.833258 -290.010778) (xy 303.785987 -290.02447) (xy 303.737132 -290.030402) (xy 303.687957 -290.028421)
			(xy 303.639738 -290.018577) (xy 303.593722 -290.001125) (xy 303.551101 -289.976518) (xy 303.51298 -289.945393)
			(xy 303.480345 -289.908556) (xy 303.454042 -289.86696) (xy 303.434751 -289.821684) (xy 303.422974 -289.7739)
			(xy 303.419014 -289.724846) (xy 303.080551 -289.724846) (xy 303.076058 -289.777049) (xy 303.062719 -289.827727)
			(xy 303.040928 -289.875386) (xy 303.026572 -289.897312) (xy 303.020612 -289.906933) (xy 303.016993 -289.929248)
			(xy 303.023317 -289.950952) (xy 303.030382 -289.959796) (xy 303.03724 -289.967162) (xy 303.043084 -289.974351)
			(xy 303.049591 -289.991684) (xy 303.04994 -290.000944) (xy 303.04994 -290.398708) (xy 303.049537 -290.407957)
			(xy 303.04304 -290.425275) (xy 303.03724 -290.43249) (xy 303.030382 -290.439856) (xy 303.023421 -290.44875)
			(xy 303.017161 -290.470417) (xy 303.020713 -290.492688) (xy 303.026572 -290.50234) (xy 303.040929 -290.524263)
			(xy 303.062712 -290.571921) (xy 303.076043 -290.622597) (xy 303.080529 -290.674805) (xy 303.080529 -290.674806)
			(xy 303.419014 -290.674806) (xy 303.422974 -290.625752) (xy 303.434751 -290.577968) (xy 303.454042 -290.532692)
			(xy 303.480345 -290.491096) (xy 303.51298 -290.454259) (xy 303.551101 -290.423134) (xy 303.593722 -290.398527)
			(xy 303.639738 -290.381075) (xy 303.687957 -290.371231) (xy 303.737132 -290.36925) (xy 303.785987 -290.375182)
			(xy 303.833258 -290.388874) (xy 303.87772 -290.409972) (xy 303.918223 -290.437928) (xy 303.953716 -290.47202)
			(xy 303.983281 -290.511364) (xy 304.006152 -290.554941) (xy 304.021736 -290.601622) (xy 304.029631 -290.650199)
			(xy 304.030126 -290.674806) (xy 304.368974 -290.674806) (xy 304.372934 -290.625752) (xy 304.384711 -290.577968)
			(xy 304.404002 -290.532692) (xy 304.430305 -290.491096) (xy 304.46294 -290.454259) (xy 304.501061 -290.423134)
			(xy 304.543682 -290.398527) (xy 304.589698 -290.381075) (xy 304.637917 -290.371231) (xy 304.687092 -290.36925)
			(xy 304.735947 -290.375182) (xy 304.783218 -290.388874) (xy 304.82768 -290.409972) (xy 304.868183 -290.437928)
			(xy 304.903676 -290.47202) (xy 304.933241 -290.511364) (xy 304.956112 -290.554941) (xy 304.971696 -290.601622)
			(xy 304.979591 -290.650199) (xy 304.980086 -290.674806) (xy 305.318934 -290.674806) (xy 305.322894 -290.625752)
			(xy 305.334671 -290.577968) (xy 305.353962 -290.532692) (xy 305.380265 -290.491096) (xy 305.4129 -290.454259)
			(xy 305.451021 -290.423134) (xy 305.493642 -290.398527) (xy 305.539658 -290.381075) (xy 305.587877 -290.371231)
			(xy 305.637052 -290.36925) (xy 305.685907 -290.375182) (xy 305.733178 -290.388874) (xy 305.77764 -290.409972)
			(xy 305.818143 -290.437928) (xy 305.853636 -290.47202) (xy 305.883201 -290.511364) (xy 305.906072 -290.554941)
			(xy 305.921656 -290.601622) (xy 305.929551 -290.650199) (xy 305.930046 -290.674806) (xy 306.268894 -290.674806)
			(xy 306.272854 -290.625752) (xy 306.284631 -290.577968) (xy 306.303922 -290.532692) (xy 306.330225 -290.491096)
			(xy 306.36286 -290.454259) (xy 306.400981 -290.423134) (xy 306.443602 -290.398527) (xy 306.489618 -290.381075)
			(xy 306.537837 -290.371231) (xy 306.587012 -290.36925) (xy 306.635867 -290.375182) (xy 306.683138 -290.388874)
			(xy 306.7276 -290.409972) (xy 306.768103 -290.437928) (xy 306.803596 -290.47202) (xy 306.833161 -290.511364)
			(xy 306.856032 -290.554941) (xy 306.871616 -290.601622) (xy 306.879511 -290.650199) (xy 306.880006 -290.674806)
			(xy 307.219108 -290.674806) (xy 307.223068 -290.625752) (xy 307.234845 -290.577968) (xy 307.254136 -290.532692)
			(xy 307.280439 -290.491096) (xy 307.313074 -290.454259) (xy 307.351195 -290.423134) (xy 307.393816 -290.398527)
			(xy 307.439832 -290.381075) (xy 307.488051 -290.371231) (xy 307.537226 -290.36925) (xy 307.586081 -290.375182)
			(xy 307.633352 -290.388874) (xy 307.677814 -290.409972) (xy 307.718317 -290.437928) (xy 307.75381 -290.47202)
			(xy 307.783375 -290.511364) (xy 307.806246 -290.554941) (xy 307.82183 -290.601622) (xy 307.829725 -290.650199)
			(xy 307.83022 -290.674806) (xy 308.169068 -290.674806) (xy 308.173028 -290.625752) (xy 308.184805 -290.577968)
			(xy 308.204096 -290.532692) (xy 308.230399 -290.491096) (xy 308.263034 -290.454259) (xy 308.301155 -290.423134)
			(xy 308.343776 -290.398527) (xy 308.389792 -290.381075) (xy 308.438011 -290.371231) (xy 308.487186 -290.36925)
			(xy 308.536041 -290.375182) (xy 308.583312 -290.388874) (xy 308.627774 -290.409972) (xy 308.668277 -290.437928)
			(xy 308.70377 -290.47202) (xy 308.733335 -290.511364) (xy 308.756206 -290.554941) (xy 308.77179 -290.601622)
			(xy 308.779685 -290.650199) (xy 308.78018 -290.674806) (xy 309.119028 -290.674806) (xy 309.122988 -290.625752)
			(xy 309.134765 -290.577968) (xy 309.154056 -290.532692) (xy 309.180359 -290.491096) (xy 309.212994 -290.454259)
			(xy 309.251115 -290.423134) (xy 309.293736 -290.398527) (xy 309.339752 -290.381075) (xy 309.387971 -290.371231)
			(xy 309.437146 -290.36925) (xy 309.486001 -290.375182) (xy 309.533272 -290.388874) (xy 309.577734 -290.409972)
			(xy 309.618237 -290.437928) (xy 309.65373 -290.47202) (xy 309.683295 -290.511364) (xy 309.706166 -290.554941)
			(xy 309.72175 -290.601622) (xy 309.729645 -290.650199) (xy 309.73014 -290.674806) (xy 310.068988 -290.674806)
			(xy 310.072948 -290.625752) (xy 310.084725 -290.577968) (xy 310.104016 -290.532692) (xy 310.130319 -290.491096)
			(xy 310.162954 -290.454259) (xy 310.201075 -290.423134) (xy 310.243696 -290.398527) (xy 310.289712 -290.381075)
			(xy 310.337931 -290.371231) (xy 310.387106 -290.36925) (xy 310.435961 -290.375182) (xy 310.483232 -290.388874)
			(xy 310.527694 -290.409972) (xy 310.568197 -290.437928) (xy 310.60369 -290.47202) (xy 310.633255 -290.511364)
			(xy 310.656126 -290.554941) (xy 310.67171 -290.601622) (xy 310.679605 -290.650199) (xy 310.6801 -290.674806)
			(xy 311.018948 -290.674806) (xy 311.022908 -290.625752) (xy 311.034685 -290.577968) (xy 311.053976 -290.532692)
			(xy 311.080279 -290.491096) (xy 311.112914 -290.454259) (xy 311.151035 -290.423134) (xy 311.193656 -290.398527)
			(xy 311.239672 -290.381075) (xy 311.287891 -290.371231) (xy 311.337066 -290.36925) (xy 311.385921 -290.375182)
			(xy 311.433192 -290.388874) (xy 311.477654 -290.409972) (xy 311.518157 -290.437928) (xy 311.55365 -290.47202)
			(xy 311.583215 -290.511364) (xy 311.606086 -290.554941) (xy 311.62167 -290.601622) (xy 311.629565 -290.650199)
			(xy 311.63006 -290.674806) (xy 311.968908 -290.674806) (xy 311.972868 -290.625752) (xy 311.984645 -290.577968)
			(xy 312.003936 -290.532692) (xy 312.030239 -290.491096) (xy 312.062874 -290.454259) (xy 312.100995 -290.423134)
			(xy 312.143616 -290.398527) (xy 312.189632 -290.381075) (xy 312.237851 -290.371231) (xy 312.287026 -290.36925)
			(xy 312.335881 -290.375182) (xy 312.383152 -290.388874) (xy 312.427614 -290.409972) (xy 312.468117 -290.437928)
			(xy 312.50361 -290.47202) (xy 312.533175 -290.511364) (xy 312.556046 -290.554941) (xy 312.57163 -290.601622)
			(xy 312.579525 -290.650199) (xy 312.58002 -290.674806) (xy 312.919122 -290.674806) (xy 312.923082 -290.625752)
			(xy 312.934859 -290.577968) (xy 312.95415 -290.532692) (xy 312.980453 -290.491096) (xy 313.013088 -290.454259)
			(xy 313.051209 -290.423134) (xy 313.09383 -290.398527) (xy 313.139846 -290.381075) (xy 313.188065 -290.371231)
			(xy 313.23724 -290.36925) (xy 313.286095 -290.375182) (xy 313.333366 -290.388874) (xy 313.377828 -290.409972)
			(xy 313.418331 -290.437928) (xy 313.453824 -290.47202) (xy 313.483389 -290.511364) (xy 313.50626 -290.554941)
			(xy 313.521844 -290.601622) (xy 313.529739 -290.650199) (xy 313.530234 -290.674806) (xy 313.869082 -290.674806)
			(xy 313.873042 -290.625752) (xy 313.884819 -290.577968) (xy 313.90411 -290.532692) (xy 313.930413 -290.491096)
			(xy 313.963048 -290.454259) (xy 314.001169 -290.423134) (xy 314.04379 -290.398527) (xy 314.089806 -290.381075)
			(xy 314.138025 -290.371231) (xy 314.1872 -290.36925) (xy 314.236055 -290.375182) (xy 314.283326 -290.388874)
			(xy 314.327788 -290.409972) (xy 314.368291 -290.437928) (xy 314.403784 -290.47202) (xy 314.433349 -290.511364)
			(xy 314.45622 -290.554941) (xy 314.471804 -290.601622) (xy 314.479699 -290.650199) (xy 314.480194 -290.674806)
			(xy 314.479699 -290.699413) (xy 314.471804 -290.74799) (xy 314.45622 -290.794671) (xy 314.433349 -290.838248)
			(xy 314.403784 -290.877592) (xy 314.368291 -290.911684) (xy 314.327788 -290.93964) (xy 314.283326 -290.960738)
			(xy 314.236055 -290.97443) (xy 314.1872 -290.980362) (xy 314.138025 -290.978381) (xy 314.089806 -290.968537)
			(xy 314.04379 -290.951085) (xy 314.001169 -290.926478) (xy 313.963048 -290.895353) (xy 313.930413 -290.858516)
			(xy 313.90411 -290.81692) (xy 313.884819 -290.771644) (xy 313.873042 -290.72386) (xy 313.869082 -290.674806)
			(xy 313.530234 -290.674806) (xy 313.529739 -290.699413) (xy 313.521844 -290.74799) (xy 313.50626 -290.794671)
			(xy 313.483389 -290.838248) (xy 313.453824 -290.877592) (xy 313.418331 -290.911684) (xy 313.377828 -290.93964)
			(xy 313.333366 -290.960738) (xy 313.286095 -290.97443) (xy 313.23724 -290.980362) (xy 313.188065 -290.978381)
			(xy 313.139846 -290.968537) (xy 313.09383 -290.951085) (xy 313.051209 -290.926478) (xy 313.013088 -290.895353)
			(xy 312.980453 -290.858516) (xy 312.95415 -290.81692) (xy 312.934859 -290.771644) (xy 312.923082 -290.72386)
			(xy 312.919122 -290.674806) (xy 312.58002 -290.674806) (xy 312.579525 -290.699413) (xy 312.57163 -290.74799)
			(xy 312.556046 -290.794671) (xy 312.533175 -290.838248) (xy 312.50361 -290.877592) (xy 312.468117 -290.911684)
			(xy 312.427614 -290.93964) (xy 312.383152 -290.960738) (xy 312.335881 -290.97443) (xy 312.287026 -290.980362)
			(xy 312.237851 -290.978381) (xy 312.189632 -290.968537) (xy 312.143616 -290.951085) (xy 312.100995 -290.926478)
			(xy 312.062874 -290.895353) (xy 312.030239 -290.858516) (xy 312.003936 -290.81692) (xy 311.984645 -290.771644)
			(xy 311.972868 -290.72386) (xy 311.968908 -290.674806) (xy 311.63006 -290.674806) (xy 311.629565 -290.699413)
			(xy 311.62167 -290.74799) (xy 311.606086 -290.794671) (xy 311.583215 -290.838248) (xy 311.55365 -290.877592)
			(xy 311.518157 -290.911684) (xy 311.477654 -290.93964) (xy 311.433192 -290.960738) (xy 311.385921 -290.97443)
			(xy 311.337066 -290.980362) (xy 311.287891 -290.978381) (xy 311.239672 -290.968537) (xy 311.193656 -290.951085)
			(xy 311.151035 -290.926478) (xy 311.112914 -290.895353) (xy 311.080279 -290.858516) (xy 311.053976 -290.81692)
			(xy 311.034685 -290.771644) (xy 311.022908 -290.72386) (xy 311.018948 -290.674806) (xy 310.6801 -290.674806)
			(xy 310.679605 -290.699413) (xy 310.67171 -290.74799) (xy 310.656126 -290.794671) (xy 310.633255 -290.838248)
			(xy 310.60369 -290.877592) (xy 310.568197 -290.911684) (xy 310.527694 -290.93964) (xy 310.483232 -290.960738)
			(xy 310.435961 -290.97443) (xy 310.387106 -290.980362) (xy 310.337931 -290.978381) (xy 310.289712 -290.968537)
			(xy 310.243696 -290.951085) (xy 310.201075 -290.926478) (xy 310.162954 -290.895353) (xy 310.130319 -290.858516)
			(xy 310.104016 -290.81692) (xy 310.084725 -290.771644) (xy 310.072948 -290.72386) (xy 310.068988 -290.674806)
			(xy 309.73014 -290.674806) (xy 309.729645 -290.699413) (xy 309.72175 -290.74799) (xy 309.706166 -290.794671)
			(xy 309.683295 -290.838248) (xy 309.65373 -290.877592) (xy 309.618237 -290.911684) (xy 309.577734 -290.93964)
			(xy 309.533272 -290.960738) (xy 309.486001 -290.97443) (xy 309.437146 -290.980362) (xy 309.387971 -290.978381)
			(xy 309.339752 -290.968537) (xy 309.293736 -290.951085) (xy 309.251115 -290.926478) (xy 309.212994 -290.895353)
			(xy 309.180359 -290.858516) (xy 309.154056 -290.81692) (xy 309.134765 -290.771644) (xy 309.122988 -290.72386)
			(xy 309.119028 -290.674806) (xy 308.78018 -290.674806) (xy 308.779685 -290.699413) (xy 308.77179 -290.74799)
			(xy 308.756206 -290.794671) (xy 308.733335 -290.838248) (xy 308.70377 -290.877592) (xy 308.668277 -290.911684)
			(xy 308.627774 -290.93964) (xy 308.583312 -290.960738) (xy 308.536041 -290.97443) (xy 308.487186 -290.980362)
			(xy 308.438011 -290.978381) (xy 308.389792 -290.968537) (xy 308.343776 -290.951085) (xy 308.301155 -290.926478)
			(xy 308.263034 -290.895353) (xy 308.230399 -290.858516) (xy 308.204096 -290.81692) (xy 308.184805 -290.771644)
			(xy 308.173028 -290.72386) (xy 308.169068 -290.674806) (xy 307.83022 -290.674806) (xy 307.829725 -290.699413)
			(xy 307.82183 -290.74799) (xy 307.806246 -290.794671) (xy 307.783375 -290.838248) (xy 307.75381 -290.877592)
			(xy 307.718317 -290.911684) (xy 307.677814 -290.93964) (xy 307.633352 -290.960738) (xy 307.586081 -290.97443)
			(xy 307.537226 -290.980362) (xy 307.488051 -290.978381) (xy 307.439832 -290.968537) (xy 307.393816 -290.951085)
			(xy 307.351195 -290.926478) (xy 307.313074 -290.895353) (xy 307.280439 -290.858516) (xy 307.254136 -290.81692)
			(xy 307.234845 -290.771644) (xy 307.223068 -290.72386) (xy 307.219108 -290.674806) (xy 306.880006 -290.674806)
			(xy 306.879511 -290.699413) (xy 306.871616 -290.74799) (xy 306.856032 -290.794671) (xy 306.833161 -290.838248)
			(xy 306.803596 -290.877592) (xy 306.768103 -290.911684) (xy 306.7276 -290.93964) (xy 306.683138 -290.960738)
			(xy 306.635867 -290.97443) (xy 306.587012 -290.980362) (xy 306.537837 -290.978381) (xy 306.489618 -290.968537)
			(xy 306.443602 -290.951085) (xy 306.400981 -290.926478) (xy 306.36286 -290.895353) (xy 306.330225 -290.858516)
			(xy 306.303922 -290.81692) (xy 306.284631 -290.771644) (xy 306.272854 -290.72386) (xy 306.268894 -290.674806)
			(xy 305.930046 -290.674806) (xy 305.929551 -290.699413) (xy 305.921656 -290.74799) (xy 305.906072 -290.794671)
			(xy 305.883201 -290.838248) (xy 305.853636 -290.877592) (xy 305.818143 -290.911684) (xy 305.77764 -290.93964)
			(xy 305.733178 -290.960738) (xy 305.685907 -290.97443) (xy 305.637052 -290.980362) (xy 305.587877 -290.978381)
			(xy 305.539658 -290.968537) (xy 305.493642 -290.951085) (xy 305.451021 -290.926478) (xy 305.4129 -290.895353)
			(xy 305.380265 -290.858516) (xy 305.353962 -290.81692) (xy 305.334671 -290.771644) (xy 305.322894 -290.72386)
			(xy 305.318934 -290.674806) (xy 304.980086 -290.674806) (xy 304.979591 -290.699413) (xy 304.971696 -290.74799)
			(xy 304.956112 -290.794671) (xy 304.933241 -290.838248) (xy 304.903676 -290.877592) (xy 304.868183 -290.911684)
			(xy 304.82768 -290.93964) (xy 304.783218 -290.960738) (xy 304.735947 -290.97443) (xy 304.687092 -290.980362)
			(xy 304.637917 -290.978381) (xy 304.589698 -290.968537) (xy 304.543682 -290.951085) (xy 304.501061 -290.926478)
			(xy 304.46294 -290.895353) (xy 304.430305 -290.858516) (xy 304.404002 -290.81692) (xy 304.384711 -290.771644)
			(xy 304.372934 -290.72386) (xy 304.368974 -290.674806) (xy 304.030126 -290.674806) (xy 304.029631 -290.699413)
			(xy 304.021736 -290.74799) (xy 304.006152 -290.794671) (xy 303.983281 -290.838248) (xy 303.953716 -290.877592)
			(xy 303.918223 -290.911684) (xy 303.87772 -290.93964) (xy 303.833258 -290.960738) (xy 303.785987 -290.97443)
			(xy 303.737132 -290.980362) (xy 303.687957 -290.978381) (xy 303.639738 -290.968537) (xy 303.593722 -290.951085)
			(xy 303.551101 -290.926478) (xy 303.51298 -290.895353) (xy 303.480345 -290.858516) (xy 303.454042 -290.81692)
			(xy 303.434751 -290.771644) (xy 303.422974 -290.72386) (xy 303.419014 -290.674806) (xy 303.080529 -290.674806)
			(xy 303.076041 -290.727013) (xy 303.062709 -290.777689) (xy 303.040924 -290.825346) (xy 303.026572 -290.847272)
			(xy 303.020649 -290.856912) (xy 303.017018 -290.879214) (xy 303.023326 -290.900911) (xy 303.030382 -290.909756)
			(xy 303.03724 -290.917122) (xy 303.043067 -290.924324) (xy 303.049584 -290.941647) (xy 303.04994 -290.950904)
			(xy 303.04994 -291.348668) (xy 303.049566 -291.35792) (xy 303.043049 -291.375238) (xy 303.03724 -291.38245)
			(xy 303.030382 -291.389816) (xy 303.023369 -291.398675) (xy 303.017124 -291.420362) (xy 303.020699 -291.442646)
			(xy 303.026572 -291.4523) (xy 303.040893 -291.474245) (xy 303.06268 -291.521897) (xy 303.076015 -291.572568)
			(xy 303.080506 -291.624766) (xy 303.419014 -291.624766) (xy 303.422974 -291.575712) (xy 303.434751 -291.527928)
			(xy 303.454042 -291.482652) (xy 303.480345 -291.441056) (xy 303.51298 -291.404219) (xy 303.551101 -291.373094)
			(xy 303.593722 -291.348487) (xy 303.639738 -291.331035) (xy 303.687957 -291.321191) (xy 303.737132 -291.31921)
			(xy 303.785987 -291.325142) (xy 303.833258 -291.338834) (xy 303.87772 -291.359932) (xy 303.918223 -291.387888)
			(xy 303.953716 -291.42198) (xy 303.983281 -291.461324) (xy 304.006152 -291.504901) (xy 304.021736 -291.551582)
			(xy 304.029631 -291.600159) (xy 304.030126 -291.624766) (xy 304.368974 -291.624766) (xy 304.372934 -291.575712)
			(xy 304.384711 -291.527928) (xy 304.404002 -291.482652) (xy 304.430305 -291.441056) (xy 304.46294 -291.404219)
			(xy 304.501061 -291.373094) (xy 304.543682 -291.348487) (xy 304.589698 -291.331035) (xy 304.637917 -291.321191)
			(xy 304.687092 -291.31921) (xy 304.735947 -291.325142) (xy 304.783218 -291.338834) (xy 304.82768 -291.359932)
			(xy 304.868183 -291.387888) (xy 304.903676 -291.42198) (xy 304.933241 -291.461324) (xy 304.956112 -291.504901)
			(xy 304.971696 -291.551582) (xy 304.979591 -291.600159) (xy 304.980086 -291.624766) (xy 305.318934 -291.624766)
			(xy 305.322894 -291.575712) (xy 305.334671 -291.527928) (xy 305.353962 -291.482652) (xy 305.380265 -291.441056)
			(xy 305.4129 -291.404219) (xy 305.451021 -291.373094) (xy 305.493642 -291.348487) (xy 305.539658 -291.331035)
			(xy 305.587877 -291.321191) (xy 305.637052 -291.31921) (xy 305.685907 -291.325142) (xy 305.733178 -291.338834)
			(xy 305.77764 -291.359932) (xy 305.818143 -291.387888) (xy 305.853636 -291.42198) (xy 305.883201 -291.461324)
			(xy 305.906072 -291.504901) (xy 305.921656 -291.551582) (xy 305.929551 -291.600159) (xy 305.930046 -291.624766)
			(xy 306.269148 -291.624766) (xy 306.273108 -291.575712) (xy 306.284885 -291.527928) (xy 306.304176 -291.482652)
			(xy 306.330479 -291.441056) (xy 306.363114 -291.404219) (xy 306.401235 -291.373094) (xy 306.443856 -291.348487)
			(xy 306.489872 -291.331035) (xy 306.538091 -291.321191) (xy 306.587266 -291.31921) (xy 306.636121 -291.325142)
			(xy 306.683392 -291.338834) (xy 306.727854 -291.359932) (xy 306.768357 -291.387888) (xy 306.80385 -291.42198)
			(xy 306.833415 -291.461324) (xy 306.856286 -291.504901) (xy 306.87187 -291.551582) (xy 306.879765 -291.600159)
			(xy 306.88026 -291.624766) (xy 308.169068 -291.624766) (xy 308.173028 -291.575712) (xy 308.184805 -291.527928)
			(xy 308.204096 -291.482652) (xy 308.230399 -291.441056) (xy 308.263034 -291.404219) (xy 308.301155 -291.373094)
			(xy 308.343776 -291.348487) (xy 308.389792 -291.331035) (xy 308.438011 -291.321191) (xy 308.487186 -291.31921)
			(xy 308.536041 -291.325142) (xy 308.583312 -291.338834) (xy 308.627774 -291.359932) (xy 308.668277 -291.387888)
			(xy 308.70377 -291.42198) (xy 308.733335 -291.461324) (xy 308.756206 -291.504901) (xy 308.77179 -291.551582)
			(xy 308.779685 -291.600159) (xy 308.78018 -291.624766) (xy 309.119028 -291.624766) (xy 309.122988 -291.575712)
			(xy 309.134765 -291.527928) (xy 309.154056 -291.482652) (xy 309.180359 -291.441056) (xy 309.212994 -291.404219)
			(xy 309.251115 -291.373094) (xy 309.293736 -291.348487) (xy 309.339752 -291.331035) (xy 309.387971 -291.321191)
			(xy 309.437146 -291.31921) (xy 309.486001 -291.325142) (xy 309.533272 -291.338834) (xy 309.577734 -291.359932)
			(xy 309.618237 -291.387888) (xy 309.65373 -291.42198) (xy 309.683295 -291.461324) (xy 309.706166 -291.504901)
			(xy 309.72175 -291.551582) (xy 309.729645 -291.600159) (xy 309.73014 -291.624766) (xy 310.068988 -291.624766)
			(xy 310.072948 -291.575712) (xy 310.084725 -291.527928) (xy 310.104016 -291.482652) (xy 310.130319 -291.441056)
			(xy 310.162954 -291.404219) (xy 310.201075 -291.373094) (xy 310.243696 -291.348487) (xy 310.289712 -291.331035)
			(xy 310.337931 -291.321191) (xy 310.387106 -291.31921) (xy 310.435961 -291.325142) (xy 310.483232 -291.338834)
			(xy 310.527694 -291.359932) (xy 310.568197 -291.387888) (xy 310.60369 -291.42198) (xy 310.633255 -291.461324)
			(xy 310.656126 -291.504901) (xy 310.67171 -291.551582) (xy 310.679605 -291.600159) (xy 310.6801 -291.624766)
			(xy 311.018948 -291.624766) (xy 311.022908 -291.575712) (xy 311.034685 -291.527928) (xy 311.053976 -291.482652)
			(xy 311.080279 -291.441056) (xy 311.112914 -291.404219) (xy 311.151035 -291.373094) (xy 311.193656 -291.348487)
			(xy 311.239672 -291.331035) (xy 311.287891 -291.321191) (xy 311.337066 -291.31921) (xy 311.385921 -291.325142)
			(xy 311.433192 -291.338834) (xy 311.477654 -291.359932) (xy 311.518157 -291.387888) (xy 311.55365 -291.42198)
			(xy 311.583215 -291.461324) (xy 311.606086 -291.504901) (xy 311.62167 -291.551582) (xy 311.629565 -291.600159)
			(xy 311.63006 -291.624766) (xy 311.968908 -291.624766) (xy 311.972868 -291.575712) (xy 311.984645 -291.527928)
			(xy 312.003936 -291.482652) (xy 312.030239 -291.441056) (xy 312.062874 -291.404219) (xy 312.100995 -291.373094)
			(xy 312.143616 -291.348487) (xy 312.189632 -291.331035) (xy 312.237851 -291.321191) (xy 312.287026 -291.31921)
			(xy 312.335881 -291.325142) (xy 312.383152 -291.338834) (xy 312.427614 -291.359932) (xy 312.468117 -291.387888)
			(xy 312.50361 -291.42198) (xy 312.533175 -291.461324) (xy 312.556046 -291.504901) (xy 312.57163 -291.551582)
			(xy 312.579525 -291.600159) (xy 312.58002 -291.624766) (xy 312.919122 -291.624766) (xy 312.923082 -291.575712)
			(xy 312.934859 -291.527928) (xy 312.95415 -291.482652) (xy 312.980453 -291.441056) (xy 313.013088 -291.404219)
			(xy 313.051209 -291.373094) (xy 313.09383 -291.348487) (xy 313.139846 -291.331035) (xy 313.188065 -291.321191)
			(xy 313.23724 -291.31921) (xy 313.286095 -291.325142) (xy 313.333366 -291.338834) (xy 313.377828 -291.359932)
			(xy 313.418331 -291.387888) (xy 313.453824 -291.42198) (xy 313.483389 -291.461324) (xy 313.50626 -291.504901)
			(xy 313.521844 -291.551582) (xy 313.529739 -291.600159) (xy 313.530234 -291.624766) (xy 313.869082 -291.624766)
			(xy 313.873042 -291.575712) (xy 313.884819 -291.527928) (xy 313.90411 -291.482652) (xy 313.930413 -291.441056)
			(xy 313.963048 -291.404219) (xy 314.001169 -291.373094) (xy 314.04379 -291.348487) (xy 314.089806 -291.331035)
			(xy 314.138025 -291.321191) (xy 314.1872 -291.31921) (xy 314.236055 -291.325142) (xy 314.283326 -291.338834)
			(xy 314.327788 -291.359932) (xy 314.368291 -291.387888) (xy 314.403784 -291.42198) (xy 314.433349 -291.461324)
			(xy 314.45622 -291.504901) (xy 314.471804 -291.551582) (xy 314.479699 -291.600159) (xy 314.480194 -291.624766)
			(xy 314.479699 -291.649373) (xy 314.471804 -291.69795) (xy 314.45622 -291.744631) (xy 314.433349 -291.788208)
			(xy 314.403784 -291.827552) (xy 314.368291 -291.861644) (xy 314.327788 -291.8896) (xy 314.283326 -291.910698)
			(xy 314.236055 -291.92439) (xy 314.1872 -291.930322) (xy 314.138025 -291.928341) (xy 314.089806 -291.918497)
			(xy 314.04379 -291.901045) (xy 314.001169 -291.876438) (xy 313.963048 -291.845313) (xy 313.930413 -291.808476)
			(xy 313.90411 -291.76688) (xy 313.884819 -291.721604) (xy 313.873042 -291.67382) (xy 313.869082 -291.624766)
			(xy 313.530234 -291.624766) (xy 313.529739 -291.649373) (xy 313.521844 -291.69795) (xy 313.50626 -291.744631)
			(xy 313.483389 -291.788208) (xy 313.453824 -291.827552) (xy 313.418331 -291.861644) (xy 313.377828 -291.8896)
			(xy 313.333366 -291.910698) (xy 313.286095 -291.92439) (xy 313.23724 -291.930322) (xy 313.188065 -291.928341)
			(xy 313.139846 -291.918497) (xy 313.09383 -291.901045) (xy 313.051209 -291.876438) (xy 313.013088 -291.845313)
			(xy 312.980453 -291.808476) (xy 312.95415 -291.76688) (xy 312.934859 -291.721604) (xy 312.923082 -291.67382)
			(xy 312.919122 -291.624766) (xy 312.58002 -291.624766) (xy 312.579525 -291.649373) (xy 312.57163 -291.69795)
			(xy 312.556046 -291.744631) (xy 312.533175 -291.788208) (xy 312.50361 -291.827552) (xy 312.468117 -291.861644)
			(xy 312.427614 -291.8896) (xy 312.383152 -291.910698) (xy 312.335881 -291.92439) (xy 312.287026 -291.930322)
			(xy 312.237851 -291.928341) (xy 312.189632 -291.918497) (xy 312.143616 -291.901045) (xy 312.100995 -291.876438)
			(xy 312.062874 -291.845313) (xy 312.030239 -291.808476) (xy 312.003936 -291.76688) (xy 311.984645 -291.721604)
			(xy 311.972868 -291.67382) (xy 311.968908 -291.624766) (xy 311.63006 -291.624766) (xy 311.629565 -291.649373)
			(xy 311.62167 -291.69795) (xy 311.606086 -291.744631) (xy 311.583215 -291.788208) (xy 311.55365 -291.827552)
			(xy 311.518157 -291.861644) (xy 311.477654 -291.8896) (xy 311.433192 -291.910698) (xy 311.385921 -291.92439)
			(xy 311.337066 -291.930322) (xy 311.287891 -291.928341) (xy 311.239672 -291.918497) (xy 311.193656 -291.901045)
			(xy 311.151035 -291.876438) (xy 311.112914 -291.845313) (xy 311.080279 -291.808476) (xy 311.053976 -291.76688)
			(xy 311.034685 -291.721604) (xy 311.022908 -291.67382) (xy 311.018948 -291.624766) (xy 310.6801 -291.624766)
			(xy 310.679605 -291.649373) (xy 310.67171 -291.69795) (xy 310.656126 -291.744631) (xy 310.633255 -291.788208)
			(xy 310.60369 -291.827552) (xy 310.568197 -291.861644) (xy 310.527694 -291.8896) (xy 310.483232 -291.910698)
			(xy 310.435961 -291.92439) (xy 310.387106 -291.930322) (xy 310.337931 -291.928341) (xy 310.289712 -291.918497)
			(xy 310.243696 -291.901045) (xy 310.201075 -291.876438) (xy 310.162954 -291.845313) (xy 310.130319 -291.808476)
			(xy 310.104016 -291.76688) (xy 310.084725 -291.721604) (xy 310.072948 -291.67382) (xy 310.068988 -291.624766)
			(xy 309.73014 -291.624766) (xy 309.729645 -291.649373) (xy 309.72175 -291.69795) (xy 309.706166 -291.744631)
			(xy 309.683295 -291.788208) (xy 309.65373 -291.827552) (xy 309.618237 -291.861644) (xy 309.577734 -291.8896)
			(xy 309.533272 -291.910698) (xy 309.486001 -291.92439) (xy 309.437146 -291.930322) (xy 309.387971 -291.928341)
			(xy 309.339752 -291.918497) (xy 309.293736 -291.901045) (xy 309.251115 -291.876438) (xy 309.212994 -291.845313)
			(xy 309.180359 -291.808476) (xy 309.154056 -291.76688) (xy 309.134765 -291.721604) (xy 309.122988 -291.67382)
			(xy 309.119028 -291.624766) (xy 308.78018 -291.624766) (xy 308.779685 -291.649373) (xy 308.77179 -291.69795)
			(xy 308.756206 -291.744631) (xy 308.733335 -291.788208) (xy 308.70377 -291.827552) (xy 308.668277 -291.861644)
			(xy 308.627774 -291.8896) (xy 308.583312 -291.910698) (xy 308.536041 -291.92439) (xy 308.487186 -291.930322)
			(xy 308.438011 -291.928341) (xy 308.389792 -291.918497) (xy 308.343776 -291.901045) (xy 308.301155 -291.876438)
			(xy 308.263034 -291.845313) (xy 308.230399 -291.808476) (xy 308.204096 -291.76688) (xy 308.184805 -291.721604)
			(xy 308.173028 -291.67382) (xy 308.169068 -291.624766) (xy 306.88026 -291.624766) (xy 306.879765 -291.649373)
			(xy 306.87187 -291.69795) (xy 306.856286 -291.744631) (xy 306.833415 -291.788208) (xy 306.80385 -291.827552)
			(xy 306.768357 -291.861644) (xy 306.727854 -291.8896) (xy 306.683392 -291.910698) (xy 306.636121 -291.92439)
			(xy 306.587266 -291.930322) (xy 306.538091 -291.928341) (xy 306.489872 -291.918497) (xy 306.443856 -291.901045)
			(xy 306.401235 -291.876438) (xy 306.363114 -291.845313) (xy 306.330479 -291.808476) (xy 306.304176 -291.76688)
			(xy 306.284885 -291.721604) (xy 306.273108 -291.67382) (xy 306.269148 -291.624766) (xy 305.930046 -291.624766)
			(xy 305.929551 -291.649373) (xy 305.921656 -291.69795) (xy 305.906072 -291.744631) (xy 305.883201 -291.788208)
			(xy 305.853636 -291.827552) (xy 305.818143 -291.861644) (xy 305.77764 -291.8896) (xy 305.733178 -291.910698)
			(xy 305.685907 -291.92439) (xy 305.637052 -291.930322) (xy 305.587877 -291.928341) (xy 305.539658 -291.918497)
			(xy 305.493642 -291.901045) (xy 305.451021 -291.876438) (xy 305.4129 -291.845313) (xy 305.380265 -291.808476)
			(xy 305.353962 -291.76688) (xy 305.334671 -291.721604) (xy 305.322894 -291.67382) (xy 305.318934 -291.624766)
			(xy 304.980086 -291.624766) (xy 304.979591 -291.649373) (xy 304.971696 -291.69795) (xy 304.956112 -291.744631)
			(xy 304.933241 -291.788208) (xy 304.903676 -291.827552) (xy 304.868183 -291.861644) (xy 304.82768 -291.8896)
			(xy 304.783218 -291.910698) (xy 304.735947 -291.92439) (xy 304.687092 -291.930322) (xy 304.637917 -291.928341)
			(xy 304.589698 -291.918497) (xy 304.543682 -291.901045) (xy 304.501061 -291.876438) (xy 304.46294 -291.845313)
			(xy 304.430305 -291.808476) (xy 304.404002 -291.76688) (xy 304.384711 -291.721604) (xy 304.372934 -291.67382)
			(xy 304.368974 -291.624766) (xy 304.030126 -291.624766) (xy 304.029631 -291.649373) (xy 304.021736 -291.69795)
			(xy 304.006152 -291.744631) (xy 303.983281 -291.788208) (xy 303.953716 -291.827552) (xy 303.918223 -291.861644)
			(xy 303.87772 -291.8896) (xy 303.833258 -291.910698) (xy 303.785987 -291.92439) (xy 303.737132 -291.930322)
			(xy 303.687957 -291.928341) (xy 303.639738 -291.918497) (xy 303.593722 -291.901045) (xy 303.551101 -291.876438)
			(xy 303.51298 -291.845313) (xy 303.480345 -291.808476) (xy 303.454042 -291.76688) (xy 303.434751 -291.721604)
			(xy 303.422974 -291.67382) (xy 303.419014 -291.624766) (xy 303.080506 -291.624766) (xy 303.080507 -291.624772)
			(xy 303.076024 -291.676976) (xy 303.062699 -291.72765) (xy 303.040921 -291.775306) (xy 303.026572 -291.797232)
			(xy 303.020686 -291.806892) (xy 303.017043 -291.829181) (xy 303.023335 -291.850871) (xy 303.030382 -291.859716)
			(xy 303.03724 -291.867082) (xy 303.043093 -291.874265) (xy 303.049594 -291.891603) (xy 303.04994 -291.900864)
			(xy 303.04994 -292.298882) (xy 303.049573 -292.308135) (xy 303.043051 -292.325453) (xy 303.03724 -292.332664)
			(xy 303.030382 -292.34003) (xy 303.023357 -292.34888) (xy 303.017115 -292.370573) (xy 303.020696 -292.39286)
			(xy 303.026572 -292.402514) (xy 303.040906 -292.424451) (xy 303.062691 -292.472105) (xy 303.076025 -292.522778)
			(xy 303.080493 -292.574726) (xy 303.419014 -292.574726) (xy 303.422974 -292.525672) (xy 303.434751 -292.477888)
			(xy 303.454042 -292.432612) (xy 303.480345 -292.391016) (xy 303.51298 -292.354179) (xy 303.551101 -292.323054)
			(xy 303.593722 -292.298447) (xy 303.639738 -292.280995) (xy 303.687957 -292.271151) (xy 303.737132 -292.26917)
			(xy 303.785987 -292.275102) (xy 303.833258 -292.288794) (xy 303.87772 -292.309892) (xy 303.918223 -292.337848)
			(xy 303.953716 -292.37194) (xy 303.983281 -292.411284) (xy 304.006152 -292.454861) (xy 304.021736 -292.501542)
			(xy 304.029631 -292.550119) (xy 304.030126 -292.574726) (xy 304.368974 -292.574726) (xy 304.372934 -292.525672)
			(xy 304.384711 -292.477888) (xy 304.404002 -292.432612) (xy 304.430305 -292.391016) (xy 304.46294 -292.354179)
			(xy 304.501061 -292.323054) (xy 304.543682 -292.298447) (xy 304.589698 -292.280995) (xy 304.637917 -292.271151)
			(xy 304.687092 -292.26917) (xy 304.735947 -292.275102) (xy 304.783218 -292.288794) (xy 304.82768 -292.309892)
			(xy 304.868183 -292.337848) (xy 304.903676 -292.37194) (xy 304.933241 -292.411284) (xy 304.956112 -292.454861)
			(xy 304.971696 -292.501542) (xy 304.979591 -292.550119) (xy 304.980086 -292.574726) (xy 305.318934 -292.574726)
			(xy 305.322894 -292.525672) (xy 305.334671 -292.477888) (xy 305.353962 -292.432612) (xy 305.380265 -292.391016)
			(xy 305.4129 -292.354179) (xy 305.451021 -292.323054) (xy 305.493642 -292.298447) (xy 305.539658 -292.280995)
			(xy 305.587877 -292.271151) (xy 305.637052 -292.26917) (xy 305.685907 -292.275102) (xy 305.733178 -292.288794)
			(xy 305.77764 -292.309892) (xy 305.818143 -292.337848) (xy 305.853636 -292.37194) (xy 305.883201 -292.411284)
			(xy 305.906072 -292.454861) (xy 305.921656 -292.501542) (xy 305.929551 -292.550119) (xy 305.930046 -292.574726)
			(xy 306.268894 -292.574726) (xy 306.272854 -292.525672) (xy 306.284631 -292.477888) (xy 306.303922 -292.432612)
			(xy 306.330225 -292.391016) (xy 306.36286 -292.354179) (xy 306.400981 -292.323054) (xy 306.443602 -292.298447)
			(xy 306.489618 -292.280995) (xy 306.537837 -292.271151) (xy 306.587012 -292.26917) (xy 306.635867 -292.275102)
			(xy 306.683138 -292.288794) (xy 306.7276 -292.309892) (xy 306.768103 -292.337848) (xy 306.803596 -292.37194)
			(xy 306.833161 -292.411284) (xy 306.856032 -292.454861) (xy 306.871616 -292.501542) (xy 306.879511 -292.550119)
			(xy 306.880006 -292.574726) (xy 307.219108 -292.574726) (xy 307.223068 -292.525672) (xy 307.234845 -292.477888)
			(xy 307.254136 -292.432612) (xy 307.280439 -292.391016) (xy 307.313074 -292.354179) (xy 307.351195 -292.323054)
			(xy 307.393816 -292.298447) (xy 307.439832 -292.280995) (xy 307.488051 -292.271151) (xy 307.537226 -292.26917)
			(xy 307.586081 -292.275102) (xy 307.633352 -292.288794) (xy 307.677814 -292.309892) (xy 307.718317 -292.337848)
			(xy 307.75381 -292.37194) (xy 307.783375 -292.411284) (xy 307.806246 -292.454861) (xy 307.82183 -292.501542)
			(xy 307.829725 -292.550119) (xy 307.83022 -292.574726) (xy 308.169068 -292.574726) (xy 308.173028 -292.525672)
			(xy 308.184805 -292.477888) (xy 308.204096 -292.432612) (xy 308.230399 -292.391016) (xy 308.263034 -292.354179)
			(xy 308.301155 -292.323054) (xy 308.343776 -292.298447) (xy 308.389792 -292.280995) (xy 308.438011 -292.271151)
			(xy 308.487186 -292.26917) (xy 308.536041 -292.275102) (xy 308.583312 -292.288794) (xy 308.627774 -292.309892)
			(xy 308.668277 -292.337848) (xy 308.70377 -292.37194) (xy 308.733335 -292.411284) (xy 308.756206 -292.454861)
			(xy 308.77179 -292.501542) (xy 308.779685 -292.550119) (xy 308.78018 -292.574726) (xy 309.119028 -292.574726)
			(xy 309.122988 -292.525672) (xy 309.134765 -292.477888) (xy 309.154056 -292.432612) (xy 309.180359 -292.391016)
			(xy 309.212994 -292.354179) (xy 309.251115 -292.323054) (xy 309.293736 -292.298447) (xy 309.339752 -292.280995)
			(xy 309.387971 -292.271151) (xy 309.437146 -292.26917) (xy 309.486001 -292.275102) (xy 309.533272 -292.288794)
			(xy 309.577734 -292.309892) (xy 309.618237 -292.337848) (xy 309.65373 -292.37194) (xy 309.683295 -292.411284)
			(xy 309.706166 -292.454861) (xy 309.72175 -292.501542) (xy 309.729645 -292.550119) (xy 309.73014 -292.574726)
			(xy 310.068988 -292.574726) (xy 310.072948 -292.525672) (xy 310.084725 -292.477888) (xy 310.104016 -292.432612)
			(xy 310.130319 -292.391016) (xy 310.162954 -292.354179) (xy 310.201075 -292.323054) (xy 310.243696 -292.298447)
			(xy 310.289712 -292.280995) (xy 310.337931 -292.271151) (xy 310.387106 -292.26917) (xy 310.435961 -292.275102)
			(xy 310.483232 -292.288794) (xy 310.527694 -292.309892) (xy 310.568197 -292.337848) (xy 310.60369 -292.37194)
			(xy 310.633255 -292.411284) (xy 310.656126 -292.454861) (xy 310.67171 -292.501542) (xy 310.679605 -292.550119)
			(xy 310.6801 -292.574726) (xy 311.018948 -292.574726) (xy 311.022908 -292.525672) (xy 311.034685 -292.477888)
			(xy 311.053976 -292.432612) (xy 311.080279 -292.391016) (xy 311.112914 -292.354179) (xy 311.151035 -292.323054)
			(xy 311.193656 -292.298447) (xy 311.239672 -292.280995) (xy 311.287891 -292.271151) (xy 311.337066 -292.26917)
			(xy 311.385921 -292.275102) (xy 311.433192 -292.288794) (xy 311.477654 -292.309892) (xy 311.518157 -292.337848)
			(xy 311.55365 -292.37194) (xy 311.583215 -292.411284) (xy 311.606086 -292.454861) (xy 311.62167 -292.501542)
			(xy 311.629565 -292.550119) (xy 311.63006 -292.574726) (xy 311.968908 -292.574726) (xy 311.972868 -292.525672)
			(xy 311.984645 -292.477888) (xy 312.003936 -292.432612) (xy 312.030239 -292.391016) (xy 312.062874 -292.354179)
			(xy 312.100995 -292.323054) (xy 312.143616 -292.298447) (xy 312.189632 -292.280995) (xy 312.237851 -292.271151)
			(xy 312.287026 -292.26917) (xy 312.335881 -292.275102) (xy 312.383152 -292.288794) (xy 312.427614 -292.309892)
			(xy 312.468117 -292.337848) (xy 312.50361 -292.37194) (xy 312.533175 -292.411284) (xy 312.556046 -292.454861)
			(xy 312.57163 -292.501542) (xy 312.579525 -292.550119) (xy 312.58002 -292.574726) (xy 312.919122 -292.574726)
			(xy 312.923082 -292.525672) (xy 312.934859 -292.477888) (xy 312.95415 -292.432612) (xy 312.980453 -292.391016)
			(xy 313.013088 -292.354179) (xy 313.051209 -292.323054) (xy 313.09383 -292.298447) (xy 313.139846 -292.280995)
			(xy 313.188065 -292.271151) (xy 313.23724 -292.26917) (xy 313.286095 -292.275102) (xy 313.333366 -292.288794)
			(xy 313.377828 -292.309892) (xy 313.418331 -292.337848) (xy 313.453824 -292.37194) (xy 313.483389 -292.411284)
			(xy 313.50626 -292.454861) (xy 313.521844 -292.501542) (xy 313.529739 -292.550119) (xy 313.530234 -292.574726)
			(xy 313.530229 -292.57498) (xy 313.869082 -292.57498) (xy 313.873042 -292.525926) (xy 313.884819 -292.478142)
			(xy 313.90411 -292.432866) (xy 313.930413 -292.39127) (xy 313.963048 -292.354433) (xy 314.001169 -292.323308)
			(xy 314.04379 -292.298701) (xy 314.089806 -292.281249) (xy 314.138025 -292.271405) (xy 314.1872 -292.269424)
			(xy 314.236055 -292.275356) (xy 314.283326 -292.289048) (xy 314.327788 -292.310146) (xy 314.368291 -292.338102)
			(xy 314.403784 -292.372194) (xy 314.433349 -292.411538) (xy 314.45622 -292.455115) (xy 314.471804 -292.501796)
			(xy 314.479699 -292.550373) (xy 314.480194 -292.57498) (xy 314.479699 -292.599587) (xy 314.471804 -292.648164)
			(xy 314.45622 -292.694845) (xy 314.433349 -292.738422) (xy 314.403784 -292.777766) (xy 314.368291 -292.811858)
			(xy 314.327788 -292.839814) (xy 314.283326 -292.860912) (xy 314.236055 -292.874604) (xy 314.1872 -292.880536)
			(xy 314.138025 -292.878555) (xy 314.089806 -292.868711) (xy 314.04379 -292.851259) (xy 314.001169 -292.826652)
			(xy 313.963048 -292.795527) (xy 313.930413 -292.75869) (xy 313.90411 -292.717094) (xy 313.884819 -292.671818)
			(xy 313.873042 -292.624034) (xy 313.869082 -292.57498) (xy 313.530229 -292.57498) (xy 313.529739 -292.599333)
			(xy 313.521844 -292.64791) (xy 313.50626 -292.694591) (xy 313.483389 -292.738168) (xy 313.453824 -292.777512)
			(xy 313.418331 -292.811604) (xy 313.377828 -292.83956) (xy 313.333366 -292.860658) (xy 313.286095 -292.87435)
			(xy 313.23724 -292.880282) (xy 313.188065 -292.878301) (xy 313.139846 -292.868457) (xy 313.09383 -292.851005)
			(xy 313.051209 -292.826398) (xy 313.013088 -292.795273) (xy 312.980453 -292.758436) (xy 312.95415 -292.71684)
			(xy 312.934859 -292.671564) (xy 312.923082 -292.62378) (xy 312.919122 -292.574726) (xy 312.58002 -292.574726)
			(xy 312.579525 -292.599333) (xy 312.57163 -292.64791) (xy 312.556046 -292.694591) (xy 312.533175 -292.738168)
			(xy 312.50361 -292.777512) (xy 312.468117 -292.811604) (xy 312.427614 -292.83956) (xy 312.383152 -292.860658)
			(xy 312.335881 -292.87435) (xy 312.287026 -292.880282) (xy 312.237851 -292.878301) (xy 312.189632 -292.868457)
			(xy 312.143616 -292.851005) (xy 312.100995 -292.826398) (xy 312.062874 -292.795273) (xy 312.030239 -292.758436)
			(xy 312.003936 -292.71684) (xy 311.984645 -292.671564) (xy 311.972868 -292.62378) (xy 311.968908 -292.574726)
			(xy 311.63006 -292.574726) (xy 311.629565 -292.599333) (xy 311.62167 -292.64791) (xy 311.606086 -292.694591)
			(xy 311.583215 -292.738168) (xy 311.55365 -292.777512) (xy 311.518157 -292.811604) (xy 311.477654 -292.83956)
			(xy 311.433192 -292.860658) (xy 311.385921 -292.87435) (xy 311.337066 -292.880282) (xy 311.287891 -292.878301)
			(xy 311.239672 -292.868457) (xy 311.193656 -292.851005) (xy 311.151035 -292.826398) (xy 311.112914 -292.795273)
			(xy 311.080279 -292.758436) (xy 311.053976 -292.71684) (xy 311.034685 -292.671564) (xy 311.022908 -292.62378)
			(xy 311.018948 -292.574726) (xy 310.6801 -292.574726) (xy 310.679605 -292.599333) (xy 310.67171 -292.64791)
			(xy 310.656126 -292.694591) (xy 310.633255 -292.738168) (xy 310.60369 -292.777512) (xy 310.568197 -292.811604)
			(xy 310.527694 -292.83956) (xy 310.483232 -292.860658) (xy 310.435961 -292.87435) (xy 310.387106 -292.880282)
			(xy 310.337931 -292.878301) (xy 310.289712 -292.868457) (xy 310.243696 -292.851005) (xy 310.201075 -292.826398)
			(xy 310.162954 -292.795273) (xy 310.130319 -292.758436) (xy 310.104016 -292.71684) (xy 310.084725 -292.671564)
			(xy 310.072948 -292.62378) (xy 310.068988 -292.574726) (xy 309.73014 -292.574726) (xy 309.729645 -292.599333)
			(xy 309.72175 -292.64791) (xy 309.706166 -292.694591) (xy 309.683295 -292.738168) (xy 309.65373 -292.777512)
			(xy 309.618237 -292.811604) (xy 309.577734 -292.83956) (xy 309.533272 -292.860658) (xy 309.486001 -292.87435)
			(xy 309.437146 -292.880282) (xy 309.387971 -292.878301) (xy 309.339752 -292.868457) (xy 309.293736 -292.851005)
			(xy 309.251115 -292.826398) (xy 309.212994 -292.795273) (xy 309.180359 -292.758436) (xy 309.154056 -292.71684)
			(xy 309.134765 -292.671564) (xy 309.122988 -292.62378) (xy 309.119028 -292.574726) (xy 308.78018 -292.574726)
			(xy 308.779685 -292.599333) (xy 308.77179 -292.64791) (xy 308.756206 -292.694591) (xy 308.733335 -292.738168)
			(xy 308.70377 -292.777512) (xy 308.668277 -292.811604) (xy 308.627774 -292.83956) (xy 308.583312 -292.860658)
			(xy 308.536041 -292.87435) (xy 308.487186 -292.880282) (xy 308.438011 -292.878301) (xy 308.389792 -292.868457)
			(xy 308.343776 -292.851005) (xy 308.301155 -292.826398) (xy 308.263034 -292.795273) (xy 308.230399 -292.758436)
			(xy 308.204096 -292.71684) (xy 308.184805 -292.671564) (xy 308.173028 -292.62378) (xy 308.169068 -292.574726)
			(xy 307.83022 -292.574726) (xy 307.829725 -292.599333) (xy 307.82183 -292.64791) (xy 307.806246 -292.694591)
			(xy 307.783375 -292.738168) (xy 307.75381 -292.777512) (xy 307.718317 -292.811604) (xy 307.677814 -292.83956)
			(xy 307.633352 -292.860658) (xy 307.586081 -292.87435) (xy 307.537226 -292.880282) (xy 307.488051 -292.878301)
			(xy 307.439832 -292.868457) (xy 307.393816 -292.851005) (xy 307.351195 -292.826398) (xy 307.313074 -292.795273)
			(xy 307.280439 -292.758436) (xy 307.254136 -292.71684) (xy 307.234845 -292.671564) (xy 307.223068 -292.62378)
			(xy 307.219108 -292.574726) (xy 306.880006 -292.574726) (xy 306.879511 -292.599333) (xy 306.871616 -292.64791)
			(xy 306.856032 -292.694591) (xy 306.833161 -292.738168) (xy 306.803596 -292.777512) (xy 306.768103 -292.811604)
			(xy 306.7276 -292.83956) (xy 306.683138 -292.860658) (xy 306.635867 -292.87435) (xy 306.587012 -292.880282)
			(xy 306.537837 -292.878301) (xy 306.489618 -292.868457) (xy 306.443602 -292.851005) (xy 306.400981 -292.826398)
			(xy 306.36286 -292.795273) (xy 306.330225 -292.758436) (xy 306.303922 -292.71684) (xy 306.284631 -292.671564)
			(xy 306.272854 -292.62378) (xy 306.268894 -292.574726) (xy 305.930046 -292.574726) (xy 305.929551 -292.599333)
			(xy 305.921656 -292.64791) (xy 305.906072 -292.694591) (xy 305.883201 -292.738168) (xy 305.853636 -292.777512)
			(xy 305.818143 -292.811604) (xy 305.77764 -292.83956) (xy 305.733178 -292.860658) (xy 305.685907 -292.87435)
			(xy 305.637052 -292.880282) (xy 305.587877 -292.878301) (xy 305.539658 -292.868457) (xy 305.493642 -292.851005)
			(xy 305.451021 -292.826398) (xy 305.4129 -292.795273) (xy 305.380265 -292.758436) (xy 305.353962 -292.71684)
			(xy 305.334671 -292.671564) (xy 305.322894 -292.62378) (xy 305.318934 -292.574726) (xy 304.980086 -292.574726)
			(xy 304.979591 -292.599333) (xy 304.971696 -292.64791) (xy 304.956112 -292.694591) (xy 304.933241 -292.738168)
			(xy 304.903676 -292.777512) (xy 304.868183 -292.811604) (xy 304.82768 -292.83956) (xy 304.783218 -292.860658)
			(xy 304.735947 -292.87435) (xy 304.687092 -292.880282) (xy 304.637917 -292.878301) (xy 304.589698 -292.868457)
			(xy 304.543682 -292.851005) (xy 304.501061 -292.826398) (xy 304.46294 -292.795273) (xy 304.430305 -292.758436)
			(xy 304.404002 -292.71684) (xy 304.384711 -292.671564) (xy 304.372934 -292.62378) (xy 304.368974 -292.574726)
			(xy 304.030126 -292.574726) (xy 304.029631 -292.599333) (xy 304.021736 -292.64791) (xy 304.006152 -292.694591)
			(xy 303.983281 -292.738168) (xy 303.953716 -292.777512) (xy 303.918223 -292.811604) (xy 303.87772 -292.83956)
			(xy 303.833258 -292.860658) (xy 303.785987 -292.87435) (xy 303.737132 -292.880282) (xy 303.687957 -292.878301)
			(xy 303.639738 -292.868457) (xy 303.593722 -292.851005) (xy 303.551101 -292.826398) (xy 303.51298 -292.795273)
			(xy 303.480345 -292.758436) (xy 303.454042 -292.71684) (xy 303.434751 -292.671564) (xy 303.422974 -292.62378)
			(xy 303.419014 -292.574726) (xy 303.080493 -292.574726) (xy 303.080515 -292.574983) (xy 303.07603 -292.627189)
			(xy 303.062702 -292.677863) (xy 303.040922 -292.72552) (xy 303.026572 -292.747446) (xy 303.020673 -292.757099)
			(xy 303.017035 -292.779393) (xy 303.023332 -292.801085) (xy 303.030382 -292.80993) (xy 303.03724 -292.817296)
			(xy 303.043056 -292.824505) (xy 303.04958 -292.841823) (xy 303.04994 -292.851078) (xy 303.04994 -293.248842)
			(xy 303.049554 -293.258093) (xy 303.043045 -293.275411) (xy 303.03724 -293.282624) (xy 303.030382 -293.28999)
			(xy 303.023392 -293.298864) (xy 303.01714 -293.320543) (xy 303.020705 -293.342821) (xy 303.026572 -293.352474)
			(xy 303.04096 -293.374378) (xy 303.06274 -293.422041) (xy 303.076066 -293.472722) (xy 303.080549 -293.524933)
			(xy 303.080548 -293.52494) (xy 303.419014 -293.52494) (xy 303.422974 -293.475886) (xy 303.434751 -293.428102)
			(xy 303.454042 -293.382826) (xy 303.480345 -293.34123) (xy 303.51298 -293.304393) (xy 303.551101 -293.273268)
			(xy 303.593722 -293.248661) (xy 303.639738 -293.231209) (xy 303.687957 -293.221365) (xy 303.737132 -293.219384)
			(xy 303.785987 -293.225316) (xy 303.833258 -293.239008) (xy 303.87772 -293.260106) (xy 303.918223 -293.288062)
			(xy 303.953716 -293.322154) (xy 303.983281 -293.361498) (xy 304.006152 -293.405075) (xy 304.021736 -293.451756)
			(xy 304.029631 -293.500333) (xy 304.030126 -293.52494) (xy 304.368974 -293.52494) (xy 304.372934 -293.475886)
			(xy 304.384711 -293.428102) (xy 304.404002 -293.382826) (xy 304.430305 -293.34123) (xy 304.46294 -293.304393)
			(xy 304.501061 -293.273268) (xy 304.543682 -293.248661) (xy 304.589698 -293.231209) (xy 304.637917 -293.221365)
			(xy 304.687092 -293.219384) (xy 304.735947 -293.225316) (xy 304.783218 -293.239008) (xy 304.82768 -293.260106)
			(xy 304.868183 -293.288062) (xy 304.903676 -293.322154) (xy 304.933241 -293.361498) (xy 304.956112 -293.405075)
			(xy 304.971696 -293.451756) (xy 304.979591 -293.500333) (xy 304.980086 -293.52494) (xy 305.318934 -293.52494)
			(xy 305.322894 -293.475886) (xy 305.334671 -293.428102) (xy 305.353962 -293.382826) (xy 305.380265 -293.34123)
			(xy 305.4129 -293.304393) (xy 305.451021 -293.273268) (xy 305.493642 -293.248661) (xy 305.539658 -293.231209)
			(xy 305.587877 -293.221365) (xy 305.637052 -293.219384) (xy 305.685907 -293.225316) (xy 305.733178 -293.239008)
			(xy 305.77764 -293.260106) (xy 305.818143 -293.288062) (xy 305.853636 -293.322154) (xy 305.883201 -293.361498)
			(xy 305.906072 -293.405075) (xy 305.921656 -293.451756) (xy 305.929551 -293.500333) (xy 305.930046 -293.52494)
			(xy 306.269148 -293.52494) (xy 306.273108 -293.475886) (xy 306.284885 -293.428102) (xy 306.304176 -293.382826)
			(xy 306.330479 -293.34123) (xy 306.363114 -293.304393) (xy 306.401235 -293.273268) (xy 306.443856 -293.248661)
			(xy 306.489872 -293.231209) (xy 306.538091 -293.221365) (xy 306.587266 -293.219384) (xy 306.636121 -293.225316)
			(xy 306.683392 -293.239008) (xy 306.727854 -293.260106) (xy 306.768357 -293.288062) (xy 306.80385 -293.322154)
			(xy 306.833415 -293.361498) (xy 306.856286 -293.405075) (xy 306.87187 -293.451756) (xy 306.879765 -293.500333)
			(xy 306.88026 -293.52494) (xy 307.219108 -293.52494) (xy 307.223068 -293.475886) (xy 307.234845 -293.428102)
			(xy 307.254136 -293.382826) (xy 307.280439 -293.34123) (xy 307.313074 -293.304393) (xy 307.351195 -293.273268)
			(xy 307.393816 -293.248661) (xy 307.439832 -293.231209) (xy 307.488051 -293.221365) (xy 307.537226 -293.219384)
			(xy 307.586081 -293.225316) (xy 307.633352 -293.239008) (xy 307.677814 -293.260106) (xy 307.718317 -293.288062)
			(xy 307.75381 -293.322154) (xy 307.783375 -293.361498) (xy 307.806246 -293.405075) (xy 307.82183 -293.451756)
			(xy 307.829725 -293.500333) (xy 307.83022 -293.52494) (xy 308.169068 -293.52494) (xy 308.173028 -293.475886)
			(xy 308.184805 -293.428102) (xy 308.204096 -293.382826) (xy 308.230399 -293.34123) (xy 308.263034 -293.304393)
			(xy 308.301155 -293.273268) (xy 308.343776 -293.248661) (xy 308.389792 -293.231209) (xy 308.438011 -293.221365)
			(xy 308.487186 -293.219384) (xy 308.536041 -293.225316) (xy 308.583312 -293.239008) (xy 308.627774 -293.260106)
			(xy 308.668277 -293.288062) (xy 308.70377 -293.322154) (xy 308.733335 -293.361498) (xy 308.756206 -293.405075)
			(xy 308.77179 -293.451756) (xy 308.779685 -293.500333) (xy 308.78018 -293.52494) (xy 309.119028 -293.52494)
			(xy 309.122988 -293.475886) (xy 309.134765 -293.428102) (xy 309.154056 -293.382826) (xy 309.180359 -293.34123)
			(xy 309.212994 -293.304393) (xy 309.251115 -293.273268) (xy 309.293736 -293.248661) (xy 309.339752 -293.231209)
			(xy 309.387971 -293.221365) (xy 309.437146 -293.219384) (xy 309.486001 -293.225316) (xy 309.533272 -293.239008)
			(xy 309.577734 -293.260106) (xy 309.618237 -293.288062) (xy 309.65373 -293.322154) (xy 309.683295 -293.361498)
			(xy 309.706166 -293.405075) (xy 309.72175 -293.451756) (xy 309.729645 -293.500333) (xy 309.73014 -293.52494)
			(xy 310.068988 -293.52494) (xy 310.072948 -293.475886) (xy 310.084725 -293.428102) (xy 310.104016 -293.382826)
			(xy 310.130319 -293.34123) (xy 310.162954 -293.304393) (xy 310.201075 -293.273268) (xy 310.243696 -293.248661)
			(xy 310.289712 -293.231209) (xy 310.337931 -293.221365) (xy 310.387106 -293.219384) (xy 310.435961 -293.225316)
			(xy 310.483232 -293.239008) (xy 310.527694 -293.260106) (xy 310.568197 -293.288062) (xy 310.60369 -293.322154)
			(xy 310.633255 -293.361498) (xy 310.656126 -293.405075) (xy 310.67171 -293.451756) (xy 310.679605 -293.500333)
			(xy 310.6801 -293.52494) (xy 311.018948 -293.52494) (xy 311.022908 -293.475886) (xy 311.034685 -293.428102)
			(xy 311.053976 -293.382826) (xy 311.080279 -293.34123) (xy 311.112914 -293.304393) (xy 311.151035 -293.273268)
			(xy 311.193656 -293.248661) (xy 311.239672 -293.231209) (xy 311.287891 -293.221365) (xy 311.337066 -293.219384)
			(xy 311.385921 -293.225316) (xy 311.433192 -293.239008) (xy 311.477654 -293.260106) (xy 311.518157 -293.288062)
			(xy 311.55365 -293.322154) (xy 311.583215 -293.361498) (xy 311.606086 -293.405075) (xy 311.62167 -293.451756)
			(xy 311.629565 -293.500333) (xy 311.63006 -293.52494) (xy 311.968908 -293.52494) (xy 311.972868 -293.475886)
			(xy 311.984645 -293.428102) (xy 312.003936 -293.382826) (xy 312.030239 -293.34123) (xy 312.062874 -293.304393)
			(xy 312.100995 -293.273268) (xy 312.143616 -293.248661) (xy 312.189632 -293.231209) (xy 312.237851 -293.221365)
			(xy 312.287026 -293.219384) (xy 312.335881 -293.225316) (xy 312.383152 -293.239008) (xy 312.427614 -293.260106)
			(xy 312.468117 -293.288062) (xy 312.50361 -293.322154) (xy 312.533175 -293.361498) (xy 312.556046 -293.405075)
			(xy 312.57163 -293.451756) (xy 312.579525 -293.500333) (xy 312.58002 -293.52494) (xy 312.919122 -293.52494)
			(xy 312.923082 -293.475886) (xy 312.934859 -293.428102) (xy 312.95415 -293.382826) (xy 312.980453 -293.34123)
			(xy 313.013088 -293.304393) (xy 313.051209 -293.273268) (xy 313.09383 -293.248661) (xy 313.139846 -293.231209)
			(xy 313.188065 -293.221365) (xy 313.23724 -293.219384) (xy 313.286095 -293.225316) (xy 313.333366 -293.239008)
			(xy 313.377828 -293.260106) (xy 313.418331 -293.288062) (xy 313.453824 -293.322154) (xy 313.483389 -293.361498)
			(xy 313.50626 -293.405075) (xy 313.521844 -293.451756) (xy 313.529739 -293.500333) (xy 313.530234 -293.52494)
			(xy 313.869082 -293.52494) (xy 313.873042 -293.475886) (xy 313.884819 -293.428102) (xy 313.90411 -293.382826)
			(xy 313.930413 -293.34123) (xy 313.963048 -293.304393) (xy 314.001169 -293.273268) (xy 314.04379 -293.248661)
			(xy 314.089806 -293.231209) (xy 314.138025 -293.221365) (xy 314.1872 -293.219384) (xy 314.236055 -293.225316)
			(xy 314.283326 -293.239008) (xy 314.327788 -293.260106) (xy 314.368291 -293.288062) (xy 314.403784 -293.322154)
			(xy 314.433349 -293.361498) (xy 314.45622 -293.405075) (xy 314.471804 -293.451756) (xy 314.479699 -293.500333)
			(xy 314.480194 -293.52494) (xy 314.479699 -293.549547) (xy 314.471804 -293.598124) (xy 314.45622 -293.644805)
			(xy 314.433349 -293.688382) (xy 314.403784 -293.727726) (xy 314.368291 -293.761818) (xy 314.327788 -293.789774)
			(xy 314.283326 -293.810872) (xy 314.236055 -293.824564) (xy 314.1872 -293.830496) (xy 314.138025 -293.828515)
			(xy 314.089806 -293.818671) (xy 314.04379 -293.801219) (xy 314.001169 -293.776612) (xy 313.963048 -293.745487)
			(xy 313.930413 -293.70865) (xy 313.90411 -293.667054) (xy 313.884819 -293.621778) (xy 313.873042 -293.573994)
			(xy 313.869082 -293.52494) (xy 313.530234 -293.52494) (xy 313.529739 -293.549547) (xy 313.521844 -293.598124)
			(xy 313.50626 -293.644805) (xy 313.483389 -293.688382) (xy 313.453824 -293.727726) (xy 313.418331 -293.761818)
			(xy 313.377828 -293.789774) (xy 313.333366 -293.810872) (xy 313.286095 -293.824564) (xy 313.23724 -293.830496)
			(xy 313.188065 -293.828515) (xy 313.139846 -293.818671) (xy 313.09383 -293.801219) (xy 313.051209 -293.776612)
			(xy 313.013088 -293.745487) (xy 312.980453 -293.70865) (xy 312.95415 -293.667054) (xy 312.934859 -293.621778)
			(xy 312.923082 -293.573994) (xy 312.919122 -293.52494) (xy 312.58002 -293.52494) (xy 312.579525 -293.549547)
			(xy 312.57163 -293.598124) (xy 312.556046 -293.644805) (xy 312.533175 -293.688382) (xy 312.50361 -293.727726)
			(xy 312.468117 -293.761818) (xy 312.427614 -293.789774) (xy 312.383152 -293.810872) (xy 312.335881 -293.824564)
			(xy 312.287026 -293.830496) (xy 312.237851 -293.828515) (xy 312.189632 -293.818671) (xy 312.143616 -293.801219)
			(xy 312.100995 -293.776612) (xy 312.062874 -293.745487) (xy 312.030239 -293.70865) (xy 312.003936 -293.667054)
			(xy 311.984645 -293.621778) (xy 311.972868 -293.573994) (xy 311.968908 -293.52494) (xy 311.63006 -293.52494)
			(xy 311.629565 -293.549547) (xy 311.62167 -293.598124) (xy 311.606086 -293.644805) (xy 311.583215 -293.688382)
			(xy 311.55365 -293.727726) (xy 311.518157 -293.761818) (xy 311.477654 -293.789774) (xy 311.433192 -293.810872)
			(xy 311.385921 -293.824564) (xy 311.337066 -293.830496) (xy 311.287891 -293.828515) (xy 311.239672 -293.818671)
			(xy 311.193656 -293.801219) (xy 311.151035 -293.776612) (xy 311.112914 -293.745487) (xy 311.080279 -293.70865)
			(xy 311.053976 -293.667054) (xy 311.034685 -293.621778) (xy 311.022908 -293.573994) (xy 311.018948 -293.52494)
			(xy 310.6801 -293.52494) (xy 310.679605 -293.549547) (xy 310.67171 -293.598124) (xy 310.656126 -293.644805)
			(xy 310.633255 -293.688382) (xy 310.60369 -293.727726) (xy 310.568197 -293.761818) (xy 310.527694 -293.789774)
			(xy 310.483232 -293.810872) (xy 310.435961 -293.824564) (xy 310.387106 -293.830496) (xy 310.337931 -293.828515)
			(xy 310.289712 -293.818671) (xy 310.243696 -293.801219) (xy 310.201075 -293.776612) (xy 310.162954 -293.745487)
			(xy 310.130319 -293.70865) (xy 310.104016 -293.667054) (xy 310.084725 -293.621778) (xy 310.072948 -293.573994)
			(xy 310.068988 -293.52494) (xy 309.73014 -293.52494) (xy 309.729645 -293.549547) (xy 309.72175 -293.598124)
			(xy 309.706166 -293.644805) (xy 309.683295 -293.688382) (xy 309.65373 -293.727726) (xy 309.618237 -293.761818)
			(xy 309.577734 -293.789774) (xy 309.533272 -293.810872) (xy 309.486001 -293.824564) (xy 309.437146 -293.830496)
			(xy 309.387971 -293.828515) (xy 309.339752 -293.818671) (xy 309.293736 -293.801219) (xy 309.251115 -293.776612)
			(xy 309.212994 -293.745487) (xy 309.180359 -293.70865) (xy 309.154056 -293.667054) (xy 309.134765 -293.621778)
			(xy 309.122988 -293.573994) (xy 309.119028 -293.52494) (xy 308.78018 -293.52494) (xy 308.779685 -293.549547)
			(xy 308.77179 -293.598124) (xy 308.756206 -293.644805) (xy 308.733335 -293.688382) (xy 308.70377 -293.727726)
			(xy 308.668277 -293.761818) (xy 308.627774 -293.789774) (xy 308.583312 -293.810872) (xy 308.536041 -293.824564)
			(xy 308.487186 -293.830496) (xy 308.438011 -293.828515) (xy 308.389792 -293.818671) (xy 308.343776 -293.801219)
			(xy 308.301155 -293.776612) (xy 308.263034 -293.745487) (xy 308.230399 -293.70865) (xy 308.204096 -293.667054)
			(xy 308.184805 -293.621778) (xy 308.173028 -293.573994) (xy 308.169068 -293.52494) (xy 307.83022 -293.52494)
			(xy 307.829725 -293.549547) (xy 307.82183 -293.598124) (xy 307.806246 -293.644805) (xy 307.783375 -293.688382)
			(xy 307.75381 -293.727726) (xy 307.718317 -293.761818) (xy 307.677814 -293.789774) (xy 307.633352 -293.810872)
			(xy 307.586081 -293.824564) (xy 307.537226 -293.830496) (xy 307.488051 -293.828515) (xy 307.439832 -293.818671)
			(xy 307.393816 -293.801219) (xy 307.351195 -293.776612) (xy 307.313074 -293.745487) (xy 307.280439 -293.70865)
			(xy 307.254136 -293.667054) (xy 307.234845 -293.621778) (xy 307.223068 -293.573994) (xy 307.219108 -293.52494)
			(xy 306.88026 -293.52494) (xy 306.879765 -293.549547) (xy 306.87187 -293.598124) (xy 306.856286 -293.644805)
			(xy 306.833415 -293.688382) (xy 306.80385 -293.727726) (xy 306.768357 -293.761818) (xy 306.727854 -293.789774)
			(xy 306.683392 -293.810872) (xy 306.636121 -293.824564) (xy 306.587266 -293.830496) (xy 306.538091 -293.828515)
			(xy 306.489872 -293.818671) (xy 306.443856 -293.801219) (xy 306.401235 -293.776612) (xy 306.363114 -293.745487)
			(xy 306.330479 -293.70865) (xy 306.304176 -293.667054) (xy 306.284885 -293.621778) (xy 306.273108 -293.573994)
			(xy 306.269148 -293.52494) (xy 305.930046 -293.52494) (xy 305.929551 -293.549547) (xy 305.921656 -293.598124)
			(xy 305.906072 -293.644805) (xy 305.883201 -293.688382) (xy 305.853636 -293.727726) (xy 305.818143 -293.761818)
			(xy 305.77764 -293.789774) (xy 305.733178 -293.810872) (xy 305.685907 -293.824564) (xy 305.637052 -293.830496)
			(xy 305.587877 -293.828515) (xy 305.539658 -293.818671) (xy 305.493642 -293.801219) (xy 305.451021 -293.776612)
			(xy 305.4129 -293.745487) (xy 305.380265 -293.70865) (xy 305.353962 -293.667054) (xy 305.334671 -293.621778)
			(xy 305.322894 -293.573994) (xy 305.318934 -293.52494) (xy 304.980086 -293.52494) (xy 304.979591 -293.549547)
			(xy 304.971696 -293.598124) (xy 304.956112 -293.644805) (xy 304.933241 -293.688382) (xy 304.903676 -293.727726)
			(xy 304.868183 -293.761818) (xy 304.82768 -293.789774) (xy 304.783218 -293.810872) (xy 304.735947 -293.824564)
			(xy 304.687092 -293.830496) (xy 304.637917 -293.828515) (xy 304.589698 -293.818671) (xy 304.543682 -293.801219)
			(xy 304.501061 -293.776612) (xy 304.46294 -293.745487) (xy 304.430305 -293.70865) (xy 304.404002 -293.667054)
			(xy 304.384711 -293.621778) (xy 304.372934 -293.573994) (xy 304.368974 -293.52494) (xy 304.030126 -293.52494)
			(xy 304.029631 -293.549547) (xy 304.021736 -293.598124) (xy 304.006152 -293.644805) (xy 303.983281 -293.688382)
			(xy 303.953716 -293.727726) (xy 303.918223 -293.761818) (xy 303.87772 -293.789774) (xy 303.833258 -293.810872)
			(xy 303.785987 -293.824564) (xy 303.737132 -293.830496) (xy 303.687957 -293.828515) (xy 303.639738 -293.818671)
			(xy 303.593722 -293.801219) (xy 303.551101 -293.776612) (xy 303.51298 -293.745487) (xy 303.480345 -293.70865)
			(xy 303.454042 -293.667054) (xy 303.434751 -293.621778) (xy 303.422974 -293.573994) (xy 303.419014 -293.52494)
			(xy 303.080548 -293.52494) (xy 303.076055 -293.577144) (xy 303.062718 -293.627822) (xy 303.040927 -293.67548)
			(xy 303.026572 -293.697406) (xy 303.020618 -293.70703) (xy 303.016997 -293.729343) (xy 303.023319 -293.751045)
			(xy 303.030382 -293.75989) (xy 303.03724 -293.767256) (xy 303.043082 -293.774447) (xy 303.04959 -293.791779)
			(xy 303.04994 -293.801038) (xy 303.04994 -294.198802) (xy 303.049534 -294.208051) (xy 303.043039 -294.225369)
			(xy 303.03724 -294.232584) (xy 303.030382 -294.23995) (xy 303.023339 -294.248789) (xy 303.017103 -294.270488)
			(xy 303.020692 -294.29278) (xy 303.026572 -294.302434) (xy 303.040924 -294.32436) (xy 303.062707 -294.372017)
			(xy 303.076039 -294.422693) (xy 303.080526 -294.4749) (xy 303.419014 -294.4749) (xy 303.422974 -294.425846)
			(xy 303.434751 -294.378062) (xy 303.454042 -294.332786) (xy 303.480345 -294.29119) (xy 303.51298 -294.254353)
			(xy 303.551101 -294.223228) (xy 303.593722 -294.198621) (xy 303.639738 -294.181169) (xy 303.687957 -294.171325)
			(xy 303.737132 -294.169344) (xy 303.785987 -294.175276) (xy 303.833258 -294.188968) (xy 303.87772 -294.210066)
			(xy 303.918223 -294.238022) (xy 303.953716 -294.272114) (xy 303.983281 -294.311458) (xy 304.006152 -294.355035)
			(xy 304.021736 -294.401716) (xy 304.029631 -294.450293) (xy 304.030126 -294.4749) (xy 304.368974 -294.4749)
			(xy 304.372934 -294.425846) (xy 304.384711 -294.378062) (xy 304.404002 -294.332786) (xy 304.430305 -294.29119)
			(xy 304.46294 -294.254353) (xy 304.501061 -294.223228) (xy 304.543682 -294.198621) (xy 304.589698 -294.181169)
			(xy 304.637917 -294.171325) (xy 304.687092 -294.169344) (xy 304.735947 -294.175276) (xy 304.783218 -294.188968)
			(xy 304.82768 -294.210066) (xy 304.868183 -294.238022) (xy 304.903676 -294.272114) (xy 304.933241 -294.311458)
			(xy 304.956112 -294.355035) (xy 304.971696 -294.401716) (xy 304.979591 -294.450293) (xy 304.980086 -294.4749)
			(xy 305.318934 -294.4749) (xy 305.322894 -294.425846) (xy 305.334671 -294.378062) (xy 305.353962 -294.332786)
			(xy 305.380265 -294.29119) (xy 305.4129 -294.254353) (xy 305.451021 -294.223228) (xy 305.493642 -294.198621)
			(xy 305.539658 -294.181169) (xy 305.587877 -294.171325) (xy 305.637052 -294.169344) (xy 305.685907 -294.175276)
			(xy 305.733178 -294.188968) (xy 305.77764 -294.210066) (xy 305.818143 -294.238022) (xy 305.853636 -294.272114)
			(xy 305.883201 -294.311458) (xy 305.906072 -294.355035) (xy 305.921656 -294.401716) (xy 305.929551 -294.450293)
			(xy 305.930046 -294.4749) (xy 306.268894 -294.4749) (xy 306.272854 -294.425846) (xy 306.284631 -294.378062)
			(xy 306.303922 -294.332786) (xy 306.330225 -294.29119) (xy 306.36286 -294.254353) (xy 306.400981 -294.223228)
			(xy 306.443602 -294.198621) (xy 306.489618 -294.181169) (xy 306.537837 -294.171325) (xy 306.587012 -294.169344)
			(xy 306.635867 -294.175276) (xy 306.683138 -294.188968) (xy 306.7276 -294.210066) (xy 306.768103 -294.238022)
			(xy 306.803596 -294.272114) (xy 306.833161 -294.311458) (xy 306.856032 -294.355035) (xy 306.871616 -294.401716)
			(xy 306.879511 -294.450293) (xy 306.880006 -294.4749) (xy 307.219108 -294.4749) (xy 307.223068 -294.425846)
			(xy 307.234845 -294.378062) (xy 307.254136 -294.332786) (xy 307.280439 -294.29119) (xy 307.313074 -294.254353)
			(xy 307.351195 -294.223228) (xy 307.393816 -294.198621) (xy 307.439832 -294.181169) (xy 307.488051 -294.171325)
			(xy 307.537226 -294.169344) (xy 307.586081 -294.175276) (xy 307.633352 -294.188968) (xy 307.677814 -294.210066)
			(xy 307.718317 -294.238022) (xy 307.75381 -294.272114) (xy 307.783375 -294.311458) (xy 307.806246 -294.355035)
			(xy 307.82183 -294.401716) (xy 307.829725 -294.450293) (xy 307.83022 -294.4749) (xy 308.169068 -294.4749)
			(xy 308.173028 -294.425846) (xy 308.184805 -294.378062) (xy 308.204096 -294.332786) (xy 308.230399 -294.29119)
			(xy 308.263034 -294.254353) (xy 308.301155 -294.223228) (xy 308.343776 -294.198621) (xy 308.389792 -294.181169)
			(xy 308.438011 -294.171325) (xy 308.487186 -294.169344) (xy 308.536041 -294.175276) (xy 308.583312 -294.188968)
			(xy 308.627774 -294.210066) (xy 308.668277 -294.238022) (xy 308.70377 -294.272114) (xy 308.733335 -294.311458)
			(xy 308.756206 -294.355035) (xy 308.77179 -294.401716) (xy 308.779685 -294.450293) (xy 308.78018 -294.4749)
			(xy 309.119028 -294.4749) (xy 309.122988 -294.425846) (xy 309.134765 -294.378062) (xy 309.154056 -294.332786)
			(xy 309.180359 -294.29119) (xy 309.212994 -294.254353) (xy 309.251115 -294.223228) (xy 309.293736 -294.198621)
			(xy 309.339752 -294.181169) (xy 309.387971 -294.171325) (xy 309.437146 -294.169344) (xy 309.486001 -294.175276)
			(xy 309.533272 -294.188968) (xy 309.577734 -294.210066) (xy 309.618237 -294.238022) (xy 309.65373 -294.272114)
			(xy 309.683295 -294.311458) (xy 309.706166 -294.355035) (xy 309.72175 -294.401716) (xy 309.729645 -294.450293)
			(xy 309.73014 -294.4749) (xy 310.068988 -294.4749) (xy 310.072948 -294.425846) (xy 310.084725 -294.378062)
			(xy 310.104016 -294.332786) (xy 310.130319 -294.29119) (xy 310.162954 -294.254353) (xy 310.201075 -294.223228)
			(xy 310.243696 -294.198621) (xy 310.289712 -294.181169) (xy 310.337931 -294.171325) (xy 310.387106 -294.169344)
			(xy 310.435961 -294.175276) (xy 310.483232 -294.188968) (xy 310.527694 -294.210066) (xy 310.568197 -294.238022)
			(xy 310.60369 -294.272114) (xy 310.633255 -294.311458) (xy 310.656126 -294.355035) (xy 310.67171 -294.401716)
			(xy 310.679605 -294.450293) (xy 310.6801 -294.4749) (xy 311.018948 -294.4749) (xy 311.022908 -294.425846)
			(xy 311.034685 -294.378062) (xy 311.053976 -294.332786) (xy 311.080279 -294.29119) (xy 311.112914 -294.254353)
			(xy 311.151035 -294.223228) (xy 311.193656 -294.198621) (xy 311.239672 -294.181169) (xy 311.287891 -294.171325)
			(xy 311.337066 -294.169344) (xy 311.385921 -294.175276) (xy 311.433192 -294.188968) (xy 311.477654 -294.210066)
			(xy 311.518157 -294.238022) (xy 311.55365 -294.272114) (xy 311.583215 -294.311458) (xy 311.606086 -294.355035)
			(xy 311.62167 -294.401716) (xy 311.629565 -294.450293) (xy 311.63006 -294.4749) (xy 311.968908 -294.4749)
			(xy 311.972868 -294.425846) (xy 311.984645 -294.378062) (xy 312.003936 -294.332786) (xy 312.030239 -294.29119)
			(xy 312.062874 -294.254353) (xy 312.100995 -294.223228) (xy 312.143616 -294.198621) (xy 312.189632 -294.181169)
			(xy 312.237851 -294.171325) (xy 312.287026 -294.169344) (xy 312.335881 -294.175276) (xy 312.383152 -294.188968)
			(xy 312.427614 -294.210066) (xy 312.468117 -294.238022) (xy 312.50361 -294.272114) (xy 312.533175 -294.311458)
			(xy 312.556046 -294.355035) (xy 312.57163 -294.401716) (xy 312.579525 -294.450293) (xy 312.58002 -294.4749)
			(xy 312.919122 -294.4749) (xy 312.923082 -294.425846) (xy 312.934859 -294.378062) (xy 312.95415 -294.332786)
			(xy 312.980453 -294.29119) (xy 313.013088 -294.254353) (xy 313.051209 -294.223228) (xy 313.09383 -294.198621)
			(xy 313.139846 -294.181169) (xy 313.188065 -294.171325) (xy 313.23724 -294.169344) (xy 313.286095 -294.175276)
			(xy 313.333366 -294.188968) (xy 313.377828 -294.210066) (xy 313.418331 -294.238022) (xy 313.453824 -294.272114)
			(xy 313.483389 -294.311458) (xy 313.50626 -294.355035) (xy 313.521844 -294.401716) (xy 313.529739 -294.450293)
			(xy 313.530234 -294.4749) (xy 313.869082 -294.4749) (xy 313.873042 -294.425846) (xy 313.884819 -294.378062)
			(xy 313.90411 -294.332786) (xy 313.930413 -294.29119) (xy 313.963048 -294.254353) (xy 314.001169 -294.223228)
			(xy 314.04379 -294.198621) (xy 314.089806 -294.181169) (xy 314.138025 -294.171325) (xy 314.1872 -294.169344)
			(xy 314.236055 -294.175276) (xy 314.283326 -294.188968) (xy 314.327788 -294.210066) (xy 314.368291 -294.238022)
			(xy 314.403784 -294.272114) (xy 314.433349 -294.311458) (xy 314.45622 -294.355035) (xy 314.471804 -294.401716)
			(xy 314.479699 -294.450293) (xy 314.480194 -294.4749) (xy 314.479699 -294.499507) (xy 314.471804 -294.548084)
			(xy 314.45622 -294.594765) (xy 314.433349 -294.638342) (xy 314.403784 -294.677686) (xy 314.368291 -294.711778)
			(xy 314.327788 -294.739734) (xy 314.283326 -294.760832) (xy 314.236055 -294.774524) (xy 314.1872 -294.780456)
			(xy 314.138025 -294.778475) (xy 314.089806 -294.768631) (xy 314.04379 -294.751179) (xy 314.001169 -294.726572)
			(xy 313.963048 -294.695447) (xy 313.930413 -294.65861) (xy 313.90411 -294.617014) (xy 313.884819 -294.571738)
			(xy 313.873042 -294.523954) (xy 313.869082 -294.4749) (xy 313.530234 -294.4749) (xy 313.529739 -294.499507)
			(xy 313.521844 -294.548084) (xy 313.50626 -294.594765) (xy 313.483389 -294.638342) (xy 313.453824 -294.677686)
			(xy 313.418331 -294.711778) (xy 313.377828 -294.739734) (xy 313.333366 -294.760832) (xy 313.286095 -294.774524)
			(xy 313.23724 -294.780456) (xy 313.188065 -294.778475) (xy 313.139846 -294.768631) (xy 313.09383 -294.751179)
			(xy 313.051209 -294.726572) (xy 313.013088 -294.695447) (xy 312.980453 -294.65861) (xy 312.95415 -294.617014)
			(xy 312.934859 -294.571738) (xy 312.923082 -294.523954) (xy 312.919122 -294.4749) (xy 312.58002 -294.4749)
			(xy 312.579525 -294.499507) (xy 312.57163 -294.548084) (xy 312.556046 -294.594765) (xy 312.533175 -294.638342)
			(xy 312.50361 -294.677686) (xy 312.468117 -294.711778) (xy 312.427614 -294.739734) (xy 312.383152 -294.760832)
			(xy 312.335881 -294.774524) (xy 312.287026 -294.780456) (xy 312.237851 -294.778475) (xy 312.189632 -294.768631)
			(xy 312.143616 -294.751179) (xy 312.100995 -294.726572) (xy 312.062874 -294.695447) (xy 312.030239 -294.65861)
			(xy 312.003936 -294.617014) (xy 311.984645 -294.571738) (xy 311.972868 -294.523954) (xy 311.968908 -294.4749)
			(xy 311.63006 -294.4749) (xy 311.629565 -294.499507) (xy 311.62167 -294.548084) (xy 311.606086 -294.594765)
			(xy 311.583215 -294.638342) (xy 311.55365 -294.677686) (xy 311.518157 -294.711778) (xy 311.477654 -294.739734)
			(xy 311.433192 -294.760832) (xy 311.385921 -294.774524) (xy 311.337066 -294.780456) (xy 311.287891 -294.778475)
			(xy 311.239672 -294.768631) (xy 311.193656 -294.751179) (xy 311.151035 -294.726572) (xy 311.112914 -294.695447)
			(xy 311.080279 -294.65861) (xy 311.053976 -294.617014) (xy 311.034685 -294.571738) (xy 311.022908 -294.523954)
			(xy 311.018948 -294.4749) (xy 310.6801 -294.4749) (xy 310.679605 -294.499507) (xy 310.67171 -294.548084)
			(xy 310.656126 -294.594765) (xy 310.633255 -294.638342) (xy 310.60369 -294.677686) (xy 310.568197 -294.711778)
			(xy 310.527694 -294.739734) (xy 310.483232 -294.760832) (xy 310.435961 -294.774524) (xy 310.387106 -294.780456)
			(xy 310.337931 -294.778475) (xy 310.289712 -294.768631) (xy 310.243696 -294.751179) (xy 310.201075 -294.726572)
			(xy 310.162954 -294.695447) (xy 310.130319 -294.65861) (xy 310.104016 -294.617014) (xy 310.084725 -294.571738)
			(xy 310.072948 -294.523954) (xy 310.068988 -294.4749) (xy 309.73014 -294.4749) (xy 309.729645 -294.499507)
			(xy 309.72175 -294.548084) (xy 309.706166 -294.594765) (xy 309.683295 -294.638342) (xy 309.65373 -294.677686)
			(xy 309.618237 -294.711778) (xy 309.577734 -294.739734) (xy 309.533272 -294.760832) (xy 309.486001 -294.774524)
			(xy 309.437146 -294.780456) (xy 309.387971 -294.778475) (xy 309.339752 -294.768631) (xy 309.293736 -294.751179)
			(xy 309.251115 -294.726572) (xy 309.212994 -294.695447) (xy 309.180359 -294.65861) (xy 309.154056 -294.617014)
			(xy 309.134765 -294.571738) (xy 309.122988 -294.523954) (xy 309.119028 -294.4749) (xy 308.78018 -294.4749)
			(xy 308.779685 -294.499507) (xy 308.77179 -294.548084) (xy 308.756206 -294.594765) (xy 308.733335 -294.638342)
			(xy 308.70377 -294.677686) (xy 308.668277 -294.711778) (xy 308.627774 -294.739734) (xy 308.583312 -294.760832)
			(xy 308.536041 -294.774524) (xy 308.487186 -294.780456) (xy 308.438011 -294.778475) (xy 308.389792 -294.768631)
			(xy 308.343776 -294.751179) (xy 308.301155 -294.726572) (xy 308.263034 -294.695447) (xy 308.230399 -294.65861)
			(xy 308.204096 -294.617014) (xy 308.184805 -294.571738) (xy 308.173028 -294.523954) (xy 308.169068 -294.4749)
			(xy 307.83022 -294.4749) (xy 307.829725 -294.499507) (xy 307.82183 -294.548084) (xy 307.806246 -294.594765)
			(xy 307.783375 -294.638342) (xy 307.75381 -294.677686) (xy 307.718317 -294.711778) (xy 307.677814 -294.739734)
			(xy 307.633352 -294.760832) (xy 307.586081 -294.774524) (xy 307.537226 -294.780456) (xy 307.488051 -294.778475)
			(xy 307.439832 -294.768631) (xy 307.393816 -294.751179) (xy 307.351195 -294.726572) (xy 307.313074 -294.695447)
			(xy 307.280439 -294.65861) (xy 307.254136 -294.617014) (xy 307.234845 -294.571738) (xy 307.223068 -294.523954)
			(xy 307.219108 -294.4749) (xy 306.880006 -294.4749) (xy 306.879511 -294.499507) (xy 306.871616 -294.548084)
			(xy 306.856032 -294.594765) (xy 306.833161 -294.638342) (xy 306.803596 -294.677686) (xy 306.768103 -294.711778)
			(xy 306.7276 -294.739734) (xy 306.683138 -294.760832) (xy 306.635867 -294.774524) (xy 306.587012 -294.780456)
			(xy 306.537837 -294.778475) (xy 306.489618 -294.768631) (xy 306.443602 -294.751179) (xy 306.400981 -294.726572)
			(xy 306.36286 -294.695447) (xy 306.330225 -294.65861) (xy 306.303922 -294.617014) (xy 306.284631 -294.571738)
			(xy 306.272854 -294.523954) (xy 306.268894 -294.4749) (xy 305.930046 -294.4749) (xy 305.929551 -294.499507)
			(xy 305.921656 -294.548084) (xy 305.906072 -294.594765) (xy 305.883201 -294.638342) (xy 305.853636 -294.677686)
			(xy 305.818143 -294.711778) (xy 305.77764 -294.739734) (xy 305.733178 -294.760832) (xy 305.685907 -294.774524)
			(xy 305.637052 -294.780456) (xy 305.587877 -294.778475) (xy 305.539658 -294.768631) (xy 305.493642 -294.751179)
			(xy 305.451021 -294.726572) (xy 305.4129 -294.695447) (xy 305.380265 -294.65861) (xy 305.353962 -294.617014)
			(xy 305.334671 -294.571738) (xy 305.322894 -294.523954) (xy 305.318934 -294.4749) (xy 304.980086 -294.4749)
			(xy 304.979591 -294.499507) (xy 304.971696 -294.548084) (xy 304.956112 -294.594765) (xy 304.933241 -294.638342)
			(xy 304.903676 -294.677686) (xy 304.868183 -294.711778) (xy 304.82768 -294.739734) (xy 304.783218 -294.760832)
			(xy 304.735947 -294.774524) (xy 304.687092 -294.780456) (xy 304.637917 -294.778475) (xy 304.589698 -294.768631)
			(xy 304.543682 -294.751179) (xy 304.501061 -294.726572) (xy 304.46294 -294.695447) (xy 304.430305 -294.65861)
			(xy 304.404002 -294.617014) (xy 304.384711 -294.571738) (xy 304.372934 -294.523954) (xy 304.368974 -294.4749)
			(xy 304.030126 -294.4749) (xy 304.029631 -294.499507) (xy 304.021736 -294.548084) (xy 304.006152 -294.594765)
			(xy 303.983281 -294.638342) (xy 303.953716 -294.677686) (xy 303.918223 -294.711778) (xy 303.87772 -294.739734)
			(xy 303.833258 -294.760832) (xy 303.785987 -294.774524) (xy 303.737132 -294.780456) (xy 303.687957 -294.778475)
			(xy 303.639738 -294.768631) (xy 303.593722 -294.751179) (xy 303.551101 -294.726572) (xy 303.51298 -294.695447)
			(xy 303.480345 -294.65861) (xy 303.454042 -294.617014) (xy 303.434751 -294.571738) (xy 303.422974 -294.523954)
			(xy 303.419014 -294.4749) (xy 303.080526 -294.4749) (xy 303.076039 -294.527107) (xy 303.062707 -294.577783)
			(xy 303.040924 -294.62544) (xy 303.026572 -294.647366) (xy 303.020654 -294.657009) (xy 303.017022 -294.679309)
			(xy 303.023327 -294.701006) (xy 303.030382 -294.70985) (xy 303.03724 -294.717216) (xy 303.043065 -294.724419)
			(xy 303.049583 -294.741742) (xy 303.04994 -294.750998) (xy 303.04994 -296.098722) (xy 303.049544 -296.107972)
			(xy 303.043042 -296.12529) (xy 303.03724 -296.132504) (xy 303.030382 -296.13987) (xy 303.023409 -296.148756)
			(xy 303.017152 -296.170427) (xy 303.02071 -296.192701) (xy 303.026572 -296.202354) (xy 303.040942 -296.224269)
			(xy 303.062724 -296.271929) (xy 303.076052 -296.322607) (xy 303.080537 -296.374817) (xy 303.080537 -296.37482)
			(xy 303.419014 -296.37482) (xy 303.422974 -296.325766) (xy 303.434751 -296.277982) (xy 303.454042 -296.232706)
			(xy 303.480345 -296.19111) (xy 303.51298 -296.154273) (xy 303.551101 -296.123148) (xy 303.593722 -296.098541)
			(xy 303.639738 -296.081089) (xy 303.687957 -296.071245) (xy 303.737132 -296.069264) (xy 303.785987 -296.075196)
			(xy 303.833258 -296.088888) (xy 303.87772 -296.109986) (xy 303.918223 -296.137942) (xy 303.953716 -296.172034)
			(xy 303.983281 -296.211378) (xy 304.006152 -296.254955) (xy 304.021736 -296.301636) (xy 304.029631 -296.350213)
			(xy 304.030126 -296.37482) (xy 304.368974 -296.37482) (xy 304.372934 -296.325766) (xy 304.384711 -296.277982)
			(xy 304.404002 -296.232706) (xy 304.430305 -296.19111) (xy 304.46294 -296.154273) (xy 304.501061 -296.123148)
			(xy 304.543682 -296.098541) (xy 304.589698 -296.081089) (xy 304.637917 -296.071245) (xy 304.687092 -296.069264)
			(xy 304.735947 -296.075196) (xy 304.783218 -296.088888) (xy 304.82768 -296.109986) (xy 304.868183 -296.137942)
			(xy 304.903676 -296.172034) (xy 304.933241 -296.211378) (xy 304.956112 -296.254955) (xy 304.971696 -296.301636)
			(xy 304.979591 -296.350213) (xy 304.980086 -296.37482) (xy 305.318934 -296.37482) (xy 305.322894 -296.325766)
			(xy 305.334671 -296.277982) (xy 305.353962 -296.232706) (xy 305.380265 -296.19111) (xy 305.4129 -296.154273)
			(xy 305.451021 -296.123148) (xy 305.493642 -296.098541) (xy 305.539658 -296.081089) (xy 305.587877 -296.071245)
			(xy 305.637052 -296.069264) (xy 305.685907 -296.075196) (xy 305.733178 -296.088888) (xy 305.77764 -296.109986)
			(xy 305.818143 -296.137942) (xy 305.853636 -296.172034) (xy 305.883201 -296.211378) (xy 305.906072 -296.254955)
			(xy 305.921656 -296.301636) (xy 305.929551 -296.350213) (xy 305.930046 -296.37482) (xy 306.268894 -296.37482)
			(xy 306.272854 -296.325766) (xy 306.284631 -296.277982) (xy 306.303922 -296.232706) (xy 306.330225 -296.19111)
			(xy 306.36286 -296.154273) (xy 306.400981 -296.123148) (xy 306.443602 -296.098541) (xy 306.489618 -296.081089)
			(xy 306.537837 -296.071245) (xy 306.587012 -296.069264) (xy 306.635867 -296.075196) (xy 306.683138 -296.088888)
			(xy 306.7276 -296.109986) (xy 306.768103 -296.137942) (xy 306.803596 -296.172034) (xy 306.833161 -296.211378)
			(xy 306.856032 -296.254955) (xy 306.871616 -296.301636) (xy 306.879511 -296.350213) (xy 306.880006 -296.37482)
			(xy 307.219108 -296.37482) (xy 307.223068 -296.325766) (xy 307.234845 -296.277982) (xy 307.254136 -296.232706)
			(xy 307.280439 -296.19111) (xy 307.313074 -296.154273) (xy 307.351195 -296.123148) (xy 307.393816 -296.098541)
			(xy 307.439832 -296.081089) (xy 307.488051 -296.071245) (xy 307.537226 -296.069264) (xy 307.586081 -296.075196)
			(xy 307.633352 -296.088888) (xy 307.677814 -296.109986) (xy 307.718317 -296.137942) (xy 307.75381 -296.172034)
			(xy 307.783375 -296.211378) (xy 307.806246 -296.254955) (xy 307.82183 -296.301636) (xy 307.829725 -296.350213)
			(xy 307.83022 -296.37482) (xy 308.169068 -296.37482) (xy 308.173028 -296.325766) (xy 308.184805 -296.277982)
			(xy 308.204096 -296.232706) (xy 308.230399 -296.19111) (xy 308.263034 -296.154273) (xy 308.301155 -296.123148)
			(xy 308.343776 -296.098541) (xy 308.389792 -296.081089) (xy 308.438011 -296.071245) (xy 308.487186 -296.069264)
			(xy 308.536041 -296.075196) (xy 308.583312 -296.088888) (xy 308.627774 -296.109986) (xy 308.668277 -296.137942)
			(xy 308.70377 -296.172034) (xy 308.733335 -296.211378) (xy 308.756206 -296.254955) (xy 308.77179 -296.301636)
			(xy 308.779685 -296.350213) (xy 308.78018 -296.37482) (xy 309.119028 -296.37482) (xy 309.122988 -296.325766)
			(xy 309.134765 -296.277982) (xy 309.154056 -296.232706) (xy 309.180359 -296.19111) (xy 309.212994 -296.154273)
			(xy 309.251115 -296.123148) (xy 309.293736 -296.098541) (xy 309.339752 -296.081089) (xy 309.387971 -296.071245)
			(xy 309.437146 -296.069264) (xy 309.486001 -296.075196) (xy 309.533272 -296.088888) (xy 309.577734 -296.109986)
			(xy 309.618237 -296.137942) (xy 309.65373 -296.172034) (xy 309.683295 -296.211378) (xy 309.706166 -296.254955)
			(xy 309.72175 -296.301636) (xy 309.729645 -296.350213) (xy 309.73014 -296.37482) (xy 310.068988 -296.37482)
			(xy 310.072948 -296.325766) (xy 310.084725 -296.277982) (xy 310.104016 -296.232706) (xy 310.130319 -296.19111)
			(xy 310.162954 -296.154273) (xy 310.201075 -296.123148) (xy 310.243696 -296.098541) (xy 310.289712 -296.081089)
			(xy 310.337931 -296.071245) (xy 310.387106 -296.069264) (xy 310.435961 -296.075196) (xy 310.483232 -296.088888)
			(xy 310.527694 -296.109986) (xy 310.568197 -296.137942) (xy 310.60369 -296.172034) (xy 310.633255 -296.211378)
			(xy 310.656126 -296.254955) (xy 310.67171 -296.301636) (xy 310.679605 -296.350213) (xy 310.6801 -296.37482)
			(xy 311.018948 -296.37482) (xy 311.022908 -296.325766) (xy 311.034685 -296.277982) (xy 311.053976 -296.232706)
			(xy 311.080279 -296.19111) (xy 311.112914 -296.154273) (xy 311.151035 -296.123148) (xy 311.193656 -296.098541)
			(xy 311.239672 -296.081089) (xy 311.287891 -296.071245) (xy 311.337066 -296.069264) (xy 311.385921 -296.075196)
			(xy 311.433192 -296.088888) (xy 311.477654 -296.109986) (xy 311.518157 -296.137942) (xy 311.55365 -296.172034)
			(xy 311.583215 -296.211378) (xy 311.606086 -296.254955) (xy 311.62167 -296.301636) (xy 311.629565 -296.350213)
			(xy 311.63006 -296.37482) (xy 311.968908 -296.37482) (xy 311.972868 -296.325766) (xy 311.984645 -296.277982)
			(xy 312.003936 -296.232706) (xy 312.030239 -296.19111) (xy 312.062874 -296.154273) (xy 312.100995 -296.123148)
			(xy 312.143616 -296.098541) (xy 312.189632 -296.081089) (xy 312.237851 -296.071245) (xy 312.287026 -296.069264)
			(xy 312.335881 -296.075196) (xy 312.383152 -296.088888) (xy 312.427614 -296.109986) (xy 312.468117 -296.137942)
			(xy 312.50361 -296.172034) (xy 312.533175 -296.211378) (xy 312.556046 -296.254955) (xy 312.57163 -296.301636)
			(xy 312.579525 -296.350213) (xy 312.58002 -296.37482) (xy 312.919122 -296.37482) (xy 312.923082 -296.325766)
			(xy 312.934859 -296.277982) (xy 312.95415 -296.232706) (xy 312.980453 -296.19111) (xy 313.013088 -296.154273)
			(xy 313.051209 -296.123148) (xy 313.09383 -296.098541) (xy 313.139846 -296.081089) (xy 313.188065 -296.071245)
			(xy 313.23724 -296.069264) (xy 313.286095 -296.075196) (xy 313.333366 -296.088888) (xy 313.377828 -296.109986)
			(xy 313.418331 -296.137942) (xy 313.453824 -296.172034) (xy 313.483389 -296.211378) (xy 313.50626 -296.254955)
			(xy 313.521844 -296.301636) (xy 313.529739 -296.350213) (xy 313.530234 -296.37482) (xy 313.869082 -296.37482)
			(xy 313.873042 -296.325766) (xy 313.884819 -296.277982) (xy 313.90411 -296.232706) (xy 313.930413 -296.19111)
			(xy 313.963048 -296.154273) (xy 314.001169 -296.123148) (xy 314.04379 -296.098541) (xy 314.089806 -296.081089)
			(xy 314.138025 -296.071245) (xy 314.1872 -296.069264) (xy 314.236055 -296.075196) (xy 314.283326 -296.088888)
			(xy 314.327788 -296.109986) (xy 314.368291 -296.137942) (xy 314.403784 -296.172034) (xy 314.433349 -296.211378)
			(xy 314.45622 -296.254955) (xy 314.471804 -296.301636) (xy 314.479699 -296.350213) (xy 314.480194 -296.37482)
			(xy 314.479699 -296.399427) (xy 314.471804 -296.448004) (xy 314.45622 -296.494685) (xy 314.433349 -296.538262)
			(xy 314.403784 -296.577606) (xy 314.368291 -296.611698) (xy 314.327788 -296.639654) (xy 314.283326 -296.660752)
			(xy 314.236055 -296.674444) (xy 314.1872 -296.680376) (xy 314.138025 -296.678395) (xy 314.089806 -296.668551)
			(xy 314.04379 -296.651099) (xy 314.001169 -296.626492) (xy 313.963048 -296.595367) (xy 313.930413 -296.55853)
			(xy 313.90411 -296.516934) (xy 313.884819 -296.471658) (xy 313.873042 -296.423874) (xy 313.869082 -296.37482)
			(xy 313.530234 -296.37482) (xy 313.529739 -296.399427) (xy 313.521844 -296.448004) (xy 313.50626 -296.494685)
			(xy 313.483389 -296.538262) (xy 313.453824 -296.577606) (xy 313.418331 -296.611698) (xy 313.377828 -296.639654)
			(xy 313.333366 -296.660752) (xy 313.286095 -296.674444) (xy 313.23724 -296.680376) (xy 313.188065 -296.678395)
			(xy 313.139846 -296.668551) (xy 313.09383 -296.651099) (xy 313.051209 -296.626492) (xy 313.013088 -296.595367)
			(xy 312.980453 -296.55853) (xy 312.95415 -296.516934) (xy 312.934859 -296.471658) (xy 312.923082 -296.423874)
			(xy 312.919122 -296.37482) (xy 312.58002 -296.37482) (xy 312.579525 -296.399427) (xy 312.57163 -296.448004)
			(xy 312.556046 -296.494685) (xy 312.533175 -296.538262) (xy 312.50361 -296.577606) (xy 312.468117 -296.611698)
			(xy 312.427614 -296.639654) (xy 312.383152 -296.660752) (xy 312.335881 -296.674444) (xy 312.287026 -296.680376)
			(xy 312.237851 -296.678395) (xy 312.189632 -296.668551) (xy 312.143616 -296.651099) (xy 312.100995 -296.626492)
			(xy 312.062874 -296.595367) (xy 312.030239 -296.55853) (xy 312.003936 -296.516934) (xy 311.984645 -296.471658)
			(xy 311.972868 -296.423874) (xy 311.968908 -296.37482) (xy 311.63006 -296.37482) (xy 311.629565 -296.399427)
			(xy 311.62167 -296.448004) (xy 311.606086 -296.494685) (xy 311.583215 -296.538262) (xy 311.55365 -296.577606)
			(xy 311.518157 -296.611698) (xy 311.477654 -296.639654) (xy 311.433192 -296.660752) (xy 311.385921 -296.674444)
			(xy 311.337066 -296.680376) (xy 311.287891 -296.678395) (xy 311.239672 -296.668551) (xy 311.193656 -296.651099)
			(xy 311.151035 -296.626492) (xy 311.112914 -296.595367) (xy 311.080279 -296.55853) (xy 311.053976 -296.516934)
			(xy 311.034685 -296.471658) (xy 311.022908 -296.423874) (xy 311.018948 -296.37482) (xy 310.6801 -296.37482)
			(xy 310.679605 -296.399427) (xy 310.67171 -296.448004) (xy 310.656126 -296.494685) (xy 310.633255 -296.538262)
			(xy 310.60369 -296.577606) (xy 310.568197 -296.611698) (xy 310.527694 -296.639654) (xy 310.483232 -296.660752)
			(xy 310.435961 -296.674444) (xy 310.387106 -296.680376) (xy 310.337931 -296.678395) (xy 310.289712 -296.668551)
			(xy 310.243696 -296.651099) (xy 310.201075 -296.626492) (xy 310.162954 -296.595367) (xy 310.130319 -296.55853)
			(xy 310.104016 -296.516934) (xy 310.084725 -296.471658) (xy 310.072948 -296.423874) (xy 310.068988 -296.37482)
			(xy 309.73014 -296.37482) (xy 309.729645 -296.399427) (xy 309.72175 -296.448004) (xy 309.706166 -296.494685)
			(xy 309.683295 -296.538262) (xy 309.65373 -296.577606) (xy 309.618237 -296.611698) (xy 309.577734 -296.639654)
			(xy 309.533272 -296.660752) (xy 309.486001 -296.674444) (xy 309.437146 -296.680376) (xy 309.387971 -296.678395)
			(xy 309.339752 -296.668551) (xy 309.293736 -296.651099) (xy 309.251115 -296.626492) (xy 309.212994 -296.595367)
			(xy 309.180359 -296.55853) (xy 309.154056 -296.516934) (xy 309.134765 -296.471658) (xy 309.122988 -296.423874)
			(xy 309.119028 -296.37482) (xy 308.78018 -296.37482) (xy 308.779685 -296.399427) (xy 308.77179 -296.448004)
			(xy 308.756206 -296.494685) (xy 308.733335 -296.538262) (xy 308.70377 -296.577606) (xy 308.668277 -296.611698)
			(xy 308.627774 -296.639654) (xy 308.583312 -296.660752) (xy 308.536041 -296.674444) (xy 308.487186 -296.680376)
			(xy 308.438011 -296.678395) (xy 308.389792 -296.668551) (xy 308.343776 -296.651099) (xy 308.301155 -296.626492)
			(xy 308.263034 -296.595367) (xy 308.230399 -296.55853) (xy 308.204096 -296.516934) (xy 308.184805 -296.471658)
			(xy 308.173028 -296.423874) (xy 308.169068 -296.37482) (xy 307.83022 -296.37482) (xy 307.829725 -296.399427)
			(xy 307.82183 -296.448004) (xy 307.806246 -296.494685) (xy 307.783375 -296.538262) (xy 307.75381 -296.577606)
			(xy 307.718317 -296.611698) (xy 307.677814 -296.639654) (xy 307.633352 -296.660752) (xy 307.586081 -296.674444)
			(xy 307.537226 -296.680376) (xy 307.488051 -296.678395) (xy 307.439832 -296.668551) (xy 307.393816 -296.651099)
			(xy 307.351195 -296.626492) (xy 307.313074 -296.595367) (xy 307.280439 -296.55853) (xy 307.254136 -296.516934)
			(xy 307.234845 -296.471658) (xy 307.223068 -296.423874) (xy 307.219108 -296.37482) (xy 306.880006 -296.37482)
			(xy 306.879511 -296.399427) (xy 306.871616 -296.448004) (xy 306.856032 -296.494685) (xy 306.833161 -296.538262)
			(xy 306.803596 -296.577606) (xy 306.768103 -296.611698) (xy 306.7276 -296.639654) (xy 306.683138 -296.660752)
			(xy 306.635867 -296.674444) (xy 306.587012 -296.680376) (xy 306.537837 -296.678395) (xy 306.489618 -296.668551)
			(xy 306.443602 -296.651099) (xy 306.400981 -296.626492) (xy 306.36286 -296.595367) (xy 306.330225 -296.55853)
			(xy 306.303922 -296.516934) (xy 306.284631 -296.471658) (xy 306.272854 -296.423874) (xy 306.268894 -296.37482)
			(xy 305.930046 -296.37482) (xy 305.929551 -296.399427) (xy 305.921656 -296.448004) (xy 305.906072 -296.494685)
			(xy 305.883201 -296.538262) (xy 305.853636 -296.577606) (xy 305.818143 -296.611698) (xy 305.77764 -296.639654)
			(xy 305.733178 -296.660752) (xy 305.685907 -296.674444) (xy 305.637052 -296.680376) (xy 305.587877 -296.678395)
			(xy 305.539658 -296.668551) (xy 305.493642 -296.651099) (xy 305.451021 -296.626492) (xy 305.4129 -296.595367)
			(xy 305.380265 -296.55853) (xy 305.353962 -296.516934) (xy 305.334671 -296.471658) (xy 305.322894 -296.423874)
			(xy 305.318934 -296.37482) (xy 304.980086 -296.37482) (xy 304.979591 -296.399427) (xy 304.971696 -296.448004)
			(xy 304.956112 -296.494685) (xy 304.933241 -296.538262) (xy 304.903676 -296.577606) (xy 304.868183 -296.611698)
			(xy 304.82768 -296.639654) (xy 304.783218 -296.660752) (xy 304.735947 -296.674444) (xy 304.687092 -296.680376)
			(xy 304.637917 -296.678395) (xy 304.589698 -296.668551) (xy 304.543682 -296.651099) (xy 304.501061 -296.626492)
			(xy 304.46294 -296.595367) (xy 304.430305 -296.55853) (xy 304.404002 -296.516934) (xy 304.384711 -296.471658)
			(xy 304.372934 -296.423874) (xy 304.368974 -296.37482) (xy 304.030126 -296.37482) (xy 304.029631 -296.399427)
			(xy 304.021736 -296.448004) (xy 304.006152 -296.494685) (xy 303.983281 -296.538262) (xy 303.953716 -296.577606)
			(xy 303.918223 -296.611698) (xy 303.87772 -296.639654) (xy 303.833258 -296.660752) (xy 303.785987 -296.674444)
			(xy 303.737132 -296.680376) (xy 303.687957 -296.678395) (xy 303.639738 -296.668551) (xy 303.593722 -296.651099)
			(xy 303.551101 -296.626492) (xy 303.51298 -296.595367) (xy 303.480345 -296.55853) (xy 303.454042 -296.516934)
			(xy 303.434751 -296.471658) (xy 303.422974 -296.423874) (xy 303.419014 -296.37482) (xy 303.080537 -296.37482)
			(xy 303.076047 -296.427025) (xy 303.062713 -296.477702) (xy 303.040926 -296.52536) (xy 303.026572 -296.547286)
			(xy 303.020636 -296.55692) (xy 303.01701 -296.579226) (xy 303.023323 -296.600925) (xy 303.030382 -296.60977)
			(xy 303.03724 -296.617136) (xy 303.043073 -296.624333) (xy 303.049586 -296.64166) (xy 303.04994 -296.650918)
			(xy 303.04994 -297.048682) (xy 303.049573 -297.057935) (xy 303.043051 -297.075253) (xy 303.03724 -297.082464)
			(xy 303.030382 -297.08983) (xy 303.023357 -297.09868) (xy 303.017115 -297.120373) (xy 303.020696 -297.14266)
			(xy 303.026572 -297.152314) (xy 303.039218 -297.171448) (xy 303.05924 -297.21271) (xy 303.07285 -297.256507)
			(xy 303.079743 -297.301849) (xy 303.080166 -297.32478) (xy 303.419014 -297.32478) (xy 303.422974 -297.275726)
			(xy 303.434751 -297.227942) (xy 303.454042 -297.182666) (xy 303.480345 -297.14107) (xy 303.51298 -297.104233)
			(xy 303.551101 -297.073108) (xy 303.593722 -297.048501) (xy 303.639738 -297.031049) (xy 303.687957 -297.021205)
			(xy 303.737132 -297.019224) (xy 303.785987 -297.025156) (xy 303.833258 -297.038848) (xy 303.87772 -297.059946)
			(xy 303.918223 -297.087902) (xy 303.953716 -297.121994) (xy 303.983281 -297.161338) (xy 304.006152 -297.204915)
			(xy 304.021736 -297.251596) (xy 304.029631 -297.300173) (xy 304.030126 -297.32478) (xy 304.029631 -297.349387)
			(xy 304.021736 -297.397964) (xy 304.006152 -297.444645) (xy 303.983281 -297.488222) (xy 303.953716 -297.527566)
			(xy 303.918223 -297.561658) (xy 303.87772 -297.589614) (xy 303.833258 -297.610712) (xy 303.785987 -297.624404)
			(xy 303.737132 -297.630336) (xy 303.687957 -297.628355) (xy 303.639738 -297.618511) (xy 303.593722 -297.601059)
			(xy 303.551101 -297.576452) (xy 303.51298 -297.545327) (xy 303.480345 -297.50849) (xy 303.454042 -297.466894)
			(xy 303.434751 -297.421618) (xy 303.422974 -297.373834) (xy 303.419014 -297.32478) (xy 303.080166 -297.32478)
			(xy 303.079743 -297.348775) (xy 303.072238 -297.396174) (xy 303.05741 -297.441814) (xy 303.035623 -297.484573)
			(xy 303.007415 -297.523397) (xy 302.97348 -297.55733) (xy 302.934655 -297.585535) (xy 302.891894 -297.607318)
			(xy 302.846252 -297.622143) (xy 302.798853 -297.629645) (xy 302.774858 -297.630088) (xy 302.74733 -297.62942)
			(xy 302.693178 -297.619474) (xy 302.641679 -297.6) (xy 302.594495 -297.571628) (xy 302.573436 -297.553888)
			(xy 302.554386 -297.537378) (xy 302.52924 -297.536362) (xy 302.522434 -297.541209) (xy 302.506604 -297.546529)
			(xy 302.498252 -297.546776) (xy 302.053752 -297.546776) (xy 302.044819 -297.547102) (xy 302.028034 -297.553217)
			(xy 302.020986 -297.558714) (xy 302.000212 -297.5754) (xy 301.954071 -297.602037) (xy 301.904006 -297.620257)
			(xy 301.851537 -297.629508) (xy 301.824898 -297.630088) (xy 301.797369 -297.629454) (xy 301.743215 -297.619498)
			(xy 301.691716 -297.600014) (xy 301.644534 -297.571632) (xy 301.623476 -297.553888) (xy 301.604426 -297.537378)
			(xy 301.57928 -297.536362) (xy 301.572464 -297.541193) (xy 301.556642 -297.546523) (xy 301.548292 -297.546776)
			(xy 301.103538 -297.546776) (xy 301.094604 -297.547095) (xy 301.07782 -297.553215) (xy 301.070772 -297.558714)
			(xy 301.050003 -297.575406) (xy 301.00386 -297.602042) (xy 300.953793 -297.62026) (xy 300.901323 -297.629509)
			(xy 300.874684 -297.630088) (xy 300.859854 -297.629884) (xy 300.830337 -297.626959) (xy 300.815756 -297.624246)
			(xy 300.815502 -297.624246) (xy 300.80431 -297.622687) (xy 300.782431 -297.628209) (xy 300.773338 -297.634914)
			(xy 300.728888 -297.671744) (xy 300.72066 -297.679364) (xy 300.711178 -297.69966) (xy 300.7106 -297.71086)
			(xy 300.7106 -297.88866) (xy 300.711154 -297.899867) (xy 300.720639 -297.92017) (xy 300.728888 -297.927776)
			(xy 300.773338 -297.964606) (xy 300.782419 -297.971344) (xy 300.80431 -297.976888) (xy 300.815502 -297.975274)
			(xy 300.81601 -297.975274) (xy 300.830527 -297.972563) (xy 300.859917 -297.96964) (xy 300.874684 -297.969432)
			(xy 300.899946 -297.969844) (xy 300.949781 -297.978157) (xy 300.997568 -297.99456) (xy 301.042003 -298.018605)
			(xy 301.081874 -298.049636) (xy 301.116094 -298.086807) (xy 301.143729 -298.129103) (xy 301.164024 -298.175371)
			(xy 301.176428 -298.224349) (xy 301.1806 -298.2747) (xy 301.180597 -298.27474) (xy 301.519094 -298.27474)
			(xy 301.523054 -298.225686) (xy 301.534831 -298.177902) (xy 301.554122 -298.132626) (xy 301.580425 -298.09103)
			(xy 301.61306 -298.054193) (xy 301.651181 -298.023068) (xy 301.693802 -297.998461) (xy 301.739818 -297.981009)
			(xy 301.788037 -297.971165) (xy 301.837212 -297.969184) (xy 301.886067 -297.975116) (xy 301.933338 -297.988808)
			(xy 301.9778 -298.009906) (xy 302.018303 -298.037862) (xy 302.053796 -298.071954) (xy 302.083361 -298.111298)
			(xy 302.106232 -298.154875) (xy 302.121816 -298.201556) (xy 302.129711 -298.250133) (xy 302.130206 -298.27474)
			(xy 302.469054 -298.27474) (xy 302.473014 -298.225686) (xy 302.484791 -298.177902) (xy 302.504082 -298.132626)
			(xy 302.530385 -298.09103) (xy 302.56302 -298.054193) (xy 302.601141 -298.023068) (xy 302.643762 -297.998461)
			(xy 302.689778 -297.981009) (xy 302.737997 -297.971165) (xy 302.787172 -297.969184) (xy 302.836027 -297.975116)
			(xy 302.883298 -297.988808) (xy 302.92776 -298.009906) (xy 302.968263 -298.037862) (xy 303.003756 -298.071954)
			(xy 303.033321 -298.111298) (xy 303.056192 -298.154875) (xy 303.071776 -298.201556) (xy 303.079671 -298.250133)
			(xy 303.080166 -298.27474) (xy 303.419014 -298.27474) (xy 303.422974 -298.225686) (xy 303.434751 -298.177902)
			(xy 303.454042 -298.132626) (xy 303.480345 -298.09103) (xy 303.51298 -298.054193) (xy 303.551101 -298.023068)
			(xy 303.593722 -297.998461) (xy 303.639738 -297.981009) (xy 303.687957 -297.971165) (xy 303.737132 -297.969184)
			(xy 303.785987 -297.975116) (xy 303.833258 -297.988808) (xy 303.87772 -298.009906) (xy 303.918223 -298.037862)
			(xy 303.953716 -298.071954) (xy 303.983281 -298.111298) (xy 304.006152 -298.154875) (xy 304.021736 -298.201556)
			(xy 304.029631 -298.250133) (xy 304.030126 -298.27474) (xy 304.029631 -298.299347) (xy 304.021736 -298.347924)
			(xy 304.006152 -298.394605) (xy 303.983281 -298.438182) (xy 303.953716 -298.477526) (xy 303.918223 -298.511618)
			(xy 303.87772 -298.539574) (xy 303.833258 -298.560672) (xy 303.785987 -298.574364) (xy 303.737132 -298.580296)
			(xy 303.687957 -298.578315) (xy 303.639738 -298.568471) (xy 303.593722 -298.551019) (xy 303.551101 -298.526412)
			(xy 303.51298 -298.495287) (xy 303.480345 -298.45845) (xy 303.454042 -298.416854) (xy 303.434751 -298.371578)
			(xy 303.422974 -298.323794) (xy 303.419014 -298.27474) (xy 303.080166 -298.27474) (xy 303.079671 -298.299347)
			(xy 303.071776 -298.347924) (xy 303.056192 -298.394605) (xy 303.033321 -298.438182) (xy 303.003756 -298.477526)
			(xy 302.968263 -298.511618) (xy 302.92776 -298.539574) (xy 302.883298 -298.560672) (xy 302.836027 -298.574364)
			(xy 302.787172 -298.580296) (xy 302.737997 -298.578315) (xy 302.689778 -298.568471) (xy 302.643762 -298.551019)
			(xy 302.601141 -298.526412) (xy 302.56302 -298.495287) (xy 302.530385 -298.45845) (xy 302.504082 -298.416854)
			(xy 302.484791 -298.371578) (xy 302.473014 -298.323794) (xy 302.469054 -298.27474) (xy 302.130206 -298.27474)
			(xy 302.129711 -298.299347) (xy 302.121816 -298.347924) (xy 302.106232 -298.394605) (xy 302.083361 -298.438182)
			(xy 302.053796 -298.477526) (xy 302.018303 -298.511618) (xy 301.9778 -298.539574) (xy 301.933338 -298.560672)
			(xy 301.886067 -298.574364) (xy 301.837212 -298.580296) (xy 301.788037 -298.578315) (xy 301.739818 -298.568471)
			(xy 301.693802 -298.551019) (xy 301.651181 -298.526412) (xy 301.61306 -298.495287) (xy 301.580425 -298.45845)
			(xy 301.554122 -298.416854) (xy 301.534831 -298.371578) (xy 301.523054 -298.323794) (xy 301.519094 -298.27474)
			(xy 301.180597 -298.27474) (xy 301.176428 -298.325051) (xy 301.164024 -298.374029) (xy 301.143729 -298.420297)
			(xy 301.116094 -298.462593) (xy 301.081874 -298.499764) (xy 301.042003 -298.530795) (xy 300.997568 -298.55484)
			(xy 300.949781 -298.571243) (xy 300.899946 -298.579556) (xy 300.874684 -298.580048) (xy 300.859854 -298.579843)
			(xy 300.830337 -298.576919) (xy 300.815756 -298.574206) (xy 300.815502 -298.574206) (xy 300.80431 -298.572656)
			(xy 300.782433 -298.578173) (xy 300.773338 -298.584874) (xy 300.728888 -298.621704) (xy 300.720678 -298.629341)
			(xy 300.711186 -298.649624) (xy 300.7106 -298.66082) (xy 300.7106 -298.838874) (xy 300.711146 -298.850082)
			(xy 300.720636 -298.870385) (xy 300.728888 -298.87799) (xy 300.773338 -298.91482) (xy 300.782418 -298.921559)
			(xy 300.80431 -298.927102) (xy 300.815502 -298.925488) (xy 300.81601 -298.925488) (xy 300.830527 -298.922777)
			(xy 300.859917 -298.919854) (xy 300.874684 -298.919646) (xy 300.899939 -298.920229) (xy 300.94976 -298.928541)
			(xy 300.997533 -298.944939) (xy 301.041956 -298.968977) (xy 301.081816 -299) (xy 301.116026 -299.03716)
			(xy 301.143653 -299.079444) (xy 301.163943 -299.125699) (xy 301.176343 -299.174663) (xy 301.18051 -299.224954)
			(xy 301.519094 -299.224954) (xy 301.523054 -299.1759) (xy 301.534831 -299.128116) (xy 301.554122 -299.08284)
			(xy 301.580425 -299.041244) (xy 301.61306 -299.004407) (xy 301.651181 -298.973282) (xy 301.693802 -298.948675)
			(xy 301.739818 -298.931223) (xy 301.788037 -298.921379) (xy 301.837212 -298.919398) (xy 301.886067 -298.92533)
			(xy 301.933338 -298.939022) (xy 301.9778 -298.96012) (xy 302.018303 -298.988076) (xy 302.053796 -299.022168)
			(xy 302.083361 -299.061512) (xy 302.106232 -299.105089) (xy 302.121816 -299.15177) (xy 302.129711 -299.200347)
			(xy 302.130206 -299.224954) (xy 302.469054 -299.224954) (xy 302.473014 -299.1759) (xy 302.484791 -299.128116)
			(xy 302.504082 -299.08284) (xy 302.530385 -299.041244) (xy 302.56302 -299.004407) (xy 302.601141 -298.973282)
			(xy 302.643762 -298.948675) (xy 302.689778 -298.931223) (xy 302.737997 -298.921379) (xy 302.787172 -298.919398)
			(xy 302.836027 -298.92533) (xy 302.883298 -298.939022) (xy 302.92776 -298.96012) (xy 302.968263 -298.988076)
			(xy 303.003756 -299.022168) (xy 303.033321 -299.061512) (xy 303.056192 -299.105089) (xy 303.071776 -299.15177)
			(xy 303.079671 -299.200347) (xy 303.080166 -299.224954) (xy 303.419014 -299.224954) (xy 303.422974 -299.1759)
			(xy 303.434751 -299.128116) (xy 303.454042 -299.08284) (xy 303.480345 -299.041244) (xy 303.51298 -299.004407)
			(xy 303.551101 -298.973282) (xy 303.593722 -298.948675) (xy 303.639738 -298.931223) (xy 303.687957 -298.921379)
			(xy 303.737132 -298.919398) (xy 303.785987 -298.92533) (xy 303.833258 -298.939022) (xy 303.87772 -298.96012)
			(xy 303.918223 -298.988076) (xy 303.953716 -299.022168) (xy 303.983281 -299.061512) (xy 304.006152 -299.105089)
			(xy 304.021736 -299.15177) (xy 304.029631 -299.200347) (xy 304.030126 -299.224954) (xy 304.029631 -299.249561)
			(xy 304.021736 -299.298138) (xy 304.006152 -299.344819) (xy 303.983281 -299.388396) (xy 303.953716 -299.42774)
			(xy 303.918223 -299.461832) (xy 303.87772 -299.489788) (xy 303.833258 -299.510886) (xy 303.785987 -299.524578)
			(xy 303.737132 -299.53051) (xy 303.687957 -299.528529) (xy 303.639738 -299.518685) (xy 303.593722 -299.501233)
			(xy 303.551101 -299.476626) (xy 303.51298 -299.445501) (xy 303.480345 -299.408664) (xy 303.454042 -299.367068)
			(xy 303.434751 -299.321792) (xy 303.422974 -299.274008) (xy 303.419014 -299.224954) (xy 303.080166 -299.224954)
			(xy 303.079671 -299.249561) (xy 303.071776 -299.298138) (xy 303.056192 -299.344819) (xy 303.033321 -299.388396)
			(xy 303.003756 -299.42774) (xy 302.968263 -299.461832) (xy 302.92776 -299.489788) (xy 302.883298 -299.510886)
			(xy 302.836027 -299.524578) (xy 302.787172 -299.53051) (xy 302.737997 -299.528529) (xy 302.689778 -299.518685)
			(xy 302.643762 -299.501233) (xy 302.601141 -299.476626) (xy 302.56302 -299.445501) (xy 302.530385 -299.408664)
			(xy 302.504082 -299.367068) (xy 302.484791 -299.321792) (xy 302.473014 -299.274008) (xy 302.469054 -299.224954)
			(xy 302.130206 -299.224954) (xy 302.129711 -299.249561) (xy 302.121816 -299.298138) (xy 302.106232 -299.344819)
			(xy 302.083361 -299.388396) (xy 302.053796 -299.42774) (xy 302.018303 -299.461832) (xy 301.9778 -299.489788)
			(xy 301.933338 -299.510886) (xy 301.886067 -299.524578) (xy 301.837212 -299.53051) (xy 301.788037 -299.528529)
			(xy 301.739818 -299.518685) (xy 301.693802 -299.501233) (xy 301.651181 -299.476626) (xy 301.61306 -299.445501)
			(xy 301.580425 -299.408664) (xy 301.554122 -299.367068) (xy 301.534831 -299.321792) (xy 301.523054 -299.274008)
			(xy 301.519094 -299.224954) (xy 301.18051 -299.224954) (xy 301.180514 -299.225) (xy 301.176343 -299.275337)
			(xy 301.163943 -299.324301) (xy 301.143653 -299.370556) (xy 301.116026 -299.41284) (xy 301.081816 -299.45)
			(xy 301.041956 -299.481023) (xy 300.997533 -299.505061) (xy 300.94976 -299.521459) (xy 300.899939 -299.529771)
			(xy 300.874684 -299.530262) (xy 300.859854 -299.530057) (xy 300.830337 -299.527133) (xy 300.815756 -299.52442)
			(xy 300.815502 -299.52442) (xy 300.80431 -299.522867) (xy 300.782432 -299.528386) (xy 300.773338 -299.535088)
			(xy 300.728888 -299.571918) (xy 300.720672 -299.579549) (xy 300.711183 -299.599836) (xy 300.7106 -299.611034)
			(xy 300.7106 -300.281848) (xy 300.711049 -300.291859) (xy 300.718724 -300.310352) (xy 300.732889 -300.324503)
			(xy 300.751389 -300.332161) (xy 300.7614 -300.332648) (xy 301.437802 -300.332648) (xy 301.448916 -300.332114)
			(xy 301.469076 -300.322753) (xy 301.476664 -300.314614) (xy 301.520606 -300.262036) (xy 301.526448 -300.240446)
			(xy 301.524416 -300.22927) (xy 301.522172 -300.215921) (xy 301.519754 -300.188958) (xy 301.51959 -300.175422)
			(xy 301.51959 -300.174914) (xy 301.520112 -300.149659) (xy 301.528425 -300.099837) (xy 301.544826 -300.052063)
			(xy 301.568867 -300.00764) (xy 301.599891 -299.96778) (xy 301.637053 -299.93357) (xy 301.679339 -299.905944)
			(xy 301.725595 -299.885654) (xy 301.77456 -299.873254) (xy 301.824898 -299.869083) (xy 301.875236 -299.873254)
			(xy 301.924201 -299.885654) (xy 301.970457 -299.905944) (xy 302.012743 -299.93357) (xy 302.049905 -299.96778)
			(xy 302.080929 -300.00764) (xy 302.10497 -300.052063) (xy 302.121371 -300.099837) (xy 302.129684 -300.149659)
			(xy 302.130206 -300.174914) (xy 302.469054 -300.174914) (xy 302.473014 -300.12586) (xy 302.484791 -300.078076)
			(xy 302.504082 -300.0328) (xy 302.530385 -299.991204) (xy 302.56302 -299.954367) (xy 302.601141 -299.923242)
			(xy 302.643762 -299.898635) (xy 302.689778 -299.881183) (xy 302.737997 -299.871339) (xy 302.787172 -299.869358)
			(xy 302.836027 -299.87529) (xy 302.883298 -299.888982) (xy 302.92776 -299.91008) (xy 302.968263 -299.938036)
			(xy 303.003756 -299.972128) (xy 303.033321 -300.011472) (xy 303.056192 -300.055049) (xy 303.071776 -300.10173)
			(xy 303.079671 -300.150307) (xy 303.080166 -300.174914) (xy 303.079671 -300.199521) (xy 303.071776 -300.248098)
			(xy 303.056192 -300.294779) (xy 303.033321 -300.338356) (xy 303.003756 -300.3777) (xy 302.968263 -300.411792)
			(xy 302.92776 -300.439748) (xy 302.883298 -300.460846) (xy 302.836027 -300.474538) (xy 302.787172 -300.48047)
			(xy 302.737997 -300.478489) (xy 302.689778 -300.468645) (xy 302.643762 -300.451193) (xy 302.601141 -300.426586)
			(xy 302.56302 -300.395461) (xy 302.530385 -300.358624) (xy 302.504082 -300.317028) (xy 302.484791 -300.271752)
			(xy 302.473014 -300.223968) (xy 302.469054 -300.174914) (xy 302.130206 -300.174914) (xy 302.129675 -300.200328)
			(xy 302.121232 -300.250451) (xy 302.1046 -300.298481) (xy 302.080238 -300.343091) (xy 302.064928 -300.363382)
			(xy 302.05934 -300.370494) (xy 302.053752 -300.387258) (xy 302.05426 -300.403006) (xy 302.055006 -300.412603)
			(xy 302.062711 -300.430228) (xy 302.069246 -300.437296) (xy 302.382428 -300.750478) (xy 302.403593 -300.77267)
			(xy 302.43799 -300.823431) (xy 302.450754 -300.851316) (xy 302.456036 -300.862049) (xy 302.474325 -300.877421)
			(xy 302.485806 -300.88078) (xy 302.543464 -300.894242) (xy 302.554656 -300.896175) (xy 302.576807 -300.891319)
			(xy 302.586136 -300.884844) (xy 302.58639 -300.884844) (xy 302.606703 -300.869565) (xy 302.65131 -300.845207)
			(xy 302.699332 -300.828565) (xy 302.749446 -300.820099) (xy 302.774858 -300.819566) (xy 302.800116 -300.820107)
			(xy 302.849943 -300.828416) (xy 302.897724 -300.844813) (xy 302.942153 -300.868851) (xy 302.982019 -300.899876)
			(xy 303.016235 -300.937039) (xy 303.043867 -300.979327) (xy 303.06416 -301.025587) (xy 303.076562 -301.074557)
			(xy 303.080732 -301.124874) (xy 303.419014 -301.124874) (xy 303.422974 -301.07582) (xy 303.434751 -301.028036)
			(xy 303.454042 -300.98276) (xy 303.480345 -300.941164) (xy 303.51298 -300.904327) (xy 303.551101 -300.873202)
			(xy 303.593722 -300.848595) (xy 303.639738 -300.831143) (xy 303.687957 -300.821299) (xy 303.737132 -300.819318)
			(xy 303.785987 -300.82525) (xy 303.833258 -300.838942) (xy 303.87772 -300.86004) (xy 303.918223 -300.887996)
			(xy 303.953716 -300.922088) (xy 303.983281 -300.961432) (xy 304.006152 -301.005009) (xy 304.021736 -301.05169)
			(xy 304.029631 -301.100267) (xy 304.030126 -301.124874) (xy 304.029631 -301.149481) (xy 304.021736 -301.198058)
			(xy 304.006152 -301.244739) (xy 303.983281 -301.288316) (xy 303.953716 -301.32766) (xy 303.918223 -301.361752)
			(xy 303.87772 -301.389708) (xy 303.833258 -301.410806) (xy 303.785987 -301.424498) (xy 303.737132 -301.43043)
			(xy 303.687957 -301.428449) (xy 303.639738 -301.418605) (xy 303.593722 -301.401153) (xy 303.551101 -301.376546)
			(xy 303.51298 -301.345421) (xy 303.480345 -301.308584) (xy 303.454042 -301.266988) (xy 303.434751 -301.221712)
			(xy 303.422974 -301.173928) (xy 303.419014 -301.124874) (xy 303.080732 -301.124874) (xy 303.080734 -301.1249)
			(xy 303.076562 -301.175243) (xy 303.06416 -301.224213) (xy 303.043867 -301.270473) (xy 303.016235 -301.312761)
			(xy 302.982019 -301.349924) (xy 302.942153 -301.380949) (xy 302.897724 -301.404987) (xy 302.849943 -301.421384)
			(xy 302.800116 -301.429693) (xy 302.774858 -301.430182) (xy 302.746868 -301.429526) (xy 302.691822 -301.419333)
			(xy 302.63955 -301.399296) (xy 302.615346 -301.385224) (xy 302.607452 -301.380794) (xy 302.589712 -301.377251)
			(xy 302.571846 -301.380091) (xy 302.563784 -301.384208) (xy 302.502824 -301.418498) (xy 302.495153 -301.423191)
			(xy 302.483472 -301.436846) (xy 302.477261 -301.453708) (xy 302.476916 -301.462694) (xy 302.476916 -301.737014)
			(xy 302.477286 -301.745991) (xy 302.483528 -301.762827) (xy 302.495177 -301.776492) (xy 302.502824 -301.78121)
			(xy 302.563784 -301.8155) (xy 302.571841 -301.819635) (xy 302.589712 -301.822487) (xy 302.607456 -301.81893)
			(xy 302.615346 -301.814484) (xy 302.639538 -301.800387) (xy 302.691813 -301.780339) (xy 302.746864 -301.77015)
			(xy 302.774858 -301.769526) (xy 302.800121 -301.769947) (xy 302.849958 -301.778258) (xy 302.897748 -301.794658)
			(xy 302.942186 -301.818701) (xy 302.98206 -301.849731) (xy 303.016282 -301.886902) (xy 303.043919 -301.929199)
			(xy 303.064217 -301.975468) (xy 303.076621 -302.024447) (xy 303.080794 -302.0748) (xy 303.080791 -302.074834)
			(xy 303.419014 -302.074834) (xy 303.422974 -302.02578) (xy 303.434751 -301.977996) (xy 303.454042 -301.93272)
			(xy 303.480345 -301.891124) (xy 303.51298 -301.854287) (xy 303.551101 -301.823162) (xy 303.593722 -301.798555)
			(xy 303.639738 -301.781103) (xy 303.687957 -301.771259) (xy 303.737132 -301.769278) (xy 303.785987 -301.77521)
			(xy 303.833258 -301.788902) (xy 303.87772 -301.81) (xy 303.918223 -301.837956) (xy 303.953716 -301.872048)
			(xy 303.983281 -301.911392) (xy 304.006152 -301.954969) (xy 304.021736 -302.00165) (xy 304.029631 -302.050227)
			(xy 304.030126 -302.074834) (xy 304.029631 -302.099441) (xy 304.021736 -302.148018) (xy 304.006152 -302.194699)
			(xy 303.983281 -302.238276) (xy 303.953716 -302.27762) (xy 303.918223 -302.311712) (xy 303.87772 -302.339668)
			(xy 303.833258 -302.360766) (xy 303.785987 -302.374458) (xy 303.737132 -302.38039) (xy 303.687957 -302.378409)
			(xy 303.639738 -302.368565) (xy 303.593722 -302.351113) (xy 303.551101 -302.326506) (xy 303.51298 -302.295381)
			(xy 303.480345 -302.258544) (xy 303.454042 -302.216948) (xy 303.434751 -302.171672) (xy 303.422974 -302.123888)
			(xy 303.419014 -302.074834) (xy 303.080791 -302.074834) (xy 303.076621 -302.125153) (xy 303.064217 -302.174132)
			(xy 303.043919 -302.220401) (xy 303.016282 -302.262698) (xy 302.98206 -302.299869) (xy 302.942186 -302.330899)
			(xy 302.897748 -302.354942) (xy 302.849958 -302.371342) (xy 302.800121 -302.379653) (xy 302.774858 -302.380142)
			(xy 302.746867 -302.379492) (xy 302.691821 -302.369298) (xy 302.639549 -302.349258) (xy 302.615346 -302.335184)
			(xy 302.607451 -302.330756) (xy 302.589712 -302.327215) (xy 302.571847 -302.330053) (xy 302.563784 -302.334168)
			(xy 302.502824 -302.368458) (xy 302.495171 -302.373176) (xy 302.483487 -302.38682) (xy 302.477268 -302.403672)
			(xy 302.476916 -302.412654) (xy 302.476916 -302.686974) (xy 302.477313 -302.695948) (xy 302.483543 -302.712784)
			(xy 302.495181 -302.726451) (xy 302.502824 -302.73117) (xy 302.563784 -302.76546) (xy 302.57184 -302.769599)
			(xy 302.589712 -302.772453) (xy 302.607457 -302.768893) (xy 302.615346 -302.764444) (xy 302.639541 -302.750352)
			(xy 302.691814 -302.730301) (xy 302.746865 -302.72011) (xy 302.774858 -302.719486) (xy 302.800117 -302.719987)
			(xy 302.849948 -302.728296) (xy 302.897732 -302.744695) (xy 302.942164 -302.768735) (xy 302.982033 -302.799761)
			(xy 303.016251 -302.836927) (xy 303.043884 -302.879218) (xy 303.064179 -302.925481) (xy 303.076582 -302.974454)
			(xy 303.080754 -303.024794) (xy 303.419014 -303.024794) (xy 303.422974 -302.97574) (xy 303.434751 -302.927956)
			(xy 303.454042 -302.88268) (xy 303.480345 -302.841084) (xy 303.51298 -302.804247) (xy 303.551101 -302.773122)
			(xy 303.593722 -302.748515) (xy 303.639738 -302.731063) (xy 303.687957 -302.721219) (xy 303.737132 -302.719238)
			(xy 303.785987 -302.72517) (xy 303.833258 -302.738862) (xy 303.87772 -302.75996) (xy 303.918223 -302.787916)
			(xy 303.953716 -302.822008) (xy 303.983281 -302.861352) (xy 304.006152 -302.904929) (xy 304.021736 -302.95161)
			(xy 304.029631 -303.000187) (xy 304.030126 -303.024794) (xy 304.029631 -303.049401) (xy 304.021736 -303.097978)
			(xy 304.006152 -303.144659) (xy 303.983281 -303.188236) (xy 303.953716 -303.22758) (xy 303.918223 -303.261672)
			(xy 303.87772 -303.289628) (xy 303.833258 -303.310726) (xy 303.785987 -303.324418) (xy 303.737132 -303.33035)
			(xy 303.687957 -303.328369) (xy 303.639738 -303.318525) (xy 303.593722 -303.301073) (xy 303.551101 -303.276466)
			(xy 303.51298 -303.245341) (xy 303.480345 -303.208504) (xy 303.454042 -303.166908) (xy 303.434751 -303.121632)
			(xy 303.422974 -303.073848) (xy 303.419014 -303.024794) (xy 303.080754 -303.024794) (xy 303.080754 -303.0248)
			(xy 303.076582 -303.075146) (xy 303.064179 -303.124119) (xy 303.043884 -303.170382) (xy 303.016251 -303.212673)
			(xy 302.982033 -303.249839) (xy 302.942164 -303.280865) (xy 302.897732 -303.304905) (xy 302.849948 -303.321304)
			(xy 302.800117 -303.329613) (xy 302.774858 -303.330102) (xy 302.746868 -303.329443) (xy 302.691823 -303.319251)
			(xy 302.63955 -303.299215) (xy 302.615346 -303.285144) (xy 302.607452 -303.280713) (xy 302.589712 -303.277168)
			(xy 302.571846 -303.280009) (xy 302.563784 -303.284128) (xy 302.502824 -303.318418) (xy 302.495144 -303.323098)
			(xy 302.483464 -303.336759) (xy 302.477258 -303.353627) (xy 302.476916 -303.362614) (xy 302.476916 -303.645316)
			(xy 302.476622 -303.66319) (xy 302.472548 -303.698706) (xy 302.468788 -303.716182) (xy 302.467518 -303.72939)
			(xy 302.468298 -303.739314) (xy 302.4765 -303.757436) (xy 302.490973 -303.771081) (xy 302.509545 -303.778204)
			(xy 302.52943 -303.777735) (xy 302.547646 -303.769745) (xy 302.554894 -303.762918) (xy 302.572319 -303.745592)
			(xy 302.611642 -303.716129) (xy 302.655173 -303.69334) (xy 302.701789 -303.67781) (xy 302.75029 -303.66994)
			(xy 302.774858 -303.669446) (xy 302.800114 -303.670027) (xy 302.849939 -303.678335) (xy 302.897716 -303.694731)
			(xy 302.942142 -303.718768) (xy 302.982006 -303.74979) (xy 303.016219 -303.786951) (xy 303.043849 -303.829237)
			(xy 303.064141 -303.875494) (xy 303.076542 -303.92446) (xy 303.080714 -303.9748) (xy 303.076542 -304.02514)
			(xy 303.064141 -304.074106) (xy 303.043849 -304.120363) (xy 303.016219 -304.162649) (xy 302.982006 -304.19981)
			(xy 302.942142 -304.230832) (xy 302.897716 -304.254869) (xy 302.849939 -304.271265) (xy 302.800114 -304.279573)
			(xy 302.774858 -304.280062) (xy 302.748914 -304.279555) (xy 302.697771 -304.270793) (xy 302.648845 -304.253513)
			(xy 302.603544 -304.228211) (xy 302.563173 -304.195615) (xy 302.528892 -304.156664) (xy 302.501688 -304.112479)
			(xy 302.482346 -304.064331) (xy 302.47142 -304.013607) (xy 302.469804 -303.987708) (xy 302.469804 -303.987454)
			(xy 302.469042 -303.978655) (xy 302.462346 -303.962328) (xy 302.450498 -303.949249) (xy 302.44288 -303.944782)
			(xy 302.369728 -303.906174) (xy 302.342042 -303.90719) (xy 302.330612 -303.91481) (xy 302.320869 -303.920958)
			(xy 302.300657 -303.932017) (xy 302.290226 -303.936908) (xy 302.141382 -304.005742) (xy 302.12665 -304.024538)
			(xy 302.12411 -304.036476) (xy 302.118292 -304.061941) (xy 302.099158 -304.110543) (xy 302.07204 -304.155184)
			(xy 302.037729 -304.194566) (xy 301.997222 -304.227542) (xy 301.9517 -304.253152) (xy 301.902486 -304.270651)
			(xy 301.851014 -304.27953) (xy 301.824898 -304.280062) (xy 301.821088 -304.280062) (xy 301.812211 -304.280371)
			(xy 301.795473 -304.286266) (xy 301.78175 -304.297519) (xy 301.776892 -304.304954) (xy 301.722028 -304.397156)
			(xy 301.709536 -304.417391) (xy 301.679503 -304.45426) (xy 301.644371 -304.486307) (xy 301.604904 -304.512834)
			(xy 301.561962 -304.533263) (xy 301.516481 -304.547148) (xy 301.469452 -304.554188) (xy 301.445676 -304.554636)
			(xy 301.255938 -304.554636) (xy 301.232035 -304.554159) (xy 301.184764 -304.547012) (xy 301.139072 -304.532945)
			(xy 301.095967 -304.512267) (xy 301.056399 -304.485434) (xy 301.02124 -304.453038) (xy 300.991266 -304.415793)
			(xy 300.978824 -304.395378) (xy 300.916594 -304.289206) (xy 300.893226 -304.275744) (xy 300.880018 -304.275744)
			(xy 300.871147 -304.27603) (xy 300.854454 -304.282034) (xy 300.840826 -304.293391) (xy 300.836076 -304.30089)
			(xy 300.780704 -304.395378) (xy 300.768283 -304.415806) (xy 300.738301 -304.453047) (xy 300.703137 -304.485439)
			(xy 300.663566 -304.512269) (xy 300.620459 -304.532945) (xy 300.574766 -304.547013) (xy 300.527494 -304.554162)
			(xy 300.50359 -304.554636) (xy 300.303946 -304.554636) (xy 300.280167 -304.554221) (xy 300.233132 -304.547191)
			(xy 300.187645 -304.533309) (xy 300.1447 -304.512876) (xy 300.105235 -304.486339) (xy 300.070109 -304.454278)
			(xy 300.040091 -304.417391) (xy 300.027594 -304.397156) (xy 299.97273 -304.304954) (xy 299.967899 -304.297496)
			(xy 299.95417 -304.286235) (xy 299.937416 -304.280348) (xy 299.928534 -304.280062) (xy 299.920914 -304.280062)
			(xy 299.912039 -304.280389) (xy 299.895301 -304.286276) (xy 299.881577 -304.297522) (xy 299.876718 -304.304954)
			(xy 299.821854 -304.397156) (xy 299.809344 -304.417379) (xy 299.779314 -304.454248) (xy 299.744185 -304.486296)
			(xy 299.704721 -304.512824) (xy 299.661782 -304.533255) (xy 299.616304 -304.547143) (xy 299.569277 -304.554186)
			(xy 299.545502 -304.554636) (xy 299.353986 -304.554636) (xy 299.330208 -304.554189) (xy 299.283174 -304.547166)
			(xy 299.237689 -304.533289) (xy 299.194744 -304.512861) (xy 299.155278 -304.486329) (xy 299.120151 -304.454272)
			(xy 299.090132 -304.417389) (xy 299.077634 -304.397156) (xy 299.02277 -304.304954) (xy 299.017915 -304.297514)
			(xy 299.004196 -304.28625) (xy 298.987453 -304.280355) (xy 298.978574 -304.280062) (xy 298.970954 -304.280062)
			(xy 298.962075 -304.280346) (xy 298.945336 -304.286253) (xy 298.931614 -304.297515) (xy 298.926758 -304.304954)
			(xy 298.871894 -304.397156) (xy 298.859357 -304.417361) (xy 298.829331 -304.45423) (xy 298.794206 -304.486279)
			(xy 298.754747 -304.512809) (xy 298.711813 -304.533243) (xy 298.666339 -304.547135) (xy 298.619316 -304.554183)
			(xy 298.595542 -304.554636) (xy 298.404026 -304.554636) (xy 298.380249 -304.554158) (xy 298.333217 -304.54714)
			(xy 298.287732 -304.533269) (xy 298.244787 -304.512846) (xy 298.20532 -304.486319) (xy 298.170193 -304.454266)
			(xy 298.140172 -304.417387) (xy 298.127674 -304.397156) (xy 298.07281 -304.304954) (xy 298.06793 -304.297533)
			(xy 298.054222 -304.286265) (xy 298.037489 -304.280361) (xy 298.028614 -304.280062) (xy 298.020994 -304.280062)
			(xy 298.012118 -304.280375) (xy 297.995379 -304.286268) (xy 297.981657 -304.29752) (xy 297.976798 -304.304954)
			(xy 297.921934 -304.397156) (xy 297.909438 -304.417388) (xy 297.879406 -304.454257) (xy 297.844274 -304.486305)
			(xy 297.804808 -304.512832) (xy 297.761867 -304.533261) (xy 297.716387 -304.547147) (xy 297.669358 -304.554188)
			(xy 297.645582 -304.554636) (xy 297.454066 -304.554636) (xy 297.430288 -304.554205) (xy 297.383253 -304.547178)
			(xy 297.337767 -304.533299) (xy 297.294822 -304.512869) (xy 297.255356 -304.486334) (xy 297.22023 -304.454275)
			(xy 297.190211 -304.41739) (xy 297.177714 -304.397156) (xy 297.12285 -304.304954) (xy 297.118007 -304.297505)
			(xy 297.104283 -304.286242) (xy 297.087535 -304.280351) (xy 297.078654 -304.280062) (xy 297.071034 -304.280062)
			(xy 297.062154 -304.280333) (xy 297.045414 -304.286245) (xy 297.031694 -304.297513) (xy 297.026838 -304.304954)
			(xy 296.971974 -304.397156) (xy 296.95945 -304.41737) (xy 296.929423 -304.454239) (xy 296.894296 -304.486288)
			(xy 296.854834 -304.512817) (xy 296.811898 -304.533249) (xy 296.766422 -304.547139) (xy 296.719397 -304.554185)
			(xy 296.695622 -304.554636) (xy 296.504106 -304.554636) (xy 296.480329 -304.554173) (xy 296.433296 -304.547153)
			(xy 296.38781 -304.533279) (xy 296.344865 -304.512854) (xy 296.305399 -304.486324) (xy 296.270272 -304.454269)
			(xy 296.240252 -304.417388) (xy 296.227754 -304.397156) (xy 296.17289 -304.304954) (xy 296.168022 -304.297524)
			(xy 296.154309 -304.286258) (xy 296.137571 -304.280358) (xy 296.128694 -304.280062) (xy 296.121074 -304.280062)
			(xy 296.112197 -304.280361) (xy 296.095457 -304.286261) (xy 296.081736 -304.297518) (xy 296.076878 -304.304954)
			(xy 296.022014 -304.397156) (xy 296.009531 -304.417397) (xy 295.979497 -304.454266) (xy 295.944363 -304.486313)
			(xy 295.904895 -304.512839) (xy 295.861951 -304.533267) (xy 295.816469 -304.547151) (xy 295.769439 -304.554189)
			(xy 295.745662 -304.554636) (xy 295.554146 -304.554636) (xy 295.530367 -304.554221) (xy 295.483332 -304.547191)
			(xy 295.437845 -304.533309) (xy 295.3949 -304.512876) (xy 295.355435 -304.486339) (xy 295.320309 -304.454278)
			(xy 295.290291 -304.417391) (xy 295.277794 -304.397156) (xy 295.22293 -304.304954) (xy 295.218099 -304.297496)
			(xy 295.20437 -304.286235) (xy 295.187616 -304.280348) (xy 295.178734 -304.280062) (xy 295.171114 -304.280062)
			(xy 295.162239 -304.280389) (xy 295.145501 -304.286276) (xy 295.131777 -304.297522) (xy 295.126918 -304.304954)
			(xy 295.072054 -304.397156) (xy 295.059544 -304.417379) (xy 295.029514 -304.454248) (xy 294.994385 -304.486296)
			(xy 294.954921 -304.512824) (xy 294.911982 -304.533255) (xy 294.866504 -304.547143) (xy 294.819477 -304.554186)
			(xy 294.795702 -304.554636) (xy 294.603932 -304.554636) (xy 294.580153 -304.554232) (xy 294.533117 -304.5472)
			(xy 294.48763 -304.533316) (xy 294.444685 -304.512881) (xy 294.40522 -304.486343) (xy 294.370095 -304.45428)
			(xy 294.340077 -304.417391) (xy 294.32758 -304.397156) (xy 294.272716 -304.304954) (xy 294.267832 -304.297535)
			(xy 294.254126 -304.286268) (xy 294.237395 -304.280362) (xy 294.22852 -304.280062) (xy 294.2209 -304.280062)
			(xy 294.212024 -304.280379) (xy 294.195286 -304.28627) (xy 294.181563 -304.29752) (xy 294.176704 -304.304954)
			(xy 294.12184 -304.397156) (xy 294.10934 -304.417385) (xy 294.079308 -304.454255) (xy 294.044177 -304.486302)
			(xy 294.004712 -304.51283) (xy 293.961772 -304.533259) (xy 293.916292 -304.547146) (xy 293.869264 -304.554187)
			(xy 293.845488 -304.554636) (xy 293.653972 -304.554636) (xy 293.630194 -304.5542) (xy 293.583159 -304.547175)
			(xy 293.537673 -304.533296) (xy 293.494729 -304.512866) (xy 293.455263 -304.486333) (xy 293.420137 -304.454274)
			(xy 293.390117 -304.41739) (xy 293.37762 -304.397156) (xy 293.322756 -304.304954) (xy 293.317909 -304.297508)
			(xy 293.304187 -304.286245) (xy 293.28744 -304.280352) (xy 293.27856 -304.280062) (xy 293.27094 -304.280062)
			(xy 293.262061 -304.280337) (xy 293.24532 -304.286247) (xy 293.2316 -304.297514) (xy 293.226744 -304.304954)
			(xy 293.17188 -304.397156) (xy 293.159352 -304.417367) (xy 293.129325 -304.454237) (xy 293.094199 -304.486285)
			(xy 293.054738 -304.512815) (xy 293.011802 -304.533247) (xy 292.966327 -304.547138) (xy 292.919302 -304.554184)
			(xy 292.895528 -304.554636) (xy 292.704012 -304.554636) (xy 292.680235 -304.554169) (xy 292.633202 -304.547149)
			(xy 292.587717 -304.533276) (xy 292.544772 -304.512852) (xy 292.505305 -304.486323) (xy 292.470179 -304.454268)
			(xy 292.440158 -304.417388) (xy 292.42766 -304.397156) (xy 292.372796 -304.304954) (xy 292.367924 -304.297526)
			(xy 292.354213 -304.28626) (xy 292.337477 -304.280359) (xy 292.3286 -304.280062) (xy 292.32098 -304.280062)
			(xy 292.312103 -304.280365) (xy 292.295364 -304.286263) (xy 292.281642 -304.297518) (xy 292.276784 -304.304954)
			(xy 292.22192 -304.397156) (xy 292.209433 -304.417394) (xy 292.1794 -304.454264) (xy 292.144266 -304.486311)
			(xy 292.104799 -304.512837) (xy 292.061856 -304.533265) (xy 292.016374 -304.54715) (xy 291.969345 -304.554189)
			(xy 291.945568 -304.554636) (xy 290.804092 -304.554636) (xy 290.780315 -304.554184) (xy 290.733281 -304.547162)
			(xy 290.687795 -304.533286) (xy 290.64485 -304.512859) (xy 290.605384 -304.486328) (xy 290.570258 -304.454271)
			(xy 290.540238 -304.417389) (xy 290.52774 -304.397156) (xy 290.472876 -304.304954) (xy 290.468017 -304.297517)
			(xy 290.4543 -304.286252) (xy 290.437558 -304.280356) (xy 290.42868 -304.280062) (xy 290.42106 -304.280062)
			(xy 290.412182 -304.280351) (xy 290.395442 -304.286255) (xy 290.381721 -304.297516) (xy 290.376864 -304.304954)
			(xy 290.322 -304.397156) (xy 290.309458 -304.417358) (xy 290.279434 -304.454228) (xy 290.24431 -304.486277)
			(xy 290.204851 -304.512807) (xy 290.161918 -304.533241) (xy 290.116444 -304.547134) (xy 290.069422 -304.554183)
			(xy 290.045648 -304.554636) (xy 289.854132 -304.554636) (xy 289.830353 -304.554232) (xy 289.783317 -304.5472)
			(xy 289.73783 -304.533316) (xy 289.694885 -304.512881) (xy 289.65542 -304.486343) (xy 289.620295 -304.45428)
			(xy 289.590277 -304.417391) (xy 289.57778 -304.397156) (xy 289.522916 -304.304954) (xy 289.518032 -304.297535)
			(xy 289.504326 -304.286268) (xy 289.487595 -304.280362) (xy 289.47872 -304.280062) (xy 289.4711 -304.280062)
			(xy 289.462224 -304.280379) (xy 289.445486 -304.28627) (xy 289.431763 -304.29752) (xy 289.426904 -304.304954)
			(xy 289.37204 -304.397156) (xy 289.35954 -304.417385) (xy 289.329508 -304.454255) (xy 289.294377 -304.486302)
			(xy 289.254912 -304.51283) (xy 289.211972 -304.533259) (xy 289.166492 -304.547146) (xy 289.119464 -304.554187)
			(xy 289.095688 -304.554636) (xy 288.903918 -304.554636) (xy 288.880141 -304.554164) (xy 288.833108 -304.547145)
			(xy 288.787623 -304.533273) (xy 288.744678 -304.512849) (xy 288.705212 -304.486321) (xy 288.670085 -304.454267)
			(xy 288.640064 -304.417388) (xy 288.627566 -304.397156) (xy 288.572702 -304.304954) (xy 288.567827 -304.297529)
			(xy 288.554117 -304.286262) (xy 288.537382 -304.28036) (xy 288.528506 -304.280062) (xy 288.520886 -304.280062)
			(xy 288.512009 -304.280369) (xy 288.49527 -304.286265) (xy 288.481548 -304.297519) (xy 288.47669 -304.304954)
			(xy 288.421826 -304.397156) (xy 288.409335 -304.417392) (xy 288.379302 -304.454261) (xy 288.34417 -304.486308)
			(xy 288.304703 -304.512835) (xy 288.261761 -304.533263) (xy 288.21628 -304.547149) (xy 288.16925 -304.554188)
			(xy 288.145474 -304.554636) (xy 287.953958 -304.554636) (xy 287.93018 -304.554211) (xy 287.883145 -304.547184)
			(xy 287.837658 -304.533303) (xy 287.794713 -304.512872) (xy 287.755248 -304.486336) (xy 287.720122 -304.454276)
			(xy 287.690103 -304.41739) (xy 287.677606 -304.397156) (xy 287.622742 -304.304954) (xy 287.617904 -304.297502)
			(xy 287.604178 -304.286239) (xy 287.587427 -304.28035) (xy 287.578546 -304.280062) (xy 287.570926 -304.280062)
			(xy 287.562051 -304.280397) (xy 287.545314 -304.28628) (xy 287.53159 -304.297523) (xy 287.52673 -304.304954)
			(xy 287.471866 -304.397156) (xy 287.459348 -304.417374) (xy 287.429319 -304.454243) (xy 287.394191 -304.486291)
			(xy 287.354729 -304.51282) (xy 287.311792 -304.533251) (xy 287.266315 -304.547141) (xy 287.219289 -304.554185)
			(xy 287.195514 -304.554636) (xy 287.003998 -304.554636) (xy 286.980221 -304.55418) (xy 286.933187 -304.547158)
			(xy 286.887702 -304.533283) (xy 286.844757 -304.512857) (xy 286.80529 -304.486326) (xy 286.770164 -304.45427)
			(xy 286.740144 -304.417388) (xy 286.727646 -304.397156) (xy 286.672782 -304.304954) (xy 286.667919 -304.29752)
			(xy 286.654204 -304.286255) (xy 286.637464 -304.280357) (xy 286.628586 -304.280062) (xy 286.620966 -304.280062)
			(xy 286.612088 -304.280355) (xy 286.595349 -304.286258) (xy 286.581627 -304.297517) (xy 286.57677 -304.304954)
			(xy 286.521906 -304.397156) (xy 286.50936 -304.417356) (xy 286.479336 -304.454225) (xy 286.444213 -304.486274)
			(xy 286.404755 -304.512805) (xy 286.361822 -304.533239) (xy 286.31635 -304.547133) (xy 286.269327 -304.554183)
			(xy 286.245554 -304.554636) (xy 286.054038 -304.554636) (xy 286.030259 -304.554227) (xy 285.983223 -304.547196)
			(xy 285.937737 -304.533313) (xy 285.894792 -304.512879) (xy 285.855326 -304.486341) (xy 285.820201 -304.454279)
			(xy 285.790183 -304.417391) (xy 285.777686 -304.397156) (xy 285.722822 -304.304954) (xy 285.717934 -304.297538)
			(xy 285.70423 -304.28627) (xy 285.6875 -304.280363) (xy 285.678626 -304.280062) (xy 285.671006 -304.280062)
			(xy 285.66213 -304.280383) (xy 285.645392 -304.286273) (xy 285.631669 -304.297521) (xy 285.62681 -304.304954)
			(xy 285.571946 -304.397156) (xy 285.559441 -304.417383) (xy 285.529411 -304.454252) (xy 285.49428 -304.4863)
			(xy 285.454816 -304.512827) (xy 285.411876 -304.533257) (xy 285.366397 -304.547145) (xy 285.31937 -304.554187)
			(xy 285.295594 -304.554636) (xy 285.104078 -304.554636) (xy 285.0803 -304.554195) (xy 285.033266 -304.547171)
			(xy 284.98778 -304.533293) (xy 284.944835 -304.512864) (xy 284.905369 -304.486331) (xy 284.870243 -304.454273)
			(xy 284.840224 -304.417389) (xy 284.827726 -304.397156) (xy 284.772862 -304.304954) (xy 284.768012 -304.297511)
			(xy 284.754291 -304.286247) (xy 284.737546 -304.280353) (xy 284.728666 -304.280062) (xy 284.721046 -304.280062)
			(xy 284.712167 -304.280341) (xy 284.695427 -304.28625) (xy 284.681706 -304.297514) (xy 284.67685 -304.304954)
			(xy 284.621986 -304.397156) (xy 284.609454 -304.417365) (xy 284.579428 -304.454234) (xy 284.544302 -304.486283)
			(xy 284.504842 -304.512812) (xy 284.461907 -304.533245) (xy 284.416432 -304.547137) (xy 284.369408 -304.554184)
			(xy 284.345634 -304.554636) (xy 284.154118 -304.554636) (xy 284.130341 -304.554164) (xy 284.083308 -304.547145)
			(xy 284.037823 -304.533273) (xy 283.994878 -304.512849) (xy 283.955412 -304.486321) (xy 283.920285 -304.454267)
			(xy 283.890264 -304.417388) (xy 283.877766 -304.397156) (xy 283.822902 -304.304954) (xy 283.818027 -304.297529)
			(xy 283.804317 -304.286262) (xy 283.787582 -304.28036) (xy 283.778706 -304.280062) (xy 283.771086 -304.280062)
			(xy 283.762209 -304.280369) (xy 283.74547 -304.286265) (xy 283.731748 -304.297519) (xy 283.72689 -304.304954)
			(xy 283.672026 -304.397156) (xy 283.659535 -304.417392) (xy 283.629502 -304.454261) (xy 283.59437 -304.486308)
			(xy 283.554903 -304.512835) (xy 283.511961 -304.533263) (xy 283.46648 -304.547149) (xy 283.41945 -304.554188)
			(xy 283.395674 -304.554636) (xy 283.204158 -304.554636) (xy 283.18038 -304.554211) (xy 283.133345 -304.547184)
			(xy 283.087858 -304.533303) (xy 283.044913 -304.512872) (xy 283.005448 -304.486336) (xy 282.970322 -304.454276)
			(xy 282.940303 -304.41739) (xy 282.927806 -304.397156) (xy 282.872942 -304.304954) (xy 282.868104 -304.297502)
			(xy 282.854378 -304.286239) (xy 282.837627 -304.28035) (xy 282.828746 -304.280062) (xy 282.821126 -304.280062)
			(xy 282.812251 -304.280397) (xy 282.795514 -304.28628) (xy 282.78179 -304.297523) (xy 282.77693 -304.304954)
			(xy 282.722066 -304.397156) (xy 282.709548 -304.417374) (xy 282.679519 -304.454243) (xy 282.644391 -304.486291)
			(xy 282.604929 -304.51282) (xy 282.561992 -304.533251) (xy 282.516515 -304.547141) (xy 282.469489 -304.554185)
			(xy 282.445714 -304.554636) (xy 282.253944 -304.554636) (xy 282.230165 -304.554222) (xy 282.18313 -304.547193)
			(xy 282.137643 -304.53331) (xy 282.094698 -304.512877) (xy 282.055233 -304.48634) (xy 282.020107 -304.454278)
			(xy 281.990089 -304.417391) (xy 281.977592 -304.397156) (xy 281.922728 -304.304954) (xy 281.917837 -304.297541)
			(xy 281.904134 -304.286272) (xy 281.887406 -304.280364) (xy 281.878532 -304.280062) (xy 281.874722 -304.280062)
			(xy 281.850727 -304.279641) (xy 281.803328 -304.272136) (xy 281.757687 -304.257308) (xy 281.714928 -304.235522)
			(xy 281.676104 -304.207313) (xy 281.642171 -304.173378) (xy 281.613966 -304.134552) (xy 281.592183 -304.091791)
			(xy 281.577358 -304.046149) (xy 281.569857 -303.998749) (xy 281.569414 -303.974754) (xy 281.569414 -303.973992)
			(xy 281.569534 -303.965142) (xy 281.57068 -303.947478) (xy 281.5717 -303.938686) (xy 281.5717 -303.938432)
			(xy 281.572404 -303.92909) (xy 281.567764 -303.910953) (xy 281.556917 -303.895695) (xy 281.549348 -303.890172)
			(xy 281.478736 -303.843436) (xy 281.457079 -303.828416) (xy 281.418558 -303.792451) (xy 281.386425 -303.750678)
			(xy 281.361545 -303.70422) (xy 281.344585 -303.654322) (xy 281.336 -303.602325) (xy 281.33548 -303.575974)
			(xy 281.33548 -303.423574) (xy 281.336035 -303.397231) (xy 281.344668 -303.345255) (xy 281.361649 -303.295379)
			(xy 281.386525 -303.248933) (xy 281.418632 -303.207159) (xy 281.457114 -303.171171) (xy 281.478736 -303.156112)
			(xy 281.549348 -303.109376) (xy 281.556873 -303.10381) (xy 281.567691 -303.08856) (xy 281.572348 -303.070452)
			(xy 281.5717 -303.061116) (xy 281.5717 -303.060608) (xy 281.569414 -303.027588) (xy 281.56889 -303.018262)
			(xy 281.562011 -303.000911) (xy 281.549387 -302.987164) (xy 281.54122 -302.98263) (xy 281.535124 -302.979582)
			(xy 281.441906 -302.931322) (xy 281.435802 -302.927936) (xy 281.425623 -302.918393) (xy 281.42184 -302.912526)
			(xy 281.35326 -302.79975) (xy 281.34564 -302.790098) (xy 281.196542 -302.641) (xy 281.189078 -302.634285)
			(xy 281.170505 -302.626709) (xy 281.160474 -302.626268) (xy 280.252932 -302.626268) (xy 280.242769 -302.626796)
			(xy 280.22404 -302.634696) (xy 280.209835 -302.649236) (xy 280.205688 -302.658526) (xy 280.171144 -302.74641)
			(xy 280.167804 -302.755994) (xy 280.168221 -302.776268) (xy 280.176489 -302.794784) (xy 280.18359 -302.802036)
			(xy 280.201473 -302.819487) (xy 280.231877 -302.859134) (xy 280.255421 -302.903203) (xy 280.271474 -302.950516)
			(xy 280.279611 -302.999812) (xy 280.28011 -303.024794) (xy 280.279588 -303.050049) (xy 280.271275 -303.099871)
			(xy 280.254874 -303.147645) (xy 280.230833 -303.192068) (xy 280.199809 -303.231928) (xy 280.162647 -303.266138)
			(xy 280.120361 -303.293764) (xy 280.074105 -303.314054) (xy 280.02514 -303.326454) (xy 279.974802 -303.330625)
			(xy 279.924464 -303.326454) (xy 279.875499 -303.314054) (xy 279.829243 -303.293764) (xy 279.786957 -303.266138)
			(xy 279.749795 -303.231928) (xy 279.718771 -303.192068) (xy 279.69473 -303.147645) (xy 279.678329 -303.099871)
			(xy 279.670016 -303.050049) (xy 279.669494 -303.024794) (xy 279.669988 -302.999812) (xy 279.678124 -302.950515)
			(xy 279.694178 -302.9032) (xy 279.717722 -302.859131) (xy 279.748128 -302.819484) (xy 279.766014 -302.802036)
			(xy 279.773086 -302.794774) (xy 279.781293 -302.776253) (xy 279.781744 -302.756001) (xy 279.77846 -302.74641)
			(xy 279.743916 -302.658526) (xy 279.739771 -302.649222) (xy 279.72559 -302.634632) (xy 279.706846 -302.626718)
			(xy 279.696672 -302.626268) (xy 279.302972 -302.626268) (xy 279.292805 -302.626751) (xy 279.274074 -302.634673)
			(xy 279.259871 -302.649229) (xy 279.255728 -302.658526) (xy 279.221184 -302.74641) (xy 279.217861 -302.755997)
			(xy 279.218278 -302.776266) (xy 279.226536 -302.794781) (xy 279.23363 -302.802036) (xy 279.25152 -302.81948)
			(xy 279.281922 -302.85913) (xy 279.305463 -302.9032) (xy 279.321515 -302.950515) (xy 279.329651 -302.999812)
			(xy 279.33015 -303.024794) (xy 279.329628 -303.050049) (xy 279.321315 -303.099871) (xy 279.304914 -303.147645)
			(xy 279.280873 -303.192068) (xy 279.249849 -303.231928) (xy 279.212687 -303.266138) (xy 279.170401 -303.293764)
			(xy 279.124145 -303.314054) (xy 279.07518 -303.326454) (xy 279.024842 -303.330625) (xy 278.974504 -303.326454)
			(xy 278.925539 -303.314054) (xy 278.879283 -303.293764) (xy 278.836997 -303.266138) (xy 278.799835 -303.231928)
			(xy 278.768811 -303.192068) (xy 278.74477 -303.147645) (xy 278.728369 -303.099871) (xy 278.720056 -303.050049)
			(xy 278.719534 -303.024794) (xy 278.720015 -302.999811) (xy 278.728153 -302.950513) (xy 278.744209 -302.903198)
			(xy 278.767756 -302.859129) (xy 278.798166 -302.819483) (xy 278.816054 -302.802036) (xy 278.82313 -302.794777)
			(xy 278.831332 -302.776255) (xy 278.831783 -302.756002) (xy 278.8285 -302.74641) (xy 278.793956 -302.658526)
			(xy 278.789856 -302.649198) (xy 278.775656 -302.634609) (xy 278.756892 -302.626707) (xy 278.746712 -302.626268)
			(xy 278.692864 -302.626268) (xy 278.668044 -302.625777) (xy 278.619008 -302.618044) (xy 278.57174 -302.602874)
			(xy 278.527362 -302.580627) (xy 278.486925 -302.551831) (xy 278.468836 -302.534828) (xy 278.467312 -302.533304)
			(xy 278.46528 -302.531526) (xy 278.228806 -302.295052) (xy 278.211689 -302.277253) (xy 278.182577 -302.237366)
			(xy 278.159916 -302.193491) (xy 278.14424 -302.146665) (xy 278.135918 -302.09799) (xy 278.13508 -302.07331)
			(xy 278.134826 -302.070262) (xy 278.133181 -302.05776) (xy 278.121154 -302.03563) (xy 278.10119 -302.020272)
			(xy 278.089106 -302.016668) (xy 278.08809 -302.016414) (xy 277.995126 -301.996094) (xy 277.986768 -301.993913)
			(xy 277.972089 -301.984833) (xy 277.966424 -301.978314) (xy 277.880826 -301.87138) (xy 277.874607 -301.864181)
			(xy 277.858162 -301.854645) (xy 277.848822 -301.852838) (xy 277.795736 -301.844456) (xy 277.777194 -301.84852)
			(xy 277.769066 -301.854108) (xy 277.750218 -301.866199) (xy 277.709711 -301.885288) (xy 277.666846 -301.898241)
			(xy 277.622546 -301.904777) (xy 277.600156 -301.905162) (xy 277.599902 -301.905162) (xy 277.575907 -301.90476)
			(xy 277.528507 -301.897252) (xy 277.482865 -301.882421) (xy 277.440106 -301.860632) (xy 277.401282 -301.832421)
			(xy 277.36735 -301.798484) (xy 277.339145 -301.759656) (xy 277.317362 -301.716894) (xy 277.302538 -301.67125)
			(xy 277.295037 -301.623849) (xy 277.294594 -301.599854) (xy 277.294785 -301.585798) (xy 277.29746 -301.557813)
			(xy 277.299928 -301.543974) (xy 277.299928 -301.543466) (xy 277.301385 -301.531235) (xy 277.294098 -301.50775)
			(xy 277.285958 -301.498508) (xy 277.226268 -301.438818) (xy 277.217053 -301.430631) (xy 277.193546 -301.42334)
			(xy 277.18131 -301.424848) (xy 277.180802 -301.424848) (xy 277.166961 -301.427298) (xy 277.138977 -301.429973)
			(xy 277.124922 -301.430182) (xy 277.110739 -301.430003) (xy 277.082499 -301.427332) (xy 277.068534 -301.424848)
			(xy 277.06828 -301.424848) (xy 277.056049 -301.423379) (xy 277.032561 -301.430671) (xy 277.023322 -301.438818)
			(xy 276.963632 -301.498254) (xy 276.955491 -301.507503) (xy 276.948172 -301.530983) (xy 276.949662 -301.543212)
			(xy 276.949662 -301.54372) (xy 276.952125 -301.557624) (xy 276.954796 -301.585735) (xy 276.954996 -301.599854)
			(xy 276.954572 -301.624679) (xy 276.946547 -301.673677) (xy 276.9307 -301.72073) (xy 276.90745 -301.7646)
			(xy 276.877408 -301.804131) (xy 276.841366 -301.83828) (xy 276.800275 -301.866149) (xy 276.755216 -301.887002)
			(xy 276.707377 -301.90029) (xy 276.658018 -301.905664) (xy 276.60844 -301.902982) (xy 276.559949 -301.892314)
			(xy 276.513823 -301.873941) (xy 276.471277 -301.848348) (xy 276.433432 -301.816209) (xy 276.401286 -301.77837)
			(xy 276.375685 -301.735829) (xy 276.357303 -301.689706) (xy 276.346626 -301.641218) (xy 276.343934 -301.59164)
			(xy 276.349299 -301.54228) (xy 276.362578 -301.494439) (xy 276.383423 -301.449376) (xy 276.411283 -301.408279)
			(xy 276.445426 -301.372231) (xy 276.484951 -301.342182) (xy 276.528816 -301.318923) (xy 276.575867 -301.303067)
			(xy 276.624863 -301.295033) (xy 276.649688 -301.294546) (xy 276.663871 -301.294725) (xy 276.692111 -301.297396)
			(xy 276.706076 -301.29988) (xy 276.70633 -301.29988) (xy 276.718561 -301.301348) (xy 276.742048 -301.294055)
			(xy 276.751288 -301.28591) (xy 276.810978 -301.226474) (xy 276.819161 -301.217256) (xy 276.826455 -301.193751)
			(xy 276.824948 -301.181516) (xy 276.824948 -301.181008) (xy 276.822489 -301.167104) (xy 276.819815 -301.138993)
			(xy 276.819614 -301.124874) (xy 276.820136 -301.099619) (xy 276.828449 -301.049797) (xy 276.84485 -301.002023)
			(xy 276.868891 -300.9576) (xy 276.899915 -300.91774) (xy 276.937077 -300.88353) (xy 276.979363 -300.855904)
			(xy 277.025619 -300.835614) (xy 277.074584 -300.823214) (xy 277.124922 -300.819043) (xy 277.17526 -300.823214)
			(xy 277.224225 -300.835614) (xy 277.270481 -300.855904) (xy 277.312767 -300.88353) (xy 277.349929 -300.91774)
			(xy 277.380953 -300.9576) (xy 277.404994 -301.002023) (xy 277.421395 -301.049797) (xy 277.429708 -301.099619)
			(xy 277.43023 -301.124874) (xy 277.430028 -301.13893) (xy 277.427361 -301.166915) (xy 277.424896 -301.180754)
			(xy 277.424896 -301.181262) (xy 277.423414 -301.193492) (xy 277.430717 -301.21698) (xy 277.438866 -301.22622)
			(xy 277.498556 -301.28591) (xy 277.5078 -301.294057) (xy 277.531284 -301.30137) (xy 277.543514 -301.29988)
			(xy 277.544022 -301.29988) (xy 277.557863 -301.297427) (xy 277.585847 -301.294754) (xy 277.599902 -301.294546)
			(xy 277.600156 -301.294546) (xy 277.622543 -301.294934) (xy 277.666832 -301.301511) (xy 277.709689 -301.314472)
			(xy 277.7502 -301.33354) (xy 277.769066 -301.3456) (xy 277.777194 -301.351188) (xy 277.795736 -301.355252)
			(xy 277.848822 -301.34687) (xy 277.858123 -301.344953) (xy 277.874542 -301.335447) (xy 277.880826 -301.328328)
			(xy 277.966424 -301.221394) (xy 277.972097 -301.214885) (xy 277.986773 -301.205804) (xy 277.995126 -301.203614)
			(xy 278.087836 -301.183294) (xy 278.08936 -301.18304) (xy 278.100326 -301.179852) (xy 278.118861 -301.166537)
			(xy 278.131151 -301.147307) (xy 278.135449 -301.124894) (xy 278.131146 -301.102481) (xy 278.118852 -301.083254)
			(xy 278.100314 -301.069943) (xy 278.08936 -301.066708) (xy 278.087836 -301.066454) (xy 277.995126 -301.046134)
			(xy 277.986762 -301.04397) (xy 277.972086 -301.034879) (xy 277.966424 -301.028354) (xy 277.847044 -300.879256)
			(xy 277.841939 -300.872325) (xy 277.836211 -300.856106) (xy 277.835868 -300.847506) (xy 277.835868 -300.452536)
			(xy 277.836267 -300.443854) (xy 277.842101 -300.427497) (xy 277.847298 -300.420532) (xy 277.849584 -300.417738)
			(xy 277.84933 -300.381924) (xy 277.8379 -300.3677) (xy 277.821901 -300.347127) (xy 277.796391 -300.301687)
			(xy 277.778958 -300.252578) (xy 277.770107 -300.201224) (xy 277.769574 -300.175168) (xy 277.769574 -300.17466)
			(xy 277.770119 -300.148574) (xy 277.778944 -300.097153) (xy 277.796366 -300.047976) (xy 277.821878 -300.002467)
			(xy 277.8379 -299.981874) (xy 277.849076 -299.968158) (xy 277.84933 -299.93209) (xy 277.847044 -299.929296)
			(xy 277.841914 -299.922381) (xy 277.836201 -299.90615) (xy 277.835868 -299.897546) (xy 277.835868 -299.502576)
			(xy 277.83624 -299.493892) (xy 277.842093 -299.477534) (xy 277.847298 -299.470572) (xy 277.849584 -299.467778)
			(xy 277.84933 -299.431964) (xy 277.8379 -299.41774) (xy 277.821874 -299.397187) (xy 277.796369 -299.35174)
			(xy 277.778944 -299.302625) (xy 277.770102 -299.251265) (xy 277.769574 -299.225208) (xy 277.769574 -299.2247)
			(xy 277.770087 -299.198612) (xy 277.778922 -299.14719) (xy 277.796353 -299.098013) (xy 277.821874 -299.052506)
			(xy 277.8379 -299.031914) (xy 277.849076 -299.018198) (xy 277.84933 -298.98213) (xy 277.847044 -298.979336)
			(xy 277.841931 -298.97241) (xy 277.836207 -298.956187) (xy 277.835868 -298.947586) (xy 277.835868 -298.552362)
			(xy 277.836279 -298.543682) (xy 277.842105 -298.527324) (xy 277.847298 -298.520358) (xy 277.849584 -298.517564)
			(xy 277.84933 -298.48175) (xy 277.8379 -298.467526) (xy 277.821868 -298.446978) (xy 277.796364 -298.401529)
			(xy 277.778941 -298.352412) (xy 277.770101 -298.301052) (xy 277.769574 -298.274994) (xy 277.769574 -298.274486)
			(xy 277.770079 -298.248398) (xy 277.778916 -298.196976) (xy 277.79635 -298.147798) (xy 277.821873 -298.102291)
			(xy 277.8379 -298.0817) (xy 277.849076 -298.067984) (xy 277.84933 -298.031916) (xy 277.847044 -298.029122)
			(xy 277.841925 -298.0222) (xy 277.836205 -298.005974) (xy 277.835868 -297.997372) (xy 277.835868 -297.664124)
			(xy 277.824438 -297.64228) (xy 277.814024 -297.635168) (xy 277.803332 -297.628589) (xy 277.778413 -297.625796)
			(xy 277.766526 -297.629834) (xy 277.714202 -297.650408) (xy 277.709741 -297.652043) (xy 277.700409 -297.653826)
			(xy 277.69566 -297.653964) (xy 277.55469 -297.653964) (xy 277.527405 -297.653321) (xy 277.473637 -297.643978)
			(xy 277.42221 -297.625711) (xy 277.374596 -297.599044) (xy 277.353014 -297.582336) (xy 277.344275 -297.576088)
			(xy 277.323519 -297.570659) (xy 277.302345 -297.574124) (xy 277.29307 -297.579542) (xy 277.27427 -297.591494)
			(xy 277.233932 -297.6104) (xy 277.191271 -297.623229) (xy 277.147196 -297.629706) (xy 277.124922 -297.630088)
			(xy 277.124668 -297.630088) (xy 277.10247 -297.629646) (xy 277.058545 -297.623193) (xy 277.016019 -297.610444)
			(xy 276.97579 -297.591667) (xy 276.957028 -297.579796) (xy 276.947457 -297.574136) (xy 276.925473 -297.570951)
			(xy 276.90421 -297.577378) (xy 276.89556 -297.584368) (xy 276.8727 -297.604434) (xy 276.869284 -297.607371)
			(xy 276.861619 -297.612101) (xy 276.85746 -297.613832) (xy 276.764242 -297.650408) (xy 276.759788 -297.65207)
			(xy 276.750453 -297.653865) (xy 276.7457 -297.653964) (xy 276.604476 -297.653964) (xy 276.57719 -297.653329)
			(xy 276.523422 -297.643983) (xy 276.471996 -297.625714) (xy 276.424381 -297.599045) (xy 276.4028 -297.582336)
			(xy 276.394069 -297.576076) (xy 276.373308 -297.570651) (xy 276.352132 -297.574121) (xy 276.342856 -297.579542)
			(xy 276.324059 -297.5915) (xy 276.28372 -297.610404) (xy 276.241058 -297.623231) (xy 276.196983 -297.629707)
			(xy 276.174708 -297.630088) (xy 276.152478 -297.629669) (xy 276.108486 -297.623232) (xy 276.065894 -297.610481)
			(xy 276.025603 -297.591683) (xy 276.006814 -297.579796) (xy 275.997173 -297.574057) (xy 275.974999 -297.570798)
			(xy 275.95355 -297.577295) (xy 275.944838 -297.584368) (xy 275.909278 -297.616372) (xy 275.904569 -297.620376)
			(xy 275.893645 -297.626153) (xy 275.887688 -297.627802) (xy 275.759164 -297.660314) (xy 275.753211 -297.661644)
			(xy 275.741016 -297.661765) (xy 275.735034 -297.660568) (xy 275.66874 -297.64482) (xy 275.640283 -297.63729)
			(xy 275.586551 -297.613263) (xy 275.538095 -297.57985) (xy 275.516848 -297.559476) (xy 275.13407 -297.176698)
			(xy 275.116713 -297.158561) (xy 275.087327 -297.117861) (xy 275.064631 -297.073085) (xy 275.049179 -297.025323)
			(xy 275.041347 -296.975738) (xy 275.040852 -296.950638) (xy 275.040852 -294.830754) (xy 275.041091 -294.813275)
			(xy 275.044912 -294.778526) (xy 275.048472 -294.761412) (xy 275.050092 -294.752192) (xy 275.047334 -294.733692)
			(xy 275.03814 -294.717402) (xy 275.0312 -294.71112) (xy 275.012507 -294.695172) (xy 274.979974 -294.658353)
			(xy 274.953757 -294.6168) (xy 274.934532 -294.571584) (xy 274.922794 -294.523874) (xy 274.918848 -294.4749)
			(xy 274.922794 -294.425926) (xy 274.934532 -294.378216) (xy 274.953757 -294.333) (xy 274.979974 -294.291447)
			(xy 275.012507 -294.254628) (xy 275.0312 -294.23868) (xy 275.038185 -294.232433) (xy 275.047411 -294.216139)
			(xy 275.05013 -294.197612) (xy 275.048472 -294.188388) (xy 275.044912 -294.171274) (xy 275.041096 -294.136525)
			(xy 275.040852 -294.119046) (xy 275.040852 -293.85768) (xy 275.040124 -293.845484) (xy 275.028848 -293.823852)
			(xy 275.019262 -293.816278) (xy 274.99812 -293.800722) (xy 274.960123 -293.764514) (xy 274.927845 -293.723125)
			(xy 274.901986 -293.677451) (xy 274.883105 -293.628479) (xy 274.871608 -293.577267) (xy 274.867746 -293.524923)
			(xy 274.580096 -293.524923) (xy 274.580096 -293.52494) (xy 274.579601 -293.549547) (xy 274.571706 -293.598124)
			(xy 274.556122 -293.644805) (xy 274.533251 -293.688382) (xy 274.503686 -293.727726) (xy 274.468193 -293.761818)
			(xy 274.42769 -293.789774) (xy 274.383228 -293.810872) (xy 274.335957 -293.824564) (xy 274.287102 -293.830496)
			(xy 274.237927 -293.828515) (xy 274.189708 -293.818671) (xy 274.143692 -293.801219) (xy 274.101071 -293.776612)
			(xy 274.06295 -293.745487) (xy 274.030315 -293.70865) (xy 274.004012 -293.667054) (xy 273.984721 -293.621778)
			(xy 273.972944 -293.573994) (xy 273.968984 -293.52494) (xy 273.630136 -293.52494) (xy 273.629641 -293.549547)
			(xy 273.621746 -293.598124) (xy 273.606162 -293.644805) (xy 273.583291 -293.688382) (xy 273.553726 -293.727726)
			(xy 273.518233 -293.761818) (xy 273.47773 -293.789774) (xy 273.433268 -293.810872) (xy 273.385997 -293.824564)
			(xy 273.337142 -293.830496) (xy 273.287967 -293.828515) (xy 273.239748 -293.818671) (xy 273.193732 -293.801219)
			(xy 273.151111 -293.776612) (xy 273.11299 -293.745487) (xy 273.080355 -293.70865) (xy 273.054052 -293.667054)
			(xy 273.034761 -293.621778) (xy 273.022984 -293.573994) (xy 273.019024 -293.52494) (xy 272.680176 -293.52494)
			(xy 272.679681 -293.549547) (xy 272.671786 -293.598124) (xy 272.656202 -293.644805) (xy 272.633331 -293.688382)
			(xy 272.603766 -293.727726) (xy 272.568273 -293.761818) (xy 272.52777 -293.789774) (xy 272.483308 -293.810872)
			(xy 272.436037 -293.824564) (xy 272.387182 -293.830496) (xy 272.338007 -293.828515) (xy 272.289788 -293.818671)
			(xy 272.243772 -293.801219) (xy 272.201151 -293.776612) (xy 272.16303 -293.745487) (xy 272.130395 -293.70865)
			(xy 272.104092 -293.667054) (xy 272.084801 -293.621778) (xy 272.073024 -293.573994) (xy 272.069064 -293.52494)
			(xy 271.730216 -293.52494) (xy 271.729721 -293.549547) (xy 271.721826 -293.598124) (xy 271.706242 -293.644805)
			(xy 271.683371 -293.688382) (xy 271.653806 -293.727726) (xy 271.618313 -293.761818) (xy 271.57781 -293.789774)
			(xy 271.533348 -293.810872) (xy 271.486077 -293.824564) (xy 271.437222 -293.830496) (xy 271.388047 -293.828515)
			(xy 271.339828 -293.818671) (xy 271.293812 -293.801219) (xy 271.251191 -293.776612) (xy 271.21307 -293.745487)
			(xy 271.180435 -293.70865) (xy 271.154132 -293.667054) (xy 271.134841 -293.621778) (xy 271.123064 -293.573994)
			(xy 271.119104 -293.52494) (xy 270.780256 -293.52494) (xy 270.779761 -293.549547) (xy 270.771866 -293.598124)
			(xy 270.756282 -293.644805) (xy 270.733411 -293.688382) (xy 270.703846 -293.727726) (xy 270.668353 -293.761818)
			(xy 270.62785 -293.789774) (xy 270.583388 -293.810872) (xy 270.536117 -293.824564) (xy 270.487262 -293.830496)
			(xy 270.438087 -293.828515) (xy 270.389868 -293.818671) (xy 270.343852 -293.801219) (xy 270.301231 -293.776612)
			(xy 270.26311 -293.745487) (xy 270.230475 -293.70865) (xy 270.204172 -293.667054) (xy 270.184881 -293.621778)
			(xy 270.173104 -293.573994) (xy 270.169144 -293.52494) (xy 266.590526 -293.52494) (xy 266.590526 -294.4749)
			(xy 268.26897 -294.4749) (xy 268.27293 -294.425846) (xy 268.284707 -294.378062) (xy 268.303998 -294.332786)
			(xy 268.330301 -294.29119) (xy 268.362936 -294.254353) (xy 268.401057 -294.223228) (xy 268.443678 -294.198621)
			(xy 268.489694 -294.181169) (xy 268.537913 -294.171325) (xy 268.587088 -294.169344) (xy 268.635943 -294.175276)
			(xy 268.683214 -294.188968) (xy 268.727676 -294.210066) (xy 268.768179 -294.238022) (xy 268.803672 -294.272114)
			(xy 268.833237 -294.311458) (xy 268.856108 -294.355035) (xy 268.871692 -294.401716) (xy 268.879587 -294.450293)
			(xy 268.880082 -294.4749) (xy 269.21893 -294.4749) (xy 269.22289 -294.425846) (xy 269.234667 -294.378062)
			(xy 269.253958 -294.332786) (xy 269.280261 -294.29119) (xy 269.312896 -294.254353) (xy 269.351017 -294.223228)
			(xy 269.393638 -294.198621) (xy 269.439654 -294.181169) (xy 269.487873 -294.171325) (xy 269.537048 -294.169344)
			(xy 269.585903 -294.175276) (xy 269.633174 -294.188968) (xy 269.677636 -294.210066) (xy 269.718139 -294.238022)
			(xy 269.753632 -294.272114) (xy 269.783197 -294.311458) (xy 269.806068 -294.355035) (xy 269.821652 -294.401716)
			(xy 269.829547 -294.450293) (xy 269.830042 -294.4749) (xy 270.169144 -294.4749) (xy 270.173104 -294.425846)
			(xy 270.184881 -294.378062) (xy 270.204172 -294.332786) (xy 270.230475 -294.29119) (xy 270.26311 -294.254353)
			(xy 270.301231 -294.223228) (xy 270.343852 -294.198621) (xy 270.389868 -294.181169) (xy 270.438087 -294.171325)
			(xy 270.487262 -294.169344) (xy 270.536117 -294.175276) (xy 270.583388 -294.188968) (xy 270.62785 -294.210066)
			(xy 270.668353 -294.238022) (xy 270.703846 -294.272114) (xy 270.733411 -294.311458) (xy 270.756282 -294.355035)
			(xy 270.771866 -294.401716) (xy 270.779761 -294.450293) (xy 270.780256 -294.4749) (xy 273.019024 -294.4749)
			(xy 273.022984 -294.425846) (xy 273.034761 -294.378062) (xy 273.054052 -294.332786) (xy 273.080355 -294.29119)
			(xy 273.11299 -294.254353) (xy 273.151111 -294.223228) (xy 273.193732 -294.198621) (xy 273.239748 -294.181169)
			(xy 273.287967 -294.171325) (xy 273.337142 -294.169344) (xy 273.385997 -294.175276) (xy 273.433268 -294.188968)
			(xy 273.47773 -294.210066) (xy 273.518233 -294.238022) (xy 273.553726 -294.272114) (xy 273.583291 -294.311458)
			(xy 273.606162 -294.355035) (xy 273.621746 -294.401716) (xy 273.629641 -294.450293) (xy 273.630136 -294.4749)
			(xy 273.629641 -294.499507) (xy 273.629309 -294.501549) (xy 273.919178 -294.501549) (xy 273.919178 -294.448251)
			(xy 273.927121 -294.395547) (xy 273.942831 -294.344617) (xy 273.965957 -294.296596) (xy 273.995981 -294.252559)
			(xy 274.032233 -294.213488) (xy 274.073904 -294.180257) (xy 274.120062 -294.153608) (xy 274.169676 -294.134136)
			(xy 274.221638 -294.122276) (xy 274.274788 -294.118293) (xy 274.327938 -294.122276) (xy 274.3799 -294.134136)
			(xy 274.429514 -294.153608) (xy 274.475672 -294.180257) (xy 274.517343 -294.213488) (xy 274.553595 -294.252559)
			(xy 274.583619 -294.296596) (xy 274.606745 -294.344617) (xy 274.622455 -294.395547) (xy 274.630398 -294.448251)
			(xy 274.630896 -294.4749) (xy 274.630398 -294.501549) (xy 274.622455 -294.554253) (xy 274.606745 -294.605183)
			(xy 274.583619 -294.653204) (xy 274.553595 -294.697241) (xy 274.517343 -294.736312) (xy 274.475672 -294.769543)
			(xy 274.429514 -294.796192) (xy 274.3799 -294.815664) (xy 274.327938 -294.827524) (xy 274.274788 -294.831508)
			(xy 274.221638 -294.827524) (xy 274.169676 -294.815664) (xy 274.120062 -294.796192) (xy 274.073904 -294.769543)
			(xy 274.032233 -294.736312) (xy 273.995981 -294.697241) (xy 273.965957 -294.653204) (xy 273.942831 -294.605183)
			(xy 273.927121 -294.554253) (xy 273.919178 -294.501549) (xy 273.629309 -294.501549) (xy 273.621746 -294.548084)
			(xy 273.606162 -294.594765) (xy 273.583291 -294.638342) (xy 273.553726 -294.677686) (xy 273.518233 -294.711778)
			(xy 273.47773 -294.739734) (xy 273.433268 -294.760832) (xy 273.385997 -294.774524) (xy 273.337142 -294.780456)
			(xy 273.287967 -294.778475) (xy 273.239748 -294.768631) (xy 273.193732 -294.751179) (xy 273.151111 -294.726572)
			(xy 273.11299 -294.695447) (xy 273.080355 -294.65861) (xy 273.054052 -294.617014) (xy 273.034761 -294.571738)
			(xy 273.022984 -294.523954) (xy 273.019024 -294.4749) (xy 270.780256 -294.4749) (xy 270.779761 -294.499507)
			(xy 270.771866 -294.548084) (xy 270.756282 -294.594765) (xy 270.733411 -294.638342) (xy 270.703846 -294.677686)
			(xy 270.668353 -294.711778) (xy 270.62785 -294.739734) (xy 270.583388 -294.760832) (xy 270.536117 -294.774524)
			(xy 270.487262 -294.780456) (xy 270.438087 -294.778475) (xy 270.389868 -294.768631) (xy 270.343852 -294.751179)
			(xy 270.301231 -294.726572) (xy 270.26311 -294.695447) (xy 270.230475 -294.65861) (xy 270.204172 -294.617014)
			(xy 270.184881 -294.571738) (xy 270.173104 -294.523954) (xy 270.169144 -294.4749) (xy 269.830042 -294.4749)
			(xy 269.829547 -294.499507) (xy 269.821652 -294.548084) (xy 269.806068 -294.594765) (xy 269.783197 -294.638342)
			(xy 269.753632 -294.677686) (xy 269.718139 -294.711778) (xy 269.677636 -294.739734) (xy 269.633174 -294.760832)
			(xy 269.585903 -294.774524) (xy 269.537048 -294.780456) (xy 269.487873 -294.778475) (xy 269.439654 -294.768631)
			(xy 269.393638 -294.751179) (xy 269.351017 -294.726572) (xy 269.312896 -294.695447) (xy 269.280261 -294.65861)
			(xy 269.253958 -294.617014) (xy 269.234667 -294.571738) (xy 269.22289 -294.523954) (xy 269.21893 -294.4749)
			(xy 268.880082 -294.4749) (xy 268.879587 -294.499507) (xy 268.871692 -294.548084) (xy 268.856108 -294.594765)
			(xy 268.833237 -294.638342) (xy 268.803672 -294.677686) (xy 268.768179 -294.711778) (xy 268.727676 -294.739734)
			(xy 268.683214 -294.760832) (xy 268.635943 -294.774524) (xy 268.587088 -294.780456) (xy 268.537913 -294.778475)
			(xy 268.489694 -294.768631) (xy 268.443678 -294.751179) (xy 268.401057 -294.726572) (xy 268.362936 -294.695447)
			(xy 268.330301 -294.65861) (xy 268.303998 -294.617014) (xy 268.284707 -294.571738) (xy 268.27293 -294.523954)
			(xy 268.26897 -294.4749) (xy 266.590526 -294.4749) (xy 266.590526 -296.37482) (xy 269.219184 -296.37482)
			(xy 269.223144 -296.325766) (xy 269.234921 -296.277982) (xy 269.254212 -296.232706) (xy 269.280515 -296.19111)
			(xy 269.31315 -296.154273) (xy 269.351271 -296.123148) (xy 269.393892 -296.098541) (xy 269.439908 -296.081089)
			(xy 269.488127 -296.071245) (xy 269.537302 -296.069264) (xy 269.586157 -296.075196) (xy 269.633428 -296.088888)
			(xy 269.67789 -296.109986) (xy 269.718393 -296.137942) (xy 269.753886 -296.172034) (xy 269.783451 -296.211378)
			(xy 269.806322 -296.254955) (xy 269.821906 -296.301636) (xy 269.829801 -296.350213) (xy 269.830296 -296.37482)
			(xy 270.16889 -296.37482) (xy 270.17285 -296.325766) (xy 270.184627 -296.277982) (xy 270.203918 -296.232706)
			(xy 270.230221 -296.19111) (xy 270.262856 -296.154273) (xy 270.300977 -296.123148) (xy 270.343598 -296.098541)
			(xy 270.389614 -296.081089) (xy 270.437833 -296.071245) (xy 270.487008 -296.069264) (xy 270.535863 -296.075196)
			(xy 270.583134 -296.088888) (xy 270.627596 -296.109986) (xy 270.668099 -296.137942) (xy 270.703592 -296.172034)
			(xy 270.733157 -296.211378) (xy 270.756028 -296.254955) (xy 270.771612 -296.301636) (xy 270.779507 -296.350213)
			(xy 270.780002 -296.37482) (xy 271.119104 -296.37482) (xy 271.123064 -296.325766) (xy 271.134841 -296.277982)
			(xy 271.154132 -296.232706) (xy 271.180435 -296.19111) (xy 271.21307 -296.154273) (xy 271.251191 -296.123148)
			(xy 271.293812 -296.098541) (xy 271.339828 -296.081089) (xy 271.388047 -296.071245) (xy 271.437222 -296.069264)
			(xy 271.486077 -296.075196) (xy 271.533348 -296.088888) (xy 271.57781 -296.109986) (xy 271.618313 -296.137942)
			(xy 271.653806 -296.172034) (xy 271.683371 -296.211378) (xy 271.706242 -296.254955) (xy 271.721826 -296.301636)
			(xy 271.729721 -296.350213) (xy 271.730216 -296.37482) (xy 272.069064 -296.37482) (xy 272.073024 -296.325766)
			(xy 272.084801 -296.277982) (xy 272.104092 -296.232706) (xy 272.130395 -296.19111) (xy 272.16303 -296.154273)
			(xy 272.201151 -296.123148) (xy 272.243772 -296.098541) (xy 272.289788 -296.081089) (xy 272.338007 -296.071245)
			(xy 272.387182 -296.069264) (xy 272.436037 -296.075196) (xy 272.483308 -296.088888) (xy 272.52777 -296.109986)
			(xy 272.568273 -296.137942) (xy 272.603766 -296.172034) (xy 272.633331 -296.211378) (xy 272.656202 -296.254955)
			(xy 272.671786 -296.301636) (xy 272.679681 -296.350213) (xy 272.680176 -296.37482) (xy 273.968984 -296.37482)
			(xy 273.972944 -296.325766) (xy 273.984721 -296.277982) (xy 274.004012 -296.232706) (xy 274.030315 -296.19111)
			(xy 274.06295 -296.154273) (xy 274.101071 -296.123148) (xy 274.143692 -296.098541) (xy 274.189708 -296.081089)
			(xy 274.237927 -296.071245) (xy 274.287102 -296.069264) (xy 274.335957 -296.075196) (xy 274.383228 -296.088888)
			(xy 274.42769 -296.109986) (xy 274.468193 -296.137942) (xy 274.503686 -296.172034) (xy 274.533251 -296.211378)
			(xy 274.556122 -296.254955) (xy 274.571706 -296.301636) (xy 274.579601 -296.350213) (xy 274.580096 -296.37482)
			(xy 274.579601 -296.399427) (xy 274.571706 -296.448004) (xy 274.556122 -296.494685) (xy 274.533251 -296.538262)
			(xy 274.503686 -296.577606) (xy 274.468193 -296.611698) (xy 274.42769 -296.639654) (xy 274.383228 -296.660752)
			(xy 274.335957 -296.674444) (xy 274.287102 -296.680376) (xy 274.237927 -296.678395) (xy 274.189708 -296.668551)
			(xy 274.143692 -296.651099) (xy 274.101071 -296.626492) (xy 274.06295 -296.595367) (xy 274.030315 -296.55853)
			(xy 274.004012 -296.516934) (xy 273.984721 -296.471658) (xy 273.972944 -296.423874) (xy 273.968984 -296.37482)
			(xy 272.680176 -296.37482) (xy 272.679681 -296.399427) (xy 272.671786 -296.448004) (xy 272.656202 -296.494685)
			(xy 272.633331 -296.538262) (xy 272.603766 -296.577606) (xy 272.568273 -296.611698) (xy 272.52777 -296.639654)
			(xy 272.483308 -296.660752) (xy 272.436037 -296.674444) (xy 272.387182 -296.680376) (xy 272.338007 -296.678395)
			(xy 272.289788 -296.668551) (xy 272.243772 -296.651099) (xy 272.201151 -296.626492) (xy 272.16303 -296.595367)
			(xy 272.130395 -296.55853) (xy 272.104092 -296.516934) (xy 272.084801 -296.471658) (xy 272.073024 -296.423874)
			(xy 272.069064 -296.37482) (xy 271.730216 -296.37482) (xy 271.729721 -296.399427) (xy 271.721826 -296.448004)
			(xy 271.706242 -296.494685) (xy 271.683371 -296.538262) (xy 271.653806 -296.577606) (xy 271.618313 -296.611698)
			(xy 271.57781 -296.639654) (xy 271.533348 -296.660752) (xy 271.486077 -296.674444) (xy 271.437222 -296.680376)
			(xy 271.388047 -296.678395) (xy 271.339828 -296.668551) (xy 271.293812 -296.651099) (xy 271.251191 -296.626492)
			(xy 271.21307 -296.595367) (xy 271.180435 -296.55853) (xy 271.154132 -296.516934) (xy 271.134841 -296.471658)
			(xy 271.123064 -296.423874) (xy 271.119104 -296.37482) (xy 270.780002 -296.37482) (xy 270.779507 -296.399427)
			(xy 270.771612 -296.448004) (xy 270.756028 -296.494685) (xy 270.733157 -296.538262) (xy 270.703592 -296.577606)
			(xy 270.668099 -296.611698) (xy 270.627596 -296.639654) (xy 270.583134 -296.660752) (xy 270.535863 -296.674444)
			(xy 270.487008 -296.680376) (xy 270.437833 -296.678395) (xy 270.389614 -296.668551) (xy 270.343598 -296.651099)
			(xy 270.300977 -296.626492) (xy 270.262856 -296.595367) (xy 270.230221 -296.55853) (xy 270.203918 -296.516934)
			(xy 270.184627 -296.471658) (xy 270.17285 -296.423874) (xy 270.16889 -296.37482) (xy 269.830296 -296.37482)
			(xy 269.829801 -296.399427) (xy 269.821906 -296.448004) (xy 269.806322 -296.494685) (xy 269.783451 -296.538262)
			(xy 269.753886 -296.577606) (xy 269.718393 -296.611698) (xy 269.67789 -296.639654) (xy 269.633428 -296.660752)
			(xy 269.586157 -296.674444) (xy 269.537302 -296.680376) (xy 269.488127 -296.678395) (xy 269.439908 -296.668551)
			(xy 269.393892 -296.651099) (xy 269.351271 -296.626492) (xy 269.31315 -296.595367) (xy 269.280515 -296.55853)
			(xy 269.254212 -296.516934) (xy 269.234921 -296.471658) (xy 269.223144 -296.423874) (xy 269.219184 -296.37482)
			(xy 266.590526 -296.37482) (xy 266.590526 -297.3248) (xy 267.633949 -297.3248) (xy 267.63812 -297.274461)
			(xy 267.650519 -297.225496) (xy 267.670808 -297.179238) (xy 267.698434 -297.136951) (xy 267.732643 -297.099787)
			(xy 267.772502 -297.068761) (xy 267.816923 -297.044718) (xy 267.864697 -297.028313) (xy 267.914518 -297.019996)
			(xy 267.939774 -297.019472) (xy 267.965169 -297.019983) (xy 268.015259 -297.028397) (xy 268.063266 -297.044981)
			(xy 268.107868 -297.069279) (xy 268.147837 -297.100619) (xy 268.165326 -297.11904) (xy 268.172692 -297.127168)
			(xy 268.192758 -297.135804) (xy 268.292072 -297.13301) (xy 268.31163 -297.123612) (xy 268.318742 -297.114976)
			(xy 268.334531 -297.096404) (xy 268.370664 -297.063685) (xy 268.411205 -297.036618) (xy 268.455277 -297.01579)
			(xy 268.501928 -297.00165) (xy 268.550147 -296.994504) (xy 268.57452 -296.994072) (xy 269.52448 -296.994072)
			(xy 269.550469 -296.994594) (xy 269.601807 -297.002722) (xy 269.651241 -297.018781) (xy 269.697554 -297.042377)
			(xy 269.739606 -297.072927) (xy 269.77636 -297.109679) (xy 269.806913 -297.151729) (xy 269.830511 -297.198041)
			(xy 269.846573 -297.247474) (xy 269.854705 -297.298811) (xy 269.854705 -297.32478) (xy 270.16889 -297.32478)
			(xy 270.17285 -297.275726) (xy 270.184627 -297.227942) (xy 270.203918 -297.182666) (xy 270.230221 -297.14107)
			(xy 270.262856 -297.104233) (xy 270.300977 -297.073108) (xy 270.343598 -297.048501) (xy 270.389614 -297.031049)
			(xy 270.437833 -297.021205) (xy 270.487008 -297.019224) (xy 270.535863 -297.025156) (xy 270.583134 -297.038848)
			(xy 270.627596 -297.059946) (xy 270.668099 -297.087902) (xy 270.703592 -297.121994) (xy 270.733157 -297.161338)
			(xy 270.756028 -297.204915) (xy 270.771612 -297.251596) (xy 270.779507 -297.300173) (xy 270.780002 -297.32478)
			(xy 271.119104 -297.32478) (xy 271.123064 -297.275726) (xy 271.134841 -297.227942) (xy 271.154132 -297.182666)
			(xy 271.180435 -297.14107) (xy 271.21307 -297.104233) (xy 271.251191 -297.073108) (xy 271.293812 -297.048501)
			(xy 271.339828 -297.031049) (xy 271.388047 -297.021205) (xy 271.437222 -297.019224) (xy 271.486077 -297.025156)
			(xy 271.533348 -297.038848) (xy 271.57781 -297.059946) (xy 271.618313 -297.087902) (xy 271.653806 -297.121994)
			(xy 271.683371 -297.161338) (xy 271.706242 -297.204915) (xy 271.721826 -297.251596) (xy 271.729721 -297.300173)
			(xy 271.730216 -297.32478) (xy 273.968984 -297.32478) (xy 273.972944 -297.275726) (xy 273.984721 -297.227942)
			(xy 274.004012 -297.182666) (xy 274.030315 -297.14107) (xy 274.06295 -297.104233) (xy 274.101071 -297.073108)
			(xy 274.143692 -297.048501) (xy 274.189708 -297.031049) (xy 274.237927 -297.021205) (xy 274.287102 -297.019224)
			(xy 274.335957 -297.025156) (xy 274.383228 -297.038848) (xy 274.42769 -297.059946) (xy 274.468193 -297.087902)
			(xy 274.503686 -297.121994) (xy 274.533251 -297.161338) (xy 274.556122 -297.204915) (xy 274.571706 -297.251596)
			(xy 274.579601 -297.300173) (xy 274.580096 -297.32478) (xy 274.579601 -297.349387) (xy 274.571706 -297.397964)
			(xy 274.556122 -297.444645) (xy 274.533251 -297.488222) (xy 274.503686 -297.527566) (xy 274.468193 -297.561658)
			(xy 274.42769 -297.589614) (xy 274.383228 -297.610712) (xy 274.335957 -297.624404) (xy 274.287102 -297.630336)
			(xy 274.237927 -297.628355) (xy 274.189708 -297.618511) (xy 274.143692 -297.601059) (xy 274.101071 -297.576452)
			(xy 274.06295 -297.545327) (xy 274.030315 -297.50849) (xy 274.004012 -297.466894) (xy 273.984721 -297.421618)
			(xy 273.972944 -297.373834) (xy 273.968984 -297.32478) (xy 271.730216 -297.32478) (xy 271.729721 -297.349387)
			(xy 271.721826 -297.397964) (xy 271.706242 -297.444645) (xy 271.683371 -297.488222) (xy 271.653806 -297.527566)
			(xy 271.618313 -297.561658) (xy 271.57781 -297.589614) (xy 271.533348 -297.610712) (xy 271.486077 -297.624404)
			(xy 271.437222 -297.630336) (xy 271.388047 -297.628355) (xy 271.339828 -297.618511) (xy 271.293812 -297.601059)
			(xy 271.251191 -297.576452) (xy 271.21307 -297.545327) (xy 271.180435 -297.50849) (xy 271.154132 -297.466894)
			(xy 271.134841 -297.421618) (xy 271.123064 -297.373834) (xy 271.119104 -297.32478) (xy 270.780002 -297.32478)
			(xy 270.779507 -297.349387) (xy 270.771612 -297.397964) (xy 270.756028 -297.444645) (xy 270.733157 -297.488222)
			(xy 270.703592 -297.527566) (xy 270.668099 -297.561658) (xy 270.627596 -297.589614) (xy 270.583134 -297.610712)
			(xy 270.535863 -297.624404) (xy 270.487008 -297.630336) (xy 270.437833 -297.628355) (xy 270.389614 -297.618511)
			(xy 270.343598 -297.601059) (xy 270.300977 -297.576452) (xy 270.262856 -297.545327) (xy 270.230221 -297.50849)
			(xy 270.203918 -297.466894) (xy 270.184627 -297.421618) (xy 270.17285 -297.373834) (xy 270.16889 -297.32478)
			(xy 269.854705 -297.32478) (xy 269.854705 -297.350789) (xy 269.846573 -297.402126) (xy 269.830511 -297.451559)
			(xy 269.806913 -297.497871) (xy 269.77636 -297.539921) (xy 269.739606 -297.576673) (xy 269.697554 -297.607223)
			(xy 269.651241 -297.630819) (xy 269.601807 -297.646878) (xy 269.550469 -297.655006) (xy 269.52448 -297.655488)
			(xy 268.57452 -297.655488) (xy 268.550146 -297.655084) (xy 268.501926 -297.647935) (xy 268.455276 -297.63379)
			(xy 268.411206 -297.612953) (xy 268.370669 -297.585877) (xy 268.334544 -297.553147) (xy 268.318742 -297.534584)
			(xy 268.311393 -297.526532) (xy 268.291771 -297.517073) (xy 268.280896 -297.516296) (xy 268.192758 -297.513756)
			(xy 268.172692 -297.522392) (xy 268.165326 -297.53052) (xy 268.14784 -297.548945) (xy 268.107876 -297.580296)
			(xy 268.063274 -297.604598) (xy 268.015264 -297.62118) (xy 267.965171 -297.629585) (xy 267.939774 -297.630088)
			(xy 267.914518 -297.629604) (xy 267.864697 -297.621287) (xy 267.816923 -297.604882) (xy 267.772502 -297.580839)
			(xy 267.732643 -297.549813) (xy 267.698434 -297.512649) (xy 267.670808 -297.470362) (xy 267.650519 -297.424104)
			(xy 267.63812 -297.375139) (xy 267.633949 -297.3248) (xy 266.590526 -297.3248) (xy 266.590526 -298.27474)
			(xy 269.218676 -298.27474) (xy 269.222636 -298.225686) (xy 269.234413 -298.177902) (xy 269.253704 -298.132626)
			(xy 269.280007 -298.09103) (xy 269.312642 -298.054193) (xy 269.350763 -298.023068) (xy 269.393384 -297.998461)
			(xy 269.4394 -297.981009) (xy 269.487619 -297.971165) (xy 269.536794 -297.969184) (xy 269.585649 -297.975116)
			(xy 269.63292 -297.988808) (xy 269.677382 -298.009906) (xy 269.717885 -298.037862) (xy 269.753378 -298.071954)
			(xy 269.782943 -298.111298) (xy 269.805814 -298.154875) (xy 269.821398 -298.201556) (xy 269.829293 -298.250133)
			(xy 269.829788 -298.27474) (xy 270.16889 -298.27474) (xy 270.17285 -298.225686) (xy 270.184627 -298.177902)
			(xy 270.203918 -298.132626) (xy 270.230221 -298.09103) (xy 270.262856 -298.054193) (xy 270.300977 -298.023068)
			(xy 270.343598 -297.998461) (xy 270.389614 -297.981009) (xy 270.437833 -297.971165) (xy 270.487008 -297.969184)
			(xy 270.535863 -297.975116) (xy 270.583134 -297.988808) (xy 270.627596 -298.009906) (xy 270.668099 -298.037862)
			(xy 270.703592 -298.071954) (xy 270.733157 -298.111298) (xy 270.756028 -298.154875) (xy 270.771612 -298.201556)
			(xy 270.779507 -298.250133) (xy 270.780002 -298.27474) (xy 271.119104 -298.27474) (xy 271.123064 -298.225686)
			(xy 271.134841 -298.177902) (xy 271.154132 -298.132626) (xy 271.180435 -298.09103) (xy 271.21307 -298.054193)
			(xy 271.251191 -298.023068) (xy 271.293812 -297.998461) (xy 271.339828 -297.981009) (xy 271.388047 -297.971165)
			(xy 271.437222 -297.969184) (xy 271.486077 -297.975116) (xy 271.533348 -297.988808) (xy 271.57781 -298.009906)
			(xy 271.618313 -298.037862) (xy 271.653806 -298.071954) (xy 271.683371 -298.111298) (xy 271.706242 -298.154875)
			(xy 271.721826 -298.201556) (xy 271.729721 -298.250133) (xy 271.730216 -298.27474) (xy 272.069064 -298.27474)
			(xy 272.073024 -298.225686) (xy 272.084801 -298.177902) (xy 272.104092 -298.132626) (xy 272.130395 -298.09103)
			(xy 272.16303 -298.054193) (xy 272.201151 -298.023068) (xy 272.243772 -297.998461) (xy 272.289788 -297.981009)
			(xy 272.338007 -297.971165) (xy 272.387182 -297.969184) (xy 272.436037 -297.975116) (xy 272.483308 -297.988808)
			(xy 272.52777 -298.009906) (xy 272.568273 -298.037862) (xy 272.603766 -298.071954) (xy 272.633331 -298.111298)
			(xy 272.656202 -298.154875) (xy 272.671786 -298.201556) (xy 272.679681 -298.250133) (xy 272.680176 -298.27474)
			(xy 273.019024 -298.27474) (xy 273.022984 -298.225686) (xy 273.034761 -298.177902) (xy 273.054052 -298.132626)
			(xy 273.080355 -298.09103) (xy 273.11299 -298.054193) (xy 273.151111 -298.023068) (xy 273.193732 -297.998461)
			(xy 273.239748 -297.981009) (xy 273.287967 -297.971165) (xy 273.337142 -297.969184) (xy 273.385997 -297.975116)
			(xy 273.433268 -297.988808) (xy 273.47773 -298.009906) (xy 273.518233 -298.037862) (xy 273.553726 -298.071954)
			(xy 273.583291 -298.111298) (xy 273.606162 -298.154875) (xy 273.621746 -298.201556) (xy 273.629641 -298.250133)
			(xy 273.630136 -298.27474) (xy 273.968984 -298.27474) (xy 273.972944 -298.225686) (xy 273.984721 -298.177902)
			(xy 274.004012 -298.132626) (xy 274.030315 -298.09103) (xy 274.06295 -298.054193) (xy 274.101071 -298.023068)
			(xy 274.143692 -297.998461) (xy 274.189708 -297.981009) (xy 274.237927 -297.971165) (xy 274.287102 -297.969184)
			(xy 274.335957 -297.975116) (xy 274.383228 -297.988808) (xy 274.42769 -298.009906) (xy 274.468193 -298.037862)
			(xy 274.503686 -298.071954) (xy 274.533251 -298.111298) (xy 274.556122 -298.154875) (xy 274.571706 -298.201556)
			(xy 274.579601 -298.250133) (xy 274.580096 -298.27474) (xy 275.868904 -298.27474) (xy 275.872864 -298.225686)
			(xy 275.884641 -298.177902) (xy 275.903932 -298.132626) (xy 275.930235 -298.09103) (xy 275.96287 -298.054193)
			(xy 276.000991 -298.023068) (xy 276.043612 -297.998461) (xy 276.089628 -297.981009) (xy 276.137847 -297.971165)
			(xy 276.187022 -297.969184) (xy 276.235877 -297.975116) (xy 276.283148 -297.988808) (xy 276.32761 -298.009906)
			(xy 276.368113 -298.037862) (xy 276.403606 -298.071954) (xy 276.433171 -298.111298) (xy 276.456042 -298.154875)
			(xy 276.471626 -298.201556) (xy 276.479521 -298.250133) (xy 276.480016 -298.27474) (xy 276.479521 -298.299347)
			(xy 276.471626 -298.347924) (xy 276.456042 -298.394605) (xy 276.433171 -298.438182) (xy 276.403606 -298.477526)
			(xy 276.368113 -298.511618) (xy 276.32761 -298.539574) (xy 276.283148 -298.560672) (xy 276.235877 -298.574364)
			(xy 276.187022 -298.580296) (xy 276.137847 -298.578315) (xy 276.089628 -298.568471) (xy 276.043612 -298.551019)
			(xy 276.000991 -298.526412) (xy 275.96287 -298.495287) (xy 275.930235 -298.45845) (xy 275.903932 -298.416854)
			(xy 275.884641 -298.371578) (xy 275.872864 -298.323794) (xy 275.868904 -298.27474) (xy 274.580096 -298.27474)
			(xy 274.579601 -298.299347) (xy 274.571706 -298.347924) (xy 274.556122 -298.394605) (xy 274.533251 -298.438182)
			(xy 274.503686 -298.477526) (xy 274.468193 -298.511618) (xy 274.42769 -298.539574) (xy 274.383228 -298.560672)
			(xy 274.335957 -298.574364) (xy 274.287102 -298.580296) (xy 274.237927 -298.578315) (xy 274.189708 -298.568471)
			(xy 274.143692 -298.551019) (xy 274.101071 -298.526412) (xy 274.06295 -298.495287) (xy 274.030315 -298.45845)
			(xy 274.004012 -298.416854) (xy 273.984721 -298.371578) (xy 273.972944 -298.323794) (xy 273.968984 -298.27474)
			(xy 273.630136 -298.27474) (xy 273.629641 -298.299347) (xy 273.621746 -298.347924) (xy 273.606162 -298.394605)
			(xy 273.583291 -298.438182) (xy 273.553726 -298.477526) (xy 273.518233 -298.511618) (xy 273.47773 -298.539574)
			(xy 273.433268 -298.560672) (xy 273.385997 -298.574364) (xy 273.337142 -298.580296) (xy 273.287967 -298.578315)
			(xy 273.239748 -298.568471) (xy 273.193732 -298.551019) (xy 273.151111 -298.526412) (xy 273.11299 -298.495287)
			(xy 273.080355 -298.45845) (xy 273.054052 -298.416854) (xy 273.034761 -298.371578) (xy 273.022984 -298.323794)
			(xy 273.019024 -298.27474) (xy 272.680176 -298.27474) (xy 272.679681 -298.299347) (xy 272.671786 -298.347924)
			(xy 272.656202 -298.394605) (xy 272.633331 -298.438182) (xy 272.603766 -298.477526) (xy 272.568273 -298.511618)
			(xy 272.52777 -298.539574) (xy 272.483308 -298.560672) (xy 272.436037 -298.574364) (xy 272.387182 -298.580296)
			(xy 272.338007 -298.578315) (xy 272.289788 -298.568471) (xy 272.243772 -298.551019) (xy 272.201151 -298.526412)
			(xy 272.16303 -298.495287) (xy 272.130395 -298.45845) (xy 272.104092 -298.416854) (xy 272.084801 -298.371578)
			(xy 272.073024 -298.323794) (xy 272.069064 -298.27474) (xy 271.730216 -298.27474) (xy 271.729721 -298.299347)
			(xy 271.721826 -298.347924) (xy 271.706242 -298.394605) (xy 271.683371 -298.438182) (xy 271.653806 -298.477526)
			(xy 271.618313 -298.511618) (xy 271.57781 -298.539574) (xy 271.533348 -298.560672) (xy 271.486077 -298.574364)
			(xy 271.437222 -298.580296) (xy 271.388047 -298.578315) (xy 271.339828 -298.568471) (xy 271.293812 -298.551019)
			(xy 271.251191 -298.526412) (xy 271.21307 -298.495287) (xy 271.180435 -298.45845) (xy 271.154132 -298.416854)
			(xy 271.134841 -298.371578) (xy 271.123064 -298.323794) (xy 271.119104 -298.27474) (xy 270.780002 -298.27474)
			(xy 270.779507 -298.299347) (xy 270.771612 -298.347924) (xy 270.756028 -298.394605) (xy 270.733157 -298.438182)
			(xy 270.703592 -298.477526) (xy 270.668099 -298.511618) (xy 270.627596 -298.539574) (xy 270.583134 -298.560672)
			(xy 270.535863 -298.574364) (xy 270.487008 -298.580296) (xy 270.437833 -298.578315) (xy 270.389614 -298.568471)
			(xy 270.343598 -298.551019) (xy 270.300977 -298.526412) (xy 270.262856 -298.495287) (xy 270.230221 -298.45845)
			(xy 270.203918 -298.416854) (xy 270.184627 -298.371578) (xy 270.17285 -298.323794) (xy 270.16889 -298.27474)
			(xy 269.829788 -298.27474) (xy 269.829293 -298.299347) (xy 269.821398 -298.347924) (xy 269.805814 -298.394605)
			(xy 269.782943 -298.438182) (xy 269.753378 -298.477526) (xy 269.717885 -298.511618) (xy 269.677382 -298.539574)
			(xy 269.63292 -298.560672) (xy 269.585649 -298.574364) (xy 269.536794 -298.580296) (xy 269.487619 -298.578315)
			(xy 269.4394 -298.568471) (xy 269.393384 -298.551019) (xy 269.350763 -298.526412) (xy 269.312642 -298.495287)
			(xy 269.280007 -298.45845) (xy 269.253704 -298.416854) (xy 269.234413 -298.371578) (xy 269.222636 -298.323794)
			(xy 269.218676 -298.27474) (xy 266.590526 -298.27474) (xy 266.590526 -299.432472) (xy 266.590696 -299.438481)
			(xy 266.593526 -299.45016) (xy 266.596114 -299.455586) (xy 266.597952 -299.459061) (xy 266.602544 -299.465442)
			(xy 266.605258 -299.468286) (xy 266.646152 -299.50918) (xy 266.649002 -299.511888) (xy 266.655378 -299.516485)
			(xy 266.658852 -299.518324) (xy 266.664279 -299.520905) (xy 266.675959 -299.523725) (xy 266.681966 -299.523912)
			(xy 267.31976 -299.523912) (xy 267.344906 -299.524166) (xy 267.349478 -299.52442) (xy 267.617956 -299.52442)
			(xy 267.627862 -299.52442) (xy 267.638784 -299.52442) (xy 267.641578 -299.524674) (xy 267.648944 -299.524674)
			(xy 267.653262 -299.524928) (xy 267.656564 -299.524928) (xy 267.667795 -299.523943) (xy 267.687835 -299.513673)
			(xy 267.695172 -299.505116) (xy 267.713968 -299.478954) (xy 267.717511 -299.473614) (xy 267.72213 -299.461665)
			(xy 267.723112 -299.455332) (xy 267.724636 -299.44314) (xy 267.70711 -299.422566) (xy 267.690126 -299.401674)
			(xy 267.663016 -299.355162) (xy 267.644464 -299.304624) (xy 267.635042 -299.251618) (xy 267.634466 -299.2247)
			(xy 267.634937 -299.200708) (xy 267.642443 -299.153315) (xy 267.65727 -299.107679) (xy 267.679053 -299.064925)
			(xy 267.707256 -299.026104) (xy 267.741184 -298.992173) (xy 267.780002 -298.963966) (xy 267.822755 -298.94218)
			(xy 267.868389 -298.927349) (xy 267.915782 -298.919839) (xy 267.939774 -298.919392) (xy 267.965062 -298.919886)
			(xy 268.014948 -298.928222) (xy 268.062775 -298.94467) (xy 268.107236 -298.96878) (xy 268.147112 -298.999891)
			(xy 268.164564 -299.018198) (xy 268.16558 -299.019214) (xy 268.172795 -299.026354) (xy 268.19127 -299.03472)
			(xy 268.201394 -299.03547) (xy 268.242796 -299.034454) (xy 268.28115 -299.033438) (xy 268.286553 -299.033169)
			(xy 268.29706 -299.030611) (xy 268.301978 -299.028358) (xy 268.311376 -299.023786) (xy 268.318742 -299.014896)
			(xy 268.33453 -298.996349) (xy 268.37062 -298.963645) (xy 268.411115 -298.936583) (xy 268.455139 -298.91575)
			(xy 268.501741 -298.901593) (xy 268.549914 -298.894421) (xy 268.574266 -298.893992) (xy 269.52448 -298.893992)
			(xy 269.548903 -298.894434) (xy 269.597219 -298.90162) (xy 269.643955 -298.915824) (xy 269.688098 -298.936739)
			(xy 269.728691 -298.963911) (xy 269.764852 -298.99675) (xy 269.795798 -299.034544) (xy 269.808706 -299.055282)
			(xy 269.811754 -299.060616) (xy 269.812008 -299.061124) (xy 269.813532 -299.063664) (xy 269.82215 -299.079526)
			(xy 269.836279 -299.112747) (xy 269.841726 -299.129958) (xy 269.842234 -299.13199) (xy 269.843758 -299.13707)
			(xy 269.84452 -299.139864) (xy 269.844774 -299.140626) (xy 269.845536 -299.143166) (xy 269.84579 -299.144436)
			(xy 269.84706 -299.14977) (xy 269.850419 -299.165319) (xy 269.854494 -299.19687) (xy 269.855188 -299.212762)
			(xy 269.855188 -299.219112) (xy 269.855188 -299.222922) (xy 269.855188 -299.223938) (xy 269.855188 -299.224954)
			(xy 269.855065 -299.240411) (xy 269.85227 -299.271197) (xy 269.8496 -299.286422) (xy 269.848076 -299.295058)
			(xy 269.842234 -299.317156) (xy 269.842234 -299.317664) (xy 269.838424 -299.32884) (xy 269.837916 -299.330872)
			(xy 269.837408 -299.332396) (xy 269.836646 -299.334936) (xy 269.836138 -299.33646) (xy 269.830042 -299.3517)
			(xy 269.830042 -299.352208) (xy 269.82426 -299.365669) (xy 269.810649 -299.391614) (xy 269.802864 -299.404024)
			(xy 269.802356 -299.404532) (xy 269.793466 -299.417486) (xy 269.792196 -299.419518) (xy 269.79118 -299.420788)
			(xy 269.790672 -299.42155) (xy 269.790418 -299.421804) (xy 269.789402 -299.423328) (xy 269.786608 -299.427392)
			(xy 269.781699 -299.437503) (xy 269.780268 -299.459905) (xy 269.783814 -299.470572) (xy 269.80642 -299.515022)
			(xy 269.80642 -299.51553) (xy 269.812262 -299.526706) (xy 269.812262 -299.527214) (xy 269.82674 -299.555916)
			(xy 269.831305 -299.564096) (xy 269.845144 -299.576696) (xy 269.862595 -299.58346) (xy 269.871952 -299.583856)
			(xy 270.153638 -299.583856) (xy 270.166338 -299.582078) (xy 270.185896 -299.576236) (xy 270.196056 -299.568108)
			(xy 270.198987 -299.565003) (xy 270.203844 -299.55798) (xy 270.205708 -299.554138) (xy 270.21663 -299.530516)
			(xy 270.246602 -299.466) (xy 270.247824 -299.462174) (xy 270.249224 -299.454265) (xy 270.249396 -299.450252)
			(xy 270.238474 -299.418756) (xy 270.233394 -299.412152) (xy 270.218498 -299.392099) (xy 270.194746 -299.348157)
			(xy 270.178449 -299.300941) (xy 270.170039 -299.251704) (xy 270.169386 -299.226732) (xy 270.169386 -299.217334)
			(xy 270.170495 -299.192491) (xy 270.179772 -299.143639) (xy 270.196841 -299.096935) (xy 270.221251 -299.053613)
			(xy 270.252357 -299.014818) (xy 270.289337 -298.981574) (xy 270.331214 -298.954761) (xy 270.376881 -298.935086)
			(xy 270.425133 -298.923069) (xy 270.474694 -298.919027) (xy 270.524255 -298.923069) (xy 270.572507 -298.935086)
			(xy 270.618174 -298.954761) (xy 270.660051 -298.981574) (xy 270.697031 -299.014818) (xy 270.728137 -299.053613)
			(xy 270.752547 -299.096935) (xy 270.769616 -299.143639) (xy 270.778893 -299.192491) (xy 270.780002 -299.217334)
			(xy 270.780002 -299.226732) (xy 270.7794 -299.251013) (xy 271.094376 -299.251013) (xy 271.094376 -299.198987)
			(xy 271.102514 -299.147601) (xy 271.118592 -299.098121) (xy 271.142212 -299.051765) (xy 271.172792 -299.009675)
			(xy 271.209581 -298.972887) (xy 271.251672 -298.942307) (xy 271.298028 -298.918689) (xy 271.347509 -298.902613)
			(xy 271.398895 -298.894475) (xy 271.424908 -298.893992) (xy 272.374868 -298.893992) (xy 272.400875 -298.894565)
			(xy 272.45225 -298.902697) (xy 272.50172 -298.918767) (xy 272.548067 -298.942378) (xy 272.590149 -298.972949)
			(xy 272.626931 -299.009727) (xy 272.657506 -299.051806) (xy 272.681121 -299.09815) (xy 272.697195 -299.147619)
			(xy 272.705333 -299.198993) (xy 272.705333 -299.224954) (xy 273.019024 -299.224954) (xy 273.022984 -299.1759)
			(xy 273.034761 -299.128116) (xy 273.054052 -299.08284) (xy 273.080355 -299.041244) (xy 273.11299 -299.004407)
			(xy 273.151111 -298.973282) (xy 273.193732 -298.948675) (xy 273.239748 -298.931223) (xy 273.287967 -298.921379)
			(xy 273.337142 -298.919398) (xy 273.385997 -298.92533) (xy 273.433268 -298.939022) (xy 273.47773 -298.96012)
			(xy 273.518233 -298.988076) (xy 273.553726 -299.022168) (xy 273.583291 -299.061512) (xy 273.606162 -299.105089)
			(xy 273.621746 -299.15177) (xy 273.629641 -299.200347) (xy 273.630136 -299.224954) (xy 273.629641 -299.249561)
			(xy 273.621746 -299.298138) (xy 273.606162 -299.344819) (xy 273.583291 -299.388396) (xy 273.553726 -299.42774)
			(xy 273.518233 -299.461832) (xy 273.47773 -299.489788) (xy 273.433268 -299.510886) (xy 273.385997 -299.524578)
			(xy 273.337142 -299.53051) (xy 273.287967 -299.528529) (xy 273.239748 -299.518685) (xy 273.193732 -299.501233)
			(xy 273.151111 -299.476626) (xy 273.11299 -299.445501) (xy 273.080355 -299.408664) (xy 273.054052 -299.367068)
			(xy 273.034761 -299.321792) (xy 273.022984 -299.274008) (xy 273.019024 -299.224954) (xy 272.705333 -299.224954)
			(xy 272.705333 -299.251007) (xy 272.697195 -299.302381) (xy 272.681121 -299.35185) (xy 272.657506 -299.398194)
			(xy 272.626931 -299.440273) (xy 272.590149 -299.477051) (xy 272.548067 -299.507622) (xy 272.50172 -299.531233)
			(xy 272.45225 -299.547303) (xy 272.400875 -299.555435) (xy 272.374868 -299.555916) (xy 271.424908 -299.555916)
			(xy 271.398895 -299.555525) (xy 271.347509 -299.547387) (xy 271.298028 -299.531311) (xy 271.251672 -299.507693)
			(xy 271.209581 -299.477113) (xy 271.172792 -299.440325) (xy 271.142212 -299.398235) (xy 271.118592 -299.351879)
			(xy 271.102514 -299.302399) (xy 271.094376 -299.251013) (xy 270.7794 -299.251013) (xy 270.779383 -299.251708)
			(xy 270.771002 -299.300958) (xy 270.7547 -299.34818) (xy 270.730912 -299.392111) (xy 270.715994 -299.412152)
			(xy 270.710914 -299.418756) (xy 270.699992 -299.450252) (xy 270.700124 -299.454269) (xy 270.701532 -299.462181)
			(xy 270.702786 -299.466) (xy 270.732758 -299.530516) (xy 270.744188 -299.555154) (xy 270.747744 -299.56125)
			(xy 270.750519 -299.565213) (xy 270.757299 -299.572112) (xy 270.761206 -299.574966) (xy 270.766794 -299.578268)
			(xy 270.776446 -299.582078) (xy 270.7894 -299.583856) (xy 270.80718 -299.583856) (xy 270.847869 -299.584297)
			(xy 270.928954 -299.591196) (xy 271.009168 -299.604914) (xy 271.087938 -299.625351) (xy 271.126458 -299.638466)
			(xy 271.146637 -299.645691) (xy 271.186403 -299.6617) (xy 271.20596 -299.67047) (xy 271.206214 -299.67047)
			(xy 271.216882 -299.67555) (xy 271.224502 -299.678852) (xy 271.231614 -299.682408) (xy 271.237202 -299.685456)
			(xy 271.240758 -299.687234) (xy 271.241012 -299.687234) (xy 271.243298 -299.688504) (xy 271.245838 -299.689774)
			(xy 271.2466 -299.690282) (xy 271.254474 -299.694346) (xy 271.254728 -299.694346) (xy 271.254982 -299.6946)
			(xy 271.255236 -299.6946) (xy 271.257014 -299.695616) (xy 271.257268 -299.695616) (xy 271.25803 -299.696124)
			(xy 271.258284 -299.696124) (xy 271.258792 -299.696378) (xy 271.262856 -299.698664) (xy 271.263364 -299.698918)
			(xy 271.285276 -299.710899) (xy 271.327969 -299.73682) (xy 271.348708 -299.750734) (xy 271.35201 -299.75302)
			(xy 271.387695 -299.778128) (xy 271.454858 -299.833836) (xy 271.486122 -299.864272) (xy 271.489932 -299.868082)
			(xy 271.492218 -299.870368) (xy 271.496195 -299.874083) (xy 271.505423 -299.879851) (xy 271.510506 -299.881798)
			(xy 271.513046 -299.88256) (xy 271.536914 -299.890287) (xy 271.581931 -299.912425) (xy 271.622723 -299.941623)
			(xy 271.658194 -299.977098) (xy 271.687389 -300.017893) (xy 271.709523 -300.062911) (xy 271.717262 -300.086776)
			(xy 271.718024 -300.089316) (xy 271.720162 -300.094705) (xy 271.726448 -300.104444) (xy 271.73047 -300.10862)
			(xy 271.733518 -300.111668) (xy 271.755694 -300.134134) (xy 271.797383 -300.181544) (xy 271.81683 -300.20641)
			(xy 271.819438 -300.209704) (xy 271.825568 -300.215448) (xy 271.829022 -300.21784) (xy 271.852471 -300.233574)
			(xy 271.897712 -300.267376) (xy 271.919446 -300.285404) (xy 271.939004 -300.30166) (xy 271.943322 -300.30293)
			(xy 271.949333 -300.302766) (xy 271.961019 -300.29995) (xy 271.966436 -300.297342) (xy 271.996408 -300.2788)
			(xy 271.996916 -300.2788) (xy 272.0467 -300.247558) (xy 272.048732 -300.246288) (xy 272.053812 -300.242478)
			(xy 272.062144 -300.234168) (xy 272.070854 -300.212335) (xy 272.070576 -300.200568) (xy 272.070322 -300.198028)
			(xy 272.06956 -300.176438) (xy 272.06956 -300.173898) (xy 272.070105 -300.149957) (xy 272.077735 -300.102685)
			(xy 272.092651 -300.057183) (xy 272.114487 -300.014567) (xy 272.142707 -299.975881) (xy 272.17662 -299.942076)
			(xy 272.215395 -299.913979) (xy 272.25808 -299.892278) (xy 272.303629 -299.877507) (xy 272.350926 -299.870028)
			(xy 272.374868 -299.869606) (xy 272.398862 -299.87005) (xy 272.446261 -299.877553) (xy 272.491902 -299.892379)
			(xy 272.534662 -299.914162) (xy 272.573486 -299.942368) (xy 272.607421 -299.9763) (xy 272.635628 -300.015123)
			(xy 272.657415 -300.057881) (xy 272.672243 -300.103522) (xy 272.679749 -300.15092) (xy 272.680176 -300.174914)
			(xy 272.680176 -300.175676) (xy 272.680031 -300.189663) (xy 272.677485 -300.21752) (xy 272.675096 -300.231302)
			(xy 272.67281 -300.243494) (xy 272.680176 -300.267624) (xy 272.748502 -300.33595) (xy 272.757744 -300.344092)
			(xy 272.78123 -300.351383) (xy 272.79346 -300.34992) (xy 272.793714 -300.34992) (xy 272.807553 -300.347454)
			(xy 272.835538 -300.344783) (xy 272.849594 -300.344586) (xy 272.850102 -300.344586) (xy 272.864094 -300.344801)
			(xy 272.891951 -300.347469) (xy 272.905728 -300.34992) (xy 272.906236 -300.34992) (xy 272.918469 -300.351422)
			(xy 272.941965 -300.344119) (xy 272.951194 -300.33595) (xy 273.010884 -300.27626) (xy 273.019027 -300.26702)
			(xy 273.026311 -300.243533) (xy 273.024854 -300.231302) (xy 273.024854 -300.230794) (xy 273.022387 -300.216955)
			(xy 273.019715 -300.18897) (xy 273.01952 -300.174914) (xy 273.020042 -300.149659) (xy 273.028355 -300.099837)
			(xy 273.044756 -300.052063) (xy 273.068797 -300.00764) (xy 273.099821 -299.96778) (xy 273.136983 -299.93357)
			(xy 273.179269 -299.905944) (xy 273.225525 -299.885654) (xy 273.27449 -299.873254) (xy 273.324828 -299.869083)
			(xy 273.375166 -299.873254) (xy 273.424131 -299.885654) (xy 273.470387 -299.905944) (xy 273.512673 -299.93357)
			(xy 273.549835 -299.96778) (xy 273.580859 -300.00764) (xy 273.6049 -300.052063) (xy 273.621301 -300.099837)
			(xy 273.629614 -300.149659) (xy 273.630136 -300.174914) (xy 273.629927 -300.188969) (xy 273.627253 -300.216953)
			(xy 273.624802 -300.230794) (xy 273.624802 -300.231302) (xy 273.623292 -300.243539) (xy 273.630576 -300.267053)
			(xy 273.638772 -300.27626) (xy 273.698462 -300.33595) (xy 273.707702 -300.3441) (xy 273.731191 -300.35141)
			(xy 273.74342 -300.34992) (xy 273.743674 -300.34992) (xy 273.757576 -300.347442) (xy 273.785688 -300.344767)
			(xy 273.799808 -300.344586) (xy 273.823786 -300.345056) (xy 273.871153 -300.352555) (xy 273.916765 -300.367368)
			(xy 273.959499 -300.38913) (xy 273.998306 -300.417305) (xy 274.032231 -300.451202) (xy 274.060438 -300.489985)
			(xy 274.082235 -300.532702) (xy 274.097086 -300.578302) (xy 274.104624 -300.625662) (xy 274.105116 -300.64964)
			(xy 274.105116 -300.650148) (xy 274.103592 -300.67885) (xy 274.103338 -300.68139) (xy 274.103338 -300.681898)
			(xy 274.102825 -300.692518) (xy 274.109386 -300.712719) (xy 274.116038 -300.721014) (xy 274.166584 -300.777148)
			(xy 274.174099 -300.784812) (xy 274.193704 -300.793504) (xy 274.20443 -300.793912) (xy 274.274788 -300.793912)
			(xy 274.290054 -300.794066) (xy 274.320457 -300.796861) (xy 274.335494 -300.7995) (xy 274.337018 -300.799754)
			(xy 274.341082 -300.800516) (xy 274.363688 -300.793404) (xy 274.439888 -300.720506) (xy 274.448016 -300.698154)
			(xy 274.446492 -300.686216) (xy 274.445504 -300.677169) (xy 274.444489 -300.658995) (xy 274.44446 -300.649894)
			(xy 274.444931 -300.625902) (xy 274.452438 -300.578509) (xy 274.467265 -300.532874) (xy 274.489049 -300.49012)
			(xy 274.517252 -300.451299) (xy 274.55118 -300.417368) (xy 274.589998 -300.389162) (xy 274.63275 -300.367375)
			(xy 274.678384 -300.352544) (xy 274.725776 -300.345033) (xy 274.749768 -300.344586) (xy 274.763823 -300.344793)
			(xy 274.791808 -300.347463) (xy 274.805648 -300.34992) (xy 274.806156 -300.34992) (xy 274.818387 -300.351417)
			(xy 274.841877 -300.344108) (xy 274.851114 -300.33595) (xy 274.910804 -300.27626) (xy 274.918944 -300.267019)
			(xy 274.926225 -300.243533) (xy 274.924774 -300.231302) (xy 274.924774 -300.230794) (xy 274.922321 -300.217017)
			(xy 274.919651 -300.18916) (xy 274.91944 -300.175168) (xy 274.91944 -300.17466) (xy 274.919657 -300.160669)
			(xy 274.922329 -300.132812) (xy 274.924774 -300.119034) (xy 274.924774 -300.118526) (xy 274.926267 -300.106296)
			(xy 274.918957 -300.082808) (xy 274.910804 -300.073568) (xy 274.851114 -300.013878) (xy 274.841874 -300.005729)
			(xy 274.818386 -299.998426) (xy 274.806156 -299.999908) (xy 274.805902 -299.999908) (xy 274.792 -300.002385)
			(xy 274.763887 -300.005058) (xy 274.749768 -300.005242) (xy 274.725777 -300.004769) (xy 274.678388 -299.997259)
			(xy 274.632756 -299.982429) (xy 274.590005 -299.960645) (xy 274.551188 -299.932441) (xy 274.51726 -299.898514)
			(xy 274.489056 -299.859697) (xy 274.467271 -299.816946) (xy 274.452441 -299.771314) (xy 274.444931 -299.723925)
			(xy 274.44446 -299.699934) (xy 274.444661 -299.685815) (xy 274.447334 -299.657704) (xy 274.449794 -299.6438)
			(xy 274.449794 -299.643292) (xy 274.451303 -299.631056) (xy 274.444017 -299.607544) (xy 274.435824 -299.598334)
			(xy 274.376388 -299.538644) (xy 274.367146 -299.530505) (xy 274.343661 -299.523219) (xy 274.33143 -299.524674)
			(xy 274.331176 -299.524674) (xy 274.317211 -299.527159) (xy 274.288971 -299.52983) (xy 274.274788 -299.530008)
			(xy 274.249967 -299.529521) (xy 274.20098 -299.521488) (xy 274.153938 -299.505636) (xy 274.11008 -299.482382)
			(xy 274.070562 -299.452339) (xy 274.036425 -299.416299) (xy 274.008568 -299.37521) (xy 273.987726 -299.330156)
			(xy 273.974447 -299.282324) (xy 273.969081 -299.232974) (xy 273.97177 -299.183405) (xy 273.982442 -299.134925)
			(xy 274.000818 -299.08881) (xy 274.026411 -299.046275) (xy 274.058549 -299.008441) (xy 274.096384 -298.976304)
			(xy 274.13892 -298.950712) (xy 274.185036 -298.932339) (xy 274.233517 -298.921668) (xy 274.283086 -298.918981)
			(xy 274.332436 -298.924349) (xy 274.380268 -298.93763) (xy 274.425321 -298.958474) (xy 274.466408 -298.986333)
			(xy 274.502447 -299.020471) (xy 274.532488 -299.05999) (xy 274.555741 -299.103849) (xy 274.571591 -299.150892)
			(xy 274.579622 -299.199879) (xy 274.580096 -299.2247) (xy 274.580092 -299.224954) (xy 275.868904 -299.224954)
			(xy 275.872864 -299.1759) (xy 275.884641 -299.128116) (xy 275.903932 -299.08284) (xy 275.930235 -299.041244)
			(xy 275.96287 -299.004407) (xy 276.000991 -298.973282) (xy 276.043612 -298.948675) (xy 276.089628 -298.931223)
			(xy 276.137847 -298.921379) (xy 276.187022 -298.919398) (xy 276.235877 -298.92533) (xy 276.283148 -298.939022)
			(xy 276.32761 -298.96012) (xy 276.368113 -298.988076) (xy 276.403606 -299.022168) (xy 276.433171 -299.061512)
			(xy 276.456042 -299.105089) (xy 276.471626 -299.15177) (xy 276.479521 -299.200347) (xy 276.480016 -299.224954)
			(xy 276.479521 -299.249561) (xy 276.471626 -299.298138) (xy 276.456042 -299.344819) (xy 276.433171 -299.388396)
			(xy 276.403606 -299.42774) (xy 276.368113 -299.461832) (xy 276.32761 -299.489788) (xy 276.283148 -299.510886)
			(xy 276.235877 -299.524578) (xy 276.187022 -299.53051) (xy 276.137847 -299.528529) (xy 276.089628 -299.518685)
			(xy 276.043612 -299.501233) (xy 276.000991 -299.476626) (xy 275.96287 -299.445501) (xy 275.930235 -299.408664)
			(xy 275.903932 -299.367068) (xy 275.884641 -299.321792) (xy 275.872864 -299.274008) (xy 275.868904 -299.224954)
			(xy 274.580092 -299.224954) (xy 274.579898 -299.238819) (xy 274.577231 -299.266931) (xy 274.574762 -299.280834)
			(xy 274.574762 -299.281342) (xy 274.573261 -299.293575) (xy 274.580564 -299.317071) (xy 274.588732 -299.3263)
			(xy 274.648168 -299.38599) (xy 274.657405 -299.394147) (xy 274.680897 -299.401462) (xy 274.693126 -299.39996)
			(xy 274.69338 -299.39996) (xy 274.707345 -299.397473) (xy 274.735585 -299.394798) (xy 274.749768 -299.394626)
			(xy 274.773762 -299.39507) (xy 274.821159 -299.402573) (xy 274.866799 -299.417399) (xy 274.909557 -299.439183)
			(xy 274.94838 -299.467389) (xy 274.982313 -299.501321) (xy 275.010518 -299.540145) (xy 275.032302 -299.582903)
			(xy 275.047128 -299.628543) (xy 275.05463 -299.67594) (xy 275.055076 -299.699934) (xy 275.054866 -299.713989)
			(xy 275.052191 -299.741972) (xy 275.049742 -299.755814) (xy 275.049742 -299.756322) (xy 275.048237 -299.768557)
			(xy 275.055531 -299.792061) (xy 275.063712 -299.80128) (xy 275.123402 -299.86097) (xy 275.13264 -299.869122)
			(xy 275.15613 -299.876425) (xy 275.16836 -299.87494) (xy 275.168614 -299.87494) (xy 275.182516 -299.872464)
			(xy 275.210629 -299.869792) (xy 275.224748 -299.869606) (xy 275.248736 -299.87008) (xy 275.296121 -299.877592)
			(xy 275.341748 -299.892424) (xy 275.384493 -299.914211) (xy 275.423304 -299.942415) (xy 275.457225 -299.976343)
			(xy 275.485422 -300.01516) (xy 275.5072 -300.057909) (xy 275.522022 -300.103539) (xy 275.529525 -300.150926)
			(xy 275.530056 -300.174914) (xy 275.529847 -300.188969) (xy 275.527173 -300.216953) (xy 275.524722 -300.230794)
			(xy 275.524722 -300.231302) (xy 275.523212 -300.243539) (xy 275.530497 -300.267051) (xy 275.538692 -300.27626)
			(xy 275.598382 -300.33595) (xy 275.607623 -300.344096) (xy 275.63111 -300.351396) (xy 275.64334 -300.34992)
			(xy 275.643594 -300.34992) (xy 275.657433 -300.347453) (xy 275.685418 -300.34478) (xy 275.699474 -300.344586)
			(xy 275.699982 -300.344586) (xy 275.713974 -300.3448) (xy 275.741831 -300.347466) (xy 275.755608 -300.34992)
			(xy 275.756116 -300.34992) (xy 275.76835 -300.351427) (xy 275.791854 -300.34413) (xy 275.801074 -300.33595)
			(xy 275.860764 -300.27626) (xy 275.868896 -300.267016) (xy 275.876168 -300.243533) (xy 275.874734 -300.231302)
			(xy 275.874734 -300.230794) (xy 275.872267 -300.216955) (xy 275.869596 -300.18897) (xy 275.8694 -300.174914)
			(xy 275.869885 -300.150094) (xy 275.877913 -300.101107) (xy 275.893762 -300.054064) (xy 275.917012 -300.010205)
			(xy 275.947051 -299.970685) (xy 275.983089 -299.936546) (xy 276.024175 -299.908686) (xy 276.069226 -299.887841)
			(xy 276.117057 -299.874559) (xy 276.166406 -299.869189) (xy 276.215974 -299.871875) (xy 276.264455 -299.882544)
			(xy 276.31057 -299.900917) (xy 276.353106 -299.926507) (xy 276.390942 -299.958643) (xy 276.42308 -299.996476)
			(xy 276.448674 -300.03901) (xy 276.467049 -300.085124) (xy 276.477722 -300.133604) (xy 276.480411 -300.183172)
			(xy 276.475046 -300.232521) (xy 276.461767 -300.280353) (xy 276.440925 -300.325406) (xy 276.413068 -300.366494)
			(xy 276.378932 -300.402534) (xy 276.339414 -300.432576) (xy 276.295556 -300.45583) (xy 276.248515 -300.471681)
			(xy 276.199528 -300.479713) (xy 276.174708 -300.480222) (xy 276.160653 -300.480014) (xy 276.132669 -300.477342)
			(xy 276.118828 -300.474888) (xy 276.11832 -300.474888) (xy 276.106089 -300.473397) (xy 276.082601 -300.480704)
			(xy 276.073362 -300.488858) (xy 276.013672 -300.548548) (xy 276.005516 -300.557786) (xy 275.998198 -300.581277)
			(xy 275.999702 -300.593506) (xy 275.999702 -300.594014) (xy 276.002168 -300.607853) (xy 276.004839 -300.635838)
			(xy 276.005036 -300.649894) (xy 276.004514 -300.675149) (xy 275.996201 -300.724971) (xy 275.9798 -300.772745)
			(xy 275.955759 -300.817168) (xy 275.924735 -300.857028) (xy 275.887573 -300.891238) (xy 275.845287 -300.918864)
			(xy 275.799031 -300.939154) (xy 275.750066 -300.951554) (xy 275.699728 -300.955725) (xy 275.64939 -300.951554)
			(xy 275.600425 -300.939154) (xy 275.554169 -300.918864) (xy 275.511883 -300.891238) (xy 275.474721 -300.857028)
			(xy 275.443697 -300.817168) (xy 275.419656 -300.772745) (xy 275.403255 -300.724971) (xy 275.394942 -300.675149)
			(xy 275.39442 -300.649894) (xy 275.394629 -300.635839) (xy 275.397301 -300.607855) (xy 275.399754 -300.594014)
			(xy 275.399754 -300.593506) (xy 275.401242 -300.581278) (xy 275.393924 -300.557798) (xy 275.385784 -300.548548)
			(xy 275.326094 -300.488858) (xy 275.316853 -300.480716) (xy 275.293366 -300.473425) (xy 275.281136 -300.474888)
			(xy 275.280882 -300.474888) (xy 275.267043 -300.477354) (xy 275.239058 -300.480024) (xy 275.225002 -300.480222)
			(xy 275.224494 -300.480222) (xy 275.210502 -300.480007) (xy 275.182645 -300.477338) (xy 275.168868 -300.474888)
			(xy 275.16836 -300.474888) (xy 275.156126 -300.473387) (xy 275.132624 -300.480681) (xy 275.123402 -300.488858)
			(xy 275.063712 -300.548548) (xy 275.055551 -300.557784) (xy 275.048226 -300.581277) (xy 275.049742 -300.593506)
			(xy 275.049742 -300.594014) (xy 275.052209 -300.607853) (xy 275.05488 -300.635838) (xy 275.055076 -300.649894)
			(xy 275.05463 -300.673887) (xy 275.047124 -300.721281) (xy 275.032296 -300.766917) (xy 275.01051 -300.809672)
			(xy 274.982304 -300.848492) (xy 274.948372 -300.882421) (xy 274.90955 -300.910624) (xy 274.866793 -300.932406)
			(xy 274.821156 -300.94723) (xy 274.773761 -300.954732) (xy 274.749768 -300.955202) (xy 274.740667 -300.955162)
			(xy 274.722495 -300.954143) (xy 274.713446 -300.95317) (xy 274.701508 -300.951646) (xy 274.679156 -300.959774)
			(xy 274.606258 -301.035974) (xy 274.599146 -301.05858) (xy 274.599908 -301.063406) (xy 274.602635 -301.078627)
			(xy 274.605564 -301.109412) (xy 274.60575 -301.124874) (xy 274.605592 -301.14014) (xy 274.602789 -301.170541)
			(xy 274.600162 -301.18558) (xy 274.599908 -301.187104) (xy 274.599146 -301.191168) (xy 274.606258 -301.213774)
			(xy 274.679156 -301.289974) (xy 274.701508 -301.298102) (xy 274.713446 -301.296578) (xy 274.722493 -301.295589)
			(xy 274.740667 -301.294572) (xy 274.749768 -301.294546) (xy 274.774594 -301.295029) (xy 274.823593 -301.303057)
			(xy 274.870647 -301.318907) (xy 274.914517 -301.342161) (xy 274.954046 -301.372206) (xy 274.988194 -301.408251)
			(xy 275.01606 -301.449346) (xy 275.036911 -301.494408) (xy 275.050196 -301.54225) (xy 275.055565 -301.591611)
			(xy 275.055118 -301.599854) (xy 275.393924 -301.599854) (xy 275.397884 -301.5508) (xy 275.409661 -301.503016)
			(xy 275.428952 -301.45774) (xy 275.455255 -301.416144) (xy 275.48789 -301.379307) (xy 275.526011 -301.348182)
			(xy 275.568632 -301.323575) (xy 275.614648 -301.306123) (xy 275.662867 -301.296279) (xy 275.712042 -301.294298)
			(xy 275.760897 -301.30023) (xy 275.808168 -301.313922) (xy 275.85263 -301.33502) (xy 275.893133 -301.362976)
			(xy 275.928626 -301.397068) (xy 275.958191 -301.436412) (xy 275.981062 -301.479989) (xy 275.996646 -301.52667)
			(xy 276.004541 -301.575247) (xy 276.005036 -301.599854) (xy 276.004541 -301.624461) (xy 275.996646 -301.673038)
			(xy 275.981062 -301.719719) (xy 275.958191 -301.763296) (xy 275.928626 -301.80264) (xy 275.893133 -301.836732)
			(xy 275.85263 -301.864688) (xy 275.808168 -301.885786) (xy 275.760897 -301.899478) (xy 275.712042 -301.90541)
			(xy 275.662867 -301.903429) (xy 275.614648 -301.893585) (xy 275.568632 -301.876133) (xy 275.526011 -301.851526)
			(xy 275.48789 -301.820401) (xy 275.455255 -301.783564) (xy 275.428952 -301.741968) (xy 275.409661 -301.696692)
			(xy 275.397884 -301.648908) (xy 275.393924 -301.599854) (xy 275.055118 -301.599854) (xy 275.052878 -301.64119)
			(xy 275.042205 -301.689681) (xy 275.023826 -301.735806) (xy 274.998228 -301.778351) (xy 274.966083 -301.816193)
			(xy 274.928239 -301.848336) (xy 274.885694 -301.873933) (xy 274.839568 -301.892309) (xy 274.791076 -301.90298)
			(xy 274.741497 -301.905665) (xy 274.692136 -301.900293) (xy 274.644295 -301.887006) (xy 274.599234 -301.866153)
			(xy 274.55814 -301.838285) (xy 274.522097 -301.804136) (xy 274.492053 -301.764605) (xy 274.468801 -301.720734)
			(xy 274.452954 -301.673679) (xy 274.444928 -301.62468) (xy 274.44446 -301.599854) (xy 274.444501 -301.590753)
			(xy 274.44552 -301.572581) (xy 274.446492 -301.563532) (xy 274.448016 -301.551594) (xy 274.439888 -301.529242)
			(xy 274.363688 -301.456344) (xy 274.341082 -301.449232) (xy 274.336256 -301.449994) (xy 274.321035 -301.452719)
			(xy 274.29025 -301.455643) (xy 274.274788 -301.455836) (xy 274.20443 -301.455836) (xy 274.193743 -301.456409)
			(xy 274.174206 -301.465084) (xy 274.166584 -301.4726) (xy 274.108672 -301.537116) (xy 274.102068 -301.556928)
			(xy 274.103084 -301.566834) (xy 274.103338 -301.567342) (xy 274.103338 -301.568866) (xy 274.105116 -301.5996)
			(xy 274.105116 -301.600108) (xy 274.10463 -301.624089) (xy 274.097098 -301.671456) (xy 274.082252 -301.717063)
			(xy 274.060458 -301.759787) (xy 274.032251 -301.798578) (xy 273.998326 -301.832481) (xy 273.959516 -301.860663)
			(xy 273.916777 -301.882429) (xy 273.871161 -301.897245) (xy 273.823789 -301.904746) (xy 273.799808 -301.905162)
			(xy 273.790704 -301.905063) (xy 273.772531 -301.903916) (xy 273.763486 -301.902876) (xy 273.751594 -301.90208)
			(xy 273.729205 -301.910164) (xy 273.72056 -301.91837) (xy 273.656044 -301.985934) (xy 273.649186 -302.00854)
			(xy 273.649948 -302.01362) (xy 273.652586 -302.028785) (xy 273.655381 -302.059442) (xy 273.655536 -302.074834)
			(xy 273.655312 -302.090555) (xy 273.652259 -302.12185) (xy 273.64944 -302.137318) (xy 273.64944 -302.138334)
			(xy 273.648932 -302.14062) (xy 273.656044 -302.16348) (xy 273.72056 -302.231298) (xy 273.729199 -302.239514)
			(xy 273.751592 -302.247606) (xy 273.763486 -302.246792) (xy 273.77253 -302.245744) (xy 273.790704 -302.2446)
			(xy 273.799808 -302.244506) (xy 273.823786 -302.244976) (xy 273.871151 -302.252476) (xy 273.916762 -302.267288)
			(xy 273.959495 -302.28905) (xy 273.9983 -302.317226) (xy 274.032223 -302.351123) (xy 274.060428 -302.389907)
			(xy 274.082223 -302.432624) (xy 274.09707 -302.478223) (xy 274.104605 -302.525583) (xy 274.105116 -302.54956)
			(xy 274.105116 -302.550068) (xy 274.103592 -302.57877) (xy 274.103338 -302.58131) (xy 274.103338 -302.581818)
			(xy 274.102829 -302.592437) (xy 274.109396 -302.612632) (xy 274.116038 -302.620934) (xy 274.166584 -302.677068)
			(xy 274.1741 -302.68473) (xy 274.193705 -302.693418) (xy 274.20443 -302.693832) (xy 274.274788 -302.693832)
			(xy 274.290054 -302.693986) (xy 274.320457 -302.696781) (xy 274.335494 -302.69942) (xy 274.337018 -302.699674)
			(xy 274.341082 -302.700436) (xy 274.363688 -302.693324) (xy 274.439888 -302.620426) (xy 274.448016 -302.598074)
			(xy 274.446492 -302.586136) (xy 274.445503 -302.577089) (xy 274.444487 -302.558915) (xy 274.44446 -302.549814)
			(xy 274.444945 -302.52499) (xy 274.452975 -302.475995) (xy 274.468826 -302.428945) (xy 274.492081 -302.385079)
			(xy 274.522126 -302.345554) (xy 274.55817 -302.31141) (xy 274.599263 -302.283547) (xy 274.644322 -302.2627)
			(xy 274.692161 -302.249417) (xy 274.741518 -302.244049) (xy 274.791094 -302.246737) (xy 274.839582 -302.257411)
			(xy 274.885704 -302.275788) (xy 274.928245 -302.301386) (xy 274.966084 -302.333529) (xy 274.998225 -302.37137)
			(xy 275.02382 -302.413912) (xy 275.042194 -302.460035) (xy 275.052865 -302.508524) (xy 275.055101 -302.549814)
			(xy 275.393924 -302.549814) (xy 275.397884 -302.50076) (xy 275.409661 -302.452976) (xy 275.428952 -302.4077)
			(xy 275.455255 -302.366104) (xy 275.48789 -302.329267) (xy 275.526011 -302.298142) (xy 275.568632 -302.273535)
			(xy 275.614648 -302.256083) (xy 275.662867 -302.246239) (xy 275.712042 -302.244258) (xy 275.760897 -302.25019)
			(xy 275.808168 -302.263882) (xy 275.85263 -302.28498) (xy 275.893133 -302.312936) (xy 275.928626 -302.347028)
			(xy 275.958191 -302.386372) (xy 275.981062 -302.429949) (xy 275.996646 -302.47663) (xy 276.004541 -302.525207)
			(xy 276.005036 -302.549814) (xy 276.343884 -302.549814) (xy 276.347844 -302.50076) (xy 276.359621 -302.452976)
			(xy 276.378912 -302.4077) (xy 276.405215 -302.366104) (xy 276.43785 -302.329267) (xy 276.475971 -302.298142)
			(xy 276.518592 -302.273535) (xy 276.564608 -302.256083) (xy 276.612827 -302.246239) (xy 276.662002 -302.244258)
			(xy 276.710857 -302.25019) (xy 276.758128 -302.263882) (xy 276.80259 -302.28498) (xy 276.843093 -302.312936)
			(xy 276.878586 -302.347028) (xy 276.908151 -302.386372) (xy 276.931022 -302.429949) (xy 276.946606 -302.47663)
			(xy 276.954501 -302.525207) (xy 276.954996 -302.549814) (xy 277.294098 -302.549814) (xy 277.298058 -302.50076)
			(xy 277.309835 -302.452976) (xy 277.329126 -302.4077) (xy 277.355429 -302.366104) (xy 277.388064 -302.329267)
			(xy 277.426185 -302.298142) (xy 277.468806 -302.273535) (xy 277.514822 -302.256083) (xy 277.563041 -302.246239)
			(xy 277.612216 -302.244258) (xy 277.661071 -302.25019) (xy 277.708342 -302.263882) (xy 277.752804 -302.28498)
			(xy 277.793307 -302.312936) (xy 277.8288 -302.347028) (xy 277.858365 -302.386372) (xy 277.881236 -302.429949)
			(xy 277.89682 -302.47663) (xy 277.904715 -302.525207) (xy 277.90521 -302.549814) (xy 277.904715 -302.574421)
			(xy 277.89682 -302.622998) (xy 277.881236 -302.669679) (xy 277.858365 -302.713256) (xy 277.8288 -302.7526)
			(xy 277.793307 -302.786692) (xy 277.752804 -302.814648) (xy 277.708342 -302.835746) (xy 277.661071 -302.849438)
			(xy 277.612216 -302.85537) (xy 277.563041 -302.853389) (xy 277.514822 -302.843545) (xy 277.468806 -302.826093)
			(xy 277.426185 -302.801486) (xy 277.388064 -302.770361) (xy 277.355429 -302.733524) (xy 277.329126 -302.691928)
			(xy 277.309835 -302.646652) (xy 277.298058 -302.598868) (xy 277.294098 -302.549814) (xy 276.954996 -302.549814)
			(xy 276.954501 -302.574421) (xy 276.946606 -302.622998) (xy 276.931022 -302.669679) (xy 276.908151 -302.713256)
			(xy 276.878586 -302.7526) (xy 276.843093 -302.786692) (xy 276.80259 -302.814648) (xy 276.758128 -302.835746)
			(xy 276.710857 -302.849438) (xy 276.662002 -302.85537) (xy 276.612827 -302.853389) (xy 276.564608 -302.843545)
			(xy 276.518592 -302.826093) (xy 276.475971 -302.801486) (xy 276.43785 -302.770361) (xy 276.405215 -302.733524)
			(xy 276.378912 -302.691928) (xy 276.359621 -302.646652) (xy 276.347844 -302.598868) (xy 276.343884 -302.549814)
			(xy 276.005036 -302.549814) (xy 276.004541 -302.574421) (xy 275.996646 -302.622998) (xy 275.981062 -302.669679)
			(xy 275.958191 -302.713256) (xy 275.928626 -302.7526) (xy 275.893133 -302.786692) (xy 275.85263 -302.814648)
			(xy 275.808168 -302.835746) (xy 275.760897 -302.849438) (xy 275.712042 -302.85537) (xy 275.662867 -302.853389)
			(xy 275.614648 -302.843545) (xy 275.568632 -302.826093) (xy 275.526011 -302.801486) (xy 275.48789 -302.770361)
			(xy 275.455255 -302.733524) (xy 275.428952 -302.691928) (xy 275.409661 -302.646652) (xy 275.397884 -302.598868)
			(xy 275.393924 -302.549814) (xy 275.055101 -302.549814) (xy 275.05555 -302.5581) (xy 275.05018 -302.607457)
			(xy 275.036894 -302.655295) (xy 275.016044 -302.700353) (xy 274.988179 -302.741444) (xy 274.954033 -302.777486)
			(xy 274.914506 -302.807529) (xy 274.870639 -302.830781) (xy 274.823588 -302.846629) (xy 274.774592 -302.854657)
			(xy 274.749768 -302.855122) (xy 274.740667 -302.855082) (xy 274.722495 -302.854063) (xy 274.713446 -302.85309)
			(xy 274.701508 -302.851566) (xy 274.679156 -302.859694) (xy 274.606258 -302.935894) (xy 274.599146 -302.9585)
			(xy 274.599908 -302.963326) (xy 274.602635 -302.978547) (xy 274.605561 -303.009332) (xy 274.60575 -303.024794)
			(xy 274.605595 -303.04006) (xy 274.6028 -303.070463) (xy 274.600162 -303.0855) (xy 274.599908 -303.087024)
			(xy 274.599146 -303.091088) (xy 274.606258 -303.113694) (xy 274.679156 -303.189894) (xy 274.701508 -303.198022)
			(xy 274.713446 -303.196498) (xy 274.722493 -303.195509) (xy 274.740667 -303.194492) (xy 274.749768 -303.194466)
			(xy 274.774592 -303.194949) (xy 274.823587 -303.202977) (xy 274.870637 -303.218825) (xy 274.914504 -303.242077)
			(xy 274.95403 -303.272119) (xy 274.988176 -303.308161) (xy 275.01604 -303.349252) (xy 275.03689 -303.39431)
			(xy 275.050174 -303.442148) (xy 275.055544 -303.491505) (xy 275.055096 -303.499774) (xy 275.393924 -303.499774)
			(xy 275.397884 -303.45072) (xy 275.409661 -303.402936) (xy 275.428952 -303.35766) (xy 275.455255 -303.316064)
			(xy 275.48789 -303.279227) (xy 275.526011 -303.248102) (xy 275.568632 -303.223495) (xy 275.614648 -303.206043)
			(xy 275.662867 -303.196199) (xy 275.712042 -303.194218) (xy 275.760897 -303.20015) (xy 275.808168 -303.213842)
			(xy 275.85263 -303.23494) (xy 275.893133 -303.262896) (xy 275.928626 -303.296988) (xy 275.958191 -303.336332)
			(xy 275.981062 -303.379909) (xy 275.996646 -303.42659) (xy 276.004541 -303.475167) (xy 276.005036 -303.499774)
			(xy 276.343884 -303.499774) (xy 276.347844 -303.45072) (xy 276.359621 -303.402936) (xy 276.378912 -303.35766)
			(xy 276.405215 -303.316064) (xy 276.43785 -303.279227) (xy 276.475971 -303.248102) (xy 276.518592 -303.223495)
			(xy 276.564608 -303.206043) (xy 276.612827 -303.196199) (xy 276.662002 -303.194218) (xy 276.710857 -303.20015)
			(xy 276.758128 -303.213842) (xy 276.80259 -303.23494) (xy 276.843093 -303.262896) (xy 276.878586 -303.296988)
			(xy 276.908151 -303.336332) (xy 276.931022 -303.379909) (xy 276.946606 -303.42659) (xy 276.954501 -303.475167)
			(xy 276.954996 -303.499774) (xy 277.294098 -303.499774) (xy 277.298058 -303.45072) (xy 277.309835 -303.402936)
			(xy 277.329126 -303.35766) (xy 277.355429 -303.316064) (xy 277.388064 -303.279227) (xy 277.426185 -303.248102)
			(xy 277.468806 -303.223495) (xy 277.514822 -303.206043) (xy 277.563041 -303.196199) (xy 277.612216 -303.194218)
			(xy 277.661071 -303.20015) (xy 277.708342 -303.213842) (xy 277.752804 -303.23494) (xy 277.793307 -303.262896)
			(xy 277.8288 -303.296988) (xy 277.858365 -303.336332) (xy 277.881236 -303.379909) (xy 277.89682 -303.42659)
			(xy 277.904715 -303.475167) (xy 277.90521 -303.499774) (xy 277.904715 -303.524381) (xy 277.89682 -303.572958)
			(xy 277.881236 -303.619639) (xy 277.858365 -303.663216) (xy 277.8288 -303.70256) (xy 277.793307 -303.736652)
			(xy 277.752804 -303.764608) (xy 277.708342 -303.785706) (xy 277.661071 -303.799398) (xy 277.612216 -303.80533)
			(xy 277.563041 -303.803349) (xy 277.514822 -303.793505) (xy 277.468806 -303.776053) (xy 277.426185 -303.751446)
			(xy 277.388064 -303.720321) (xy 277.355429 -303.683484) (xy 277.329126 -303.641888) (xy 277.309835 -303.596612)
			(xy 277.298058 -303.548828) (xy 277.294098 -303.499774) (xy 276.954996 -303.499774) (xy 276.954501 -303.524381)
			(xy 276.946606 -303.572958) (xy 276.931022 -303.619639) (xy 276.908151 -303.663216) (xy 276.878586 -303.70256)
			(xy 276.843093 -303.736652) (xy 276.80259 -303.764608) (xy 276.758128 -303.785706) (xy 276.710857 -303.799398)
			(xy 276.662002 -303.80533) (xy 276.612827 -303.803349) (xy 276.564608 -303.793505) (xy 276.518592 -303.776053)
			(xy 276.475971 -303.751446) (xy 276.43785 -303.720321) (xy 276.405215 -303.683484) (xy 276.378912 -303.641888)
			(xy 276.359621 -303.596612) (xy 276.347844 -303.548828) (xy 276.343884 -303.499774) (xy 276.005036 -303.499774)
			(xy 276.004541 -303.524381) (xy 275.996646 -303.572958) (xy 275.981062 -303.619639) (xy 275.958191 -303.663216)
			(xy 275.928626 -303.70256) (xy 275.893133 -303.736652) (xy 275.85263 -303.764608) (xy 275.808168 -303.785706)
			(xy 275.760897 -303.799398) (xy 275.712042 -303.80533) (xy 275.662867 -303.803349) (xy 275.614648 -303.793505)
			(xy 275.568632 -303.776053) (xy 275.526011 -303.751446) (xy 275.48789 -303.720321) (xy 275.455255 -303.683484)
			(xy 275.428952 -303.641888) (xy 275.409661 -303.596612) (xy 275.397884 -303.548828) (xy 275.393924 -303.499774)
			(xy 275.055096 -303.499774) (xy 275.052859 -303.54108) (xy 275.042187 -303.589567) (xy 275.023812 -303.63569)
			(xy 274.998217 -303.678231) (xy 274.966076 -303.716071) (xy 274.928236 -303.748213) (xy 274.885695 -303.773809)
			(xy 274.839573 -303.792186) (xy 274.791086 -303.802858) (xy 274.741511 -303.805545) (xy 274.692154 -303.800175)
			(xy 274.644316 -303.786892) (xy 274.599258 -303.766043) (xy 274.558166 -303.73818) (xy 274.522123 -303.704035)
			(xy 274.49208 -303.664509) (xy 274.468827 -303.620643) (xy 274.452978 -303.573593) (xy 274.44495 -303.524598)
			(xy 274.44446 -303.499774) (xy 274.4445 -303.490673) (xy 274.445518 -303.472501) (xy 274.446492 -303.463452)
			(xy 274.448016 -303.451514) (xy 274.439888 -303.429162) (xy 274.363688 -303.356264) (xy 274.341082 -303.349152)
			(xy 274.336256 -303.349914) (xy 274.321035 -303.35264) (xy 274.29025 -303.355564) (xy 274.274788 -303.355756)
			(xy 274.20443 -303.355756) (xy 274.193744 -303.35633) (xy 274.174208 -303.365007) (xy 274.166584 -303.37252)
			(xy 274.108672 -303.437036) (xy 274.102068 -303.456848) (xy 274.103084 -303.466754) (xy 274.103338 -303.467262)
			(xy 274.103338 -303.468786) (xy 274.105116 -303.49952) (xy 274.105116 -303.500028) (xy 274.104628 -303.524008)
			(xy 274.097094 -303.571372) (xy 274.082247 -303.616976) (xy 274.060451 -303.659698) (xy 274.032244 -303.698486)
			(xy 273.998319 -303.732387) (xy 273.95951 -303.760566) (xy 273.916773 -303.782331) (xy 273.871158 -303.797146)
			(xy 273.823788 -303.804646) (xy 273.799808 -303.805082) (xy 273.79064 -303.80499) (xy 273.77234 -303.803847)
			(xy 273.763232 -303.802796) (xy 273.762978 -303.802796) (xy 273.751171 -303.80197) (xy 273.728901 -303.809902)
			(xy 273.720306 -303.818036) (xy 273.65579 -303.8856) (xy 273.648678 -303.90846) (xy 273.65071 -303.920398)
			(xy 273.654686 -303.947434) (xy 273.65469 -303.974754) (xy 278.719038 -303.974754) (xy 278.722998 -303.9257)
			(xy 278.734775 -303.877916) (xy 278.754066 -303.83264) (xy 278.780369 -303.791044) (xy 278.813004 -303.754207)
			(xy 278.851125 -303.723082) (xy 278.893746 -303.698475) (xy 278.939762 -303.681023) (xy 278.987981 -303.671179)
			(xy 279.037156 -303.669198) (xy 279.086011 -303.67513) (xy 279.133282 -303.688822) (xy 279.177744 -303.70992)
			(xy 279.218247 -303.737876) (xy 279.25374 -303.771968) (xy 279.283305 -303.811312) (xy 279.306176 -303.854889)
			(xy 279.32176 -303.90157) (xy 279.329655 -303.950147) (xy 279.33015 -303.974754) (xy 279.668998 -303.974754)
			(xy 279.672958 -303.9257) (xy 279.684735 -303.877916) (xy 279.704026 -303.83264) (xy 279.730329 -303.791044)
			(xy 279.762964 -303.754207) (xy 279.801085 -303.723082) (xy 279.843706 -303.698475) (xy 279.889722 -303.681023)
			(xy 279.937941 -303.671179) (xy 279.987116 -303.669198) (xy 280.035971 -303.67513) (xy 280.083242 -303.688822)
			(xy 280.127704 -303.70992) (xy 280.168207 -303.737876) (xy 280.2037 -303.771968) (xy 280.233265 -303.811312)
			(xy 280.256136 -303.854889) (xy 280.27172 -303.90157) (xy 280.279615 -303.950147) (xy 280.28011 -303.974754)
			(xy 280.618958 -303.974754) (xy 280.622918 -303.9257) (xy 280.634695 -303.877916) (xy 280.653986 -303.83264)
			(xy 280.680289 -303.791044) (xy 280.712924 -303.754207) (xy 280.751045 -303.723082) (xy 280.793666 -303.698475)
			(xy 280.839682 -303.681023) (xy 280.887901 -303.671179) (xy 280.937076 -303.669198) (xy 280.985931 -303.67513)
			(xy 281.033202 -303.688822) (xy 281.077664 -303.70992) (xy 281.118167 -303.737876) (xy 281.15366 -303.771968)
			(xy 281.183225 -303.811312) (xy 281.206096 -303.854889) (xy 281.22168 -303.90157) (xy 281.229575 -303.950147)
			(xy 281.23007 -303.974754) (xy 281.229575 -303.999361) (xy 281.22168 -304.047938) (xy 281.206096 -304.094619)
			(xy 281.183225 -304.138196) (xy 281.15366 -304.17754) (xy 281.118167 -304.211632) (xy 281.077664 -304.239588)
			(xy 281.033202 -304.260686) (xy 280.985931 -304.274378) (xy 280.937076 -304.28031) (xy 280.887901 -304.278329)
			(xy 280.839682 -304.268485) (xy 280.793666 -304.251033) (xy 280.751045 -304.226426) (xy 280.712924 -304.195301)
			(xy 280.680289 -304.158464) (xy 280.653986 -304.116868) (xy 280.634695 -304.071592) (xy 280.622918 -304.023808)
			(xy 280.618958 -303.974754) (xy 280.28011 -303.974754) (xy 280.279615 -303.999361) (xy 280.27172 -304.047938)
			(xy 280.256136 -304.094619) (xy 280.233265 -304.138196) (xy 280.2037 -304.17754) (xy 280.168207 -304.211632)
			(xy 280.127704 -304.239588) (xy 280.083242 -304.260686) (xy 280.035971 -304.274378) (xy 279.987116 -304.28031)
			(xy 279.937941 -304.278329) (xy 279.889722 -304.268485) (xy 279.843706 -304.251033) (xy 279.801085 -304.226426)
			(xy 279.762964 -304.195301) (xy 279.730329 -304.158464) (xy 279.704026 -304.116868) (xy 279.684735 -304.071592)
			(xy 279.672958 -304.023808) (xy 279.668998 -303.974754) (xy 279.33015 -303.974754) (xy 279.329655 -303.999361)
			(xy 279.32176 -304.047938) (xy 279.306176 -304.094619) (xy 279.283305 -304.138196) (xy 279.25374 -304.17754)
			(xy 279.218247 -304.211632) (xy 279.177744 -304.239588) (xy 279.133282 -304.260686) (xy 279.086011 -304.274378)
			(xy 279.037156 -304.28031) (xy 278.987981 -304.278329) (xy 278.939762 -304.268485) (xy 278.893746 -304.251033)
			(xy 278.851125 -304.226426) (xy 278.813004 -304.195301) (xy 278.780369 -304.158464) (xy 278.754066 -304.116868)
			(xy 278.734775 -304.071592) (xy 278.722998 -304.023808) (xy 278.719038 -303.974754) (xy 273.65469 -303.974754)
			(xy 273.654694 -304.002076) (xy 273.65071 -304.02911) (xy 273.648678 -304.041048) (xy 273.65579 -304.063908)
			(xy 273.720306 -304.131472) (xy 273.728947 -304.139537) (xy 273.751183 -304.147477) (xy 273.762978 -304.146712)
			(xy 273.763232 -304.146712) (xy 273.77234 -304.145659) (xy 273.79064 -304.144518) (xy 273.799808 -304.144426)
			(xy 273.8238 -304.144873) (xy 273.871192 -304.152381) (xy 273.916827 -304.16721) (xy 273.959579 -304.188997)
			(xy 273.998397 -304.217203) (xy 274.032324 -304.251135) (xy 274.060525 -304.289957) (xy 274.082306 -304.332712)
			(xy 274.097129 -304.378349) (xy 274.10463 -304.425742) (xy 274.105116 -304.449734) (xy 274.103338 -304.481484)
			(xy 274.103338 -304.481992) (xy 274.10267 -304.492632) (xy 274.109244 -304.512893) (xy 274.116038 -304.521108)
			(xy 274.166584 -304.577496) (xy 274.174102 -304.585154) (xy 274.193706 -304.593837) (xy 274.20443 -304.59426)
			(xy 274.263612 -304.59426) (xy 274.265644 -304.594006) (xy 274.274788 -304.594006) (xy 274.28999 -304.594171)
			(xy 274.320265 -304.59697) (xy 274.33524 -304.599594) (xy 274.336256 -304.599594) (xy 274.341336 -304.60061)
			(xy 274.363942 -304.593498) (xy 274.431506 -304.528982) (xy 274.439577 -304.520344) (xy 274.447522 -304.498106)
			(xy 274.446746 -304.48631) (xy 274.446746 -304.486056) (xy 274.445697 -304.477012) (xy 274.444551 -304.458838)
			(xy 274.44446 -304.449734) (xy 274.444943 -304.424909) (xy 274.452971 -304.375913) (xy 274.468819 -304.328862)
			(xy 274.492071 -304.284994) (xy 274.522114 -304.245466) (xy 274.558157 -304.21132) (xy 274.599249 -304.183455)
			(xy 274.644308 -304.162605) (xy 274.692147 -304.14932) (xy 274.741505 -304.143949) (xy 274.791081 -304.146636)
			(xy 274.83957 -304.157307) (xy 274.885694 -304.175683) (xy 274.928236 -304.20128) (xy 274.966077 -304.233421)
			(xy 274.998219 -304.271262) (xy 275.023816 -304.313805) (xy 275.042192 -304.359928) (xy 275.052864 -304.408417)
			(xy 275.055103 -304.449734) (xy 275.393924 -304.449734) (xy 275.397884 -304.40068) (xy 275.409661 -304.352896)
			(xy 275.428952 -304.30762) (xy 275.455255 -304.266024) (xy 275.48789 -304.229187) (xy 275.526011 -304.198062)
			(xy 275.568632 -304.173455) (xy 275.614648 -304.156003) (xy 275.662867 -304.146159) (xy 275.712042 -304.144178)
			(xy 275.760897 -304.15011) (xy 275.808168 -304.163802) (xy 275.85263 -304.1849) (xy 275.893133 -304.212856)
			(xy 275.928626 -304.246948) (xy 275.958191 -304.286292) (xy 275.981062 -304.329869) (xy 275.996646 -304.37655)
			(xy 276.004541 -304.425127) (xy 276.005036 -304.449734) (xy 276.343884 -304.449734) (xy 276.347844 -304.40068)
			(xy 276.359621 -304.352896) (xy 276.378912 -304.30762) (xy 276.405215 -304.266024) (xy 276.43785 -304.229187)
			(xy 276.475971 -304.198062) (xy 276.518592 -304.173455) (xy 276.564608 -304.156003) (xy 276.612827 -304.146159)
			(xy 276.662002 -304.144178) (xy 276.710857 -304.15011) (xy 276.758128 -304.163802) (xy 276.80259 -304.1849)
			(xy 276.843093 -304.212856) (xy 276.878586 -304.246948) (xy 276.908151 -304.286292) (xy 276.931022 -304.329869)
			(xy 276.946606 -304.37655) (xy 276.954501 -304.425127) (xy 276.954996 -304.449734) (xy 277.294098 -304.449734)
			(xy 277.298058 -304.40068) (xy 277.309835 -304.352896) (xy 277.329126 -304.30762) (xy 277.355429 -304.266024)
			(xy 277.388064 -304.229187) (xy 277.426185 -304.198062) (xy 277.468806 -304.173455) (xy 277.514822 -304.156003)
			(xy 277.563041 -304.146159) (xy 277.612216 -304.144178) (xy 277.661071 -304.15011) (xy 277.708342 -304.163802)
			(xy 277.752804 -304.1849) (xy 277.793307 -304.212856) (xy 277.8288 -304.246948) (xy 277.858365 -304.286292)
			(xy 277.881236 -304.329869) (xy 277.89682 -304.37655) (xy 277.904715 -304.425127) (xy 277.90521 -304.449734)
			(xy 277.904715 -304.474341) (xy 277.89682 -304.522918) (xy 277.881236 -304.569599) (xy 277.858365 -304.613176)
			(xy 277.8288 -304.65252) (xy 277.793307 -304.686612) (xy 277.752804 -304.714568) (xy 277.708342 -304.735666)
			(xy 277.661071 -304.749358) (xy 277.612216 -304.75529) (xy 277.563041 -304.753309) (xy 277.514822 -304.743465)
			(xy 277.468806 -304.726013) (xy 277.426185 -304.701406) (xy 277.388064 -304.670281) (xy 277.355429 -304.633444)
			(xy 277.329126 -304.591848) (xy 277.309835 -304.546572) (xy 277.298058 -304.498788) (xy 277.294098 -304.449734)
			(xy 276.954996 -304.449734) (xy 276.954501 -304.474341) (xy 276.946606 -304.522918) (xy 276.931022 -304.569599)
			(xy 276.908151 -304.613176) (xy 276.878586 -304.65252) (xy 276.843093 -304.686612) (xy 276.80259 -304.714568)
			(xy 276.758128 -304.735666) (xy 276.710857 -304.749358) (xy 276.662002 -304.75529) (xy 276.612827 -304.753309)
			(xy 276.564608 -304.743465) (xy 276.518592 -304.726013) (xy 276.475971 -304.701406) (xy 276.43785 -304.670281)
			(xy 276.405215 -304.633444) (xy 276.378912 -304.591848) (xy 276.359621 -304.546572) (xy 276.347844 -304.498788)
			(xy 276.343884 -304.449734) (xy 276.005036 -304.449734) (xy 276.004541 -304.474341) (xy 275.996646 -304.522918)
			(xy 275.981062 -304.569599) (xy 275.958191 -304.613176) (xy 275.928626 -304.65252) (xy 275.893133 -304.686612)
			(xy 275.85263 -304.714568) (xy 275.808168 -304.735666) (xy 275.760897 -304.749358) (xy 275.712042 -304.75529)
			(xy 275.662867 -304.753309) (xy 275.614648 -304.743465) (xy 275.568632 -304.726013) (xy 275.526011 -304.701406)
			(xy 275.48789 -304.670281) (xy 275.455255 -304.633444) (xy 275.428952 -304.591848) (xy 275.409661 -304.546572)
			(xy 275.397884 -304.498788) (xy 275.393924 -304.449734) (xy 275.055103 -304.449734) (xy 275.055551 -304.457993)
			(xy 275.050181 -304.507351) (xy 275.036896 -304.55519) (xy 275.016046 -304.600249) (xy 274.988181 -304.641341)
			(xy 274.954035 -304.677384) (xy 274.914508 -304.707428) (xy 274.87064 -304.73068) (xy 274.823589 -304.746529)
			(xy 274.774593 -304.754557) (xy 274.749768 -304.755042) (xy 274.749514 -304.755042) (xy 274.724342 -304.754507)
			(xy 274.674685 -304.746215) (xy 274.650708 -304.738532) (xy 274.646898 -304.737262) (xy 274.639786 -304.735992)
			(xy 274.627502 -304.734633) (xy 274.604019 -304.742206) (xy 274.594828 -304.75047) (xy 274.586192 -304.75936)
			(xy 274.578826 -304.782982) (xy 274.58289 -304.803556) (xy 274.584414 -304.80762) (xy 274.584922 -304.809144)
			(xy 274.58543 -304.810668) (xy 274.591018 -304.827178) (xy 274.591018 -304.827686) (xy 274.592542 -304.832258)
			(xy 274.592542 -304.832512) (xy 274.594828 -304.839878) (xy 274.595844 -304.84318) (xy 274.596352 -304.845466)
			(xy 274.597622 -304.851054) (xy 274.598384 -304.85461) (xy 274.598384 -304.854864) (xy 274.5994 -304.859944)
			(xy 274.604226 -304.892456) (xy 274.604226 -304.892964) (xy 274.60448 -304.89525) (xy 274.60448 -304.89652)
			(xy 274.604734 -304.898298) (xy 274.604988 -304.902616) (xy 274.604988 -304.906426) (xy 274.605242 -304.908204)
			(xy 274.605242 -304.910236) (xy 274.605496 -304.911252) (xy 274.605496 -304.919634) (xy 274.605496 -304.92319)
			(xy 274.605496 -304.924714) (xy 278.719038 -304.924714) (xy 278.722998 -304.87566) (xy 278.734775 -304.827876)
			(xy 278.754066 -304.7826) (xy 278.780369 -304.741004) (xy 278.813004 -304.704167) (xy 278.851125 -304.673042)
			(xy 278.893746 -304.648435) (xy 278.939762 -304.630983) (xy 278.987981 -304.621139) (xy 279.037156 -304.619158)
			(xy 279.086011 -304.62509) (xy 279.133282 -304.638782) (xy 279.177744 -304.65988) (xy 279.218247 -304.687836)
			(xy 279.25374 -304.721928) (xy 279.283305 -304.761272) (xy 279.306176 -304.804849) (xy 279.32176 -304.85153)
			(xy 279.329655 -304.900107) (xy 279.33015 -304.924714) (xy 279.668998 -304.924714) (xy 279.672958 -304.87566)
			(xy 279.684735 -304.827876) (xy 279.704026 -304.7826) (xy 279.730329 -304.741004) (xy 279.762964 -304.704167)
			(xy 279.801085 -304.673042) (xy 279.843706 -304.648435) (xy 279.889722 -304.630983) (xy 279.937941 -304.621139)
			(xy 279.987116 -304.619158) (xy 280.035971 -304.62509) (xy 280.083242 -304.638782) (xy 280.127704 -304.65988)
			(xy 280.168207 -304.687836) (xy 280.2037 -304.721928) (xy 280.233265 -304.761272) (xy 280.256136 -304.804849)
			(xy 280.27172 -304.85153) (xy 280.279615 -304.900107) (xy 280.28011 -304.924714) (xy 280.618958 -304.924714)
			(xy 280.622918 -304.87566) (xy 280.634695 -304.827876) (xy 280.653986 -304.7826) (xy 280.680289 -304.741004)
			(xy 280.712924 -304.704167) (xy 280.751045 -304.673042) (xy 280.793666 -304.648435) (xy 280.839682 -304.630983)
			(xy 280.887901 -304.621139) (xy 280.937076 -304.619158) (xy 280.985931 -304.62509) (xy 281.033202 -304.638782)
			(xy 281.077664 -304.65988) (xy 281.118167 -304.687836) (xy 281.15366 -304.721928) (xy 281.183225 -304.761272)
			(xy 281.206096 -304.804849) (xy 281.22168 -304.85153) (xy 281.229575 -304.900107) (xy 281.23007 -304.924714)
			(xy 281.568918 -304.924714) (xy 281.572878 -304.87566) (xy 281.584655 -304.827876) (xy 281.603946 -304.7826)
			(xy 281.630249 -304.741004) (xy 281.662884 -304.704167) (xy 281.701005 -304.673042) (xy 281.743626 -304.648435)
			(xy 281.789642 -304.630983) (xy 281.837861 -304.621139) (xy 281.887036 -304.619158) (xy 281.935891 -304.62509)
			(xy 281.983162 -304.638782) (xy 282.027624 -304.65988) (xy 282.068127 -304.687836) (xy 282.10362 -304.721928)
			(xy 282.133185 -304.761272) (xy 282.156056 -304.804849) (xy 282.17164 -304.85153) (xy 282.179535 -304.900107)
			(xy 282.18003 -304.924714) (xy 282.519132 -304.924714) (xy 282.523092 -304.87566) (xy 282.534869 -304.827876)
			(xy 282.55416 -304.7826) (xy 282.580463 -304.741004) (xy 282.613098 -304.704167) (xy 282.651219 -304.673042)
			(xy 282.69384 -304.648435) (xy 282.739856 -304.630983) (xy 282.788075 -304.621139) (xy 282.83725 -304.619158)
			(xy 282.886105 -304.62509) (xy 282.933376 -304.638782) (xy 282.977838 -304.65988) (xy 283.018341 -304.687836)
			(xy 283.053834 -304.721928) (xy 283.083399 -304.761272) (xy 283.10627 -304.804849) (xy 283.121854 -304.85153)
			(xy 283.129749 -304.900107) (xy 283.130244 -304.924714) (xy 283.469092 -304.924714) (xy 283.473052 -304.87566)
			(xy 283.484829 -304.827876) (xy 283.50412 -304.7826) (xy 283.530423 -304.741004) (xy 283.563058 -304.704167)
			(xy 283.601179 -304.673042) (xy 283.6438 -304.648435) (xy 283.689816 -304.630983) (xy 283.738035 -304.621139)
			(xy 283.78721 -304.619158) (xy 283.836065 -304.62509) (xy 283.883336 -304.638782) (xy 283.927798 -304.65988)
			(xy 283.968301 -304.687836) (xy 284.003794 -304.721928) (xy 284.033359 -304.761272) (xy 284.05623 -304.804849)
			(xy 284.071814 -304.85153) (xy 284.079709 -304.900107) (xy 284.080204 -304.924714) (xy 284.419052 -304.924714)
			(xy 284.423012 -304.87566) (xy 284.434789 -304.827876) (xy 284.45408 -304.7826) (xy 284.480383 -304.741004)
			(xy 284.513018 -304.704167) (xy 284.551139 -304.673042) (xy 284.59376 -304.648435) (xy 284.639776 -304.630983)
			(xy 284.687995 -304.621139) (xy 284.73717 -304.619158) (xy 284.786025 -304.62509) (xy 284.833296 -304.638782)
			(xy 284.877758 -304.65988) (xy 284.918261 -304.687836) (xy 284.953754 -304.721928) (xy 284.983319 -304.761272)
			(xy 285.00619 -304.804849) (xy 285.021774 -304.85153) (xy 285.029669 -304.900107) (xy 285.030164 -304.924714)
			(xy 285.369012 -304.924714) (xy 285.372972 -304.87566) (xy 285.384749 -304.827876) (xy 285.40404 -304.7826)
			(xy 285.430343 -304.741004) (xy 285.462978 -304.704167) (xy 285.501099 -304.673042) (xy 285.54372 -304.648435)
			(xy 285.589736 -304.630983) (xy 285.637955 -304.621139) (xy 285.68713 -304.619158) (xy 285.735985 -304.62509)
			(xy 285.783256 -304.638782) (xy 285.827718 -304.65988) (xy 285.868221 -304.687836) (xy 285.903714 -304.721928)
			(xy 285.933279 -304.761272) (xy 285.95615 -304.804849) (xy 285.971734 -304.85153) (xy 285.979629 -304.900107)
			(xy 285.980124 -304.924714) (xy 286.318972 -304.924714) (xy 286.322932 -304.87566) (xy 286.334709 -304.827876)
			(xy 286.354 -304.7826) (xy 286.380303 -304.741004) (xy 286.412938 -304.704167) (xy 286.451059 -304.673042)
			(xy 286.49368 -304.648435) (xy 286.539696 -304.630983) (xy 286.587915 -304.621139) (xy 286.63709 -304.619158)
			(xy 286.685945 -304.62509) (xy 286.733216 -304.638782) (xy 286.777678 -304.65988) (xy 286.818181 -304.687836)
			(xy 286.853674 -304.721928) (xy 286.883239 -304.761272) (xy 286.90611 -304.804849) (xy 286.921694 -304.85153)
			(xy 286.929589 -304.900107) (xy 286.930084 -304.924714) (xy 287.268932 -304.924714) (xy 287.272892 -304.87566)
			(xy 287.284669 -304.827876) (xy 287.30396 -304.7826) (xy 287.330263 -304.741004) (xy 287.362898 -304.704167)
			(xy 287.401019 -304.673042) (xy 287.44364 -304.648435) (xy 287.489656 -304.630983) (xy 287.537875 -304.621139)
			(xy 287.58705 -304.619158) (xy 287.635905 -304.62509) (xy 287.683176 -304.638782) (xy 287.727638 -304.65988)
			(xy 287.768141 -304.687836) (xy 287.803634 -304.721928) (xy 287.833199 -304.761272) (xy 287.85607 -304.804849)
			(xy 287.871654 -304.85153) (xy 287.879549 -304.900107) (xy 287.880044 -304.924714) (xy 288.218892 -304.924714)
			(xy 288.222852 -304.87566) (xy 288.234629 -304.827876) (xy 288.25392 -304.7826) (xy 288.280223 -304.741004)
			(xy 288.312858 -304.704167) (xy 288.350979 -304.673042) (xy 288.3936 -304.648435) (xy 288.439616 -304.630983)
			(xy 288.487835 -304.621139) (xy 288.53701 -304.619158) (xy 288.585865 -304.62509) (xy 288.633136 -304.638782)
			(xy 288.677598 -304.65988) (xy 288.718101 -304.687836) (xy 288.753594 -304.721928) (xy 288.783159 -304.761272)
			(xy 288.80603 -304.804849) (xy 288.821614 -304.85153) (xy 288.829509 -304.900107) (xy 288.830004 -304.924714)
			(xy 289.169106 -304.924714) (xy 289.173066 -304.87566) (xy 289.184843 -304.827876) (xy 289.204134 -304.7826)
			(xy 289.230437 -304.741004) (xy 289.263072 -304.704167) (xy 289.301193 -304.673042) (xy 289.343814 -304.648435)
			(xy 289.38983 -304.630983) (xy 289.438049 -304.621139) (xy 289.487224 -304.619158) (xy 289.536079 -304.62509)
			(xy 289.58335 -304.638782) (xy 289.627812 -304.65988) (xy 289.668315 -304.687836) (xy 289.703808 -304.721928)
			(xy 289.733373 -304.761272) (xy 289.756244 -304.804849) (xy 289.771828 -304.85153) (xy 289.779723 -304.900107)
			(xy 289.780218 -304.924714) (xy 290.119066 -304.924714) (xy 290.123026 -304.87566) (xy 290.134803 -304.827876)
			(xy 290.154094 -304.7826) (xy 290.180397 -304.741004) (xy 290.213032 -304.704167) (xy 290.251153 -304.673042)
			(xy 290.293774 -304.648435) (xy 290.33979 -304.630983) (xy 290.388009 -304.621139) (xy 290.437184 -304.619158)
			(xy 290.486039 -304.62509) (xy 290.53331 -304.638782) (xy 290.577772 -304.65988) (xy 290.618275 -304.687836)
			(xy 290.653768 -304.721928) (xy 290.683333 -304.761272) (xy 290.706204 -304.804849) (xy 290.721788 -304.85153)
			(xy 290.729683 -304.900107) (xy 290.730178 -304.924714) (xy 292.018986 -304.924714) (xy 292.022946 -304.87566)
			(xy 292.034723 -304.827876) (xy 292.054014 -304.7826) (xy 292.080317 -304.741004) (xy 292.112952 -304.704167)
			(xy 292.151073 -304.673042) (xy 292.193694 -304.648435) (xy 292.23971 -304.630983) (xy 292.287929 -304.621139)
			(xy 292.337104 -304.619158) (xy 292.385959 -304.62509) (xy 292.43323 -304.638782) (xy 292.477692 -304.65988)
			(xy 292.518195 -304.687836) (xy 292.553688 -304.721928) (xy 292.583253 -304.761272) (xy 292.606124 -304.804849)
			(xy 292.621708 -304.85153) (xy 292.629603 -304.900107) (xy 292.630098 -304.924714) (xy 292.968946 -304.924714)
			(xy 292.972906 -304.87566) (xy 292.984683 -304.827876) (xy 293.003974 -304.7826) (xy 293.030277 -304.741004)
			(xy 293.062912 -304.704167) (xy 293.101033 -304.673042) (xy 293.143654 -304.648435) (xy 293.18967 -304.630983)
			(xy 293.237889 -304.621139) (xy 293.287064 -304.619158) (xy 293.335919 -304.62509) (xy 293.38319 -304.638782)
			(xy 293.427652 -304.65988) (xy 293.468155 -304.687836) (xy 293.503648 -304.721928) (xy 293.533213 -304.761272)
			(xy 293.556084 -304.804849) (xy 293.571668 -304.85153) (xy 293.579563 -304.900107) (xy 293.580058 -304.924714)
			(xy 293.918906 -304.924714) (xy 293.922866 -304.87566) (xy 293.934643 -304.827876) (xy 293.953934 -304.7826)
			(xy 293.980237 -304.741004) (xy 294.012872 -304.704167) (xy 294.050993 -304.673042) (xy 294.093614 -304.648435)
			(xy 294.13963 -304.630983) (xy 294.187849 -304.621139) (xy 294.237024 -304.619158) (xy 294.285879 -304.62509)
			(xy 294.33315 -304.638782) (xy 294.377612 -304.65988) (xy 294.418115 -304.687836) (xy 294.453608 -304.721928)
			(xy 294.483173 -304.761272) (xy 294.506044 -304.804849) (xy 294.521628 -304.85153) (xy 294.529523 -304.900107)
			(xy 294.530018 -304.924714) (xy 294.86912 -304.924714) (xy 294.87308 -304.87566) (xy 294.884857 -304.827876)
			(xy 294.904148 -304.7826) (xy 294.930451 -304.741004) (xy 294.963086 -304.704167) (xy 295.001207 -304.673042)
			(xy 295.043828 -304.648435) (xy 295.089844 -304.630983) (xy 295.138063 -304.621139) (xy 295.187238 -304.619158)
			(xy 295.236093 -304.62509) (xy 295.283364 -304.638782) (xy 295.327826 -304.65988) (xy 295.368329 -304.687836)
			(xy 295.403822 -304.721928) (xy 295.433387 -304.761272) (xy 295.456258 -304.804849) (xy 295.471842 -304.85153)
			(xy 295.479737 -304.900107) (xy 295.480232 -304.924714) (xy 295.81908 -304.924714) (xy 295.82304 -304.87566)
			(xy 295.834817 -304.827876) (xy 295.854108 -304.7826) (xy 295.880411 -304.741004) (xy 295.913046 -304.704167)
			(xy 295.951167 -304.673042) (xy 295.993788 -304.648435) (xy 296.039804 -304.630983) (xy 296.088023 -304.621139)
			(xy 296.137198 -304.619158) (xy 296.186053 -304.62509) (xy 296.233324 -304.638782) (xy 296.277786 -304.65988)
			(xy 296.318289 -304.687836) (xy 296.353782 -304.721928) (xy 296.383347 -304.761272) (xy 296.406218 -304.804849)
			(xy 296.421802 -304.85153) (xy 296.429697 -304.900107) (xy 296.430192 -304.924714) (xy 296.76904 -304.924714)
			(xy 296.773 -304.87566) (xy 296.784777 -304.827876) (xy 296.804068 -304.7826) (xy 296.830371 -304.741004)
			(xy 296.863006 -304.704167) (xy 296.901127 -304.673042) (xy 296.943748 -304.648435) (xy 296.989764 -304.630983)
			(xy 297.037983 -304.621139) (xy 297.087158 -304.619158) (xy 297.136013 -304.62509) (xy 297.183284 -304.638782)
			(xy 297.227746 -304.65988) (xy 297.268249 -304.687836) (xy 297.303742 -304.721928) (xy 297.333307 -304.761272)
			(xy 297.356178 -304.804849) (xy 297.371762 -304.85153) (xy 297.379657 -304.900107) (xy 297.380152 -304.924714)
			(xy 297.719 -304.924714) (xy 297.72296 -304.87566) (xy 297.734737 -304.827876) (xy 297.754028 -304.7826)
			(xy 297.780331 -304.741004) (xy 297.812966 -304.704167) (xy 297.851087 -304.673042) (xy 297.893708 -304.648435)
			(xy 297.939724 -304.630983) (xy 297.987943 -304.621139) (xy 298.037118 -304.619158) (xy 298.085973 -304.62509)
			(xy 298.133244 -304.638782) (xy 298.177706 -304.65988) (xy 298.218209 -304.687836) (xy 298.253702 -304.721928)
			(xy 298.283267 -304.761272) (xy 298.306138 -304.804849) (xy 298.321722 -304.85153) (xy 298.329617 -304.900107)
			(xy 298.330112 -304.924714) (xy 298.66896 -304.924714) (xy 298.67292 -304.87566) (xy 298.684697 -304.827876)
			(xy 298.703988 -304.7826) (xy 298.730291 -304.741004) (xy 298.762926 -304.704167) (xy 298.801047 -304.673042)
			(xy 298.843668 -304.648435) (xy 298.889684 -304.630983) (xy 298.937903 -304.621139) (xy 298.987078 -304.619158)
			(xy 299.035933 -304.62509) (xy 299.083204 -304.638782) (xy 299.127666 -304.65988) (xy 299.168169 -304.687836)
			(xy 299.203662 -304.721928) (xy 299.233227 -304.761272) (xy 299.256098 -304.804849) (xy 299.271682 -304.85153)
			(xy 299.279577 -304.900107) (xy 299.280072 -304.924714) (xy 299.61892 -304.924714) (xy 299.62288 -304.87566)
			(xy 299.634657 -304.827876) (xy 299.653948 -304.7826) (xy 299.680251 -304.741004) (xy 299.712886 -304.704167)
			(xy 299.751007 -304.673042) (xy 299.793628 -304.648435) (xy 299.839644 -304.630983) (xy 299.887863 -304.621139)
			(xy 299.937038 -304.619158) (xy 299.985893 -304.62509) (xy 300.033164 -304.638782) (xy 300.077626 -304.65988)
			(xy 300.118129 -304.687836) (xy 300.153622 -304.721928) (xy 300.183187 -304.761272) (xy 300.206058 -304.804849)
			(xy 300.221642 -304.85153) (xy 300.229537 -304.900107) (xy 300.230032 -304.924714) (xy 300.56888 -304.924714)
			(xy 300.57284 -304.87566) (xy 300.584617 -304.827876) (xy 300.603908 -304.7826) (xy 300.630211 -304.741004)
			(xy 300.662846 -304.704167) (xy 300.700967 -304.673042) (xy 300.743588 -304.648435) (xy 300.789604 -304.630983)
			(xy 300.837823 -304.621139) (xy 300.886998 -304.619158) (xy 300.935853 -304.62509) (xy 300.983124 -304.638782)
			(xy 301.027586 -304.65988) (xy 301.068089 -304.687836) (xy 301.103582 -304.721928) (xy 301.133147 -304.761272)
			(xy 301.156018 -304.804849) (xy 301.171602 -304.85153) (xy 301.179497 -304.900107) (xy 301.179992 -304.924714)
			(xy 301.179497 -304.949321) (xy 301.171602 -304.997898) (xy 301.156018 -305.044579) (xy 301.133147 -305.088156)
			(xy 301.103582 -305.1275) (xy 301.068089 -305.161592) (xy 301.027586 -305.189548) (xy 300.983124 -305.210646)
			(xy 300.935853 -305.224338) (xy 300.886998 -305.23027) (xy 300.837823 -305.228289) (xy 300.789604 -305.218445)
			(xy 300.743588 -305.200993) (xy 300.700967 -305.176386) (xy 300.662846 -305.145261) (xy 300.630211 -305.108424)
			(xy 300.603908 -305.066828) (xy 300.584617 -305.021552) (xy 300.57284 -304.973768) (xy 300.56888 -304.924714)
			(xy 300.230032 -304.924714) (xy 300.229537 -304.949321) (xy 300.221642 -304.997898) (xy 300.206058 -305.044579)
			(xy 300.183187 -305.088156) (xy 300.153622 -305.1275) (xy 300.118129 -305.161592) (xy 300.077626 -305.189548)
			(xy 300.033164 -305.210646) (xy 299.985893 -305.224338) (xy 299.937038 -305.23027) (xy 299.887863 -305.228289)
			(xy 299.839644 -305.218445) (xy 299.793628 -305.200993) (xy 299.751007 -305.176386) (xy 299.712886 -305.145261)
			(xy 299.680251 -305.108424) (xy 299.653948 -305.066828) (xy 299.634657 -305.021552) (xy 299.62288 -304.973768)
			(xy 299.61892 -304.924714) (xy 299.280072 -304.924714) (xy 299.279577 -304.949321) (xy 299.271682 -304.997898)
			(xy 299.256098 -305.044579) (xy 299.233227 -305.088156) (xy 299.203662 -305.1275) (xy 299.168169 -305.161592)
			(xy 299.127666 -305.189548) (xy 299.083204 -305.210646) (xy 299.035933 -305.224338) (xy 298.987078 -305.23027)
			(xy 298.937903 -305.228289) (xy 298.889684 -305.218445) (xy 298.843668 -305.200993) (xy 298.801047 -305.176386)
			(xy 298.762926 -305.145261) (xy 298.730291 -305.108424) (xy 298.703988 -305.066828) (xy 298.684697 -305.021552)
			(xy 298.67292 -304.973768) (xy 298.66896 -304.924714) (xy 298.330112 -304.924714) (xy 298.329617 -304.949321)
			(xy 298.321722 -304.997898) (xy 298.306138 -305.044579) (xy 298.283267 -305.088156) (xy 298.253702 -305.1275)
			(xy 298.218209 -305.161592) (xy 298.177706 -305.189548) (xy 298.133244 -305.210646) (xy 298.085973 -305.224338)
			(xy 298.037118 -305.23027) (xy 297.987943 -305.228289) (xy 297.939724 -305.218445) (xy 297.893708 -305.200993)
			(xy 297.851087 -305.176386) (xy 297.812966 -305.145261) (xy 297.780331 -305.108424) (xy 297.754028 -305.066828)
			(xy 297.734737 -305.021552) (xy 297.72296 -304.973768) (xy 297.719 -304.924714) (xy 297.380152 -304.924714)
			(xy 297.379657 -304.949321) (xy 297.371762 -304.997898) (xy 297.356178 -305.044579) (xy 297.333307 -305.088156)
			(xy 297.303742 -305.1275) (xy 297.268249 -305.161592) (xy 297.227746 -305.189548) (xy 297.183284 -305.210646)
			(xy 297.136013 -305.224338) (xy 297.087158 -305.23027) (xy 297.037983 -305.228289) (xy 296.989764 -305.218445)
			(xy 296.943748 -305.200993) (xy 296.901127 -305.176386) (xy 296.863006 -305.145261) (xy 296.830371 -305.108424)
			(xy 296.804068 -305.066828) (xy 296.784777 -305.021552) (xy 296.773 -304.973768) (xy 296.76904 -304.924714)
			(xy 296.430192 -304.924714) (xy 296.429697 -304.949321) (xy 296.421802 -304.997898) (xy 296.406218 -305.044579)
			(xy 296.383347 -305.088156) (xy 296.353782 -305.1275) (xy 296.318289 -305.161592) (xy 296.277786 -305.189548)
			(xy 296.233324 -305.210646) (xy 296.186053 -305.224338) (xy 296.137198 -305.23027) (xy 296.088023 -305.228289)
			(xy 296.039804 -305.218445) (xy 295.993788 -305.200993) (xy 295.951167 -305.176386) (xy 295.913046 -305.145261)
			(xy 295.880411 -305.108424) (xy 295.854108 -305.066828) (xy 295.834817 -305.021552) (xy 295.82304 -304.973768)
			(xy 295.81908 -304.924714) (xy 295.480232 -304.924714) (xy 295.479737 -304.949321) (xy 295.471842 -304.997898)
			(xy 295.456258 -305.044579) (xy 295.433387 -305.088156) (xy 295.403822 -305.1275) (xy 295.368329 -305.161592)
			(xy 295.327826 -305.189548) (xy 295.283364 -305.210646) (xy 295.236093 -305.224338) (xy 295.187238 -305.23027)
			(xy 295.138063 -305.228289) (xy 295.089844 -305.218445) (xy 295.043828 -305.200993) (xy 295.001207 -305.176386)
			(xy 294.963086 -305.145261) (xy 294.930451 -305.108424) (xy 294.904148 -305.066828) (xy 294.884857 -305.021552)
			(xy 294.87308 -304.973768) (xy 294.86912 -304.924714) (xy 294.530018 -304.924714) (xy 294.529523 -304.949321)
			(xy 294.521628 -304.997898) (xy 294.506044 -305.044579) (xy 294.483173 -305.088156) (xy 294.453608 -305.1275)
			(xy 294.418115 -305.161592) (xy 294.377612 -305.189548) (xy 294.33315 -305.210646) (xy 294.285879 -305.224338)
			(xy 294.237024 -305.23027) (xy 294.187849 -305.228289) (xy 294.13963 -305.218445) (xy 294.093614 -305.200993)
			(xy 294.050993 -305.176386) (xy 294.012872 -305.145261) (xy 293.980237 -305.108424) (xy 293.953934 -305.066828)
			(xy 293.934643 -305.021552) (xy 293.922866 -304.973768) (xy 293.918906 -304.924714) (xy 293.580058 -304.924714)
			(xy 293.579563 -304.949321) (xy 293.571668 -304.997898) (xy 293.556084 -305.044579) (xy 293.533213 -305.088156)
			(xy 293.503648 -305.1275) (xy 293.468155 -305.161592) (xy 293.427652 -305.189548) (xy 293.38319 -305.210646)
			(xy 293.335919 -305.224338) (xy 293.287064 -305.23027) (xy 293.237889 -305.228289) (xy 293.18967 -305.218445)
			(xy 293.143654 -305.200993) (xy 293.101033 -305.176386) (xy 293.062912 -305.145261) (xy 293.030277 -305.108424)
			(xy 293.003974 -305.066828) (xy 292.984683 -305.021552) (xy 292.972906 -304.973768) (xy 292.968946 -304.924714)
			(xy 292.630098 -304.924714) (xy 292.629603 -304.949321) (xy 292.621708 -304.997898) (xy 292.606124 -305.044579)
			(xy 292.583253 -305.088156) (xy 292.553688 -305.1275) (xy 292.518195 -305.161592) (xy 292.477692 -305.189548)
			(xy 292.43323 -305.210646) (xy 292.385959 -305.224338) (xy 292.337104 -305.23027) (xy 292.287929 -305.228289)
			(xy 292.23971 -305.218445) (xy 292.193694 -305.200993) (xy 292.151073 -305.176386) (xy 292.112952 -305.145261)
			(xy 292.080317 -305.108424) (xy 292.054014 -305.066828) (xy 292.034723 -305.021552) (xy 292.022946 -304.973768)
			(xy 292.018986 -304.924714) (xy 290.730178 -304.924714) (xy 290.729683 -304.949321) (xy 290.721788 -304.997898)
			(xy 290.706204 -305.044579) (xy 290.683333 -305.088156) (xy 290.653768 -305.1275) (xy 290.618275 -305.161592)
			(xy 290.577772 -305.189548) (xy 290.53331 -305.210646) (xy 290.486039 -305.224338) (xy 290.437184 -305.23027)
			(xy 290.388009 -305.228289) (xy 290.33979 -305.218445) (xy 290.293774 -305.200993) (xy 290.251153 -305.176386)
			(xy 290.213032 -305.145261) (xy 290.180397 -305.108424) (xy 290.154094 -305.066828) (xy 290.134803 -305.021552)
			(xy 290.123026 -304.973768) (xy 290.119066 -304.924714) (xy 289.780218 -304.924714) (xy 289.779723 -304.949321)
			(xy 289.771828 -304.997898) (xy 289.756244 -305.044579) (xy 289.733373 -305.088156) (xy 289.703808 -305.1275)
			(xy 289.668315 -305.161592) (xy 289.627812 -305.189548) (xy 289.58335 -305.210646) (xy 289.536079 -305.224338)
			(xy 289.487224 -305.23027) (xy 289.438049 -305.228289) (xy 289.38983 -305.218445) (xy 289.343814 -305.200993)
			(xy 289.301193 -305.176386) (xy 289.263072 -305.145261) (xy 289.230437 -305.108424) (xy 289.204134 -305.066828)
			(xy 289.184843 -305.021552) (xy 289.173066 -304.973768) (xy 289.169106 -304.924714) (xy 288.830004 -304.924714)
			(xy 288.829509 -304.949321) (xy 288.821614 -304.997898) (xy 288.80603 -305.044579) (xy 288.783159 -305.088156)
			(xy 288.753594 -305.1275) (xy 288.718101 -305.161592) (xy 288.677598 -305.189548) (xy 288.633136 -305.210646)
			(xy 288.585865 -305.224338) (xy 288.53701 -305.23027) (xy 288.487835 -305.228289) (xy 288.439616 -305.218445)
			(xy 288.3936 -305.200993) (xy 288.350979 -305.176386) (xy 288.312858 -305.145261) (xy 288.280223 -305.108424)
			(xy 288.25392 -305.066828) (xy 288.234629 -305.021552) (xy 288.222852 -304.973768) (xy 288.218892 -304.924714)
			(xy 287.880044 -304.924714) (xy 287.879549 -304.949321) (xy 287.871654 -304.997898) (xy 287.85607 -305.044579)
			(xy 287.833199 -305.088156) (xy 287.803634 -305.1275) (xy 287.768141 -305.161592) (xy 287.727638 -305.189548)
			(xy 287.683176 -305.210646) (xy 287.635905 -305.224338) (xy 287.58705 -305.23027) (xy 287.537875 -305.228289)
			(xy 287.489656 -305.218445) (xy 287.44364 -305.200993) (xy 287.401019 -305.176386) (xy 287.362898 -305.145261)
			(xy 287.330263 -305.108424) (xy 287.30396 -305.066828) (xy 287.284669 -305.021552) (xy 287.272892 -304.973768)
			(xy 287.268932 -304.924714) (xy 286.930084 -304.924714) (xy 286.929589 -304.949321) (xy 286.921694 -304.997898)
			(xy 286.90611 -305.044579) (xy 286.883239 -305.088156) (xy 286.853674 -305.1275) (xy 286.818181 -305.161592)
			(xy 286.777678 -305.189548) (xy 286.733216 -305.210646) (xy 286.685945 -305.224338) (xy 286.63709 -305.23027)
			(xy 286.587915 -305.228289) (xy 286.539696 -305.218445) (xy 286.49368 -305.200993) (xy 286.451059 -305.176386)
			(xy 286.412938 -305.145261) (xy 286.380303 -305.108424) (xy 286.354 -305.066828) (xy 286.334709 -305.021552)
			(xy 286.322932 -304.973768) (xy 286.318972 -304.924714) (xy 285.980124 -304.924714) (xy 285.979629 -304.949321)
			(xy 285.971734 -304.997898) (xy 285.95615 -305.044579) (xy 285.933279 -305.088156) (xy 285.903714 -305.1275)
			(xy 285.868221 -305.161592) (xy 285.827718 -305.189548) (xy 285.783256 -305.210646) (xy 285.735985 -305.224338)
			(xy 285.68713 -305.23027) (xy 285.637955 -305.228289) (xy 285.589736 -305.218445) (xy 285.54372 -305.200993)
			(xy 285.501099 -305.176386) (xy 285.462978 -305.145261) (xy 285.430343 -305.108424) (xy 285.40404 -305.066828)
			(xy 285.384749 -305.021552) (xy 285.372972 -304.973768) (xy 285.369012 -304.924714) (xy 285.030164 -304.924714)
			(xy 285.029669 -304.949321) (xy 285.021774 -304.997898) (xy 285.00619 -305.044579) (xy 284.983319 -305.088156)
			(xy 284.953754 -305.1275) (xy 284.918261 -305.161592) (xy 284.877758 -305.189548) (xy 284.833296 -305.210646)
			(xy 284.786025 -305.224338) (xy 284.73717 -305.23027) (xy 284.687995 -305.228289) (xy 284.639776 -305.218445)
			(xy 284.59376 -305.200993) (xy 284.551139 -305.176386) (xy 284.513018 -305.145261) (xy 284.480383 -305.108424)
			(xy 284.45408 -305.066828) (xy 284.434789 -305.021552) (xy 284.423012 -304.973768) (xy 284.419052 -304.924714)
			(xy 284.080204 -304.924714) (xy 284.079709 -304.949321) (xy 284.071814 -304.997898) (xy 284.05623 -305.044579)
			(xy 284.033359 -305.088156) (xy 284.003794 -305.1275) (xy 283.968301 -305.161592) (xy 283.927798 -305.189548)
			(xy 283.883336 -305.210646) (xy 283.836065 -305.224338) (xy 283.78721 -305.23027) (xy 283.738035 -305.228289)
			(xy 283.689816 -305.218445) (xy 283.6438 -305.200993) (xy 283.601179 -305.176386) (xy 283.563058 -305.145261)
			(xy 283.530423 -305.108424) (xy 283.50412 -305.066828) (xy 283.484829 -305.021552) (xy 283.473052 -304.973768)
			(xy 283.469092 -304.924714) (xy 283.130244 -304.924714) (xy 283.129749 -304.949321) (xy 283.121854 -304.997898)
			(xy 283.10627 -305.044579) (xy 283.083399 -305.088156) (xy 283.053834 -305.1275) (xy 283.018341 -305.161592)
			(xy 282.977838 -305.189548) (xy 282.933376 -305.210646) (xy 282.886105 -305.224338) (xy 282.83725 -305.23027)
			(xy 282.788075 -305.228289) (xy 282.739856 -305.218445) (xy 282.69384 -305.200993) (xy 282.651219 -305.176386)
			(xy 282.613098 -305.145261) (xy 282.580463 -305.108424) (xy 282.55416 -305.066828) (xy 282.534869 -305.021552)
			(xy 282.523092 -304.973768) (xy 282.519132 -304.924714) (xy 282.18003 -304.924714) (xy 282.179535 -304.949321)
			(xy 282.17164 -304.997898) (xy 282.156056 -305.044579) (xy 282.133185 -305.088156) (xy 282.10362 -305.1275)
			(xy 282.068127 -305.161592) (xy 282.027624 -305.189548) (xy 281.983162 -305.210646) (xy 281.935891 -305.224338)
			(xy 281.887036 -305.23027) (xy 281.837861 -305.228289) (xy 281.789642 -305.218445) (xy 281.743626 -305.200993)
			(xy 281.701005 -305.176386) (xy 281.662884 -305.145261) (xy 281.630249 -305.108424) (xy 281.603946 -305.066828)
			(xy 281.584655 -305.021552) (xy 281.572878 -304.973768) (xy 281.568918 -304.924714) (xy 281.23007 -304.924714)
			(xy 281.229575 -304.949321) (xy 281.22168 -304.997898) (xy 281.206096 -305.044579) (xy 281.183225 -305.088156)
			(xy 281.15366 -305.1275) (xy 281.118167 -305.161592) (xy 281.077664 -305.189548) (xy 281.033202 -305.210646)
			(xy 280.985931 -305.224338) (xy 280.937076 -305.23027) (xy 280.887901 -305.228289) (xy 280.839682 -305.218445)
			(xy 280.793666 -305.200993) (xy 280.751045 -305.176386) (xy 280.712924 -305.145261) (xy 280.680289 -305.108424)
			(xy 280.653986 -305.066828) (xy 280.634695 -305.021552) (xy 280.622918 -304.973768) (xy 280.618958 -304.924714)
			(xy 280.28011 -304.924714) (xy 280.279615 -304.949321) (xy 280.27172 -304.997898) (xy 280.256136 -305.044579)
			(xy 280.233265 -305.088156) (xy 280.2037 -305.1275) (xy 280.168207 -305.161592) (xy 280.127704 -305.189548)
			(xy 280.083242 -305.210646) (xy 280.035971 -305.224338) (xy 279.987116 -305.23027) (xy 279.937941 -305.228289)
			(xy 279.889722 -305.218445) (xy 279.843706 -305.200993) (xy 279.801085 -305.176386) (xy 279.762964 -305.145261)
			(xy 279.730329 -305.108424) (xy 279.704026 -305.066828) (xy 279.684735 -305.021552) (xy 279.672958 -304.973768)
			(xy 279.668998 -304.924714) (xy 279.33015 -304.924714) (xy 279.329655 -304.949321) (xy 279.32176 -304.997898)
			(xy 279.306176 -305.044579) (xy 279.283305 -305.088156) (xy 279.25374 -305.1275) (xy 279.218247 -305.161592)
			(xy 279.177744 -305.189548) (xy 279.133282 -305.210646) (xy 279.086011 -305.224338) (xy 279.037156 -305.23027)
			(xy 278.987981 -305.228289) (xy 278.939762 -305.218445) (xy 278.893746 -305.200993) (xy 278.851125 -305.176386)
			(xy 278.813004 -305.145261) (xy 278.780369 -305.108424) (xy 278.754066 -305.066828) (xy 278.734775 -305.021552)
			(xy 278.722998 -304.973768) (xy 278.719038 -304.924714) (xy 274.605496 -304.924714) (xy 274.605496 -304.925222)
			(xy 274.60534 -304.940488) (xy 274.602545 -304.970891) (xy 274.599908 -304.985928) (xy 274.599908 -304.98669)
			(xy 274.599146 -304.991262) (xy 274.606004 -305.013868) (xy 274.67052 -305.081432) (xy 274.679159 -305.089645)
			(xy 274.701552 -305.097722) (xy 274.713446 -305.096926) (xy 274.72249 -305.095877) (xy 274.740664 -305.094731)
			(xy 274.749768 -305.09464) (xy 274.774585 -305.095123) (xy 274.823565 -305.103148) (xy 274.870602 -305.118991)
			(xy 274.914456 -305.142234) (xy 274.953972 -305.172267) (xy 274.988109 -305.208297) (xy 275.015968 -305.249374)
			(xy 275.036814 -305.294418) (xy 275.050098 -305.342241) (xy 275.05547 -305.391582) (xy 275.055017 -305.399948)
			(xy 275.393924 -305.399948) (xy 275.397884 -305.350894) (xy 275.409661 -305.30311) (xy 275.428952 -305.257834)
			(xy 275.455255 -305.216238) (xy 275.48789 -305.179401) (xy 275.526011 -305.148276) (xy 275.568632 -305.123669)
			(xy 275.614648 -305.106217) (xy 275.662867 -305.096373) (xy 275.712042 -305.094392) (xy 275.760897 -305.100324)
			(xy 275.808168 -305.114016) (xy 275.85263 -305.135114) (xy 275.893133 -305.16307) (xy 275.928626 -305.197162)
			(xy 275.958191 -305.236506) (xy 275.981062 -305.280083) (xy 275.996646 -305.326764) (xy 276.004541 -305.375341)
			(xy 276.005036 -305.399948) (xy 276.343884 -305.399948) (xy 276.347844 -305.350894) (xy 276.359621 -305.30311)
			(xy 276.378912 -305.257834) (xy 276.405215 -305.216238) (xy 276.43785 -305.179401) (xy 276.475971 -305.148276)
			(xy 276.518592 -305.123669) (xy 276.564608 -305.106217) (xy 276.612827 -305.096373) (xy 276.662002 -305.094392)
			(xy 276.710857 -305.100324) (xy 276.758128 -305.114016) (xy 276.80259 -305.135114) (xy 276.843093 -305.16307)
			(xy 276.878586 -305.197162) (xy 276.908151 -305.236506) (xy 276.931022 -305.280083) (xy 276.946606 -305.326764)
			(xy 276.954501 -305.375341) (xy 276.954996 -305.399948) (xy 277.294098 -305.399948) (xy 277.298058 -305.350894)
			(xy 277.309835 -305.30311) (xy 277.329126 -305.257834) (xy 277.355429 -305.216238) (xy 277.388064 -305.179401)
			(xy 277.426185 -305.148276) (xy 277.468806 -305.123669) (xy 277.514822 -305.106217) (xy 277.563041 -305.096373)
			(xy 277.612216 -305.094392) (xy 277.661071 -305.100324) (xy 277.708342 -305.114016) (xy 277.752804 -305.135114)
			(xy 277.793307 -305.16307) (xy 277.8288 -305.197162) (xy 277.858365 -305.236506) (xy 277.881236 -305.280083)
			(xy 277.89682 -305.326764) (xy 277.904715 -305.375341) (xy 277.90521 -305.399948) (xy 277.904715 -305.424555)
			(xy 277.89682 -305.473132) (xy 277.881236 -305.519813) (xy 277.858365 -305.56339) (xy 277.8288 -305.602734)
			(xy 277.793307 -305.636826) (xy 277.752804 -305.664782) (xy 277.708342 -305.68588) (xy 277.661071 -305.699572)
			(xy 277.612216 -305.705504) (xy 277.563041 -305.703523) (xy 277.514822 -305.693679) (xy 277.468806 -305.676227)
			(xy 277.426185 -305.65162) (xy 277.388064 -305.620495) (xy 277.355429 -305.583658) (xy 277.329126 -305.542062)
			(xy 277.309835 -305.496786) (xy 277.298058 -305.449002) (xy 277.294098 -305.399948) (xy 276.954996 -305.399948)
			(xy 276.954501 -305.424555) (xy 276.946606 -305.473132) (xy 276.931022 -305.519813) (xy 276.908151 -305.56339)
			(xy 276.878586 -305.602734) (xy 276.843093 -305.636826) (xy 276.80259 -305.664782) (xy 276.758128 -305.68588)
			(xy 276.710857 -305.699572) (xy 276.662002 -305.705504) (xy 276.612827 -305.703523) (xy 276.564608 -305.693679)
			(xy 276.518592 -305.676227) (xy 276.475971 -305.65162) (xy 276.43785 -305.620495) (xy 276.405215 -305.583658)
			(xy 276.378912 -305.542062) (xy 276.359621 -305.496786) (xy 276.347844 -305.449002) (xy 276.343884 -305.399948)
			(xy 276.005036 -305.399948) (xy 276.004541 -305.424555) (xy 275.996646 -305.473132) (xy 275.981062 -305.519813)
			(xy 275.958191 -305.56339) (xy 275.928626 -305.602734) (xy 275.893133 -305.636826) (xy 275.85263 -305.664782)
			(xy 275.808168 -305.68588) (xy 275.760897 -305.699572) (xy 275.712042 -305.705504) (xy 275.662867 -305.703523)
			(xy 275.614648 -305.693679) (xy 275.568632 -305.676227) (xy 275.526011 -305.65162) (xy 275.48789 -305.620495)
			(xy 275.455255 -305.583658) (xy 275.428952 -305.542062) (xy 275.409661 -305.496786) (xy 275.397884 -305.449002)
			(xy 275.393924 -305.399948) (xy 275.055017 -305.399948) (xy 275.052789 -305.441143) (xy 275.042125 -305.489617)
			(xy 275.02376 -305.535728) (xy 274.998177 -305.57826) (xy 274.96605 -305.616093) (xy 274.928225 -305.64823)
			(xy 274.8857 -305.673824) (xy 274.839594 -305.692202) (xy 274.791123 -305.702878) (xy 274.741562 -305.705572)
			(xy 274.692219 -305.700213) (xy 274.644393 -305.686941) (xy 274.599344 -305.666107) (xy 274.558259 -305.63826)
			(xy 274.52222 -305.604132) (xy 274.492178 -305.564624) (xy 274.468922 -305.520776) (xy 274.453067 -305.473743)
			(xy 274.44503 -305.424765) (xy 274.44446 -305.399948) (xy 274.444558 -305.390844) (xy 274.445703 -305.372671)
			(xy 274.446746 -305.363626) (xy 274.447552 -305.35173) (xy 274.439482 -305.329326) (xy 274.431252 -305.3207)
			(xy 274.363688 -305.256184) (xy 274.341082 -305.249326) (xy 274.336002 -305.250088) (xy 274.320837 -305.252727)
			(xy 274.29018 -305.255525) (xy 274.274788 -305.255676) (xy 274.20443 -305.255676) (xy 274.193742 -305.256248)
			(xy 274.174197 -305.264915) (xy 274.166584 -305.27244) (xy 274.108672 -305.336956) (xy 274.102068 -305.356768)
			(xy 274.103084 -305.366674) (xy 274.103338 -305.367182) (xy 274.103338 -305.368706) (xy 274.105116 -305.399694)
			(xy 274.105116 -305.400202) (xy 274.104623 -305.424178) (xy 274.097079 -305.471534) (xy 274.082225 -305.517128)
			(xy 274.060426 -305.559839) (xy 274.032217 -305.598617) (xy 273.998293 -305.632509) (xy 273.959488 -305.66068)
			(xy 273.916756 -305.682438) (xy 273.871147 -305.697248) (xy 273.823784 -305.704746) (xy 273.799808 -305.705256)
			(xy 273.79064 -305.705164) (xy 273.77234 -305.70402) (xy 273.763232 -305.70297) (xy 273.762978 -305.70297)
			(xy 273.751172 -305.702145) (xy 273.72891 -305.710085) (xy 273.720306 -305.71821) (xy 273.65579 -305.785774)
			(xy 273.648678 -305.808634) (xy 273.65071 -305.820572) (xy 273.65468 -305.847607) (xy 273.654678 -305.874928)
			(xy 278.719038 -305.874928) (xy 278.722998 -305.825874) (xy 278.734775 -305.77809) (xy 278.754066 -305.732814)
			(xy 278.780369 -305.691218) (xy 278.813004 -305.654381) (xy 278.851125 -305.623256) (xy 278.893746 -305.598649)
			(xy 278.939762 -305.581197) (xy 278.987981 -305.571353) (xy 279.037156 -305.569372) (xy 279.086011 -305.575304)
			(xy 279.133282 -305.588996) (xy 279.177744 -305.610094) (xy 279.218247 -305.63805) (xy 279.25374 -305.672142)
			(xy 279.283305 -305.711486) (xy 279.306176 -305.755063) (xy 279.32176 -305.801744) (xy 279.329655 -305.850321)
			(xy 279.33015 -305.874928) (xy 279.668998 -305.874928) (xy 279.672958 -305.825874) (xy 279.684735 -305.77809)
			(xy 279.704026 -305.732814) (xy 279.730329 -305.691218) (xy 279.762964 -305.654381) (xy 279.801085 -305.623256)
			(xy 279.843706 -305.598649) (xy 279.889722 -305.581197) (xy 279.937941 -305.571353) (xy 279.987116 -305.569372)
			(xy 280.035971 -305.575304) (xy 280.083242 -305.588996) (xy 280.127704 -305.610094) (xy 280.168207 -305.63805)
			(xy 280.2037 -305.672142) (xy 280.233265 -305.711486) (xy 280.256136 -305.755063) (xy 280.27172 -305.801744)
			(xy 280.279615 -305.850321) (xy 280.28011 -305.874928) (xy 280.618958 -305.874928) (xy 280.622918 -305.825874)
			(xy 280.634695 -305.77809) (xy 280.653986 -305.732814) (xy 280.680289 -305.691218) (xy 280.712924 -305.654381)
			(xy 280.751045 -305.623256) (xy 280.793666 -305.598649) (xy 280.839682 -305.581197) (xy 280.887901 -305.571353)
			(xy 280.937076 -305.569372) (xy 280.985931 -305.575304) (xy 281.033202 -305.588996) (xy 281.077664 -305.610094)
			(xy 281.118167 -305.63805) (xy 281.15366 -305.672142) (xy 281.183225 -305.711486) (xy 281.206096 -305.755063)
			(xy 281.22168 -305.801744) (xy 281.229575 -305.850321) (xy 281.23007 -305.874928) (xy 281.568918 -305.874928)
			(xy 281.572878 -305.825874) (xy 281.584655 -305.77809) (xy 281.603946 -305.732814) (xy 281.630249 -305.691218)
			(xy 281.662884 -305.654381) (xy 281.701005 -305.623256) (xy 281.743626 -305.598649) (xy 281.789642 -305.581197)
			(xy 281.837861 -305.571353) (xy 281.887036 -305.569372) (xy 281.935891 -305.575304) (xy 281.983162 -305.588996)
			(xy 282.027624 -305.610094) (xy 282.068127 -305.63805) (xy 282.10362 -305.672142) (xy 282.133185 -305.711486)
			(xy 282.156056 -305.755063) (xy 282.17164 -305.801744) (xy 282.179535 -305.850321) (xy 282.18003 -305.874928)
			(xy 282.519132 -305.874928) (xy 282.523092 -305.825874) (xy 282.534869 -305.77809) (xy 282.55416 -305.732814)
			(xy 282.580463 -305.691218) (xy 282.613098 -305.654381) (xy 282.651219 -305.623256) (xy 282.69384 -305.598649)
			(xy 282.739856 -305.581197) (xy 282.788075 -305.571353) (xy 282.83725 -305.569372) (xy 282.886105 -305.575304)
			(xy 282.933376 -305.588996) (xy 282.977838 -305.610094) (xy 283.018341 -305.63805) (xy 283.053834 -305.672142)
			(xy 283.083399 -305.711486) (xy 283.10627 -305.755063) (xy 283.121854 -305.801744) (xy 283.129749 -305.850321)
			(xy 283.130244 -305.874928) (xy 283.469092 -305.874928) (xy 283.473052 -305.825874) (xy 283.484829 -305.77809)
			(xy 283.50412 -305.732814) (xy 283.530423 -305.691218) (xy 283.563058 -305.654381) (xy 283.601179 -305.623256)
			(xy 283.6438 -305.598649) (xy 283.689816 -305.581197) (xy 283.738035 -305.571353) (xy 283.78721 -305.569372)
			(xy 283.836065 -305.575304) (xy 283.883336 -305.588996) (xy 283.927798 -305.610094) (xy 283.968301 -305.63805)
			(xy 284.003794 -305.672142) (xy 284.033359 -305.711486) (xy 284.05623 -305.755063) (xy 284.071814 -305.801744)
			(xy 284.079709 -305.850321) (xy 284.080204 -305.874928) (xy 284.419052 -305.874928) (xy 284.423012 -305.825874)
			(xy 284.434789 -305.77809) (xy 284.45408 -305.732814) (xy 284.480383 -305.691218) (xy 284.513018 -305.654381)
			(xy 284.551139 -305.623256) (xy 284.59376 -305.598649) (xy 284.639776 -305.581197) (xy 284.687995 -305.571353)
			(xy 284.73717 -305.569372) (xy 284.786025 -305.575304) (xy 284.833296 -305.588996) (xy 284.877758 -305.610094)
			(xy 284.918261 -305.63805) (xy 284.953754 -305.672142) (xy 284.983319 -305.711486) (xy 285.00619 -305.755063)
			(xy 285.021774 -305.801744) (xy 285.029669 -305.850321) (xy 285.030164 -305.874928) (xy 285.369012 -305.874928)
			(xy 285.372972 -305.825874) (xy 285.384749 -305.77809) (xy 285.40404 -305.732814) (xy 285.430343 -305.691218)
			(xy 285.462978 -305.654381) (xy 285.501099 -305.623256) (xy 285.54372 -305.598649) (xy 285.589736 -305.581197)
			(xy 285.637955 -305.571353) (xy 285.68713 -305.569372) (xy 285.735985 -305.575304) (xy 285.783256 -305.588996)
			(xy 285.827718 -305.610094) (xy 285.868221 -305.63805) (xy 285.903714 -305.672142) (xy 285.933279 -305.711486)
			(xy 285.95615 -305.755063) (xy 285.971734 -305.801744) (xy 285.979629 -305.850321) (xy 285.980124 -305.874928)
			(xy 286.318972 -305.874928) (xy 286.322932 -305.825874) (xy 286.334709 -305.77809) (xy 286.354 -305.732814)
			(xy 286.380303 -305.691218) (xy 286.412938 -305.654381) (xy 286.451059 -305.623256) (xy 286.49368 -305.598649)
			(xy 286.539696 -305.581197) (xy 286.587915 -305.571353) (xy 286.63709 -305.569372) (xy 286.685945 -305.575304)
			(xy 286.733216 -305.588996) (xy 286.777678 -305.610094) (xy 286.818181 -305.63805) (xy 286.853674 -305.672142)
			(xy 286.883239 -305.711486) (xy 286.90611 -305.755063) (xy 286.921694 -305.801744) (xy 286.929589 -305.850321)
			(xy 286.930084 -305.874928) (xy 287.268932 -305.874928) (xy 287.272892 -305.825874) (xy 287.284669 -305.77809)
			(xy 287.30396 -305.732814) (xy 287.330263 -305.691218) (xy 287.362898 -305.654381) (xy 287.401019 -305.623256)
			(xy 287.44364 -305.598649) (xy 287.489656 -305.581197) (xy 287.537875 -305.571353) (xy 287.58705 -305.569372)
			(xy 287.635905 -305.575304) (xy 287.683176 -305.588996) (xy 287.727638 -305.610094) (xy 287.768141 -305.63805)
			(xy 287.803634 -305.672142) (xy 287.833199 -305.711486) (xy 287.85607 -305.755063) (xy 287.871654 -305.801744)
			(xy 287.879549 -305.850321) (xy 287.880044 -305.874928) (xy 288.218892 -305.874928) (xy 288.222852 -305.825874)
			(xy 288.234629 -305.77809) (xy 288.25392 -305.732814) (xy 288.280223 -305.691218) (xy 288.312858 -305.654381)
			(xy 288.350979 -305.623256) (xy 288.3936 -305.598649) (xy 288.439616 -305.581197) (xy 288.487835 -305.571353)
			(xy 288.53701 -305.569372) (xy 288.585865 -305.575304) (xy 288.633136 -305.588996) (xy 288.677598 -305.610094)
			(xy 288.718101 -305.63805) (xy 288.753594 -305.672142) (xy 288.783159 -305.711486) (xy 288.80603 -305.755063)
			(xy 288.821614 -305.801744) (xy 288.829509 -305.850321) (xy 288.830004 -305.874928) (xy 289.169106 -305.874928)
			(xy 289.173066 -305.825874) (xy 289.184843 -305.77809) (xy 289.204134 -305.732814) (xy 289.230437 -305.691218)
			(xy 289.263072 -305.654381) (xy 289.301193 -305.623256) (xy 289.343814 -305.598649) (xy 289.38983 -305.581197)
			(xy 289.438049 -305.571353) (xy 289.487224 -305.569372) (xy 289.536079 -305.575304) (xy 289.58335 -305.588996)
			(xy 289.627812 -305.610094) (xy 289.668315 -305.63805) (xy 289.703808 -305.672142) (xy 289.733373 -305.711486)
			(xy 289.756244 -305.755063) (xy 289.771828 -305.801744) (xy 289.779723 -305.850321) (xy 289.780218 -305.874928)
			(xy 290.119066 -305.874928) (xy 290.123026 -305.825874) (xy 290.134803 -305.77809) (xy 290.154094 -305.732814)
			(xy 290.180397 -305.691218) (xy 290.213032 -305.654381) (xy 290.251153 -305.623256) (xy 290.293774 -305.598649)
			(xy 290.33979 -305.581197) (xy 290.388009 -305.571353) (xy 290.437184 -305.569372) (xy 290.486039 -305.575304)
			(xy 290.53331 -305.588996) (xy 290.577772 -305.610094) (xy 290.618275 -305.63805) (xy 290.653768 -305.672142)
			(xy 290.683333 -305.711486) (xy 290.706204 -305.755063) (xy 290.721788 -305.801744) (xy 290.729683 -305.850321)
			(xy 290.730178 -305.874928) (xy 292.018986 -305.874928) (xy 292.022946 -305.825874) (xy 292.034723 -305.77809)
			(xy 292.054014 -305.732814) (xy 292.080317 -305.691218) (xy 292.112952 -305.654381) (xy 292.151073 -305.623256)
			(xy 292.193694 -305.598649) (xy 292.23971 -305.581197) (xy 292.287929 -305.571353) (xy 292.337104 -305.569372)
			(xy 292.385959 -305.575304) (xy 292.43323 -305.588996) (xy 292.477692 -305.610094) (xy 292.518195 -305.63805)
			(xy 292.553688 -305.672142) (xy 292.583253 -305.711486) (xy 292.606124 -305.755063) (xy 292.621708 -305.801744)
			(xy 292.629603 -305.850321) (xy 292.630098 -305.874928) (xy 292.968946 -305.874928) (xy 292.972906 -305.825874)
			(xy 292.984683 -305.77809) (xy 293.003974 -305.732814) (xy 293.030277 -305.691218) (xy 293.062912 -305.654381)
			(xy 293.101033 -305.623256) (xy 293.143654 -305.598649) (xy 293.18967 -305.581197) (xy 293.237889 -305.571353)
			(xy 293.287064 -305.569372) (xy 293.335919 -305.575304) (xy 293.38319 -305.588996) (xy 293.427652 -305.610094)
			(xy 293.468155 -305.63805) (xy 293.503648 -305.672142) (xy 293.533213 -305.711486) (xy 293.556084 -305.755063)
			(xy 293.571668 -305.801744) (xy 293.579563 -305.850321) (xy 293.580058 -305.874928) (xy 293.918906 -305.874928)
			(xy 293.922866 -305.825874) (xy 293.934643 -305.77809) (xy 293.953934 -305.732814) (xy 293.980237 -305.691218)
			(xy 294.012872 -305.654381) (xy 294.050993 -305.623256) (xy 294.093614 -305.598649) (xy 294.13963 -305.581197)
			(xy 294.187849 -305.571353) (xy 294.237024 -305.569372) (xy 294.285879 -305.575304) (xy 294.33315 -305.588996)
			(xy 294.377612 -305.610094) (xy 294.418115 -305.63805) (xy 294.453608 -305.672142) (xy 294.483173 -305.711486)
			(xy 294.506044 -305.755063) (xy 294.521628 -305.801744) (xy 294.529523 -305.850321) (xy 294.530018 -305.874928)
			(xy 294.86912 -305.874928) (xy 294.87308 -305.825874) (xy 294.884857 -305.77809) (xy 294.904148 -305.732814)
			(xy 294.930451 -305.691218) (xy 294.963086 -305.654381) (xy 295.001207 -305.623256) (xy 295.043828 -305.598649)
			(xy 295.089844 -305.581197) (xy 295.138063 -305.571353) (xy 295.187238 -305.569372) (xy 295.236093 -305.575304)
			(xy 295.283364 -305.588996) (xy 295.327826 -305.610094) (xy 295.368329 -305.63805) (xy 295.403822 -305.672142)
			(xy 295.433387 -305.711486) (xy 295.456258 -305.755063) (xy 295.471842 -305.801744) (xy 295.479737 -305.850321)
			(xy 295.480232 -305.874928) (xy 295.81908 -305.874928) (xy 295.82304 -305.825874) (xy 295.834817 -305.77809)
			(xy 295.854108 -305.732814) (xy 295.880411 -305.691218) (xy 295.913046 -305.654381) (xy 295.951167 -305.623256)
			(xy 295.993788 -305.598649) (xy 296.039804 -305.581197) (xy 296.088023 -305.571353) (xy 296.137198 -305.569372)
			(xy 296.186053 -305.575304) (xy 296.233324 -305.588996) (xy 296.277786 -305.610094) (xy 296.318289 -305.63805)
			(xy 296.353782 -305.672142) (xy 296.383347 -305.711486) (xy 296.406218 -305.755063) (xy 296.421802 -305.801744)
			(xy 296.429697 -305.850321) (xy 296.430192 -305.874928) (xy 296.76904 -305.874928) (xy 296.773 -305.825874)
			(xy 296.784777 -305.77809) (xy 296.804068 -305.732814) (xy 296.830371 -305.691218) (xy 296.863006 -305.654381)
			(xy 296.901127 -305.623256) (xy 296.943748 -305.598649) (xy 296.989764 -305.581197) (xy 297.037983 -305.571353)
			(xy 297.087158 -305.569372) (xy 297.136013 -305.575304) (xy 297.183284 -305.588996) (xy 297.227746 -305.610094)
			(xy 297.268249 -305.63805) (xy 297.303742 -305.672142) (xy 297.333307 -305.711486) (xy 297.356178 -305.755063)
			(xy 297.371762 -305.801744) (xy 297.379657 -305.850321) (xy 297.380152 -305.874928) (xy 297.719 -305.874928)
			(xy 297.72296 -305.825874) (xy 297.734737 -305.77809) (xy 297.754028 -305.732814) (xy 297.780331 -305.691218)
			(xy 297.812966 -305.654381) (xy 297.851087 -305.623256) (xy 297.893708 -305.598649) (xy 297.939724 -305.581197)
			(xy 297.987943 -305.571353) (xy 298.037118 -305.569372) (xy 298.085973 -305.575304) (xy 298.133244 -305.588996)
			(xy 298.177706 -305.610094) (xy 298.218209 -305.63805) (xy 298.253702 -305.672142) (xy 298.283267 -305.711486)
			(xy 298.306138 -305.755063) (xy 298.321722 -305.801744) (xy 298.329617 -305.850321) (xy 298.330112 -305.874928)
			(xy 298.66896 -305.874928) (xy 298.67292 -305.825874) (xy 298.684697 -305.77809) (xy 298.703988 -305.732814)
			(xy 298.730291 -305.691218) (xy 298.762926 -305.654381) (xy 298.801047 -305.623256) (xy 298.843668 -305.598649)
			(xy 298.889684 -305.581197) (xy 298.937903 -305.571353) (xy 298.987078 -305.569372) (xy 299.035933 -305.575304)
			(xy 299.083204 -305.588996) (xy 299.127666 -305.610094) (xy 299.168169 -305.63805) (xy 299.203662 -305.672142)
			(xy 299.233227 -305.711486) (xy 299.256098 -305.755063) (xy 299.271682 -305.801744) (xy 299.279577 -305.850321)
			(xy 299.280072 -305.874928) (xy 299.61892 -305.874928) (xy 299.62288 -305.825874) (xy 299.634657 -305.77809)
			(xy 299.653948 -305.732814) (xy 299.680251 -305.691218) (xy 299.712886 -305.654381) (xy 299.751007 -305.623256)
			(xy 299.793628 -305.598649) (xy 299.839644 -305.581197) (xy 299.887863 -305.571353) (xy 299.937038 -305.569372)
			(xy 299.985893 -305.575304) (xy 300.033164 -305.588996) (xy 300.077626 -305.610094) (xy 300.118129 -305.63805)
			(xy 300.153622 -305.672142) (xy 300.183187 -305.711486) (xy 300.206058 -305.755063) (xy 300.221642 -305.801744)
			(xy 300.229537 -305.850321) (xy 300.230032 -305.874928) (xy 300.56888 -305.874928) (xy 300.57284 -305.825874)
			(xy 300.584617 -305.77809) (xy 300.603908 -305.732814) (xy 300.630211 -305.691218) (xy 300.662846 -305.654381)
			(xy 300.700967 -305.623256) (xy 300.743588 -305.598649) (xy 300.789604 -305.581197) (xy 300.837823 -305.571353)
			(xy 300.886998 -305.569372) (xy 300.935853 -305.575304) (xy 300.983124 -305.588996) (xy 301.027586 -305.610094)
			(xy 301.068089 -305.63805) (xy 301.103582 -305.672142) (xy 301.133147 -305.711486) (xy 301.156018 -305.755063)
			(xy 301.171602 -305.801744) (xy 301.179497 -305.850321) (xy 301.179992 -305.874928) (xy 301.519094 -305.874928)
			(xy 301.523054 -305.825874) (xy 301.534831 -305.77809) (xy 301.554122 -305.732814) (xy 301.580425 -305.691218)
			(xy 301.61306 -305.654381) (xy 301.651181 -305.623256) (xy 301.693802 -305.598649) (xy 301.739818 -305.581197)
			(xy 301.788037 -305.571353) (xy 301.837212 -305.569372) (xy 301.886067 -305.575304) (xy 301.933338 -305.588996)
			(xy 301.9778 -305.610094) (xy 302.018303 -305.63805) (xy 302.053796 -305.672142) (xy 302.083361 -305.711486)
			(xy 302.106232 -305.755063) (xy 302.121816 -305.801744) (xy 302.129711 -305.850321) (xy 302.130206 -305.874928)
			(xy 302.469054 -305.874928) (xy 302.473014 -305.825874) (xy 302.484791 -305.77809) (xy 302.504082 -305.732814)
			(xy 302.530385 -305.691218) (xy 302.56302 -305.654381) (xy 302.601141 -305.623256) (xy 302.643762 -305.598649)
			(xy 302.689778 -305.581197) (xy 302.737997 -305.571353) (xy 302.787172 -305.569372) (xy 302.836027 -305.575304)
			(xy 302.883298 -305.588996) (xy 302.92776 -305.610094) (xy 302.968263 -305.63805) (xy 303.003756 -305.672142)
			(xy 303.033321 -305.711486) (xy 303.056192 -305.755063) (xy 303.071776 -305.801744) (xy 303.079671 -305.850321)
			(xy 303.080166 -305.874928) (xy 303.079671 -305.899535) (xy 303.071776 -305.948112) (xy 303.056192 -305.994793)
			(xy 303.033321 -306.03837) (xy 303.003756 -306.077714) (xy 302.968263 -306.111806) (xy 302.92776 -306.139762)
			(xy 302.883298 -306.16086) (xy 302.836027 -306.174552) (xy 302.787172 -306.180484) (xy 302.737997 -306.178503)
			(xy 302.689778 -306.168659) (xy 302.643762 -306.151207) (xy 302.601141 -306.1266) (xy 302.56302 -306.095475)
			(xy 302.530385 -306.058638) (xy 302.504082 -306.017042) (xy 302.484791 -305.971766) (xy 302.473014 -305.923982)
			(xy 302.469054 -305.874928) (xy 302.130206 -305.874928) (xy 302.129711 -305.899535) (xy 302.121816 -305.948112)
			(xy 302.106232 -305.994793) (xy 302.083361 -306.03837) (xy 302.053796 -306.077714) (xy 302.018303 -306.111806)
			(xy 301.9778 -306.139762) (xy 301.933338 -306.16086) (xy 301.886067 -306.174552) (xy 301.837212 -306.180484)
			(xy 301.788037 -306.178503) (xy 301.739818 -306.168659) (xy 301.693802 -306.151207) (xy 301.651181 -306.1266)
			(xy 301.61306 -306.095475) (xy 301.580425 -306.058638) (xy 301.554122 -306.017042) (xy 301.534831 -305.971766)
			(xy 301.523054 -305.923982) (xy 301.519094 -305.874928) (xy 301.179992 -305.874928) (xy 301.179497 -305.899535)
			(xy 301.171602 -305.948112) (xy 301.156018 -305.994793) (xy 301.133147 -306.03837) (xy 301.103582 -306.077714)
			(xy 301.068089 -306.111806) (xy 301.027586 -306.139762) (xy 300.983124 -306.16086) (xy 300.935853 -306.174552)
			(xy 300.886998 -306.180484) (xy 300.837823 -306.178503) (xy 300.789604 -306.168659) (xy 300.743588 -306.151207)
			(xy 300.700967 -306.1266) (xy 300.662846 -306.095475) (xy 300.630211 -306.058638) (xy 300.603908 -306.017042)
			(xy 300.584617 -305.971766) (xy 300.57284 -305.923982) (xy 300.56888 -305.874928) (xy 300.230032 -305.874928)
			(xy 300.229537 -305.899535) (xy 300.221642 -305.948112) (xy 300.206058 -305.994793) (xy 300.183187 -306.03837)
			(xy 300.153622 -306.077714) (xy 300.118129 -306.111806) (xy 300.077626 -306.139762) (xy 300.033164 -306.16086)
			(xy 299.985893 -306.174552) (xy 299.937038 -306.180484) (xy 299.887863 -306.178503) (xy 299.839644 -306.168659)
			(xy 299.793628 -306.151207) (xy 299.751007 -306.1266) (xy 299.712886 -306.095475) (xy 299.680251 -306.058638)
			(xy 299.653948 -306.017042) (xy 299.634657 -305.971766) (xy 299.62288 -305.923982) (xy 299.61892 -305.874928)
			(xy 299.280072 -305.874928) (xy 299.279577 -305.899535) (xy 299.271682 -305.948112) (xy 299.256098 -305.994793)
			(xy 299.233227 -306.03837) (xy 299.203662 -306.077714) (xy 299.168169 -306.111806) (xy 299.127666 -306.139762)
			(xy 299.083204 -306.16086) (xy 299.035933 -306.174552) (xy 298.987078 -306.180484) (xy 298.937903 -306.178503)
			(xy 298.889684 -306.168659) (xy 298.843668 -306.151207) (xy 298.801047 -306.1266) (xy 298.762926 -306.095475)
			(xy 298.730291 -306.058638) (xy 298.703988 -306.017042) (xy 298.684697 -305.971766) (xy 298.67292 -305.923982)
			(xy 298.66896 -305.874928) (xy 298.330112 -305.874928) (xy 298.329617 -305.899535) (xy 298.321722 -305.948112)
			(xy 298.306138 -305.994793) (xy 298.283267 -306.03837) (xy 298.253702 -306.077714) (xy 298.218209 -306.111806)
			(xy 298.177706 -306.139762) (xy 298.133244 -306.16086) (xy 298.085973 -306.174552) (xy 298.037118 -306.180484)
			(xy 297.987943 -306.178503) (xy 297.939724 -306.168659) (xy 297.893708 -306.151207) (xy 297.851087 -306.1266)
			(xy 297.812966 -306.095475) (xy 297.780331 -306.058638) (xy 297.754028 -306.017042) (xy 297.734737 -305.971766)
			(xy 297.72296 -305.923982) (xy 297.719 -305.874928) (xy 297.380152 -305.874928) (xy 297.379657 -305.899535)
			(xy 297.371762 -305.948112) (xy 297.356178 -305.994793) (xy 297.333307 -306.03837) (xy 297.303742 -306.077714)
			(xy 297.268249 -306.111806) (xy 297.227746 -306.139762) (xy 297.183284 -306.16086) (xy 297.136013 -306.174552)
			(xy 297.087158 -306.180484) (xy 297.037983 -306.178503) (xy 296.989764 -306.168659) (xy 296.943748 -306.151207)
			(xy 296.901127 -306.1266) (xy 296.863006 -306.095475) (xy 296.830371 -306.058638) (xy 296.804068 -306.017042)
			(xy 296.784777 -305.971766) (xy 296.773 -305.923982) (xy 296.76904 -305.874928) (xy 296.430192 -305.874928)
			(xy 296.429697 -305.899535) (xy 296.421802 -305.948112) (xy 296.406218 -305.994793) (xy 296.383347 -306.03837)
			(xy 296.353782 -306.077714) (xy 296.318289 -306.111806) (xy 296.277786 -306.139762) (xy 296.233324 -306.16086)
			(xy 296.186053 -306.174552) (xy 296.137198 -306.180484) (xy 296.088023 -306.178503) (xy 296.039804 -306.168659)
			(xy 295.993788 -306.151207) (xy 295.951167 -306.1266) (xy 295.913046 -306.095475) (xy 295.880411 -306.058638)
			(xy 295.854108 -306.017042) (xy 295.834817 -305.971766) (xy 295.82304 -305.923982) (xy 295.81908 -305.874928)
			(xy 295.480232 -305.874928) (xy 295.479737 -305.899535) (xy 295.471842 -305.948112) (xy 295.456258 -305.994793)
			(xy 295.433387 -306.03837) (xy 295.403822 -306.077714) (xy 295.368329 -306.111806) (xy 295.327826 -306.139762)
			(xy 295.283364 -306.16086) (xy 295.236093 -306.174552) (xy 295.187238 -306.180484) (xy 295.138063 -306.178503)
			(xy 295.089844 -306.168659) (xy 295.043828 -306.151207) (xy 295.001207 -306.1266) (xy 294.963086 -306.095475)
			(xy 294.930451 -306.058638) (xy 294.904148 -306.017042) (xy 294.884857 -305.971766) (xy 294.87308 -305.923982)
			(xy 294.86912 -305.874928) (xy 294.530018 -305.874928) (xy 294.529523 -305.899535) (xy 294.521628 -305.948112)
			(xy 294.506044 -305.994793) (xy 294.483173 -306.03837) (xy 294.453608 -306.077714) (xy 294.418115 -306.111806)
			(xy 294.377612 -306.139762) (xy 294.33315 -306.16086) (xy 294.285879 -306.174552) (xy 294.237024 -306.180484)
			(xy 294.187849 -306.178503) (xy 294.13963 -306.168659) (xy 294.093614 -306.151207) (xy 294.050993 -306.1266)
			(xy 294.012872 -306.095475) (xy 293.980237 -306.058638) (xy 293.953934 -306.017042) (xy 293.934643 -305.971766)
			(xy 293.922866 -305.923982) (xy 293.918906 -305.874928) (xy 293.580058 -305.874928) (xy 293.579563 -305.899535)
			(xy 293.571668 -305.948112) (xy 293.556084 -305.994793) (xy 293.533213 -306.03837) (xy 293.503648 -306.077714)
			(xy 293.468155 -306.111806) (xy 293.427652 -306.139762) (xy 293.38319 -306.16086) (xy 293.335919 -306.174552)
			(xy 293.287064 -306.180484) (xy 293.237889 -306.178503) (xy 293.18967 -306.168659) (xy 293.143654 -306.151207)
			(xy 293.101033 -306.1266) (xy 293.062912 -306.095475) (xy 293.030277 -306.058638) (xy 293.003974 -306.017042)
			(xy 292.984683 -305.971766) (xy 292.972906 -305.923982) (xy 292.968946 -305.874928) (xy 292.630098 -305.874928)
			(xy 292.629603 -305.899535) (xy 292.621708 -305.948112) (xy 292.606124 -305.994793) (xy 292.583253 -306.03837)
			(xy 292.553688 -306.077714) (xy 292.518195 -306.111806) (xy 292.477692 -306.139762) (xy 292.43323 -306.16086)
			(xy 292.385959 -306.174552) (xy 292.337104 -306.180484) (xy 292.287929 -306.178503) (xy 292.23971 -306.168659)
			(xy 292.193694 -306.151207) (xy 292.151073 -306.1266) (xy 292.112952 -306.095475) (xy 292.080317 -306.058638)
			(xy 292.054014 -306.017042) (xy 292.034723 -305.971766) (xy 292.022946 -305.923982) (xy 292.018986 -305.874928)
			(xy 290.730178 -305.874928) (xy 290.729683 -305.899535) (xy 290.721788 -305.948112) (xy 290.706204 -305.994793)
			(xy 290.683333 -306.03837) (xy 290.653768 -306.077714) (xy 290.618275 -306.111806) (xy 290.577772 -306.139762)
			(xy 290.53331 -306.16086) (xy 290.486039 -306.174552) (xy 290.437184 -306.180484) (xy 290.388009 -306.178503)
			(xy 290.33979 -306.168659) (xy 290.293774 -306.151207) (xy 290.251153 -306.1266) (xy 290.213032 -306.095475)
			(xy 290.180397 -306.058638) (xy 290.154094 -306.017042) (xy 290.134803 -305.971766) (xy 290.123026 -305.923982)
			(xy 290.119066 -305.874928) (xy 289.780218 -305.874928) (xy 289.779723 -305.899535) (xy 289.771828 -305.948112)
			(xy 289.756244 -305.994793) (xy 289.733373 -306.03837) (xy 289.703808 -306.077714) (xy 289.668315 -306.111806)
			(xy 289.627812 -306.139762) (xy 289.58335 -306.16086) (xy 289.536079 -306.174552) (xy 289.487224 -306.180484)
			(xy 289.438049 -306.178503) (xy 289.38983 -306.168659) (xy 289.343814 -306.151207) (xy 289.301193 -306.1266)
			(xy 289.263072 -306.095475) (xy 289.230437 -306.058638) (xy 289.204134 -306.017042) (xy 289.184843 -305.971766)
			(xy 289.173066 -305.923982) (xy 289.169106 -305.874928) (xy 288.830004 -305.874928) (xy 288.829509 -305.899535)
			(xy 288.821614 -305.948112) (xy 288.80603 -305.994793) (xy 288.783159 -306.03837) (xy 288.753594 -306.077714)
			(xy 288.718101 -306.111806) (xy 288.677598 -306.139762) (xy 288.633136 -306.16086) (xy 288.585865 -306.174552)
			(xy 288.53701 -306.180484) (xy 288.487835 -306.178503) (xy 288.439616 -306.168659) (xy 288.3936 -306.151207)
			(xy 288.350979 -306.1266) (xy 288.312858 -306.095475) (xy 288.280223 -306.058638) (xy 288.25392 -306.017042)
			(xy 288.234629 -305.971766) (xy 288.222852 -305.923982) (xy 288.218892 -305.874928) (xy 287.880044 -305.874928)
			(xy 287.879549 -305.899535) (xy 287.871654 -305.948112) (xy 287.85607 -305.994793) (xy 287.833199 -306.03837)
			(xy 287.803634 -306.077714) (xy 287.768141 -306.111806) (xy 287.727638 -306.139762) (xy 287.683176 -306.16086)
			(xy 287.635905 -306.174552) (xy 287.58705 -306.180484) (xy 287.537875 -306.178503) (xy 287.489656 -306.168659)
			(xy 287.44364 -306.151207) (xy 287.401019 -306.1266) (xy 287.362898 -306.095475) (xy 287.330263 -306.058638)
			(xy 287.30396 -306.017042) (xy 287.284669 -305.971766) (xy 287.272892 -305.923982) (xy 287.268932 -305.874928)
			(xy 286.930084 -305.874928) (xy 286.929589 -305.899535) (xy 286.921694 -305.948112) (xy 286.90611 -305.994793)
			(xy 286.883239 -306.03837) (xy 286.853674 -306.077714) (xy 286.818181 -306.111806) (xy 286.777678 -306.139762)
			(xy 286.733216 -306.16086) (xy 286.685945 -306.174552) (xy 286.63709 -306.180484) (xy 286.587915 -306.178503)
			(xy 286.539696 -306.168659) (xy 286.49368 -306.151207) (xy 286.451059 -306.1266) (xy 286.412938 -306.095475)
			(xy 286.380303 -306.058638) (xy 286.354 -306.017042) (xy 286.334709 -305.971766) (xy 286.322932 -305.923982)
			(xy 286.318972 -305.874928) (xy 285.980124 -305.874928) (xy 285.979629 -305.899535) (xy 285.971734 -305.948112)
			(xy 285.95615 -305.994793) (xy 285.933279 -306.03837) (xy 285.903714 -306.077714) (xy 285.868221 -306.111806)
			(xy 285.827718 -306.139762) (xy 285.783256 -306.16086) (xy 285.735985 -306.174552) (xy 285.68713 -306.180484)
			(xy 285.637955 -306.178503) (xy 285.589736 -306.168659) (xy 285.54372 -306.151207) (xy 285.501099 -306.1266)
			(xy 285.462978 -306.095475) (xy 285.430343 -306.058638) (xy 285.40404 -306.017042) (xy 285.384749 -305.971766)
			(xy 285.372972 -305.923982) (xy 285.369012 -305.874928) (xy 285.030164 -305.874928) (xy 285.029669 -305.899535)
			(xy 285.021774 -305.948112) (xy 285.00619 -305.994793) (xy 284.983319 -306.03837) (xy 284.953754 -306.077714)
			(xy 284.918261 -306.111806) (xy 284.877758 -306.139762) (xy 284.833296 -306.16086) (xy 284.786025 -306.174552)
			(xy 284.73717 -306.180484) (xy 284.687995 -306.178503) (xy 284.639776 -306.168659) (xy 284.59376 -306.151207)
			(xy 284.551139 -306.1266) (xy 284.513018 -306.095475) (xy 284.480383 -306.058638) (xy 284.45408 -306.017042)
			(xy 284.434789 -305.971766) (xy 284.423012 -305.923982) (xy 284.419052 -305.874928) (xy 284.080204 -305.874928)
			(xy 284.079709 -305.899535) (xy 284.071814 -305.948112) (xy 284.05623 -305.994793) (xy 284.033359 -306.03837)
			(xy 284.003794 -306.077714) (xy 283.968301 -306.111806) (xy 283.927798 -306.139762) (xy 283.883336 -306.16086)
			(xy 283.836065 -306.174552) (xy 283.78721 -306.180484) (xy 283.738035 -306.178503) (xy 283.689816 -306.168659)
			(xy 283.6438 -306.151207) (xy 283.601179 -306.1266) (xy 283.563058 -306.095475) (xy 283.530423 -306.058638)
			(xy 283.50412 -306.017042) (xy 283.484829 -305.971766) (xy 283.473052 -305.923982) (xy 283.469092 -305.874928)
			(xy 283.130244 -305.874928) (xy 283.129749 -305.899535) (xy 283.121854 -305.948112) (xy 283.10627 -305.994793)
			(xy 283.083399 -306.03837) (xy 283.053834 -306.077714) (xy 283.018341 -306.111806) (xy 282.977838 -306.139762)
			(xy 282.933376 -306.16086) (xy 282.886105 -306.174552) (xy 282.83725 -306.180484) (xy 282.788075 -306.178503)
			(xy 282.739856 -306.168659) (xy 282.69384 -306.151207) (xy 282.651219 -306.1266) (xy 282.613098 -306.095475)
			(xy 282.580463 -306.058638) (xy 282.55416 -306.017042) (xy 282.534869 -305.971766) (xy 282.523092 -305.923982)
			(xy 282.519132 -305.874928) (xy 282.18003 -305.874928) (xy 282.179535 -305.899535) (xy 282.17164 -305.948112)
			(xy 282.156056 -305.994793) (xy 282.133185 -306.03837) (xy 282.10362 -306.077714) (xy 282.068127 -306.111806)
			(xy 282.027624 -306.139762) (xy 281.983162 -306.16086) (xy 281.935891 -306.174552) (xy 281.887036 -306.180484)
			(xy 281.837861 -306.178503) (xy 281.789642 -306.168659) (xy 281.743626 -306.151207) (xy 281.701005 -306.1266)
			(xy 281.662884 -306.095475) (xy 281.630249 -306.058638) (xy 281.603946 -306.017042) (xy 281.584655 -305.971766)
			(xy 281.572878 -305.923982) (xy 281.568918 -305.874928) (xy 281.23007 -305.874928) (xy 281.229575 -305.899535)
			(xy 281.22168 -305.948112) (xy 281.206096 -305.994793) (xy 281.183225 -306.03837) (xy 281.15366 -306.077714)
			(xy 281.118167 -306.111806) (xy 281.077664 -306.139762) (xy 281.033202 -306.16086) (xy 280.985931 -306.174552)
			(xy 280.937076 -306.180484) (xy 280.887901 -306.178503) (xy 280.839682 -306.168659) (xy 280.793666 -306.151207)
			(xy 280.751045 -306.1266) (xy 280.712924 -306.095475) (xy 280.680289 -306.058638) (xy 280.653986 -306.017042)
			(xy 280.634695 -305.971766) (xy 280.622918 -305.923982) (xy 280.618958 -305.874928) (xy 280.28011 -305.874928)
			(xy 280.279615 -305.899535) (xy 280.27172 -305.948112) (xy 280.256136 -305.994793) (xy 280.233265 -306.03837)
			(xy 280.2037 -306.077714) (xy 280.168207 -306.111806) (xy 280.127704 -306.139762) (xy 280.083242 -306.16086)
			(xy 280.035971 -306.174552) (xy 279.987116 -306.180484) (xy 279.937941 -306.178503) (xy 279.889722 -306.168659)
			(xy 279.843706 -306.151207) (xy 279.801085 -306.1266) (xy 279.762964 -306.095475) (xy 279.730329 -306.058638)
			(xy 279.704026 -306.017042) (xy 279.684735 -305.971766) (xy 279.672958 -305.923982) (xy 279.668998 -305.874928)
			(xy 279.33015 -305.874928) (xy 279.329655 -305.899535) (xy 279.32176 -305.948112) (xy 279.306176 -305.994793)
			(xy 279.283305 -306.03837) (xy 279.25374 -306.077714) (xy 279.218247 -306.111806) (xy 279.177744 -306.139762)
			(xy 279.133282 -306.16086) (xy 279.086011 -306.174552) (xy 279.037156 -306.180484) (xy 278.987981 -306.178503)
			(xy 278.939762 -306.168659) (xy 278.893746 -306.151207) (xy 278.851125 -306.1266) (xy 278.813004 -306.095475)
			(xy 278.780369 -306.058638) (xy 278.754066 -306.017042) (xy 278.734775 -305.971766) (xy 278.722998 -305.923982)
			(xy 278.719038 -305.874928) (xy 273.654678 -305.874928) (xy 273.654676 -305.902248) (xy 273.65071 -305.929284)
			(xy 273.648678 -305.941222) (xy 273.65579 -305.964082) (xy 273.720306 -306.031646) (xy 273.728946 -306.039714)
			(xy 273.751182 -306.047658) (xy 273.762978 -306.046886) (xy 273.763232 -306.046886) (xy 273.77234 -306.045833)
			(xy 273.79064 -306.044691) (xy 273.799808 -306.0446) (xy 273.823786 -306.04507) (xy 273.871152 -306.052569)
			(xy 273.916763 -306.067382) (xy 273.959496 -306.089144) (xy 273.998302 -306.11732) (xy 274.032225 -306.151217)
			(xy 274.060431 -306.19) (xy 274.082226 -306.232717) (xy 274.097075 -306.278317) (xy 274.104611 -306.325676)
			(xy 274.105116 -306.349654) (xy 274.105116 -306.350162) (xy 274.103592 -306.379118) (xy 274.103338 -306.381658)
			(xy 274.103338 -306.382166) (xy 274.102818 -306.392789) (xy 274.10937 -306.412998) (xy 274.116038 -306.421282)
			(xy 274.166584 -306.477416) (xy 274.174097 -306.485084) (xy 274.193703 -306.493782) (xy 274.20443 -306.49418)
			(xy 274.274788 -306.49418) (xy 274.290117 -306.494328) (xy 274.320648 -306.497124) (xy 274.335748 -306.499768)
			(xy 274.33651 -306.499768) (xy 274.341082 -306.50053) (xy 274.363688 -306.493672) (xy 274.431252 -306.429156)
			(xy 274.439477 -306.42052) (xy 274.447583 -306.398124) (xy 274.446746 -306.38623) (xy 274.445697 -306.377186)
			(xy 274.444553 -306.359012) (xy 274.44446 -306.349908) (xy 274.444945 -306.325084) (xy 274.452977 -306.276089)
			(xy 274.468828 -306.22904) (xy 274.492084 -306.185175) (xy 274.522129 -306.14565) (xy 274.558173 -306.111507)
			(xy 274.599267 -306.083645) (xy 274.644326 -306.062798) (xy 274.692165 -306.049516) (xy 274.741523 -306.044149)
			(xy 274.791098 -306.046838) (xy 274.839585 -306.057512) (xy 274.885707 -306.07589) (xy 274.928247 -306.101488)
			(xy 274.966086 -306.133631) (xy 274.998226 -306.171472) (xy 275.023821 -306.214015) (xy 275.042195 -306.260138)
			(xy 275.052865 -306.308626) (xy 275.055101 -306.349908) (xy 275.393924 -306.349908) (xy 275.397884 -306.300854)
			(xy 275.409661 -306.25307) (xy 275.428952 -306.207794) (xy 275.455255 -306.166198) (xy 275.48789 -306.129361)
			(xy 275.526011 -306.098236) (xy 275.568632 -306.073629) (xy 275.614648 -306.056177) (xy 275.662867 -306.046333)
			(xy 275.712042 -306.044352) (xy 275.760897 -306.050284) (xy 275.808168 -306.063976) (xy 275.85263 -306.085074)
			(xy 275.893133 -306.11303) (xy 275.928626 -306.147122) (xy 275.958191 -306.186466) (xy 275.981062 -306.230043)
			(xy 275.996646 -306.276724) (xy 276.004541 -306.325301) (xy 276.005036 -306.349908) (xy 276.343884 -306.349908)
			(xy 276.347844 -306.300854) (xy 276.359621 -306.25307) (xy 276.378912 -306.207794) (xy 276.405215 -306.166198)
			(xy 276.43785 -306.129361) (xy 276.475971 -306.098236) (xy 276.518592 -306.073629) (xy 276.564608 -306.056177)
			(xy 276.612827 -306.046333) (xy 276.662002 -306.044352) (xy 276.710857 -306.050284) (xy 276.758128 -306.063976)
			(xy 276.80259 -306.085074) (xy 276.843093 -306.11303) (xy 276.878586 -306.147122) (xy 276.908151 -306.186466)
			(xy 276.931022 -306.230043) (xy 276.946606 -306.276724) (xy 276.954501 -306.325301) (xy 276.954996 -306.349908)
			(xy 277.294098 -306.349908) (xy 277.298058 -306.300854) (xy 277.309835 -306.25307) (xy 277.329126 -306.207794)
			(xy 277.355429 -306.166198) (xy 277.388064 -306.129361) (xy 277.426185 -306.098236) (xy 277.468806 -306.073629)
			(xy 277.514822 -306.056177) (xy 277.563041 -306.046333) (xy 277.612216 -306.044352) (xy 277.661071 -306.050284)
			(xy 277.708342 -306.063976) (xy 277.752804 -306.085074) (xy 277.793307 -306.11303) (xy 277.8288 -306.147122)
			(xy 277.858365 -306.186466) (xy 277.881236 -306.230043) (xy 277.89682 -306.276724) (xy 277.904715 -306.325301)
			(xy 277.90521 -306.349908) (xy 277.904715 -306.374515) (xy 277.89682 -306.423092) (xy 277.881236 -306.469773)
			(xy 277.858365 -306.51335) (xy 277.8288 -306.552694) (xy 277.793307 -306.586786) (xy 277.752804 -306.614742)
			(xy 277.708342 -306.63584) (xy 277.661071 -306.649532) (xy 277.612216 -306.655464) (xy 277.563041 -306.653483)
			(xy 277.514822 -306.643639) (xy 277.468806 -306.626187) (xy 277.426185 -306.60158) (xy 277.388064 -306.570455)
			(xy 277.355429 -306.533618) (xy 277.329126 -306.492022) (xy 277.309835 -306.446746) (xy 277.298058 -306.398962)
			(xy 277.294098 -306.349908) (xy 276.954996 -306.349908) (xy 276.954501 -306.374515) (xy 276.946606 -306.423092)
			(xy 276.931022 -306.469773) (xy 276.908151 -306.51335) (xy 276.878586 -306.552694) (xy 276.843093 -306.586786)
			(xy 276.80259 -306.614742) (xy 276.758128 -306.63584) (xy 276.710857 -306.649532) (xy 276.662002 -306.655464)
			(xy 276.612827 -306.653483) (xy 276.564608 -306.643639) (xy 276.518592 -306.626187) (xy 276.475971 -306.60158)
			(xy 276.43785 -306.570455) (xy 276.405215 -306.533618) (xy 276.378912 -306.492022) (xy 276.359621 -306.446746)
			(xy 276.347844 -306.398962) (xy 276.343884 -306.349908) (xy 276.005036 -306.349908) (xy 276.004541 -306.374515)
			(xy 275.996646 -306.423092) (xy 275.981062 -306.469773) (xy 275.958191 -306.51335) (xy 275.928626 -306.552694)
			(xy 275.893133 -306.586786) (xy 275.85263 -306.614742) (xy 275.808168 -306.63584) (xy 275.760897 -306.649532)
			(xy 275.712042 -306.655464) (xy 275.662867 -306.653483) (xy 275.614648 -306.643639) (xy 275.568632 -306.626187)
			(xy 275.526011 -306.60158) (xy 275.48789 -306.570455) (xy 275.455255 -306.533618) (xy 275.428952 -306.492022)
			(xy 275.409661 -306.446746) (xy 275.397884 -306.398962) (xy 275.393924 -306.349908) (xy 275.055101 -306.349908)
			(xy 275.05555 -306.358202) (xy 275.050179 -306.407558) (xy 275.036894 -306.455396) (xy 275.016044 -306.500454)
			(xy 274.988178 -306.541545) (xy 274.954032 -306.577587) (xy 274.914505 -306.607629) (xy 274.870638 -306.630881)
			(xy 274.823587 -306.646729) (xy 274.774592 -306.654757) (xy 274.749768 -306.655216) (xy 274.740664 -306.655118)
			(xy 274.722491 -306.653975) (xy 274.713446 -306.65293) (xy 274.701556 -306.652142) (xy 274.679177 -306.660234)
			(xy 274.67052 -306.668424) (xy 274.606004 -306.735988) (xy 274.599146 -306.758594) (xy 274.599908 -306.763674)
			(xy 274.602548 -306.778839) (xy 274.605348 -306.809496) (xy 274.605496 -306.824888) (xy 278.719038 -306.824888)
			(xy 278.722998 -306.775834) (xy 278.734775 -306.72805) (xy 278.754066 -306.682774) (xy 278.780369 -306.641178)
			(xy 278.813004 -306.604341) (xy 278.851125 -306.573216) (xy 278.893746 -306.548609) (xy 278.939762 -306.531157)
			(xy 278.987981 -306.521313) (xy 279.037156 -306.519332) (xy 279.086011 -306.525264) (xy 279.133282 -306.538956)
			(xy 279.177744 -306.560054) (xy 279.218247 -306.58801) (xy 279.25374 -306.622102) (xy 279.283305 -306.661446)
			(xy 279.306176 -306.705023) (xy 279.32176 -306.751704) (xy 279.329655 -306.800281) (xy 279.33015 -306.824888)
			(xy 279.668998 -306.824888) (xy 279.672958 -306.775834) (xy 279.684735 -306.72805) (xy 279.704026 -306.682774)
			(xy 279.730329 -306.641178) (xy 279.762964 -306.604341) (xy 279.801085 -306.573216) (xy 279.843706 -306.548609)
			(xy 279.889722 -306.531157) (xy 279.937941 -306.521313) (xy 279.987116 -306.519332) (xy 280.035971 -306.525264)
			(xy 280.083242 -306.538956) (xy 280.127704 -306.560054) (xy 280.168207 -306.58801) (xy 280.2037 -306.622102)
			(xy 280.233265 -306.661446) (xy 280.256136 -306.705023) (xy 280.27172 -306.751704) (xy 280.279615 -306.800281)
			(xy 280.28011 -306.824888) (xy 280.618958 -306.824888) (xy 280.622918 -306.775834) (xy 280.634695 -306.72805)
			(xy 280.653986 -306.682774) (xy 280.680289 -306.641178) (xy 280.712924 -306.604341) (xy 280.751045 -306.573216)
			(xy 280.793666 -306.548609) (xy 280.839682 -306.531157) (xy 280.887901 -306.521313) (xy 280.937076 -306.519332)
			(xy 280.985931 -306.525264) (xy 281.033202 -306.538956) (xy 281.077664 -306.560054) (xy 281.118167 -306.58801)
			(xy 281.15366 -306.622102) (xy 281.183225 -306.661446) (xy 281.206096 -306.705023) (xy 281.22168 -306.751704)
			(xy 281.229575 -306.800281) (xy 281.23007 -306.824888) (xy 281.568918 -306.824888) (xy 281.572878 -306.775834)
			(xy 281.584655 -306.72805) (xy 281.603946 -306.682774) (xy 281.630249 -306.641178) (xy 281.662884 -306.604341)
			(xy 281.701005 -306.573216) (xy 281.743626 -306.548609) (xy 281.789642 -306.531157) (xy 281.837861 -306.521313)
			(xy 281.887036 -306.519332) (xy 281.935891 -306.525264) (xy 281.983162 -306.538956) (xy 282.027624 -306.560054)
			(xy 282.068127 -306.58801) (xy 282.10362 -306.622102) (xy 282.133185 -306.661446) (xy 282.156056 -306.705023)
			(xy 282.17164 -306.751704) (xy 282.179535 -306.800281) (xy 282.18003 -306.824888) (xy 282.519132 -306.824888)
			(xy 282.523092 -306.775834) (xy 282.534869 -306.72805) (xy 282.55416 -306.682774) (xy 282.580463 -306.641178)
			(xy 282.613098 -306.604341) (xy 282.651219 -306.573216) (xy 282.69384 -306.548609) (xy 282.739856 -306.531157)
			(xy 282.788075 -306.521313) (xy 282.83725 -306.519332) (xy 282.886105 -306.525264) (xy 282.933376 -306.538956)
			(xy 282.977838 -306.560054) (xy 283.018341 -306.58801) (xy 283.053834 -306.622102) (xy 283.083399 -306.661446)
			(xy 283.10627 -306.705023) (xy 283.121854 -306.751704) (xy 283.129749 -306.800281) (xy 283.130244 -306.824888)
			(xy 283.469092 -306.824888) (xy 283.473052 -306.775834) (xy 283.484829 -306.72805) (xy 283.50412 -306.682774)
			(xy 283.530423 -306.641178) (xy 283.563058 -306.604341) (xy 283.601179 -306.573216) (xy 283.6438 -306.548609)
			(xy 283.689816 -306.531157) (xy 283.738035 -306.521313) (xy 283.78721 -306.519332) (xy 283.836065 -306.525264)
			(xy 283.883336 -306.538956) (xy 283.927798 -306.560054) (xy 283.968301 -306.58801) (xy 284.003794 -306.622102)
			(xy 284.033359 -306.661446) (xy 284.05623 -306.705023) (xy 284.071814 -306.751704) (xy 284.079709 -306.800281)
			(xy 284.080204 -306.824888) (xy 284.419052 -306.824888) (xy 284.423012 -306.775834) (xy 284.434789 -306.72805)
			(xy 284.45408 -306.682774) (xy 284.480383 -306.641178) (xy 284.513018 -306.604341) (xy 284.551139 -306.573216)
			(xy 284.59376 -306.548609) (xy 284.639776 -306.531157) (xy 284.687995 -306.521313) (xy 284.73717 -306.519332)
			(xy 284.786025 -306.525264) (xy 284.833296 -306.538956) (xy 284.877758 -306.560054) (xy 284.918261 -306.58801)
			(xy 284.953754 -306.622102) (xy 284.983319 -306.661446) (xy 285.00619 -306.705023) (xy 285.021774 -306.751704)
			(xy 285.029669 -306.800281) (xy 285.030164 -306.824888) (xy 285.369012 -306.824888) (xy 285.372972 -306.775834)
			(xy 285.384749 -306.72805) (xy 285.40404 -306.682774) (xy 285.430343 -306.641178) (xy 285.462978 -306.604341)
			(xy 285.501099 -306.573216) (xy 285.54372 -306.548609) (xy 285.589736 -306.531157) (xy 285.637955 -306.521313)
			(xy 285.68713 -306.519332) (xy 285.735985 -306.525264) (xy 285.783256 -306.538956) (xy 285.827718 -306.560054)
			(xy 285.868221 -306.58801) (xy 285.903714 -306.622102) (xy 285.933279 -306.661446) (xy 285.95615 -306.705023)
			(xy 285.971734 -306.751704) (xy 285.979629 -306.800281) (xy 285.980124 -306.824888) (xy 286.318972 -306.824888)
			(xy 286.322932 -306.775834) (xy 286.334709 -306.72805) (xy 286.354 -306.682774) (xy 286.380303 -306.641178)
			(xy 286.412938 -306.604341) (xy 286.451059 -306.573216) (xy 286.49368 -306.548609) (xy 286.539696 -306.531157)
			(xy 286.587915 -306.521313) (xy 286.63709 -306.519332) (xy 286.685945 -306.525264) (xy 286.733216 -306.538956)
			(xy 286.777678 -306.560054) (xy 286.818181 -306.58801) (xy 286.853674 -306.622102) (xy 286.883239 -306.661446)
			(xy 286.90611 -306.705023) (xy 286.921694 -306.751704) (xy 286.929589 -306.800281) (xy 286.930084 -306.824888)
			(xy 287.268932 -306.824888) (xy 287.272892 -306.775834) (xy 287.284669 -306.72805) (xy 287.30396 -306.682774)
			(xy 287.330263 -306.641178) (xy 287.362898 -306.604341) (xy 287.401019 -306.573216) (xy 287.44364 -306.548609)
			(xy 287.489656 -306.531157) (xy 287.537875 -306.521313) (xy 287.58705 -306.519332) (xy 287.635905 -306.525264)
			(xy 287.683176 -306.538956) (xy 287.727638 -306.560054) (xy 287.768141 -306.58801) (xy 287.803634 -306.622102)
			(xy 287.833199 -306.661446) (xy 287.85607 -306.705023) (xy 287.871654 -306.751704) (xy 287.879549 -306.800281)
			(xy 287.880044 -306.824888) (xy 288.218892 -306.824888) (xy 288.222852 -306.775834) (xy 288.234629 -306.72805)
			(xy 288.25392 -306.682774) (xy 288.280223 -306.641178) (xy 288.312858 -306.604341) (xy 288.350979 -306.573216)
			(xy 288.3936 -306.548609) (xy 288.439616 -306.531157) (xy 288.487835 -306.521313) (xy 288.53701 -306.519332)
			(xy 288.585865 -306.525264) (xy 288.633136 -306.538956) (xy 288.677598 -306.560054) (xy 288.718101 -306.58801)
			(xy 288.753594 -306.622102) (xy 288.783159 -306.661446) (xy 288.80603 -306.705023) (xy 288.821614 -306.751704)
			(xy 288.829509 -306.800281) (xy 288.830004 -306.824888) (xy 289.169106 -306.824888) (xy 289.173066 -306.775834)
			(xy 289.184843 -306.72805) (xy 289.204134 -306.682774) (xy 289.230437 -306.641178) (xy 289.263072 -306.604341)
			(xy 289.301193 -306.573216) (xy 289.343814 -306.548609) (xy 289.38983 -306.531157) (xy 289.438049 -306.521313)
			(xy 289.487224 -306.519332) (xy 289.536079 -306.525264) (xy 289.58335 -306.538956) (xy 289.627812 -306.560054)
			(xy 289.668315 -306.58801) (xy 289.703808 -306.622102) (xy 289.733373 -306.661446) (xy 289.756244 -306.705023)
			(xy 289.771828 -306.751704) (xy 289.779723 -306.800281) (xy 289.780218 -306.824888) (xy 290.119066 -306.824888)
			(xy 290.123026 -306.775834) (xy 290.134803 -306.72805) (xy 290.154094 -306.682774) (xy 290.180397 -306.641178)
			(xy 290.213032 -306.604341) (xy 290.251153 -306.573216) (xy 290.293774 -306.548609) (xy 290.33979 -306.531157)
			(xy 290.388009 -306.521313) (xy 290.437184 -306.519332) (xy 290.486039 -306.525264) (xy 290.53331 -306.538956)
			(xy 290.577772 -306.560054) (xy 290.618275 -306.58801) (xy 290.653768 -306.622102) (xy 290.683333 -306.661446)
			(xy 290.706204 -306.705023) (xy 290.721788 -306.751704) (xy 290.729683 -306.800281) (xy 290.730178 -306.824888)
			(xy 292.018986 -306.824888) (xy 292.022946 -306.775834) (xy 292.034723 -306.72805) (xy 292.054014 -306.682774)
			(xy 292.080317 -306.641178) (xy 292.112952 -306.604341) (xy 292.151073 -306.573216) (xy 292.193694 -306.548609)
			(xy 292.23971 -306.531157) (xy 292.287929 -306.521313) (xy 292.337104 -306.519332) (xy 292.385959 -306.525264)
			(xy 292.43323 -306.538956) (xy 292.477692 -306.560054) (xy 292.518195 -306.58801) (xy 292.553688 -306.622102)
			(xy 292.583253 -306.661446) (xy 292.606124 -306.705023) (xy 292.621708 -306.751704) (xy 292.629603 -306.800281)
			(xy 292.630098 -306.824888) (xy 292.968946 -306.824888) (xy 292.972906 -306.775834) (xy 292.984683 -306.72805)
			(xy 293.003974 -306.682774) (xy 293.030277 -306.641178) (xy 293.062912 -306.604341) (xy 293.101033 -306.573216)
			(xy 293.143654 -306.548609) (xy 293.18967 -306.531157) (xy 293.237889 -306.521313) (xy 293.287064 -306.519332)
			(xy 293.335919 -306.525264) (xy 293.38319 -306.538956) (xy 293.427652 -306.560054) (xy 293.468155 -306.58801)
			(xy 293.503648 -306.622102) (xy 293.533213 -306.661446) (xy 293.556084 -306.705023) (xy 293.571668 -306.751704)
			(xy 293.579563 -306.800281) (xy 293.580058 -306.824888) (xy 293.918906 -306.824888) (xy 293.922866 -306.775834)
			(xy 293.934643 -306.72805) (xy 293.953934 -306.682774) (xy 293.980237 -306.641178) (xy 294.012872 -306.604341)
			(xy 294.050993 -306.573216) (xy 294.093614 -306.548609) (xy 294.13963 -306.531157) (xy 294.187849 -306.521313)
			(xy 294.237024 -306.519332) (xy 294.285879 -306.525264) (xy 294.33315 -306.538956) (xy 294.377612 -306.560054)
			(xy 294.418115 -306.58801) (xy 294.453608 -306.622102) (xy 294.483173 -306.661446) (xy 294.506044 -306.705023)
			(xy 294.521628 -306.751704) (xy 294.529523 -306.800281) (xy 294.530018 -306.824888) (xy 294.529523 -306.849495)
			(xy 294.521628 -306.898072) (xy 294.506044 -306.944753) (xy 294.483173 -306.98833) (xy 294.453608 -307.027674)
			(xy 294.418115 -307.061766) (xy 294.377612 -307.089722) (xy 294.33315 -307.11082) (xy 294.285879 -307.124512)
			(xy 294.237024 -307.130444) (xy 294.187849 -307.128463) (xy 294.13963 -307.118619) (xy 294.093614 -307.101167)
			(xy 294.050993 -307.07656) (xy 294.012872 -307.045435) (xy 293.980237 -307.008598) (xy 293.953934 -306.967002)
			(xy 293.934643 -306.921726) (xy 293.922866 -306.873942) (xy 293.918906 -306.824888) (xy 293.580058 -306.824888)
			(xy 293.579563 -306.849495) (xy 293.571668 -306.898072) (xy 293.556084 -306.944753) (xy 293.533213 -306.98833)
			(xy 293.503648 -307.027674) (xy 293.468155 -307.061766) (xy 293.427652 -307.089722) (xy 293.38319 -307.11082)
			(xy 293.335919 -307.124512) (xy 293.287064 -307.130444) (xy 293.237889 -307.128463) (xy 293.18967 -307.118619)
			(xy 293.143654 -307.101167) (xy 293.101033 -307.07656) (xy 293.062912 -307.045435) (xy 293.030277 -307.008598)
			(xy 293.003974 -306.967002) (xy 292.984683 -306.921726) (xy 292.972906 -306.873942) (xy 292.968946 -306.824888)
			(xy 292.630098 -306.824888) (xy 292.629603 -306.849495) (xy 292.621708 -306.898072) (xy 292.606124 -306.944753)
			(xy 292.583253 -306.98833) (xy 292.553688 -307.027674) (xy 292.518195 -307.061766) (xy 292.477692 -307.089722)
			(xy 292.43323 -307.11082) (xy 292.385959 -307.124512) (xy 292.337104 -307.130444) (xy 292.287929 -307.128463)
			(xy 292.23971 -307.118619) (xy 292.193694 -307.101167) (xy 292.151073 -307.07656) (xy 292.112952 -307.045435)
			(xy 292.080317 -307.008598) (xy 292.054014 -306.967002) (xy 292.034723 -306.921726) (xy 292.022946 -306.873942)
			(xy 292.018986 -306.824888) (xy 290.730178 -306.824888) (xy 290.729683 -306.849495) (xy 290.721788 -306.898072)
			(xy 290.706204 -306.944753) (xy 290.683333 -306.98833) (xy 290.653768 -307.027674) (xy 290.618275 -307.061766)
			(xy 290.577772 -307.089722) (xy 290.53331 -307.11082) (xy 290.486039 -307.124512) (xy 290.437184 -307.130444)
			(xy 290.388009 -307.128463) (xy 290.33979 -307.118619) (xy 290.293774 -307.101167) (xy 290.251153 -307.07656)
			(xy 290.213032 -307.045435) (xy 290.180397 -307.008598) (xy 290.154094 -306.967002) (xy 290.134803 -306.921726)
			(xy 290.123026 -306.873942) (xy 290.119066 -306.824888) (xy 289.780218 -306.824888) (xy 289.779723 -306.849495)
			(xy 289.771828 -306.898072) (xy 289.756244 -306.944753) (xy 289.733373 -306.98833) (xy 289.703808 -307.027674)
			(xy 289.668315 -307.061766) (xy 289.627812 -307.089722) (xy 289.58335 -307.11082) (xy 289.536079 -307.124512)
			(xy 289.487224 -307.130444) (xy 289.438049 -307.128463) (xy 289.38983 -307.118619) (xy 289.343814 -307.101167)
			(xy 289.301193 -307.07656) (xy 289.263072 -307.045435) (xy 289.230437 -307.008598) (xy 289.204134 -306.967002)
			(xy 289.184843 -306.921726) (xy 289.173066 -306.873942) (xy 289.169106 -306.824888) (xy 288.830004 -306.824888)
			(xy 288.829509 -306.849495) (xy 288.821614 -306.898072) (xy 288.80603 -306.944753) (xy 288.783159 -306.98833)
			(xy 288.753594 -307.027674) (xy 288.718101 -307.061766) (xy 288.677598 -307.089722) (xy 288.633136 -307.11082)
			(xy 288.585865 -307.124512) (xy 288.53701 -307.130444) (xy 288.487835 -307.128463) (xy 288.439616 -307.118619)
			(xy 288.3936 -307.101167) (xy 288.350979 -307.07656) (xy 288.312858 -307.045435) (xy 288.280223 -307.008598)
			(xy 288.25392 -306.967002) (xy 288.234629 -306.921726) (xy 288.222852 -306.873942) (xy 288.218892 -306.824888)
			(xy 287.880044 -306.824888) (xy 287.879549 -306.849495) (xy 287.871654 -306.898072) (xy 287.85607 -306.944753)
			(xy 287.833199 -306.98833) (xy 287.803634 -307.027674) (xy 287.768141 -307.061766) (xy 287.727638 -307.089722)
			(xy 287.683176 -307.11082) (xy 287.635905 -307.124512) (xy 287.58705 -307.130444) (xy 287.537875 -307.128463)
			(xy 287.489656 -307.118619) (xy 287.44364 -307.101167) (xy 287.401019 -307.07656) (xy 287.362898 -307.045435)
			(xy 287.330263 -307.008598) (xy 287.30396 -306.967002) (xy 287.284669 -306.921726) (xy 287.272892 -306.873942)
			(xy 287.268932 -306.824888) (xy 286.930084 -306.824888) (xy 286.929589 -306.849495) (xy 286.921694 -306.898072)
			(xy 286.90611 -306.944753) (xy 286.883239 -306.98833) (xy 286.853674 -307.027674) (xy 286.818181 -307.061766)
			(xy 286.777678 -307.089722) (xy 286.733216 -307.11082) (xy 286.685945 -307.124512) (xy 286.63709 -307.130444)
			(xy 286.587915 -307.128463) (xy 286.539696 -307.118619) (xy 286.49368 -307.101167) (xy 286.451059 -307.07656)
			(xy 286.412938 -307.045435) (xy 286.380303 -307.008598) (xy 286.354 -306.967002) (xy 286.334709 -306.921726)
			(xy 286.322932 -306.873942) (xy 286.318972 -306.824888) (xy 285.980124 -306.824888) (xy 285.979629 -306.849495)
			(xy 285.971734 -306.898072) (xy 285.95615 -306.944753) (xy 285.933279 -306.98833) (xy 285.903714 -307.027674)
			(xy 285.868221 -307.061766) (xy 285.827718 -307.089722) (xy 285.783256 -307.11082) (xy 285.735985 -307.124512)
			(xy 285.68713 -307.130444) (xy 285.637955 -307.128463) (xy 285.589736 -307.118619) (xy 285.54372 -307.101167)
			(xy 285.501099 -307.07656) (xy 285.462978 -307.045435) (xy 285.430343 -307.008598) (xy 285.40404 -306.967002)
			(xy 285.384749 -306.921726) (xy 285.372972 -306.873942) (xy 285.369012 -306.824888) (xy 285.030164 -306.824888)
			(xy 285.029669 -306.849495) (xy 285.021774 -306.898072) (xy 285.00619 -306.944753) (xy 284.983319 -306.98833)
			(xy 284.953754 -307.027674) (xy 284.918261 -307.061766) (xy 284.877758 -307.089722) (xy 284.833296 -307.11082)
			(xy 284.786025 -307.124512) (xy 284.73717 -307.130444) (xy 284.687995 -307.128463) (xy 284.639776 -307.118619)
			(xy 284.59376 -307.101167) (xy 284.551139 -307.07656) (xy 284.513018 -307.045435) (xy 284.480383 -307.008598)
			(xy 284.45408 -306.967002) (xy 284.434789 -306.921726) (xy 284.423012 -306.873942) (xy 284.419052 -306.824888)
			(xy 284.080204 -306.824888) (xy 284.079709 -306.849495) (xy 284.071814 -306.898072) (xy 284.05623 -306.944753)
			(xy 284.033359 -306.98833) (xy 284.003794 -307.027674) (xy 283.968301 -307.061766) (xy 283.927798 -307.089722)
			(xy 283.883336 -307.11082) (xy 283.836065 -307.124512) (xy 283.78721 -307.130444) (xy 283.738035 -307.128463)
			(xy 283.689816 -307.118619) (xy 283.6438 -307.101167) (xy 283.601179 -307.07656) (xy 283.563058 -307.045435)
			(xy 283.530423 -307.008598) (xy 283.50412 -306.967002) (xy 283.484829 -306.921726) (xy 283.473052 -306.873942)
			(xy 283.469092 -306.824888) (xy 283.130244 -306.824888) (xy 283.129749 -306.849495) (xy 283.121854 -306.898072)
			(xy 283.10627 -306.944753) (xy 283.083399 -306.98833) (xy 283.053834 -307.027674) (xy 283.018341 -307.061766)
			(xy 282.977838 -307.089722) (xy 282.933376 -307.11082) (xy 282.886105 -307.124512) (xy 282.83725 -307.130444)
			(xy 282.788075 -307.128463) (xy 282.739856 -307.118619) (xy 282.69384 -307.101167) (xy 282.651219 -307.07656)
			(xy 282.613098 -307.045435) (xy 282.580463 -307.008598) (xy 282.55416 -306.967002) (xy 282.534869 -306.921726)
			(xy 282.523092 -306.873942) (xy 282.519132 -306.824888) (xy 282.18003 -306.824888) (xy 282.179535 -306.849495)
			(xy 282.17164 -306.898072) (xy 282.156056 -306.944753) (xy 282.133185 -306.98833) (xy 282.10362 -307.027674)
			(xy 282.068127 -307.061766) (xy 282.027624 -307.089722) (xy 281.983162 -307.11082) (xy 281.935891 -307.124512)
			(xy 281.887036 -307.130444) (xy 281.837861 -307.128463) (xy 281.789642 -307.118619) (xy 281.743626 -307.101167)
			(xy 281.701005 -307.07656) (xy 281.662884 -307.045435) (xy 281.630249 -307.008598) (xy 281.603946 -306.967002)
			(xy 281.584655 -306.921726) (xy 281.572878 -306.873942) (xy 281.568918 -306.824888) (xy 281.23007 -306.824888)
			(xy 281.229575 -306.849495) (xy 281.22168 -306.898072) (xy 281.206096 -306.944753) (xy 281.183225 -306.98833)
			(xy 281.15366 -307.027674) (xy 281.118167 -307.061766) (xy 281.077664 -307.089722) (xy 281.033202 -307.11082)
			(xy 280.985931 -307.124512) (xy 280.937076 -307.130444) (xy 280.887901 -307.128463) (xy 280.839682 -307.118619)
			(xy 280.793666 -307.101167) (xy 280.751045 -307.07656) (xy 280.712924 -307.045435) (xy 280.680289 -307.008598)
			(xy 280.653986 -306.967002) (xy 280.634695 -306.921726) (xy 280.622918 -306.873942) (xy 280.618958 -306.824888)
			(xy 280.28011 -306.824888) (xy 280.279615 -306.849495) (xy 280.27172 -306.898072) (xy 280.256136 -306.944753)
			(xy 280.233265 -306.98833) (xy 280.2037 -307.027674) (xy 280.168207 -307.061766) (xy 280.127704 -307.089722)
			(xy 280.083242 -307.11082) (xy 280.035971 -307.124512) (xy 279.987116 -307.130444) (xy 279.937941 -307.128463)
			(xy 279.889722 -307.118619) (xy 279.843706 -307.101167) (xy 279.801085 -307.07656) (xy 279.762964 -307.045435)
			(xy 279.730329 -307.008598) (xy 279.704026 -306.967002) (xy 279.684735 -306.921726) (xy 279.672958 -306.873942)
			(xy 279.668998 -306.824888) (xy 279.33015 -306.824888) (xy 279.329655 -306.849495) (xy 279.32176 -306.898072)
			(xy 279.306176 -306.944753) (xy 279.283305 -306.98833) (xy 279.25374 -307.027674) (xy 279.218247 -307.061766)
			(xy 279.177744 -307.089722) (xy 279.133282 -307.11082) (xy 279.086011 -307.124512) (xy 279.037156 -307.130444)
			(xy 278.987981 -307.128463) (xy 278.939762 -307.118619) (xy 278.893746 -307.101167) (xy 278.851125 -307.07656)
			(xy 278.813004 -307.045435) (xy 278.780369 -307.008598) (xy 278.754066 -306.967002) (xy 278.734775 -306.921726)
			(xy 278.722998 -306.873942) (xy 278.719038 -306.824888) (xy 274.605496 -306.824888) (xy 274.605348 -306.840217)
			(xy 274.602553 -306.870748) (xy 274.599908 -306.885848) (xy 274.599908 -306.88661) (xy 274.599146 -306.891182)
			(xy 274.606004 -306.913788) (xy 274.67052 -306.981352) (xy 274.67916 -306.989563) (xy 274.701552 -306.997635)
			(xy 274.713446 -306.996846) (xy 274.72249 -306.995797) (xy 274.740664 -306.994651) (xy 274.749768 -306.99456)
			(xy 274.774593 -306.995043) (xy 274.823588 -307.003071) (xy 274.87064 -307.01892) (xy 274.914508 -307.042172)
			(xy 274.954035 -307.072216) (xy 274.988181 -307.108258) (xy 275.016046 -307.149351) (xy 275.036896 -307.19441)
			(xy 275.050181 -307.242249) (xy 275.055551 -307.291606) (xy 275.055103 -307.299868) (xy 275.393924 -307.299868)
			(xy 275.397884 -307.250814) (xy 275.409661 -307.20303) (xy 275.428952 -307.157754) (xy 275.455255 -307.116158)
			(xy 275.48789 -307.079321) (xy 275.526011 -307.048196) (xy 275.568632 -307.023589) (xy 275.614648 -307.006137)
			(xy 275.662867 -306.996293) (xy 275.712042 -306.994312) (xy 275.760897 -307.000244) (xy 275.808168 -307.013936)
			(xy 275.85263 -307.035034) (xy 275.893133 -307.06299) (xy 275.928626 -307.097082) (xy 275.958191 -307.136426)
			(xy 275.981062 -307.180003) (xy 275.996646 -307.226684) (xy 276.004541 -307.275261) (xy 276.005036 -307.299868)
			(xy 276.343884 -307.299868) (xy 276.347844 -307.250814) (xy 276.359621 -307.20303) (xy 276.378912 -307.157754)
			(xy 276.405215 -307.116158) (xy 276.43785 -307.079321) (xy 276.475971 -307.048196) (xy 276.518592 -307.023589)
			(xy 276.564608 -307.006137) (xy 276.612827 -306.996293) (xy 276.662002 -306.994312) (xy 276.710857 -307.000244)
			(xy 276.758128 -307.013936) (xy 276.80259 -307.035034) (xy 276.843093 -307.06299) (xy 276.878586 -307.097082)
			(xy 276.908151 -307.136426) (xy 276.931022 -307.180003) (xy 276.946606 -307.226684) (xy 276.954501 -307.275261)
			(xy 276.954996 -307.299868) (xy 277.294098 -307.299868) (xy 277.298058 -307.250814) (xy 277.309835 -307.20303)
			(xy 277.329126 -307.157754) (xy 277.355429 -307.116158) (xy 277.388064 -307.079321) (xy 277.426185 -307.048196)
			(xy 277.468806 -307.023589) (xy 277.514822 -307.006137) (xy 277.563041 -306.996293) (xy 277.612216 -306.994312)
			(xy 277.661071 -307.000244) (xy 277.708342 -307.013936) (xy 277.752804 -307.035034) (xy 277.793307 -307.06299)
			(xy 277.8288 -307.097082) (xy 277.858365 -307.136426) (xy 277.881236 -307.180003) (xy 277.89682 -307.226684)
			(xy 277.904715 -307.275261) (xy 277.90521 -307.299868) (xy 277.904715 -307.324475) (xy 277.89682 -307.373052)
			(xy 277.881236 -307.419733) (xy 277.858365 -307.46331) (xy 277.8288 -307.502654) (xy 277.793307 -307.536746)
			(xy 277.752804 -307.564702) (xy 277.708342 -307.5858) (xy 277.661071 -307.599492) (xy 277.612216 -307.605424)
			(xy 277.563041 -307.603443) (xy 277.514822 -307.593599) (xy 277.468806 -307.576147) (xy 277.426185 -307.55154)
			(xy 277.388064 -307.520415) (xy 277.355429 -307.483578) (xy 277.329126 -307.441982) (xy 277.309835 -307.396706)
			(xy 277.298058 -307.348922) (xy 277.294098 -307.299868) (xy 276.954996 -307.299868) (xy 276.954501 -307.324475)
			(xy 276.946606 -307.373052) (xy 276.931022 -307.419733) (xy 276.908151 -307.46331) (xy 276.878586 -307.502654)
			(xy 276.843093 -307.536746) (xy 276.80259 -307.564702) (xy 276.758128 -307.5858) (xy 276.710857 -307.599492)
			(xy 276.662002 -307.605424) (xy 276.612827 -307.603443) (xy 276.564608 -307.593599) (xy 276.518592 -307.576147)
			(xy 276.475971 -307.55154) (xy 276.43785 -307.520415) (xy 276.405215 -307.483578) (xy 276.378912 -307.441982)
			(xy 276.359621 -307.396706) (xy 276.347844 -307.348922) (xy 276.343884 -307.299868) (xy 276.005036 -307.299868)
			(xy 276.004541 -307.324475) (xy 275.996646 -307.373052) (xy 275.981062 -307.419733) (xy 275.958191 -307.46331)
			(xy 275.928626 -307.502654) (xy 275.893133 -307.536746) (xy 275.85263 -307.564702) (xy 275.808168 -307.5858)
			(xy 275.760897 -307.599492) (xy 275.712042 -307.605424) (xy 275.662867 -307.603443) (xy 275.614648 -307.593599)
			(xy 275.568632 -307.576147) (xy 275.526011 -307.55154) (xy 275.48789 -307.520415) (xy 275.455255 -307.483578)
			(xy 275.428952 -307.441982) (xy 275.409661 -307.396706) (xy 275.397884 -307.348922) (xy 275.393924 -307.299868)
			(xy 275.055103 -307.299868) (xy 275.052864 -307.341183) (xy 275.042192 -307.389671) (xy 275.023816 -307.435795)
			(xy 274.99822 -307.478337) (xy 274.966078 -307.516178) (xy 274.928237 -307.54832) (xy 274.885695 -307.573916)
			(xy 274.839571 -307.592292) (xy 274.791083 -307.602964) (xy 274.741506 -307.605651) (xy 274.692149 -307.600281)
			(xy 274.64431 -307.586996) (xy 274.599251 -307.566146) (xy 274.558158 -307.538281) (xy 274.522116 -307.504135)
			(xy 274.492072 -307.464608) (xy 274.46882 -307.42074) (xy 274.452971 -307.373688) (xy 274.444943 -307.324693)
			(xy 274.44446 -307.299868) (xy 274.444558 -307.290764) (xy 274.445701 -307.272591) (xy 274.446746 -307.263546)
			(xy 274.447534 -307.251657) (xy 274.43944 -307.229279) (xy 274.431252 -307.22062) (xy 274.363688 -307.156104)
			(xy 274.341082 -307.149246) (xy 274.336002 -307.150008) (xy 274.320837 -307.152647) (xy 274.29018 -307.155444)
			(xy 274.274788 -307.155596) (xy 274.20443 -307.155596) (xy 274.193742 -307.156168) (xy 274.1742 -307.164838)
			(xy 274.166584 -307.17236) (xy 274.108672 -307.236876) (xy 274.102068 -307.256688) (xy 274.103084 -307.266594)
			(xy 274.103338 -307.267102) (xy 274.103338 -307.268626) (xy 274.105116 -307.299614) (xy 274.105116 -307.300122)
			(xy 274.104629 -307.324102) (xy 274.097095 -307.371467) (xy 274.082248 -307.417072) (xy 274.060453 -307.459795)
			(xy 274.032246 -307.498584) (xy 273.998321 -307.532485) (xy 273.959512 -307.560665) (xy 273.916774 -307.58243)
			(xy 273.871159 -307.597245) (xy 273.823788 -307.604746) (xy 273.799808 -307.605176) (xy 273.79064 -307.605084)
			(xy 273.77234 -307.603941) (xy 273.763232 -307.60289) (xy 273.762978 -307.60289) (xy 273.751171 -307.602064)
			(xy 273.728901 -307.609995) (xy 273.720306 -307.61813) (xy 273.65579 -307.685694) (xy 273.648678 -307.708554)
			(xy 273.65071 -307.720492) (xy 273.654678 -307.747527) (xy 273.654674 -307.774848) (xy 278.719038 -307.774848)
			(xy 278.722998 -307.725794) (xy 278.734775 -307.67801) (xy 278.754066 -307.632734) (xy 278.780369 -307.591138)
			(xy 278.813004 -307.554301) (xy 278.851125 -307.523176) (xy 278.893746 -307.498569) (xy 278.939762 -307.481117)
			(xy 278.987981 -307.471273) (xy 279.037156 -307.469292) (xy 279.086011 -307.475224) (xy 279.133282 -307.488916)
			(xy 279.177744 -307.510014) (xy 279.218247 -307.53797) (xy 279.25374 -307.572062) (xy 279.283305 -307.611406)
			(xy 279.306176 -307.654983) (xy 279.32176 -307.701664) (xy 279.329655 -307.750241) (xy 279.33015 -307.774848)
			(xy 279.668998 -307.774848) (xy 279.672958 -307.725794) (xy 279.684735 -307.67801) (xy 279.704026 -307.632734)
			(xy 279.730329 -307.591138) (xy 279.762964 -307.554301) (xy 279.801085 -307.523176) (xy 279.843706 -307.498569)
			(xy 279.889722 -307.481117) (xy 279.937941 -307.471273) (xy 279.987116 -307.469292) (xy 280.035971 -307.475224)
			(xy 280.083242 -307.488916) (xy 280.127704 -307.510014) (xy 280.168207 -307.53797) (xy 280.2037 -307.572062)
			(xy 280.233265 -307.611406) (xy 280.256136 -307.654983) (xy 280.27172 -307.701664) (xy 280.279615 -307.750241)
			(xy 280.28011 -307.774848) (xy 280.618958 -307.774848) (xy 280.622918 -307.725794) (xy 280.634695 -307.67801)
			(xy 280.653986 -307.632734) (xy 280.680289 -307.591138) (xy 280.712924 -307.554301) (xy 280.751045 -307.523176)
			(xy 280.793666 -307.498569) (xy 280.839682 -307.481117) (xy 280.887901 -307.471273) (xy 280.937076 -307.469292)
			(xy 280.985931 -307.475224) (xy 281.033202 -307.488916) (xy 281.077664 -307.510014) (xy 281.118167 -307.53797)
			(xy 281.15366 -307.572062) (xy 281.183225 -307.611406) (xy 281.206096 -307.654983) (xy 281.22168 -307.701664)
			(xy 281.229575 -307.750241) (xy 281.23007 -307.774848) (xy 281.568918 -307.774848) (xy 281.572878 -307.725794)
			(xy 281.584655 -307.67801) (xy 281.603946 -307.632734) (xy 281.630249 -307.591138) (xy 281.662884 -307.554301)
			(xy 281.701005 -307.523176) (xy 281.743626 -307.498569) (xy 281.789642 -307.481117) (xy 281.837861 -307.471273)
			(xy 281.887036 -307.469292) (xy 281.935891 -307.475224) (xy 281.983162 -307.488916) (xy 282.027624 -307.510014)
			(xy 282.068127 -307.53797) (xy 282.10362 -307.572062) (xy 282.133185 -307.611406) (xy 282.156056 -307.654983)
			(xy 282.17164 -307.701664) (xy 282.179535 -307.750241) (xy 282.18003 -307.774848) (xy 282.519132 -307.774848)
			(xy 282.523092 -307.725794) (xy 282.534869 -307.67801) (xy 282.55416 -307.632734) (xy 282.580463 -307.591138)
			(xy 282.613098 -307.554301) (xy 282.651219 -307.523176) (xy 282.69384 -307.498569) (xy 282.739856 -307.481117)
			(xy 282.788075 -307.471273) (xy 282.83725 -307.469292) (xy 282.886105 -307.475224) (xy 282.933376 -307.488916)
			(xy 282.977838 -307.510014) (xy 283.018341 -307.53797) (xy 283.053834 -307.572062) (xy 283.083399 -307.611406)
			(xy 283.10627 -307.654983) (xy 283.121854 -307.701664) (xy 283.129749 -307.750241) (xy 283.130244 -307.774848)
			(xy 283.469092 -307.774848) (xy 283.473052 -307.725794) (xy 283.484829 -307.67801) (xy 283.50412 -307.632734)
			(xy 283.530423 -307.591138) (xy 283.563058 -307.554301) (xy 283.601179 -307.523176) (xy 283.6438 -307.498569)
			(xy 283.689816 -307.481117) (xy 283.738035 -307.471273) (xy 283.78721 -307.469292) (xy 283.836065 -307.475224)
			(xy 283.883336 -307.488916) (xy 283.927798 -307.510014) (xy 283.968301 -307.53797) (xy 284.003794 -307.572062)
			(xy 284.033359 -307.611406) (xy 284.05623 -307.654983) (xy 284.071814 -307.701664) (xy 284.079709 -307.750241)
			(xy 284.080204 -307.774848) (xy 284.419052 -307.774848) (xy 284.423012 -307.725794) (xy 284.434789 -307.67801)
			(xy 284.45408 -307.632734) (xy 284.480383 -307.591138) (xy 284.513018 -307.554301) (xy 284.551139 -307.523176)
			(xy 284.59376 -307.498569) (xy 284.639776 -307.481117) (xy 284.687995 -307.471273) (xy 284.73717 -307.469292)
			(xy 284.786025 -307.475224) (xy 284.833296 -307.488916) (xy 284.877758 -307.510014) (xy 284.918261 -307.53797)
			(xy 284.953754 -307.572062) (xy 284.983319 -307.611406) (xy 285.00619 -307.654983) (xy 285.021774 -307.701664)
			(xy 285.029669 -307.750241) (xy 285.030164 -307.774848) (xy 285.369012 -307.774848) (xy 285.372972 -307.725794)
			(xy 285.384749 -307.67801) (xy 285.40404 -307.632734) (xy 285.430343 -307.591138) (xy 285.462978 -307.554301)
			(xy 285.501099 -307.523176) (xy 285.54372 -307.498569) (xy 285.589736 -307.481117) (xy 285.637955 -307.471273)
			(xy 285.68713 -307.469292) (xy 285.735985 -307.475224) (xy 285.783256 -307.488916) (xy 285.827718 -307.510014)
			(xy 285.868221 -307.53797) (xy 285.903714 -307.572062) (xy 285.933279 -307.611406) (xy 285.95615 -307.654983)
			(xy 285.971734 -307.701664) (xy 285.979629 -307.750241) (xy 285.980124 -307.774848) (xy 286.318972 -307.774848)
			(xy 286.322932 -307.725794) (xy 286.334709 -307.67801) (xy 286.354 -307.632734) (xy 286.380303 -307.591138)
			(xy 286.412938 -307.554301) (xy 286.451059 -307.523176) (xy 286.49368 -307.498569) (xy 286.539696 -307.481117)
			(xy 286.587915 -307.471273) (xy 286.63709 -307.469292) (xy 286.685945 -307.475224) (xy 286.733216 -307.488916)
			(xy 286.777678 -307.510014) (xy 286.818181 -307.53797) (xy 286.853674 -307.572062) (xy 286.883239 -307.611406)
			(xy 286.90611 -307.654983) (xy 286.921694 -307.701664) (xy 286.929589 -307.750241) (xy 286.930084 -307.774848)
			(xy 287.268932 -307.774848) (xy 287.272892 -307.725794) (xy 287.284669 -307.67801) (xy 287.30396 -307.632734)
			(xy 287.330263 -307.591138) (xy 287.362898 -307.554301) (xy 287.401019 -307.523176) (xy 287.44364 -307.498569)
			(xy 287.489656 -307.481117) (xy 287.537875 -307.471273) (xy 287.58705 -307.469292) (xy 287.635905 -307.475224)
			(xy 287.683176 -307.488916) (xy 287.727638 -307.510014) (xy 287.768141 -307.53797) (xy 287.803634 -307.572062)
			(xy 287.833199 -307.611406) (xy 287.85607 -307.654983) (xy 287.871654 -307.701664) (xy 287.879549 -307.750241)
			(xy 287.880044 -307.774848) (xy 288.219146 -307.774848) (xy 288.223106 -307.725794) (xy 288.234883 -307.67801)
			(xy 288.254174 -307.632734) (xy 288.280477 -307.591138) (xy 288.313112 -307.554301) (xy 288.351233 -307.523176)
			(xy 288.393854 -307.498569) (xy 288.43987 -307.481117) (xy 288.488089 -307.471273) (xy 288.537264 -307.469292)
			(xy 288.586119 -307.475224) (xy 288.63339 -307.488916) (xy 288.677852 -307.510014) (xy 288.718355 -307.53797)
			(xy 288.753848 -307.572062) (xy 288.783413 -307.611406) (xy 288.806284 -307.654983) (xy 288.821868 -307.701664)
			(xy 288.829763 -307.750241) (xy 288.830258 -307.774848) (xy 289.169106 -307.774848) (xy 289.173066 -307.725794)
			(xy 289.184843 -307.67801) (xy 289.204134 -307.632734) (xy 289.230437 -307.591138) (xy 289.263072 -307.554301)
			(xy 289.301193 -307.523176) (xy 289.343814 -307.498569) (xy 289.38983 -307.481117) (xy 289.438049 -307.471273)
			(xy 289.487224 -307.469292) (xy 289.536079 -307.475224) (xy 289.58335 -307.488916) (xy 289.627812 -307.510014)
			(xy 289.668315 -307.53797) (xy 289.703808 -307.572062) (xy 289.733373 -307.611406) (xy 289.756244 -307.654983)
			(xy 289.771828 -307.701664) (xy 289.779723 -307.750241) (xy 289.780218 -307.774848) (xy 290.119066 -307.774848)
			(xy 290.123026 -307.725794) (xy 290.134803 -307.67801) (xy 290.154094 -307.632734) (xy 290.180397 -307.591138)
			(xy 290.213032 -307.554301) (xy 290.251153 -307.523176) (xy 290.293774 -307.498569) (xy 290.33979 -307.481117)
			(xy 290.388009 -307.471273) (xy 290.437184 -307.469292) (xy 290.486039 -307.475224) (xy 290.53331 -307.488916)
			(xy 290.577772 -307.510014) (xy 290.618275 -307.53797) (xy 290.653768 -307.572062) (xy 290.683333 -307.611406)
			(xy 290.706204 -307.654983) (xy 290.721788 -307.701664) (xy 290.729683 -307.750241) (xy 290.730178 -307.774848)
			(xy 292.018986 -307.774848) (xy 292.022946 -307.725794) (xy 292.034723 -307.67801) (xy 292.054014 -307.632734)
			(xy 292.080317 -307.591138) (xy 292.112952 -307.554301) (xy 292.151073 -307.523176) (xy 292.193694 -307.498569)
			(xy 292.23971 -307.481117) (xy 292.287929 -307.471273) (xy 292.337104 -307.469292) (xy 292.385959 -307.475224)
			(xy 292.43323 -307.488916) (xy 292.477692 -307.510014) (xy 292.518195 -307.53797) (xy 292.553688 -307.572062)
			(xy 292.583253 -307.611406) (xy 292.606124 -307.654983) (xy 292.621708 -307.701664) (xy 292.629603 -307.750241)
			(xy 292.630098 -307.774848) (xy 292.968946 -307.774848) (xy 292.972906 -307.725794) (xy 292.984683 -307.67801)
			(xy 293.003974 -307.632734) (xy 293.030277 -307.591138) (xy 293.062912 -307.554301) (xy 293.101033 -307.523176)
			(xy 293.143654 -307.498569) (xy 293.18967 -307.481117) (xy 293.237889 -307.471273) (xy 293.287064 -307.469292)
			(xy 293.335919 -307.475224) (xy 293.38319 -307.488916) (xy 293.427652 -307.510014) (xy 293.468155 -307.53797)
			(xy 293.503648 -307.572062) (xy 293.533213 -307.611406) (xy 293.556084 -307.654983) (xy 293.571668 -307.701664)
			(xy 293.579563 -307.750241) (xy 293.580058 -307.774848) (xy 293.579563 -307.799455) (xy 293.571668 -307.848032)
			(xy 293.556084 -307.894713) (xy 293.533213 -307.93829) (xy 293.503648 -307.977634) (xy 293.468155 -308.011726)
			(xy 293.427652 -308.039682) (xy 293.38319 -308.06078) (xy 293.335919 -308.074472) (xy 293.287064 -308.080404)
			(xy 293.237889 -308.078423) (xy 293.18967 -308.068579) (xy 293.143654 -308.051127) (xy 293.101033 -308.02652)
			(xy 293.062912 -307.995395) (xy 293.030277 -307.958558) (xy 293.003974 -307.916962) (xy 292.984683 -307.871686)
			(xy 292.972906 -307.823902) (xy 292.968946 -307.774848) (xy 292.630098 -307.774848) (xy 292.629603 -307.799455)
			(xy 292.621708 -307.848032) (xy 292.606124 -307.894713) (xy 292.583253 -307.93829) (xy 292.553688 -307.977634)
			(xy 292.518195 -308.011726) (xy 292.477692 -308.039682) (xy 292.43323 -308.06078) (xy 292.385959 -308.074472)
			(xy 292.337104 -308.080404) (xy 292.287929 -308.078423) (xy 292.23971 -308.068579) (xy 292.193694 -308.051127)
			(xy 292.151073 -308.02652) (xy 292.112952 -307.995395) (xy 292.080317 -307.958558) (xy 292.054014 -307.916962)
			(xy 292.034723 -307.871686) (xy 292.022946 -307.823902) (xy 292.018986 -307.774848) (xy 290.730178 -307.774848)
			(xy 290.729683 -307.799455) (xy 290.721788 -307.848032) (xy 290.706204 -307.894713) (xy 290.683333 -307.93829)
			(xy 290.653768 -307.977634) (xy 290.618275 -308.011726) (xy 290.577772 -308.039682) (xy 290.53331 -308.06078)
			(xy 290.486039 -308.074472) (xy 290.437184 -308.080404) (xy 290.388009 -308.078423) (xy 290.33979 -308.068579)
			(xy 290.293774 -308.051127) (xy 290.251153 -308.02652) (xy 290.213032 -307.995395) (xy 290.180397 -307.958558)
			(xy 290.154094 -307.916962) (xy 290.134803 -307.871686) (xy 290.123026 -307.823902) (xy 290.119066 -307.774848)
			(xy 289.780218 -307.774848) (xy 289.779723 -307.799455) (xy 289.771828 -307.848032) (xy 289.756244 -307.894713)
			(xy 289.733373 -307.93829) (xy 289.703808 -307.977634) (xy 289.668315 -308.011726) (xy 289.627812 -308.039682)
			(xy 289.58335 -308.06078) (xy 289.536079 -308.074472) (xy 289.487224 -308.080404) (xy 289.438049 -308.078423)
			(xy 289.38983 -308.068579) (xy 289.343814 -308.051127) (xy 289.301193 -308.02652) (xy 289.263072 -307.995395)
			(xy 289.230437 -307.958558) (xy 289.204134 -307.916962) (xy 289.184843 -307.871686) (xy 289.173066 -307.823902)
			(xy 289.169106 -307.774848) (xy 288.830258 -307.774848) (xy 288.829763 -307.799455) (xy 288.821868 -307.848032)
			(xy 288.806284 -307.894713) (xy 288.783413 -307.93829) (xy 288.753848 -307.977634) (xy 288.718355 -308.011726)
			(xy 288.677852 -308.039682) (xy 288.63339 -308.06078) (xy 288.586119 -308.074472) (xy 288.537264 -308.080404)
			(xy 288.488089 -308.078423) (xy 288.43987 -308.068579) (xy 288.393854 -308.051127) (xy 288.351233 -308.02652)
			(xy 288.313112 -307.995395) (xy 288.280477 -307.958558) (xy 288.254174 -307.916962) (xy 288.234883 -307.871686)
			(xy 288.223106 -307.823902) (xy 288.219146 -307.774848) (xy 287.880044 -307.774848) (xy 287.879549 -307.799455)
			(xy 287.871654 -307.848032) (xy 287.85607 -307.894713) (xy 287.833199 -307.93829) (xy 287.803634 -307.977634)
			(xy 287.768141 -308.011726) (xy 287.727638 -308.039682) (xy 287.683176 -308.06078) (xy 287.635905 -308.074472)
			(xy 287.58705 -308.080404) (xy 287.537875 -308.078423) (xy 287.489656 -308.068579) (xy 287.44364 -308.051127)
			(xy 287.401019 -308.02652) (xy 287.362898 -307.995395) (xy 287.330263 -307.958558) (xy 287.30396 -307.916962)
			(xy 287.284669 -307.871686) (xy 287.272892 -307.823902) (xy 287.268932 -307.774848) (xy 286.930084 -307.774848)
			(xy 286.929589 -307.799455) (xy 286.921694 -307.848032) (xy 286.90611 -307.894713) (xy 286.883239 -307.93829)
			(xy 286.853674 -307.977634) (xy 286.818181 -308.011726) (xy 286.777678 -308.039682) (xy 286.733216 -308.06078)
			(xy 286.685945 -308.074472) (xy 286.63709 -308.080404) (xy 286.587915 -308.078423) (xy 286.539696 -308.068579)
			(xy 286.49368 -308.051127) (xy 286.451059 -308.02652) (xy 286.412938 -307.995395) (xy 286.380303 -307.958558)
			(xy 286.354 -307.916962) (xy 286.334709 -307.871686) (xy 286.322932 -307.823902) (xy 286.318972 -307.774848)
			(xy 285.980124 -307.774848) (xy 285.979629 -307.799455) (xy 285.971734 -307.848032) (xy 285.95615 -307.894713)
			(xy 285.933279 -307.93829) (xy 285.903714 -307.977634) (xy 285.868221 -308.011726) (xy 285.827718 -308.039682)
			(xy 285.783256 -308.06078) (xy 285.735985 -308.074472) (xy 285.68713 -308.080404) (xy 285.637955 -308.078423)
			(xy 285.589736 -308.068579) (xy 285.54372 -308.051127) (xy 285.501099 -308.02652) (xy 285.462978 -307.995395)
			(xy 285.430343 -307.958558) (xy 285.40404 -307.916962) (xy 285.384749 -307.871686) (xy 285.372972 -307.823902)
			(xy 285.369012 -307.774848) (xy 285.030164 -307.774848) (xy 285.029669 -307.799455) (xy 285.021774 -307.848032)
			(xy 285.00619 -307.894713) (xy 284.983319 -307.93829) (xy 284.953754 -307.977634) (xy 284.918261 -308.011726)
			(xy 284.877758 -308.039682) (xy 284.833296 -308.06078) (xy 284.786025 -308.074472) (xy 284.73717 -308.080404)
			(xy 284.687995 -308.078423) (xy 284.639776 -308.068579) (xy 284.59376 -308.051127) (xy 284.551139 -308.02652)
			(xy 284.513018 -307.995395) (xy 284.480383 -307.958558) (xy 284.45408 -307.916962) (xy 284.434789 -307.871686)
			(xy 284.423012 -307.823902) (xy 284.419052 -307.774848) (xy 284.080204 -307.774848) (xy 284.079709 -307.799455)
			(xy 284.071814 -307.848032) (xy 284.05623 -307.894713) (xy 284.033359 -307.93829) (xy 284.003794 -307.977634)
			(xy 283.968301 -308.011726) (xy 283.927798 -308.039682) (xy 283.883336 -308.06078) (xy 283.836065 -308.074472)
			(xy 283.78721 -308.080404) (xy 283.738035 -308.078423) (xy 283.689816 -308.068579) (xy 283.6438 -308.051127)
			(xy 283.601179 -308.02652) (xy 283.563058 -307.995395) (xy 283.530423 -307.958558) (xy 283.50412 -307.916962)
			(xy 283.484829 -307.871686) (xy 283.473052 -307.823902) (xy 283.469092 -307.774848) (xy 283.130244 -307.774848)
			(xy 283.129749 -307.799455) (xy 283.121854 -307.848032) (xy 283.10627 -307.894713) (xy 283.083399 -307.93829)
			(xy 283.053834 -307.977634) (xy 283.018341 -308.011726) (xy 282.977838 -308.039682) (xy 282.933376 -308.06078)
			(xy 282.886105 -308.074472) (xy 282.83725 -308.080404) (xy 282.788075 -308.078423) (xy 282.739856 -308.068579)
			(xy 282.69384 -308.051127) (xy 282.651219 -308.02652) (xy 282.613098 -307.995395) (xy 282.580463 -307.958558)
			(xy 282.55416 -307.916962) (xy 282.534869 -307.871686) (xy 282.523092 -307.823902) (xy 282.519132 -307.774848)
			(xy 282.18003 -307.774848) (xy 282.179535 -307.799455) (xy 282.17164 -307.848032) (xy 282.156056 -307.894713)
			(xy 282.133185 -307.93829) (xy 282.10362 -307.977634) (xy 282.068127 -308.011726) (xy 282.027624 -308.039682)
			(xy 281.983162 -308.06078) (xy 281.935891 -308.074472) (xy 281.887036 -308.080404) (xy 281.837861 -308.078423)
			(xy 281.789642 -308.068579) (xy 281.743626 -308.051127) (xy 281.701005 -308.02652) (xy 281.662884 -307.995395)
			(xy 281.630249 -307.958558) (xy 281.603946 -307.916962) (xy 281.584655 -307.871686) (xy 281.572878 -307.823902)
			(xy 281.568918 -307.774848) (xy 281.23007 -307.774848) (xy 281.229575 -307.799455) (xy 281.22168 -307.848032)
			(xy 281.206096 -307.894713) (xy 281.183225 -307.93829) (xy 281.15366 -307.977634) (xy 281.118167 -308.011726)
			(xy 281.077664 -308.039682) (xy 281.033202 -308.06078) (xy 280.985931 -308.074472) (xy 280.937076 -308.080404)
			(xy 280.887901 -308.078423) (xy 280.839682 -308.068579) (xy 280.793666 -308.051127) (xy 280.751045 -308.02652)
			(xy 280.712924 -307.995395) (xy 280.680289 -307.958558) (xy 280.653986 -307.916962) (xy 280.634695 -307.871686)
			(xy 280.622918 -307.823902) (xy 280.618958 -307.774848) (xy 280.28011 -307.774848) (xy 280.279615 -307.799455)
			(xy 280.27172 -307.848032) (xy 280.256136 -307.894713) (xy 280.233265 -307.93829) (xy 280.2037 -307.977634)
			(xy 280.168207 -308.011726) (xy 280.127704 -308.039682) (xy 280.083242 -308.06078) (xy 280.035971 -308.074472)
			(xy 279.987116 -308.080404) (xy 279.937941 -308.078423) (xy 279.889722 -308.068579) (xy 279.843706 -308.051127)
			(xy 279.801085 -308.02652) (xy 279.762964 -307.995395) (xy 279.730329 -307.958558) (xy 279.704026 -307.916962)
			(xy 279.684735 -307.871686) (xy 279.672958 -307.823902) (xy 279.668998 -307.774848) (xy 279.33015 -307.774848)
			(xy 279.329655 -307.799455) (xy 279.32176 -307.848032) (xy 279.306176 -307.894713) (xy 279.283305 -307.93829)
			(xy 279.25374 -307.977634) (xy 279.218247 -308.011726) (xy 279.177744 -308.039682) (xy 279.133282 -308.06078)
			(xy 279.086011 -308.074472) (xy 279.037156 -308.080404) (xy 278.987981 -308.078423) (xy 278.939762 -308.068579)
			(xy 278.893746 -308.051127) (xy 278.851125 -308.02652) (xy 278.813004 -307.995395) (xy 278.780369 -307.958558)
			(xy 278.754066 -307.916962) (xy 278.734775 -307.871686) (xy 278.722998 -307.823902) (xy 278.719038 -307.774848)
			(xy 273.654674 -307.774848) (xy 273.654671 -307.802167) (xy 273.65071 -307.829204) (xy 273.648678 -307.841142)
			(xy 273.65579 -307.864002) (xy 273.720306 -307.931566) (xy 273.728947 -307.939632) (xy 273.751183 -307.947572)
			(xy 273.762978 -307.946806) (xy 273.763232 -307.946806) (xy 273.77234 -307.945753) (xy 273.79064 -307.944611)
			(xy 273.799808 -307.94452) (xy 273.823785 -307.94499) (xy 273.87115 -307.95249) (xy 273.91676 -307.967303)
			(xy 273.959492 -307.989065) (xy 273.998296 -308.017241) (xy 274.032217 -308.051138) (xy 274.060421 -308.089922)
			(xy 274.082214 -308.132639) (xy 274.097059 -308.178238) (xy 274.104593 -308.225597) (xy 274.105116 -308.249574)
			(xy 274.105116 -308.250082) (xy 274.103592 -308.279038) (xy 274.103338 -308.281578) (xy 274.103338 -308.282086)
			(xy 274.102822 -308.292707) (xy 274.10938 -308.312911) (xy 274.116038 -308.321202) (xy 274.166584 -308.377336)
			(xy 274.174099 -308.385002) (xy 274.193704 -308.393696) (xy 274.20443 -308.3941) (xy 274.274788 -308.3941)
			(xy 274.290117 -308.394248) (xy 274.320648 -308.397043) (xy 274.335748 -308.399688) (xy 274.33651 -308.399688)
			(xy 274.341082 -308.40045) (xy 274.363688 -308.393592) (xy 274.431252 -308.329076) (xy 274.439462 -308.320436)
			(xy 274.447533 -308.298044) (xy 274.446746 -308.28615) (xy 274.445697 -308.277106) (xy 274.444552 -308.258932)
			(xy 274.44446 -308.249828) (xy 274.444944 -308.225003) (xy 274.452972 -308.176008) (xy 274.468821 -308.128957)
			(xy 274.492074 -308.08509) (xy 274.522118 -308.045562) (xy 274.558161 -308.011417) (xy 274.599253 -307.983552)
			(xy 274.644313 -307.962703) (xy 274.692151 -307.949419) (xy 274.741509 -307.944049) (xy 274.791085 -307.946736)
			(xy 274.839574 -307.957408) (xy 274.885697 -307.975785) (xy 274.928239 -308.001381) (xy 274.966079 -308.033524)
			(xy 274.998221 -308.071364) (xy 275.023817 -308.113907) (xy 275.042193 -308.16003) (xy 275.052864 -308.208519)
			(xy 275.055103 -308.249828) (xy 275.393924 -308.249828) (xy 275.397884 -308.200774) (xy 275.409661 -308.15299)
			(xy 275.428952 -308.107714) (xy 275.455255 -308.066118) (xy 275.48789 -308.029281) (xy 275.526011 -307.998156)
			(xy 275.568632 -307.973549) (xy 275.614648 -307.956097) (xy 275.662867 -307.946253) (xy 275.712042 -307.944272)
			(xy 275.760897 -307.950204) (xy 275.808168 -307.963896) (xy 275.85263 -307.984994) (xy 275.893133 -308.01295)
			(xy 275.928626 -308.047042) (xy 275.958191 -308.086386) (xy 275.981062 -308.129963) (xy 275.996646 -308.176644)
			(xy 276.004541 -308.225221) (xy 276.005036 -308.249828) (xy 276.343884 -308.249828) (xy 276.347844 -308.200774)
			(xy 276.359621 -308.15299) (xy 276.378912 -308.107714) (xy 276.405215 -308.066118) (xy 276.43785 -308.029281)
			(xy 276.475971 -307.998156) (xy 276.518592 -307.973549) (xy 276.564608 -307.956097) (xy 276.612827 -307.946253)
			(xy 276.662002 -307.944272) (xy 276.710857 -307.950204) (xy 276.758128 -307.963896) (xy 276.80259 -307.984994)
			(xy 276.843093 -308.01295) (xy 276.878586 -308.047042) (xy 276.908151 -308.086386) (xy 276.931022 -308.129963)
			(xy 276.946606 -308.176644) (xy 276.954501 -308.225221) (xy 276.954996 -308.249828) (xy 277.294098 -308.249828)
			(xy 277.298058 -308.200774) (xy 277.309835 -308.15299) (xy 277.329126 -308.107714) (xy 277.355429 -308.066118)
			(xy 277.388064 -308.029281) (xy 277.426185 -307.998156) (xy 277.468806 -307.973549) (xy 277.514822 -307.956097)
			(xy 277.563041 -307.946253) (xy 277.612216 -307.944272) (xy 277.661071 -307.950204) (xy 277.708342 -307.963896)
			(xy 277.752804 -307.984994) (xy 277.793307 -308.01295) (xy 277.8288 -308.047042) (xy 277.858365 -308.086386)
			(xy 277.881236 -308.129963) (xy 277.89682 -308.176644) (xy 277.904715 -308.225221) (xy 277.90521 -308.249828)
			(xy 277.904715 -308.274435) (xy 277.89682 -308.323012) (xy 277.881236 -308.369693) (xy 277.858365 -308.41327)
			(xy 277.8288 -308.452614) (xy 277.793307 -308.486706) (xy 277.752804 -308.514662) (xy 277.708342 -308.53576)
			(xy 277.661071 -308.549452) (xy 277.612216 -308.555384) (xy 277.563041 -308.553403) (xy 277.514822 -308.543559)
			(xy 277.468806 -308.526107) (xy 277.426185 -308.5015) (xy 277.388064 -308.470375) (xy 277.355429 -308.433538)
			(xy 277.329126 -308.391942) (xy 277.309835 -308.346666) (xy 277.298058 -308.298882) (xy 277.294098 -308.249828)
			(xy 276.954996 -308.249828) (xy 276.954501 -308.274435) (xy 276.946606 -308.323012) (xy 276.931022 -308.369693)
			(xy 276.908151 -308.41327) (xy 276.878586 -308.452614) (xy 276.843093 -308.486706) (xy 276.80259 -308.514662)
			(xy 276.758128 -308.53576) (xy 276.710857 -308.549452) (xy 276.662002 -308.555384) (xy 276.612827 -308.553403)
			(xy 276.564608 -308.543559) (xy 276.518592 -308.526107) (xy 276.475971 -308.5015) (xy 276.43785 -308.470375)
			(xy 276.405215 -308.433538) (xy 276.378912 -308.391942) (xy 276.359621 -308.346666) (xy 276.347844 -308.298882)
			(xy 276.343884 -308.249828) (xy 276.005036 -308.249828) (xy 276.004541 -308.274435) (xy 275.996646 -308.323012)
			(xy 275.981062 -308.369693) (xy 275.958191 -308.41327) (xy 275.928626 -308.452614) (xy 275.893133 -308.486706)
			(xy 275.85263 -308.514662) (xy 275.808168 -308.53576) (xy 275.760897 -308.549452) (xy 275.712042 -308.555384)
			(xy 275.662867 -308.553403) (xy 275.614648 -308.543559) (xy 275.568632 -308.526107) (xy 275.526011 -308.5015)
			(xy 275.48789 -308.470375) (xy 275.455255 -308.433538) (xy 275.428952 -308.391942) (xy 275.409661 -308.346666)
			(xy 275.397884 -308.298882) (xy 275.393924 -308.249828) (xy 275.055103 -308.249828) (xy 275.055551 -308.258095)
			(xy 275.05018 -308.307453) (xy 275.036895 -308.355291) (xy 275.016046 -308.40035) (xy 274.988181 -308.441442)
			(xy 274.954035 -308.477485) (xy 274.914507 -308.507528) (xy 274.87064 -308.53078) (xy 274.823588 -308.546629)
			(xy 274.774593 -308.554657) (xy 274.749768 -308.555136) (xy 274.740664 -308.555038) (xy 274.722491 -308.553895)
			(xy 274.713446 -308.55285) (xy 274.701557 -308.552062) (xy 274.679179 -308.560156) (xy 274.67052 -308.568344)
			(xy 274.606004 -308.635908) (xy 274.599146 -308.658514) (xy 274.599908 -308.663594) (xy 274.602547 -308.678759)
			(xy 274.605345 -308.709416) (xy 274.605496 -308.724808) (xy 278.719038 -308.724808) (xy 278.722998 -308.675754)
			(xy 278.734775 -308.62797) (xy 278.754066 -308.582694) (xy 278.780369 -308.541098) (xy 278.813004 -308.504261)
			(xy 278.851125 -308.473136) (xy 278.893746 -308.448529) (xy 278.939762 -308.431077) (xy 278.987981 -308.421233)
			(xy 279.037156 -308.419252) (xy 279.086011 -308.425184) (xy 279.133282 -308.438876) (xy 279.177744 -308.459974)
			(xy 279.218247 -308.48793) (xy 279.25374 -308.522022) (xy 279.283305 -308.561366) (xy 279.306176 -308.604943)
			(xy 279.32176 -308.651624) (xy 279.329655 -308.700201) (xy 279.33015 -308.724808) (xy 279.668998 -308.724808)
			(xy 279.672958 -308.675754) (xy 279.684735 -308.62797) (xy 279.704026 -308.582694) (xy 279.730329 -308.541098)
			(xy 279.762964 -308.504261) (xy 279.801085 -308.473136) (xy 279.843706 -308.448529) (xy 279.889722 -308.431077)
			(xy 279.937941 -308.421233) (xy 279.987116 -308.419252) (xy 280.035971 -308.425184) (xy 280.083242 -308.438876)
			(xy 280.127704 -308.459974) (xy 280.168207 -308.48793) (xy 280.2037 -308.522022) (xy 280.233265 -308.561366)
			(xy 280.256136 -308.604943) (xy 280.27172 -308.651624) (xy 280.279615 -308.700201) (xy 280.28011 -308.724808)
			(xy 280.618958 -308.724808) (xy 280.622918 -308.675754) (xy 280.634695 -308.62797) (xy 280.653986 -308.582694)
			(xy 280.680289 -308.541098) (xy 280.712924 -308.504261) (xy 280.751045 -308.473136) (xy 280.793666 -308.448529)
			(xy 280.839682 -308.431077) (xy 280.887901 -308.421233) (xy 280.937076 -308.419252) (xy 280.985931 -308.425184)
			(xy 281.033202 -308.438876) (xy 281.077664 -308.459974) (xy 281.118167 -308.48793) (xy 281.15366 -308.522022)
			(xy 281.183225 -308.561366) (xy 281.206096 -308.604943) (xy 281.22168 -308.651624) (xy 281.229575 -308.700201)
			(xy 281.23007 -308.724808) (xy 281.229903 -308.733095) (xy 281.568959 -308.733095) (xy 281.571645 -308.683521)
			(xy 281.582316 -308.635035) (xy 281.600691 -308.588914) (xy 281.626285 -308.546374) (xy 281.658424 -308.508534)
			(xy 281.696262 -308.476393) (xy 281.738802 -308.450797) (xy 281.784922 -308.43242) (xy 281.833407 -308.421747)
			(xy 281.88298 -308.419059) (xy 281.932336 -308.424427) (xy 281.980173 -308.437708) (xy 282.02523 -308.458554)
			(xy 282.066322 -308.486416) (xy 282.102364 -308.520558) (xy 282.132409 -308.560081) (xy 282.155663 -308.603945)
			(xy 282.171514 -308.650992) (xy 282.179545 -308.699985) (xy 282.18003 -308.724808) (xy 282.179854 -308.738991)
			(xy 282.177181 -308.767231) (xy 282.174696 -308.781196) (xy 282.172521 -308.795161) (xy 282.1751 -308.823295)
			(xy 282.18529 -308.849645) (xy 282.202312 -308.872194) (xy 282.224862 -308.889214) (xy 282.251213 -308.899402)
			(xy 282.279347 -308.901979) (xy 282.293314 -308.899814) (xy 282.30728 -308.89734) (xy 282.33552 -308.894666)
			(xy 282.349702 -308.89448) (xy 282.374523 -308.89498) (xy 282.423511 -308.903012) (xy 282.470554 -308.918863)
			(xy 282.514412 -308.942116) (xy 282.553932 -308.972158) (xy 282.58807 -309.008198) (xy 282.615927 -309.049286)
			(xy 282.636771 -309.09434) (xy 282.650051 -309.142173) (xy 282.655416 -309.191511) (xy 282.994169 -309.191511)
			(xy 282.999538 -309.142158) (xy 283.012821 -309.094323) (xy 283.033667 -309.049267) (xy 283.061529 -309.008178)
			(xy 283.09567 -308.972137) (xy 283.135193 -308.942095) (xy 283.179056 -308.918843) (xy 283.226103 -308.902994)
			(xy 283.275094 -308.894965) (xy 283.299916 -308.89448) (xy 283.314099 -308.894655) (xy 283.342339 -308.897328)
			(xy 283.356304 -308.899814) (xy 283.370269 -308.901986) (xy 283.398402 -308.899406) (xy 283.42475 -308.889215)
			(xy 283.447298 -308.872193) (xy 283.464318 -308.849645) (xy 283.474507 -308.823295) (xy 283.477085 -308.795162)
			(xy 283.474922 -308.781196) (xy 283.472449 -308.76723) (xy 283.469775 -308.73899) (xy 283.469588 -308.724808)
			(xy 283.470069 -308.699986) (xy 283.478099 -308.650997) (xy 283.49395 -308.603952) (xy 283.517202 -308.56009)
			(xy 283.547244 -308.520569) (xy 283.583284 -308.486429) (xy 283.624373 -308.458569) (xy 283.669428 -308.437723)
			(xy 283.717262 -308.424441) (xy 283.766614 -308.419073) (xy 283.816185 -308.42176) (xy 283.864668 -308.432432)
			(xy 283.910785 -308.450806) (xy 283.953323 -308.4764) (xy 283.991159 -308.508538) (xy 284.023298 -308.546374)
			(xy 284.048892 -308.588911) (xy 284.067267 -308.635029) (xy 284.077939 -308.683511) (xy 284.080178 -308.724808)
			(xy 284.419052 -308.724808) (xy 284.423012 -308.675754) (xy 284.434789 -308.62797) (xy 284.45408 -308.582694)
			(xy 284.480383 -308.541098) (xy 284.513018 -308.504261) (xy 284.551139 -308.473136) (xy 284.59376 -308.448529)
			(xy 284.639776 -308.431077) (xy 284.687995 -308.421233) (xy 284.73717 -308.419252) (xy 284.786025 -308.425184)
			(xy 284.833296 -308.438876) (xy 284.877758 -308.459974) (xy 284.918261 -308.48793) (xy 284.953754 -308.522022)
			(xy 284.983319 -308.561366) (xy 285.00619 -308.604943) (xy 285.021774 -308.651624) (xy 285.029669 -308.700201)
			(xy 285.030164 -308.724808) (xy 285.369012 -308.724808) (xy 285.372972 -308.675754) (xy 285.384749 -308.62797)
			(xy 285.40404 -308.582694) (xy 285.430343 -308.541098) (xy 285.462978 -308.504261) (xy 285.501099 -308.473136)
			(xy 285.54372 -308.448529) (xy 285.589736 -308.431077) (xy 285.637955 -308.421233) (xy 285.68713 -308.419252)
			(xy 285.735985 -308.425184) (xy 285.783256 -308.438876) (xy 285.827718 -308.459974) (xy 285.868221 -308.48793)
			(xy 285.903714 -308.522022) (xy 285.933279 -308.561366) (xy 285.95615 -308.604943) (xy 285.971734 -308.651624)
			(xy 285.979629 -308.700201) (xy 285.980124 -308.724808) (xy 286.318972 -308.724808) (xy 286.322932 -308.675754)
			(xy 286.334709 -308.62797) (xy 286.354 -308.582694) (xy 286.380303 -308.541098) (xy 286.412938 -308.504261)
			(xy 286.451059 -308.473136) (xy 286.49368 -308.448529) (xy 286.539696 -308.431077) (xy 286.587915 -308.421233)
			(xy 286.63709 -308.419252) (xy 286.685945 -308.425184) (xy 286.733216 -308.438876) (xy 286.777678 -308.459974)
			(xy 286.818181 -308.48793) (xy 286.853674 -308.522022) (xy 286.883239 -308.561366) (xy 286.90611 -308.604943)
			(xy 286.921694 -308.651624) (xy 286.929589 -308.700201) (xy 286.930084 -308.724808) (xy 286.929917 -308.733104)
			(xy 287.268946 -308.733104) (xy 287.27163 -308.683528) (xy 287.2823 -308.635039) (xy 287.300675 -308.588915)
			(xy 287.326269 -308.546371) (xy 287.358409 -308.508529) (xy 287.396249 -308.476386) (xy 287.43879 -308.450787)
			(xy 287.484912 -308.432409) (xy 287.5334 -308.421734) (xy 287.582976 -308.419045) (xy 287.632334 -308.424412)
			(xy 287.680174 -308.437694) (xy 287.725234 -308.458541) (xy 287.766328 -308.486403) (xy 287.802373 -308.520547)
			(xy 287.83242 -308.560072) (xy 287.855675 -308.603938) (xy 287.871527 -308.650988) (xy 287.879559 -308.699983)
			(xy 287.880044 -308.724808) (xy 287.879868 -308.738991) (xy 287.877195 -308.767231) (xy 287.87471 -308.781196)
			(xy 287.872424 -308.793642) (xy 287.87979 -308.817264) (xy 287.95726 -308.894734) (xy 287.980882 -308.9021)
			(xy 287.993328 -308.899814) (xy 288.007294 -308.897338) (xy 288.035533 -308.894666) (xy 288.049716 -308.89448)
			(xy 288.063963 -308.894645) (xy 288.092331 -308.897316) (xy 288.106358 -308.899814) (xy 288.118804 -308.9021)
			(xy 288.142426 -308.894734) (xy 288.211006 -308.826408) (xy 288.219173 -308.817179) (xy 288.226475 -308.793683)
			(xy 288.224976 -308.78145) (xy 288.224976 -308.780942) (xy 288.222509 -308.767039) (xy 288.21984 -308.738927)
			(xy 288.219642 -308.724808) (xy 288.220069 -308.699987) (xy 288.228099 -308.650999) (xy 288.243948 -308.603956)
			(xy 288.267198 -308.560096) (xy 288.297238 -308.520575) (xy 288.333276 -308.486435) (xy 288.374363 -308.458575)
			(xy 288.419415 -308.437728) (xy 288.467246 -308.424444) (xy 288.516596 -308.419074) (xy 288.566165 -308.421758)
			(xy 288.614647 -308.432425) (xy 288.660764 -308.450796) (xy 288.703302 -308.476385) (xy 288.74114 -308.508519)
			(xy 288.773281 -308.54635) (xy 288.798878 -308.588884) (xy 288.817258 -308.634997) (xy 288.827935 -308.683477)
			(xy 288.83018 -308.724808) (xy 290.119066 -308.724808) (xy 290.123026 -308.675754) (xy 290.134803 -308.62797)
			(xy 290.154094 -308.582694) (xy 290.180397 -308.541098) (xy 290.213032 -308.504261) (xy 290.251153 -308.473136)
			(xy 290.293774 -308.448529) (xy 290.33979 -308.431077) (xy 290.388009 -308.421233) (xy 290.437184 -308.419252)
			(xy 290.486039 -308.425184) (xy 290.53331 -308.438876) (xy 290.577772 -308.459974) (xy 290.618275 -308.48793)
			(xy 290.653768 -308.522022) (xy 290.683333 -308.561366) (xy 290.706204 -308.604943) (xy 290.721788 -308.651624)
			(xy 290.729683 -308.700201) (xy 290.730178 -308.724808) (xy 290.730012 -308.733072) (xy 292.019091 -308.733072)
			(xy 292.02178 -308.683505) (xy 292.032452 -308.635026) (xy 292.050828 -308.588912) (xy 292.076421 -308.546378)
			(xy 292.108558 -308.508546) (xy 292.146393 -308.47641) (xy 292.188928 -308.45082) (xy 292.235043 -308.432447)
			(xy 292.283523 -308.421777) (xy 292.33309 -308.419091) (xy 292.382439 -308.42446) (xy 292.430269 -308.437741)
			(xy 292.475321 -308.458586) (xy 292.516406 -308.486444) (xy 292.552444 -308.520583) (xy 292.582484 -308.560102)
			(xy 292.605734 -308.60396) (xy 292.621583 -308.651002) (xy 292.629613 -308.699988) (xy 292.630098 -308.724808)
			(xy 292.629923 -308.738991) (xy 292.62725 -308.767231) (xy 292.624764 -308.781196) (xy 292.622478 -308.793642)
			(xy 292.629844 -308.817264) (xy 292.707314 -308.894734) (xy 292.730936 -308.9021) (xy 292.743382 -308.899814)
			(xy 292.757347 -308.89733) (xy 292.785587 -308.894663) (xy 292.79977 -308.89448) (xy 292.813953 -308.894661)
			(xy 292.842193 -308.89733) (xy 292.856158 -308.899814) (xy 292.868604 -308.9021) (xy 292.892226 -308.894734)
			(xy 292.969696 -308.817264) (xy 292.977062 -308.793642) (xy 292.974776 -308.781196) (xy 292.972303 -308.76723)
			(xy 292.969629 -308.73899) (xy 292.969442 -308.724808) (xy 292.969964 -308.699553) (xy 292.978277 -308.649731)
			(xy 292.994678 -308.601957) (xy 293.018719 -308.557534) (xy 293.049743 -308.517674) (xy 293.086905 -308.483464)
			(xy 293.129191 -308.455838) (xy 293.175447 -308.435548) (xy 293.224412 -308.423148) (xy 293.27475 -308.418977)
			(xy 293.325088 -308.423148) (xy 293.374053 -308.435548) (xy 293.420309 -308.455838) (xy 293.462595 -308.483464)
			(xy 293.499757 -308.517674) (xy 293.530781 -308.557534) (xy 293.554822 -308.601957) (xy 293.571223 -308.649731)
			(xy 293.579536 -308.699553) (xy 293.580058 -308.724808) (xy 293.579883 -308.738991) (xy 293.57721 -308.767231)
			(xy 293.574724 -308.781196) (xy 293.572438 -308.793642) (xy 293.579804 -308.817264) (xy 293.657274 -308.894734)
			(xy 293.680896 -308.9021) (xy 293.693342 -308.899814) (xy 293.707308 -308.897336) (xy 293.735547 -308.894665)
			(xy 293.74973 -308.89448) (xy 293.763913 -308.894653) (xy 293.792153 -308.897327) (xy 293.806118 -308.899814)
			(xy 293.818564 -308.9021) (xy 293.842186 -308.894734) (xy 293.919656 -308.817264) (xy 293.927022 -308.793642)
			(xy 293.924736 -308.781196) (xy 293.922263 -308.76723) (xy 293.919589 -308.73899) (xy 293.919402 -308.724808)
			(xy 293.919869 -308.699987) (xy 293.927899 -308.650997) (xy 293.943749 -308.603953) (xy 293.967001 -308.560092)
			(xy 293.997043 -308.520571) (xy 294.033082 -308.48643) (xy 294.07417 -308.45857) (xy 294.119225 -308.437724)
			(xy 294.167058 -308.424442) (xy 294.216409 -308.419073) (xy 294.26598 -308.42176) (xy 294.314462 -308.43243)
			(xy 294.36058 -308.450803) (xy 294.403118 -308.476396) (xy 294.440954 -308.508533) (xy 294.473094 -308.546368)
			(xy 294.498689 -308.588904) (xy 294.517065 -308.635021) (xy 294.527738 -308.683503) (xy 294.530427 -308.733073)
			(xy 294.525061 -308.782425) (xy 294.511782 -308.830259) (xy 294.490939 -308.875314) (xy 294.463081 -308.916404)
			(xy 294.428943 -308.952445) (xy 294.389423 -308.982489) (xy 294.345564 -309.005744) (xy 294.29852 -309.021596)
			(xy 294.249531 -309.029629) (xy 294.22471 -309.030116) (xy 294.210527 -309.029938) (xy 294.182287 -309.027267)
			(xy 294.168322 -309.024782) (xy 294.155876 -309.022496) (xy 294.132254 -309.029862) (xy 294.054784 -309.107332)
			(xy 294.047418 -309.130954) (xy 294.049704 -309.1434) (xy 294.052177 -309.157367) (xy 294.054851 -309.185606)
			(xy 294.055038 -309.199788) (xy 294.054516 -309.225043) (xy 294.046203 -309.274865) (xy 294.029802 -309.322639)
			(xy 294.005761 -309.367062) (xy 293.974737 -309.406922) (xy 293.937575 -309.441132) (xy 293.895289 -309.468758)
			(xy 293.849033 -309.489048) (xy 293.800068 -309.501448) (xy 293.74973 -309.505619) (xy 293.699392 -309.501448)
			(xy 293.650427 -309.489048) (xy 293.604171 -309.468758) (xy 293.561885 -309.441132) (xy 293.524723 -309.406922)
			(xy 293.493699 -309.367062) (xy 293.469658 -309.322639) (xy 293.453257 -309.274865) (xy 293.444944 -309.225043)
			(xy 293.444422 -309.199788) (xy 293.444596 -309.185605) (xy 293.44727 -309.157365) (xy 293.449756 -309.1434)
			(xy 293.452042 -309.130954) (xy 293.444676 -309.107332) (xy 293.367206 -309.029862) (xy 293.343584 -309.022496)
			(xy 293.331138 -309.024782) (xy 293.317173 -309.027263) (xy 293.288933 -309.029932) (xy 293.27475 -309.030116)
			(xy 293.260567 -309.029932) (xy 293.232327 -309.027265) (xy 293.218362 -309.024782) (xy 293.205916 -309.022496)
			(xy 293.182294 -309.029862) (xy 293.104824 -309.107332) (xy 293.097458 -309.130954) (xy 293.099744 -309.1434)
			(xy 293.102216 -309.157367) (xy 293.104891 -309.185606) (xy 293.105078 -309.199788) (xy 293.104556 -309.225043)
			(xy 293.096243 -309.274865) (xy 293.079842 -309.322639) (xy 293.055801 -309.367062) (xy 293.024777 -309.406922)
			(xy 292.987615 -309.441132) (xy 292.945329 -309.468758) (xy 292.899073 -309.489048) (xy 292.850108 -309.501448)
			(xy 292.79977 -309.505619) (xy 292.749432 -309.501448) (xy 292.700467 -309.489048) (xy 292.654211 -309.468758)
			(xy 292.611925 -309.441132) (xy 292.574763 -309.406922) (xy 292.543739 -309.367062) (xy 292.519698 -309.322639)
			(xy 292.503297 -309.274865) (xy 292.494984 -309.225043) (xy 292.494462 -309.199788) (xy 292.494637 -309.185605)
			(xy 292.49731 -309.157365) (xy 292.499796 -309.1434) (xy 292.502082 -309.130954) (xy 292.494716 -309.107332)
			(xy 292.417246 -309.029862) (xy 292.393624 -309.022496) (xy 292.381178 -309.024782) (xy 292.367212 -309.027257)
			(xy 292.338972 -309.02993) (xy 292.32479 -309.030116) (xy 292.29997 -309.029611) (xy 292.250984 -309.021579)
			(xy 292.203943 -309.005727) (xy 292.160086 -308.982474) (xy 292.120569 -308.952432) (xy 292.086433 -308.916392)
			(xy 292.058577 -308.875305) (xy 292.037735 -308.830252) (xy 292.024456 -308.782421) (xy 292.019091 -308.733072)
			(xy 290.730012 -308.733072) (xy 290.729683 -308.749415) (xy 290.721788 -308.797992) (xy 290.706204 -308.844673)
			(xy 290.683333 -308.88825) (xy 290.653768 -308.927594) (xy 290.618275 -308.961686) (xy 290.577772 -308.989642)
			(xy 290.53331 -309.01074) (xy 290.486039 -309.024432) (xy 290.437184 -309.030364) (xy 290.388009 -309.028383)
			(xy 290.33979 -309.018539) (xy 290.293774 -309.001087) (xy 290.251153 -308.97648) (xy 290.213032 -308.945355)
			(xy 290.180397 -308.908518) (xy 290.154094 -308.866922) (xy 290.134803 -308.821646) (xy 290.123026 -308.773862)
			(xy 290.119066 -308.724808) (xy 288.83018 -308.724808) (xy 288.830628 -308.733046) (xy 288.825267 -308.782397)
			(xy 288.811992 -308.830231) (xy 288.791154 -308.875287) (xy 288.763301 -308.916378) (xy 288.729168 -308.952423)
			(xy 288.689653 -308.98247) (xy 288.645798 -309.005729) (xy 288.598757 -309.021587) (xy 288.549771 -309.029626)
			(xy 288.52495 -309.030116) (xy 288.510703 -309.029949) (xy 288.482336 -309.027276) (xy 288.468308 -309.024782)
			(xy 288.455862 -309.022496) (xy 288.43224 -309.029862) (xy 288.36366 -309.098188) (xy 288.355491 -309.107416)
			(xy 288.348192 -309.130913) (xy 288.34969 -309.143146) (xy 288.34969 -309.143654) (xy 288.352158 -309.157557)
			(xy 288.354826 -309.185669) (xy 288.355024 -309.199788) (xy 288.354502 -309.225043) (xy 288.346189 -309.274865)
			(xy 288.329788 -309.322639) (xy 288.305747 -309.367062) (xy 288.274723 -309.406922) (xy 288.237561 -309.441132)
			(xy 288.195275 -309.468758) (xy 288.149019 -309.489048) (xy 288.100054 -309.501448) (xy 288.049716 -309.505619)
			(xy 287.999378 -309.501448) (xy 287.950413 -309.489048) (xy 287.904157 -309.468758) (xy 287.861871 -309.441132)
			(xy 287.824709 -309.406922) (xy 287.793685 -309.367062) (xy 287.769644 -309.322639) (xy 287.753243 -309.274865)
			(xy 287.74493 -309.225043) (xy 287.744408 -309.199788) (xy 287.744583 -309.185605) (xy 287.747256 -309.157365)
			(xy 287.749742 -309.1434) (xy 287.752028 -309.130954) (xy 287.744662 -309.107332) (xy 287.667192 -309.029862)
			(xy 287.64357 -309.022496) (xy 287.631124 -309.024782) (xy 287.617159 -309.027265) (xy 287.588919 -309.029932)
			(xy 287.574736 -309.030116) (xy 287.549911 -309.029661) (xy 287.500915 -309.021634) (xy 287.453864 -309.005786)
			(xy 287.409996 -308.982535) (xy 287.370468 -308.952492) (xy 287.336321 -308.91645) (xy 287.308454 -308.875359)
			(xy 287.287604 -308.8303) (xy 287.274317 -308.782462) (xy 287.268946 -308.733104) (xy 286.929917 -308.733104)
			(xy 286.929589 -308.749415) (xy 286.921694 -308.797992) (xy 286.90611 -308.844673) (xy 286.883239 -308.88825)
			(xy 286.853674 -308.927594) (xy 286.818181 -308.961686) (xy 286.777678 -308.989642) (xy 286.733216 -309.01074)
			(xy 286.685945 -309.024432) (xy 286.63709 -309.030364) (xy 286.587915 -309.028383) (xy 286.539696 -309.018539)
			(xy 286.49368 -309.001087) (xy 286.451059 -308.97648) (xy 286.412938 -308.945355) (xy 286.380303 -308.908518)
			(xy 286.354 -308.866922) (xy 286.334709 -308.821646) (xy 286.322932 -308.773862) (xy 286.318972 -308.724808)
			(xy 285.980124 -308.724808) (xy 285.979629 -308.749415) (xy 285.971734 -308.797992) (xy 285.95615 -308.844673)
			(xy 285.933279 -308.88825) (xy 285.903714 -308.927594) (xy 285.868221 -308.961686) (xy 285.827718 -308.989642)
			(xy 285.783256 -309.01074) (xy 285.735985 -309.024432) (xy 285.68713 -309.030364) (xy 285.637955 -309.028383)
			(xy 285.589736 -309.018539) (xy 285.54372 -309.001087) (xy 285.501099 -308.97648) (xy 285.462978 -308.945355)
			(xy 285.430343 -308.908518) (xy 285.40404 -308.866922) (xy 285.384749 -308.821646) (xy 285.372972 -308.773862)
			(xy 285.369012 -308.724808) (xy 285.030164 -308.724808) (xy 285.029669 -308.749415) (xy 285.021774 -308.797992)
			(xy 285.00619 -308.844673) (xy 284.983319 -308.88825) (xy 284.953754 -308.927594) (xy 284.918261 -308.961686)
			(xy 284.877758 -308.989642) (xy 284.833296 -309.01074) (xy 284.786025 -309.024432) (xy 284.73717 -309.030364)
			(xy 284.687995 -309.028383) (xy 284.639776 -309.018539) (xy 284.59376 -309.001087) (xy 284.551139 -308.97648)
			(xy 284.513018 -308.945355) (xy 284.480383 -308.908518) (xy 284.45408 -308.866922) (xy 284.434789 -308.821646)
			(xy 284.423012 -308.773862) (xy 284.419052 -308.724808) (xy 284.080178 -308.724808) (xy 284.080627 -308.733082)
			(xy 284.075259 -308.782434) (xy 284.061978 -308.830268) (xy 284.041133 -308.875323) (xy 284.013274 -308.916413)
			(xy 283.979134 -308.952453) (xy 283.939613 -308.982496) (xy 283.895752 -309.005749) (xy 283.848707 -309.0216)
			(xy 283.799718 -309.02963) (xy 283.774896 -309.030116) (xy 283.760713 -309.02994) (xy 283.732473 -309.027267)
			(xy 283.718508 -309.024782) (xy 283.704541 -309.022628) (xy 283.67641 -309.025205) (xy 283.650063 -309.035393)
			(xy 283.627516 -309.052411) (xy 283.610496 -309.074957) (xy 283.600306 -309.101304) (xy 283.597727 -309.129435)
			(xy 283.59989 -309.1434) (xy 283.602362 -309.157367) (xy 283.605037 -309.185606) (xy 283.605224 -309.199788)
			(xy 283.604735 -309.22461) (xy 283.596705 -309.273601) (xy 283.580855 -309.320648) (xy 283.557602 -309.36451)
			(xy 283.52756 -309.404033) (xy 283.491519 -309.438174) (xy 283.450429 -309.466035) (xy 283.405373 -309.486881)
			(xy 283.357538 -309.500163) (xy 283.308185 -309.505531) (xy 283.258613 -309.502843) (xy 283.210129 -309.492172)
			(xy 283.16401 -309.473796) (xy 283.121472 -309.448202) (xy 283.083635 -309.416062) (xy 283.051496 -309.378225)
			(xy 283.025902 -309.335686) (xy 283.007527 -309.289567) (xy 282.996856 -309.241083) (xy 282.994169 -309.191511)
			(xy 282.655416 -309.191511) (xy 282.655417 -309.191524) (xy 282.652729 -309.241092) (xy 282.642056 -309.289573)
			(xy 282.623681 -309.335689) (xy 282.598087 -309.378224) (xy 282.565949 -309.416059) (xy 282.528113 -309.448195)
			(xy 282.485577 -309.473787) (xy 282.43946 -309.49216) (xy 282.390979 -309.50283) (xy 282.34141 -309.505517)
			(xy 282.292059 -309.500148) (xy 282.244227 -309.486866) (xy 282.199174 -309.466021) (xy 282.158087 -309.438161)
			(xy 282.122049 -309.404021) (xy 282.092008 -309.364501) (xy 282.068757 -309.320641) (xy 282.052908 -309.273597)
			(xy 282.044879 -309.224609) (xy 282.044394 -309.199788) (xy 282.044569 -309.185605) (xy 282.047242 -309.157365)
			(xy 282.049728 -309.1434) (xy 282.051879 -309.129433) (xy 282.0493 -309.101304) (xy 282.039111 -309.074958)
			(xy 282.022094 -309.052412) (xy 281.999549 -309.035393) (xy 281.973204 -309.025202) (xy 281.945075 -309.022621)
			(xy 281.93111 -309.024782) (xy 281.917143 -309.027253) (xy 281.888904 -309.029928) (xy 281.874722 -309.030116)
			(xy 281.849899 -309.029646) (xy 281.800906 -309.021617) (xy 281.753857 -309.005768) (xy 281.709993 -308.982516)
			(xy 281.670468 -308.952474) (xy 281.636324 -308.916433) (xy 281.608461 -308.875342) (xy 281.587613 -308.830286)
			(xy 281.574329 -308.78245) (xy 281.568959 -308.733095) (xy 281.229903 -308.733095) (xy 281.229575 -308.749415)
			(xy 281.22168 -308.797992) (xy 281.206096 -308.844673) (xy 281.183225 -308.88825) (xy 281.15366 -308.927594)
			(xy 281.118167 -308.961686) (xy 281.077664 -308.989642) (xy 281.033202 -309.01074) (xy 280.985931 -309.024432)
			(xy 280.937076 -309.030364) (xy 280.887901 -309.028383) (xy 280.839682 -309.018539) (xy 280.793666 -309.001087)
			(xy 280.751045 -308.97648) (xy 280.712924 -308.945355) (xy 280.680289 -308.908518) (xy 280.653986 -308.866922)
			(xy 280.634695 -308.821646) (xy 280.622918 -308.773862) (xy 280.618958 -308.724808) (xy 280.28011 -308.724808)
			(xy 280.279615 -308.749415) (xy 280.27172 -308.797992) (xy 280.256136 -308.844673) (xy 280.233265 -308.88825)
			(xy 280.2037 -308.927594) (xy 280.168207 -308.961686) (xy 280.127704 -308.989642) (xy 280.083242 -309.01074)
			(xy 280.035971 -309.024432) (xy 279.987116 -309.030364) (xy 279.937941 -309.028383) (xy 279.889722 -309.018539)
			(xy 279.843706 -309.001087) (xy 279.801085 -308.97648) (xy 279.762964 -308.945355) (xy 279.730329 -308.908518)
			(xy 279.704026 -308.866922) (xy 279.684735 -308.821646) (xy 279.672958 -308.773862) (xy 279.668998 -308.724808)
			(xy 279.33015 -308.724808) (xy 279.329655 -308.749415) (xy 279.32176 -308.797992) (xy 279.306176 -308.844673)
			(xy 279.283305 -308.88825) (xy 279.25374 -308.927594) (xy 279.218247 -308.961686) (xy 279.177744 -308.989642)
			(xy 279.133282 -309.01074) (xy 279.086011 -309.024432) (xy 279.037156 -309.030364) (xy 278.987981 -309.028383)
			(xy 278.939762 -309.018539) (xy 278.893746 -309.001087) (xy 278.851125 -308.97648) (xy 278.813004 -308.945355)
			(xy 278.780369 -308.908518) (xy 278.754066 -308.866922) (xy 278.734775 -308.821646) (xy 278.722998 -308.773862)
			(xy 278.719038 -308.724808) (xy 274.605496 -308.724808) (xy 274.605347 -308.740137) (xy 274.60255 -308.770667)
			(xy 274.599908 -308.785768) (xy 274.599908 -308.78653) (xy 274.599146 -308.791102) (xy 274.606004 -308.813708)
			(xy 274.67052 -308.881272) (xy 274.679161 -308.88948) (xy 274.701552 -308.89755) (xy 274.713446 -308.896766)
			(xy 274.72249 -308.895717) (xy 274.740664 -308.894571) (xy 274.749768 -308.89448) (xy 274.774591 -308.894963)
			(xy 274.823583 -308.90299) (xy 274.870631 -308.918837) (xy 274.914495 -308.942088) (xy 274.954019 -308.972128)
			(xy 274.988163 -309.008168) (xy 275.016027 -309.049257) (xy 275.036875 -309.094312) (xy 275.05016 -309.142147)
			(xy 275.05553 -309.1915) (xy 275.055081 -309.199788) (xy 275.393924 -309.199788) (xy 275.397884 -309.150734)
			(xy 275.409661 -309.10295) (xy 275.428952 -309.057674) (xy 275.455255 -309.016078) (xy 275.48789 -308.979241)
			(xy 275.526011 -308.948116) (xy 275.568632 -308.923509) (xy 275.614648 -308.906057) (xy 275.662867 -308.896213)
			(xy 275.712042 -308.894232) (xy 275.760897 -308.900164) (xy 275.808168 -308.913856) (xy 275.85263 -308.934954)
			(xy 275.893133 -308.96291) (xy 275.928626 -308.997002) (xy 275.958191 -309.036346) (xy 275.981062 -309.079923)
			(xy 275.996646 -309.126604) (xy 276.004541 -309.175181) (xy 276.005036 -309.199788) (xy 276.343884 -309.199788)
			(xy 276.347844 -309.150734) (xy 276.359621 -309.10295) (xy 276.378912 -309.057674) (xy 276.405215 -309.016078)
			(xy 276.43785 -308.979241) (xy 276.475971 -308.948116) (xy 276.518592 -308.923509) (xy 276.564608 -308.906057)
			(xy 276.612827 -308.896213) (xy 276.662002 -308.894232) (xy 276.710857 -308.900164) (xy 276.758128 -308.913856)
			(xy 276.80259 -308.934954) (xy 276.843093 -308.96291) (xy 276.878586 -308.997002) (xy 276.908151 -309.036346)
			(xy 276.931022 -309.079923) (xy 276.946606 -309.126604) (xy 276.954501 -309.175181) (xy 276.954996 -309.199788)
			(xy 277.294098 -309.199788) (xy 277.298058 -309.150734) (xy 277.309835 -309.10295) (xy 277.329126 -309.057674)
			(xy 277.355429 -309.016078) (xy 277.388064 -308.979241) (xy 277.426185 -308.948116) (xy 277.468806 -308.923509)
			(xy 277.514822 -308.906057) (xy 277.563041 -308.896213) (xy 277.612216 -308.894232) (xy 277.661071 -308.900164)
			(xy 277.708342 -308.913856) (xy 277.752804 -308.934954) (xy 277.793307 -308.96291) (xy 277.8288 -308.997002)
			(xy 277.858365 -309.036346) (xy 277.881236 -309.079923) (xy 277.89682 -309.126604) (xy 277.904715 -309.175181)
			(xy 277.90521 -309.199788) (xy 277.904715 -309.224395) (xy 277.89682 -309.272972) (xy 277.881236 -309.319653)
			(xy 277.858365 -309.36323) (xy 277.8288 -309.402574) (xy 277.793307 -309.436666) (xy 277.752804 -309.464622)
			(xy 277.708342 -309.48572) (xy 277.661071 -309.499412) (xy 277.612216 -309.505344) (xy 277.563041 -309.503363)
			(xy 277.514822 -309.493519) (xy 277.468806 -309.476067) (xy 277.426185 -309.45146) (xy 277.388064 -309.420335)
			(xy 277.355429 -309.383498) (xy 277.329126 -309.341902) (xy 277.309835 -309.296626) (xy 277.298058 -309.248842)
			(xy 277.294098 -309.199788) (xy 276.954996 -309.199788) (xy 276.954501 -309.224395) (xy 276.946606 -309.272972)
			(xy 276.931022 -309.319653) (xy 276.908151 -309.36323) (xy 276.878586 -309.402574) (xy 276.843093 -309.436666)
			(xy 276.80259 -309.464622) (xy 276.758128 -309.48572) (xy 276.710857 -309.499412) (xy 276.662002 -309.505344)
			(xy 276.612827 -309.503363) (xy 276.564608 -309.493519) (xy 276.518592 -309.476067) (xy 276.475971 -309.45146)
			(xy 276.43785 -309.420335) (xy 276.405215 -309.383498) (xy 276.378912 -309.341902) (xy 276.359621 -309.296626)
			(xy 276.347844 -309.248842) (xy 276.343884 -309.199788) (xy 276.005036 -309.199788) (xy 276.004541 -309.224395)
			(xy 275.996646 -309.272972) (xy 275.981062 -309.319653) (xy 275.958191 -309.36323) (xy 275.928626 -309.402574)
			(xy 275.893133 -309.436666) (xy 275.85263 -309.464622) (xy 275.808168 -309.48572) (xy 275.760897 -309.499412)
			(xy 275.712042 -309.505344) (xy 275.662867 -309.503363) (xy 275.614648 -309.493519) (xy 275.568632 -309.476067)
			(xy 275.526011 -309.45146) (xy 275.48789 -309.420335) (xy 275.455255 -309.383498) (xy 275.428952 -309.341902)
			(xy 275.409661 -309.296626) (xy 275.397884 -309.248842) (xy 275.393924 -309.199788) (xy 275.055081 -309.199788)
			(xy 275.052845 -309.241073) (xy 275.042176 -309.289558) (xy 275.023802 -309.335678) (xy 274.998209 -309.378218)
			(xy 274.966071 -309.416057) (xy 274.928234 -309.448197) (xy 274.885696 -309.473793) (xy 274.839577 -309.49217)
			(xy 274.791093 -309.502843) (xy 274.74152 -309.505531) (xy 274.692166 -309.500164) (xy 274.644331 -309.486882)
			(xy 274.599274 -309.466036) (xy 274.558183 -309.438176) (xy 274.522142 -309.404034) (xy 274.492099 -309.364512)
			(xy 274.468845 -309.320649) (xy 274.452995 -309.273602) (xy 274.444965 -309.224611) (xy 274.44446 -309.199788)
			(xy 274.444557 -309.190684) (xy 274.445699 -309.17251) (xy 274.446746 -309.163466) (xy 274.447538 -309.151575)
			(xy 274.43945 -309.129191) (xy 274.431252 -309.12054) (xy 274.363688 -309.056024) (xy 274.341082 -309.049166)
			(xy 274.336002 -309.049928) (xy 274.320837 -309.052567) (xy 274.29018 -309.055364) (xy 274.274788 -309.055516)
			(xy 274.20443 -309.055516) (xy 274.193743 -309.056089) (xy 274.174203 -309.064761) (xy 274.166584 -309.07228)
			(xy 274.108672 -309.136796) (xy 274.102068 -309.156608) (xy 274.103084 -309.166514) (xy 274.103338 -309.167022)
			(xy 274.103338 -309.168546) (xy 274.105116 -309.199534) (xy 274.105116 -309.200042) (xy 274.104627 -309.224021)
			(xy 274.097091 -309.271384) (xy 274.082243 -309.316986) (xy 274.060446 -309.359706) (xy 274.032239 -309.398492)
			(xy 273.998314 -309.432391) (xy 273.959506 -309.460569) (xy 273.91677 -309.482332) (xy 273.871156 -309.497146)
			(xy 273.823787 -309.504646) (xy 273.799808 -309.505096) (xy 273.79064 -309.505004) (xy 273.77234 -309.503861)
			(xy 273.763232 -309.50281) (xy 273.762978 -309.50281) (xy 273.751171 -309.501984) (xy 273.728903 -309.509918)
			(xy 273.720306 -309.51805) (xy 273.65579 -309.585614) (xy 273.648678 -309.608474) (xy 273.65071 -309.620412)
			(xy 273.654685 -309.647448) (xy 273.65469 -309.702089) (xy 273.65071 -309.729124) (xy 273.648678 -309.741062)
			(xy 273.65579 -309.763922) (xy 273.720306 -309.831486) (xy 273.728943 -309.839562) (xy 273.751181 -309.847515)
			(xy 273.762978 -309.846726) (xy 273.763232 -309.846726) (xy 273.77234 -309.845673) (xy 273.79064 -309.844531)
			(xy 273.799808 -309.84444) (xy 273.825059 -309.844962) (xy 273.874872 -309.853276) (xy 273.922637 -309.869674)
			(xy 273.967052 -309.893711) (xy 274.006904 -309.924731) (xy 274.041108 -309.961887) (xy 274.068729 -310.004166)
			(xy 274.089015 -310.050414) (xy 274.101413 -310.099371) (xy 274.105583 -310.1497) (xy 274.105579 -310.149748)
			(xy 274.443964 -310.149748) (xy 274.447924 -310.100694) (xy 274.459701 -310.05291) (xy 274.478992 -310.007634)
			(xy 274.505295 -309.966038) (xy 274.53793 -309.929201) (xy 274.576051 -309.898076) (xy 274.618672 -309.873469)
			(xy 274.664688 -309.856017) (xy 274.712907 -309.846173) (xy 274.762082 -309.844192) (xy 274.810937 -309.850124)
			(xy 274.858208 -309.863816) (xy 274.90267 -309.884914) (xy 274.943173 -309.91287) (xy 274.978666 -309.946962)
			(xy 275.008231 -309.986306) (xy 275.031102 -310.029883) (xy 275.046686 -310.076564) (xy 275.054581 -310.125141)
			(xy 275.055076 -310.149748) (xy 275.393924 -310.149748) (xy 275.397884 -310.100694) (xy 275.409661 -310.05291)
			(xy 275.428952 -310.007634) (xy 275.455255 -309.966038) (xy 275.48789 -309.929201) (xy 275.526011 -309.898076)
			(xy 275.568632 -309.873469) (xy 275.614648 -309.856017) (xy 275.662867 -309.846173) (xy 275.712042 -309.844192)
			(xy 275.760897 -309.850124) (xy 275.808168 -309.863816) (xy 275.85263 -309.884914) (xy 275.893133 -309.91287)
			(xy 275.928626 -309.946962) (xy 275.958191 -309.986306) (xy 275.981062 -310.029883) (xy 275.996646 -310.076564)
			(xy 276.004541 -310.125141) (xy 276.005036 -310.149748) (xy 276.343884 -310.149748) (xy 276.347844 -310.100694)
			(xy 276.359621 -310.05291) (xy 276.378912 -310.007634) (xy 276.405215 -309.966038) (xy 276.43785 -309.929201)
			(xy 276.475971 -309.898076) (xy 276.518592 -309.873469) (xy 276.564608 -309.856017) (xy 276.612827 -309.846173)
			(xy 276.662002 -309.844192) (xy 276.710857 -309.850124) (xy 276.758128 -309.863816) (xy 276.80259 -309.884914)
			(xy 276.843093 -309.91287) (xy 276.878586 -309.946962) (xy 276.908151 -309.986306) (xy 276.931022 -310.029883)
			(xy 276.946606 -310.076564) (xy 276.954501 -310.125141) (xy 276.954996 -310.149748) (xy 277.294098 -310.149748)
			(xy 277.298058 -310.100694) (xy 277.309835 -310.05291) (xy 277.329126 -310.007634) (xy 277.355429 -309.966038)
			(xy 277.388064 -309.929201) (xy 277.426185 -309.898076) (xy 277.468806 -309.873469) (xy 277.514822 -309.856017)
			(xy 277.563041 -309.846173) (xy 277.612216 -309.844192) (xy 277.661071 -309.850124) (xy 277.708342 -309.863816)
			(xy 277.752804 -309.884914) (xy 277.793307 -309.91287) (xy 277.8288 -309.946962) (xy 277.858365 -309.986306)
			(xy 277.881236 -310.029883) (xy 277.89682 -310.076564) (xy 277.904715 -310.125141) (xy 277.905043 -310.141429)
			(xy 278.244229 -310.141429) (xy 278.249593 -310.092089) (xy 278.262869 -310.044267) (xy 278.283705 -309.999222)
			(xy 278.311555 -309.958141) (xy 278.345683 -309.922106) (xy 278.385192 -309.892068) (xy 278.429039 -309.868816)
			(xy 278.47607 -309.852964) (xy 278.525047 -309.844929) (xy 278.549862 -309.84444) (xy 278.564045 -309.844621)
			(xy 278.592285 -309.84729) (xy 278.60625 -309.849774) (xy 278.618696 -309.85206) (xy 278.642318 -309.844694)
			(xy 278.719788 -309.767224) (xy 278.727154 -309.743602) (xy 278.724868 -309.731156) (xy 278.722389 -309.717191)
			(xy 278.719719 -309.688951) (xy 278.719534 -309.674768) (xy 278.720056 -309.649513) (xy 278.728369 -309.599691)
			(xy 278.74477 -309.551917) (xy 278.768811 -309.507494) (xy 278.799835 -309.467634) (xy 278.836997 -309.433424)
			(xy 278.879283 -309.405798) (xy 278.925539 -309.385508) (xy 278.974504 -309.373108) (xy 279.024842 -309.368937)
			(xy 279.07518 -309.373108) (xy 279.124145 -309.385508) (xy 279.170401 -309.405798) (xy 279.212687 -309.433424)
			(xy 279.249849 -309.467634) (xy 279.280873 -309.507494) (xy 279.304914 -309.551917) (xy 279.321315 -309.599691)
			(xy 279.329628 -309.649513) (xy 279.33015 -309.674768) (xy 279.329968 -309.688951) (xy 279.327299 -309.717191)
			(xy 279.324816 -309.731156) (xy 279.32253 -309.743602) (xy 279.329896 -309.767224) (xy 279.407366 -309.844694)
			(xy 279.430988 -309.85206) (xy 279.443434 -309.849774) (xy 279.4574 -309.847297) (xy 279.485639 -309.844625)
			(xy 279.499822 -309.84444) (xy 279.52464 -309.844901) (xy 279.573621 -309.852935) (xy 279.620658 -309.868786)
			(xy 279.66451 -309.892038) (xy 279.704024 -309.922078) (xy 279.738157 -309.958114) (xy 279.766011 -309.999198)
			(xy 279.786852 -310.044247) (xy 279.80013 -310.092073) (xy 279.805497 -310.141416) (xy 280.144129 -310.141416)
			(xy 280.149496 -310.092075) (xy 280.162774 -310.044253) (xy 280.183613 -309.999208) (xy 280.211465 -309.958128)
			(xy 280.245596 -309.922095) (xy 280.285107 -309.892058) (xy 280.328956 -309.868809) (xy 280.375989 -309.852959)
			(xy 280.424966 -309.844927) (xy 280.449782 -309.84444) (xy 280.463965 -309.844618) (xy 280.492205 -309.847289)
			(xy 280.50617 -309.849774) (xy 280.518616 -309.85206) (xy 280.542238 -309.844694) (xy 280.619708 -309.767224)
			(xy 280.627074 -309.743602) (xy 280.624788 -309.731156) (xy 280.622309 -309.71719) (xy 280.619639 -309.688951)
			(xy 280.619454 -309.674768) (xy 280.619976 -309.649513) (xy 280.628289 -309.599691) (xy 280.64469 -309.551917)
			(xy 280.668731 -309.507494) (xy 280.699755 -309.467634) (xy 280.736917 -309.433424) (xy 280.779203 -309.405798)
			(xy 280.825459 -309.385508) (xy 280.874424 -309.373108) (xy 280.924762 -309.368937) (xy 280.9751 -309.373108)
			(xy 281.024065 -309.385508) (xy 281.070321 -309.405798) (xy 281.112607 -309.433424) (xy 281.149769 -309.467634)
			(xy 281.180793 -309.507494) (xy 281.204834 -309.551917) (xy 281.221235 -309.599691) (xy 281.229548 -309.649513)
			(xy 281.23007 -309.674768) (xy 281.22989 -309.688951) (xy 281.22722 -309.717191) (xy 281.224736 -309.731156)
			(xy 281.22245 -309.743602) (xy 281.229816 -309.767224) (xy 281.307286 -309.844694) (xy 281.330908 -309.85206)
			(xy 281.343354 -309.849774) (xy 281.357319 -309.847294) (xy 281.385559 -309.844625) (xy 281.399742 -309.84444)
			(xy 281.424558 -309.844923) (xy 281.473535 -309.852959) (xy 281.520567 -309.868812) (xy 281.564414 -309.892064)
			(xy 281.603923 -309.922104) (xy 281.638052 -309.95814) (xy 281.665901 -309.999221) (xy 281.686738 -310.044267)
			(xy 281.700013 -310.092091) (xy 281.705377 -310.141432) (xy 281.704926 -310.149748) (xy 282.043898 -310.149748)
			(xy 282.047858 -310.100694) (xy 282.059635 -310.05291) (xy 282.078926 -310.007634) (xy 282.105229 -309.966038)
			(xy 282.137864 -309.929201) (xy 282.175985 -309.898076) (xy 282.218606 -309.873469) (xy 282.264622 -309.856017)
			(xy 282.312841 -309.846173) (xy 282.362016 -309.844192) (xy 282.410871 -309.850124) (xy 282.458142 -309.863816)
			(xy 282.502604 -309.884914) (xy 282.543107 -309.91287) (xy 282.5786 -309.946962) (xy 282.608165 -309.986306)
			(xy 282.631036 -310.029883) (xy 282.64662 -310.076564) (xy 282.654515 -310.125141) (xy 282.65501 -310.149748)
			(xy 282.994112 -310.149748) (xy 282.998072 -310.100694) (xy 283.009849 -310.05291) (xy 283.02914 -310.007634)
			(xy 283.055443 -309.966038) (xy 283.088078 -309.929201) (xy 283.126199 -309.898076) (xy 283.16882 -309.873469)
			(xy 283.214836 -309.856017) (xy 283.263055 -309.846173) (xy 283.31223 -309.844192) (xy 283.361085 -309.850124)
			(xy 283.408356 -309.863816) (xy 283.452818 -309.884914) (xy 283.493321 -309.91287) (xy 283.528814 -309.946962)
			(xy 283.558379 -309.986306) (xy 283.58125 -310.029883) (xy 283.596834 -310.076564) (xy 283.604729 -310.125141)
			(xy 283.605224 -310.149748) (xy 283.944072 -310.149748) (xy 283.948032 -310.100694) (xy 283.959809 -310.05291)
			(xy 283.9791 -310.007634) (xy 284.005403 -309.966038) (xy 284.038038 -309.929201) (xy 284.076159 -309.898076)
			(xy 284.11878 -309.873469) (xy 284.164796 -309.856017) (xy 284.213015 -309.846173) (xy 284.26219 -309.844192)
			(xy 284.311045 -309.850124) (xy 284.358316 -309.863816) (xy 284.402778 -309.884914) (xy 284.443281 -309.91287)
			(xy 284.478774 -309.946962) (xy 284.508339 -309.986306) (xy 284.53121 -310.029883) (xy 284.546794 -310.076564)
			(xy 284.554689 -310.125141) (xy 284.555184 -310.149748) (xy 284.894032 -310.149748) (xy 284.897992 -310.100694)
			(xy 284.909769 -310.05291) (xy 284.92906 -310.007634) (xy 284.955363 -309.966038) (xy 284.987998 -309.929201)
			(xy 285.026119 -309.898076) (xy 285.06874 -309.873469) (xy 285.114756 -309.856017) (xy 285.162975 -309.846173)
			(xy 285.21215 -309.844192) (xy 285.261005 -309.850124) (xy 285.308276 -309.863816) (xy 285.352738 -309.884914)
			(xy 285.393241 -309.91287) (xy 285.428734 -309.946962) (xy 285.458299 -309.986306) (xy 285.48117 -310.029883)
			(xy 285.496754 -310.076564) (xy 285.504649 -310.125141) (xy 285.505144 -310.149748) (xy 285.843992 -310.149748)
			(xy 285.847952 -310.100694) (xy 285.859729 -310.05291) (xy 285.87902 -310.007634) (xy 285.905323 -309.966038)
			(xy 285.937958 -309.929201) (xy 285.976079 -309.898076) (xy 286.0187 -309.873469) (xy 286.064716 -309.856017)
			(xy 286.112935 -309.846173) (xy 286.16211 -309.844192) (xy 286.210965 -309.850124) (xy 286.258236 -309.863816)
			(xy 286.302698 -309.884914) (xy 286.343201 -309.91287) (xy 286.378694 -309.946962) (xy 286.408259 -309.986306)
			(xy 286.43113 -310.029883) (xy 286.446714 -310.076564) (xy 286.454609 -310.125141) (xy 286.455104 -310.149748)
			(xy 286.793952 -310.149748) (xy 286.797912 -310.100694) (xy 286.809689 -310.05291) (xy 286.82898 -310.007634)
			(xy 286.855283 -309.966038) (xy 286.887918 -309.929201) (xy 286.926039 -309.898076) (xy 286.96866 -309.873469)
			(xy 287.014676 -309.856017) (xy 287.062895 -309.846173) (xy 287.11207 -309.844192) (xy 287.160925 -309.850124)
			(xy 287.208196 -309.863816) (xy 287.252658 -309.884914) (xy 287.293161 -309.91287) (xy 287.328654 -309.946962)
			(xy 287.358219 -309.986306) (xy 287.38109 -310.029883) (xy 287.396674 -310.076564) (xy 287.404569 -310.125141)
			(xy 287.405064 -310.149748) (xy 287.743912 -310.149748) (xy 287.747872 -310.100694) (xy 287.759649 -310.05291)
			(xy 287.77894 -310.007634) (xy 287.805243 -309.966038) (xy 287.837878 -309.929201) (xy 287.875999 -309.898076)
			(xy 287.91862 -309.873469) (xy 287.964636 -309.856017) (xy 288.012855 -309.846173) (xy 288.06203 -309.844192)
			(xy 288.110885 -309.850124) (xy 288.158156 -309.863816) (xy 288.202618 -309.884914) (xy 288.243121 -309.91287)
			(xy 288.278614 -309.946962) (xy 288.308179 -309.986306) (xy 288.33105 -310.029883) (xy 288.346634 -310.076564)
			(xy 288.354529 -310.125141) (xy 288.355024 -310.149748) (xy 288.694126 -310.149748) (xy 288.698086 -310.100694)
			(xy 288.709863 -310.05291) (xy 288.729154 -310.007634) (xy 288.755457 -309.966038) (xy 288.788092 -309.929201)
			(xy 288.826213 -309.898076) (xy 288.868834 -309.873469) (xy 288.91485 -309.856017) (xy 288.963069 -309.846173)
			(xy 289.012244 -309.844192) (xy 289.061099 -309.850124) (xy 289.10837 -309.863816) (xy 289.152832 -309.884914)
			(xy 289.193335 -309.91287) (xy 289.228828 -309.946962) (xy 289.258393 -309.986306) (xy 289.281264 -310.029883)
			(xy 289.296848 -310.076564) (xy 289.304743 -310.125141) (xy 289.305238 -310.149748) (xy 289.644086 -310.149748)
			(xy 289.648046 -310.100694) (xy 289.659823 -310.05291) (xy 289.679114 -310.007634) (xy 289.705417 -309.966038)
			(xy 289.738052 -309.929201) (xy 289.776173 -309.898076) (xy 289.818794 -309.873469) (xy 289.86481 -309.856017)
			(xy 289.913029 -309.846173) (xy 289.962204 -309.844192) (xy 290.011059 -309.850124) (xy 290.05833 -309.863816)
			(xy 290.102792 -309.884914) (xy 290.143295 -309.91287) (xy 290.178788 -309.946962) (xy 290.208353 -309.986306)
			(xy 290.231224 -310.029883) (xy 290.246808 -310.076564) (xy 290.254703 -310.125141) (xy 290.255198 -310.149748)
			(xy 290.594046 -310.149748) (xy 290.598006 -310.100694) (xy 290.609783 -310.05291) (xy 290.629074 -310.007634)
			(xy 290.655377 -309.966038) (xy 290.688012 -309.929201) (xy 290.726133 -309.898076) (xy 290.768754 -309.873469)
			(xy 290.81477 -309.856017) (xy 290.862989 -309.846173) (xy 290.912164 -309.844192) (xy 290.961019 -309.850124)
			(xy 291.00829 -309.863816) (xy 291.052752 -309.884914) (xy 291.093255 -309.91287) (xy 291.128748 -309.946962)
			(xy 291.158313 -309.986306) (xy 291.181184 -310.029883) (xy 291.196768 -310.076564) (xy 291.204663 -310.125141)
			(xy 291.205158 -310.149748) (xy 291.544006 -310.149748) (xy 291.547966 -310.100694) (xy 291.559743 -310.05291)
			(xy 291.579034 -310.007634) (xy 291.605337 -309.966038) (xy 291.637972 -309.929201) (xy 291.676093 -309.898076)
			(xy 291.718714 -309.873469) (xy 291.76473 -309.856017) (xy 291.812949 -309.846173) (xy 291.862124 -309.844192)
			(xy 291.910979 -309.850124) (xy 291.95825 -309.863816) (xy 292.002712 -309.884914) (xy 292.043215 -309.91287)
			(xy 292.078708 -309.946962) (xy 292.108273 -309.986306) (xy 292.131144 -310.029883) (xy 292.146728 -310.076564)
			(xy 292.154623 -310.125141) (xy 292.155118 -310.149748) (xy 292.493966 -310.149748) (xy 292.497926 -310.100694)
			(xy 292.509703 -310.05291) (xy 292.528994 -310.007634) (xy 292.555297 -309.966038) (xy 292.587932 -309.929201)
			(xy 292.626053 -309.898076) (xy 292.668674 -309.873469) (xy 292.71469 -309.856017) (xy 292.762909 -309.846173)
			(xy 292.812084 -309.844192) (xy 292.860939 -309.850124) (xy 292.90821 -309.863816) (xy 292.952672 -309.884914)
			(xy 292.993175 -309.91287) (xy 293.028668 -309.946962) (xy 293.058233 -309.986306) (xy 293.081104 -310.029883)
			(xy 293.096688 -310.076564) (xy 293.104583 -310.125141) (xy 293.105078 -310.149748) (xy 293.443926 -310.149748)
			(xy 293.447886 -310.100694) (xy 293.459663 -310.05291) (xy 293.478954 -310.007634) (xy 293.505257 -309.966038)
			(xy 293.537892 -309.929201) (xy 293.576013 -309.898076) (xy 293.618634 -309.873469) (xy 293.66465 -309.856017)
			(xy 293.712869 -309.846173) (xy 293.762044 -309.844192) (xy 293.810899 -309.850124) (xy 293.85817 -309.863816)
			(xy 293.902632 -309.884914) (xy 293.943135 -309.91287) (xy 293.978628 -309.946962) (xy 294.008193 -309.986306)
			(xy 294.031064 -310.029883) (xy 294.046648 -310.076564) (xy 294.054543 -310.125141) (xy 294.055038 -310.149748)
			(xy 294.054543 -310.174355) (xy 294.046648 -310.222932) (xy 294.031064 -310.269613) (xy 294.008193 -310.31319)
			(xy 293.978628 -310.352534) (xy 293.943135 -310.386626) (xy 293.902632 -310.414582) (xy 293.85817 -310.43568)
			(xy 293.810899 -310.449372) (xy 293.762044 -310.455304) (xy 293.712869 -310.453323) (xy 293.66465 -310.443479)
			(xy 293.618634 -310.426027) (xy 293.576013 -310.40142) (xy 293.537892 -310.370295) (xy 293.505257 -310.333458)
			(xy 293.478954 -310.291862) (xy 293.459663 -310.246586) (xy 293.447886 -310.198802) (xy 293.443926 -310.149748)
			(xy 293.105078 -310.149748) (xy 293.104583 -310.174355) (xy 293.096688 -310.222932) (xy 293.081104 -310.269613)
			(xy 293.058233 -310.31319) (xy 293.028668 -310.352534) (xy 292.993175 -310.386626) (xy 292.952672 -310.414582)
			(xy 292.90821 -310.43568) (xy 292.860939 -310.449372) (xy 292.812084 -310.455304) (xy 292.762909 -310.453323)
			(xy 292.71469 -310.443479) (xy 292.668674 -310.426027) (xy 292.626053 -310.40142) (xy 292.587932 -310.370295)
			(xy 292.555297 -310.333458) (xy 292.528994 -310.291862) (xy 292.509703 -310.246586) (xy 292.497926 -310.198802)
			(xy 292.493966 -310.149748) (xy 292.155118 -310.149748) (xy 292.154623 -310.174355) (xy 292.146728 -310.222932)
			(xy 292.131144 -310.269613) (xy 292.108273 -310.31319) (xy 292.078708 -310.352534) (xy 292.043215 -310.386626)
			(xy 292.002712 -310.414582) (xy 291.95825 -310.43568) (xy 291.910979 -310.449372) (xy 291.862124 -310.455304)
			(xy 291.812949 -310.453323) (xy 291.76473 -310.443479) (xy 291.718714 -310.426027) (xy 291.676093 -310.40142)
			(xy 291.637972 -310.370295) (xy 291.605337 -310.333458) (xy 291.579034 -310.291862) (xy 291.559743 -310.246586)
			(xy 291.547966 -310.198802) (xy 291.544006 -310.149748) (xy 291.205158 -310.149748) (xy 291.204663 -310.174355)
			(xy 291.196768 -310.222932) (xy 291.181184 -310.269613) (xy 291.158313 -310.31319) (xy 291.128748 -310.352534)
			(xy 291.093255 -310.386626) (xy 291.052752 -310.414582) (xy 291.00829 -310.43568) (xy 290.961019 -310.449372)
			(xy 290.912164 -310.455304) (xy 290.862989 -310.453323) (xy 290.81477 -310.443479) (xy 290.768754 -310.426027)
			(xy 290.726133 -310.40142) (xy 290.688012 -310.370295) (xy 290.655377 -310.333458) (xy 290.629074 -310.291862)
			(xy 290.609783 -310.246586) (xy 290.598006 -310.198802) (xy 290.594046 -310.149748) (xy 290.255198 -310.149748)
			(xy 290.254703 -310.174355) (xy 290.246808 -310.222932) (xy 290.231224 -310.269613) (xy 290.208353 -310.31319)
			(xy 290.178788 -310.352534) (xy 290.143295 -310.386626) (xy 290.102792 -310.414582) (xy 290.05833 -310.43568)
			(xy 290.011059 -310.449372) (xy 289.962204 -310.455304) (xy 289.913029 -310.453323) (xy 289.86481 -310.443479)
			(xy 289.818794 -310.426027) (xy 289.776173 -310.40142) (xy 289.738052 -310.370295) (xy 289.705417 -310.333458)
			(xy 289.679114 -310.291862) (xy 289.659823 -310.246586) (xy 289.648046 -310.198802) (xy 289.644086 -310.149748)
			(xy 289.305238 -310.149748) (xy 289.304743 -310.174355) (xy 289.296848 -310.222932) (xy 289.281264 -310.269613)
			(xy 289.258393 -310.31319) (xy 289.228828 -310.352534) (xy 289.193335 -310.386626) (xy 289.152832 -310.414582)
			(xy 289.10837 -310.43568) (xy 289.061099 -310.449372) (xy 289.012244 -310.455304) (xy 288.963069 -310.453323)
			(xy 288.91485 -310.443479) (xy 288.868834 -310.426027) (xy 288.826213 -310.40142) (xy 288.788092 -310.370295)
			(xy 288.755457 -310.333458) (xy 288.729154 -310.291862) (xy 288.709863 -310.246586) (xy 288.698086 -310.198802)
			(xy 288.694126 -310.149748) (xy 288.355024 -310.149748) (xy 288.354529 -310.174355) (xy 288.346634 -310.222932)
			(xy 288.33105 -310.269613) (xy 288.308179 -310.31319) (xy 288.278614 -310.352534) (xy 288.243121 -310.386626)
			(xy 288.202618 -310.414582) (xy 288.158156 -310.43568) (xy 288.110885 -310.449372) (xy 288.06203 -310.455304)
			(xy 288.012855 -310.453323) (xy 287.964636 -310.443479) (xy 287.91862 -310.426027) (xy 287.875999 -310.40142)
			(xy 287.837878 -310.370295) (xy 287.805243 -310.333458) (xy 287.77894 -310.291862) (xy 287.759649 -310.246586)
			(xy 287.747872 -310.198802) (xy 287.743912 -310.149748) (xy 287.405064 -310.149748) (xy 287.404569 -310.174355)
			(xy 287.396674 -310.222932) (xy 287.38109 -310.269613) (xy 287.358219 -310.31319) (xy 287.328654 -310.352534)
			(xy 287.293161 -310.386626) (xy 287.252658 -310.414582) (xy 287.208196 -310.43568) (xy 287.160925 -310.449372)
			(xy 287.11207 -310.455304) (xy 287.062895 -310.453323) (xy 287.014676 -310.443479) (xy 286.96866 -310.426027)
			(xy 286.926039 -310.40142) (xy 286.887918 -310.370295) (xy 286.855283 -310.333458) (xy 286.82898 -310.291862)
			(xy 286.809689 -310.246586) (xy 286.797912 -310.198802) (xy 286.793952 -310.149748) (xy 286.455104 -310.149748)
			(xy 286.454609 -310.174355) (xy 286.446714 -310.222932) (xy 286.43113 -310.269613) (xy 286.408259 -310.31319)
			(xy 286.378694 -310.352534) (xy 286.343201 -310.386626) (xy 286.302698 -310.414582) (xy 286.258236 -310.43568)
			(xy 286.210965 -310.449372) (xy 286.16211 -310.455304) (xy 286.112935 -310.453323) (xy 286.064716 -310.443479)
			(xy 286.0187 -310.426027) (xy 285.976079 -310.40142) (xy 285.937958 -310.370295) (xy 285.905323 -310.333458)
			(xy 285.87902 -310.291862) (xy 285.859729 -310.246586) (xy 285.847952 -310.198802) (xy 285.843992 -310.149748)
			(xy 285.505144 -310.149748) (xy 285.504649 -310.174355) (xy 285.496754 -310.222932) (xy 285.48117 -310.269613)
			(xy 285.458299 -310.31319) (xy 285.428734 -310.352534) (xy 285.393241 -310.386626) (xy 285.352738 -310.414582)
			(xy 285.308276 -310.43568) (xy 285.261005 -310.449372) (xy 285.21215 -310.455304) (xy 285.162975 -310.453323)
			(xy 285.114756 -310.443479) (xy 285.06874 -310.426027) (xy 285.026119 -310.40142) (xy 284.987998 -310.370295)
			(xy 284.955363 -310.333458) (xy 284.92906 -310.291862) (xy 284.909769 -310.246586) (xy 284.897992 -310.198802)
			(xy 284.894032 -310.149748) (xy 284.555184 -310.149748) (xy 284.554689 -310.174355) (xy 284.546794 -310.222932)
			(xy 284.53121 -310.269613) (xy 284.508339 -310.31319) (xy 284.478774 -310.352534) (xy 284.443281 -310.386626)
			(xy 284.402778 -310.414582) (xy 284.358316 -310.43568) (xy 284.311045 -310.449372) (xy 284.26219 -310.455304)
			(xy 284.213015 -310.453323) (xy 284.164796 -310.443479) (xy 284.11878 -310.426027) (xy 284.076159 -310.40142)
			(xy 284.038038 -310.370295) (xy 284.005403 -310.333458) (xy 283.9791 -310.291862) (xy 283.959809 -310.246586)
			(xy 283.948032 -310.198802) (xy 283.944072 -310.149748) (xy 283.605224 -310.149748) (xy 283.604729 -310.174355)
			(xy 283.596834 -310.222932) (xy 283.58125 -310.269613) (xy 283.558379 -310.31319) (xy 283.528814 -310.352534)
			(xy 283.493321 -310.386626) (xy 283.452818 -310.414582) (xy 283.408356 -310.43568) (xy 283.361085 -310.449372)
			(xy 283.31223 -310.455304) (xy 283.263055 -310.453323) (xy 283.214836 -310.443479) (xy 283.16882 -310.426027)
			(xy 283.126199 -310.40142) (xy 283.088078 -310.370295) (xy 283.055443 -310.333458) (xy 283.02914 -310.291862)
			(xy 283.009849 -310.246586) (xy 282.998072 -310.198802) (xy 282.994112 -310.149748) (xy 282.65501 -310.149748)
			(xy 282.654515 -310.174355) (xy 282.64662 -310.222932) (xy 282.631036 -310.269613) (xy 282.608165 -310.31319)
			(xy 282.5786 -310.352534) (xy 282.543107 -310.386626) (xy 282.502604 -310.414582) (xy 282.458142 -310.43568)
			(xy 282.410871 -310.449372) (xy 282.362016 -310.455304) (xy 282.312841 -310.453323) (xy 282.264622 -310.443479)
			(xy 282.218606 -310.426027) (xy 282.175985 -310.40142) (xy 282.137864 -310.370295) (xy 282.105229 -310.333458)
			(xy 282.078926 -310.291862) (xy 282.059635 -310.246586) (xy 282.047858 -310.198802) (xy 282.043898 -310.149748)
			(xy 281.704926 -310.149748) (xy 281.702688 -310.190991) (xy 281.692018 -310.239462) (xy 281.673646 -310.285569)
			(xy 281.648058 -310.328096) (xy 281.615928 -310.365923) (xy 281.578101 -310.398055) (xy 281.535574 -310.423644)
			(xy 281.489468 -310.442016) (xy 281.440997 -310.452688) (xy 281.391438 -310.455377) (xy 281.342097 -310.450014)
			(xy 281.294273 -310.43674) (xy 281.249227 -310.415904) (xy 281.208144 -310.388055) (xy 281.172108 -310.353928)
			(xy 281.142068 -310.31442) (xy 281.118814 -310.270572) (xy 281.10296 -310.223541) (xy 281.094924 -310.174564)
			(xy 281.094434 -310.149748) (xy 281.094617 -310.135565) (xy 281.097285 -310.107325) (xy 281.099768 -310.09336)
			(xy 281.102054 -310.080914) (xy 281.094688 -310.057292) (xy 281.017218 -309.979822) (xy 280.993596 -309.972456)
			(xy 280.98115 -309.974742) (xy 280.967184 -309.977221) (xy 280.938945 -309.979891) (xy 280.924762 -309.980076)
			(xy 280.910579 -309.979905) (xy 280.882339 -309.977229) (xy 280.868374 -309.974742) (xy 280.855928 -309.972456)
			(xy 280.832306 -309.979822) (xy 280.754836 -310.057292) (xy 280.74747 -310.080914) (xy 280.749756 -310.09336)
			(xy 280.752236 -310.107325) (xy 280.754906 -310.135565) (xy 280.75509 -310.149748) (xy 280.75457 -310.174564)
			(xy 280.746534 -310.22354) (xy 280.730679 -310.270572) (xy 280.707426 -310.314419) (xy 280.677385 -310.353926)
			(xy 280.641348 -310.388054) (xy 280.600266 -310.415902) (xy 280.555219 -310.436737) (xy 280.507395 -310.45001)
			(xy 280.458054 -310.455372) (xy 280.408495 -310.45268) (xy 280.360025 -310.442007) (xy 280.313919 -310.423634)
			(xy 280.271394 -310.398043) (xy 280.233568 -310.365911) (xy 280.201439 -310.328082) (xy 280.175853 -310.285554)
			(xy 280.157484 -310.239446) (xy 280.146815 -310.190975) (xy 280.144129 -310.141416) (xy 279.805497 -310.141416)
			(xy 279.805497 -310.141418) (xy 279.80281 -310.190981) (xy 279.79214 -310.239456) (xy 279.773769 -310.285567)
			(xy 279.748181 -310.328099) (xy 279.716049 -310.36593) (xy 279.67822 -310.398066) (xy 279.635691 -310.423658)
			(xy 279.589581 -310.442033) (xy 279.541107 -310.452706) (xy 279.491544 -310.455398) (xy 279.442199 -310.450035)
			(xy 279.394371 -310.436761) (xy 279.349321 -310.415924) (xy 279.308235 -310.388073) (xy 279.272195 -310.353943)
			(xy 279.242152 -310.314432) (xy 279.218897 -310.270582) (xy 279.203041 -310.223546) (xy 279.195004 -310.174566)
			(xy 279.194514 -310.149748) (xy 279.194697 -310.135565) (xy 279.197365 -310.107325) (xy 279.199848 -310.09336)
			(xy 279.202134 -310.080914) (xy 279.194768 -310.057292) (xy 279.117298 -309.979822) (xy 279.093676 -309.972456)
			(xy 279.08123 -309.974742) (xy 279.067265 -309.977224) (xy 279.039025 -309.979892) (xy 279.024842 -309.980076)
			(xy 279.010659 -309.979894) (xy 278.982419 -309.977226) (xy 278.968454 -309.974742) (xy 278.956008 -309.972456)
			(xy 278.932386 -309.979822) (xy 278.854916 -310.057292) (xy 278.84755 -310.080914) (xy 278.849836 -310.09336)
			(xy 278.852316 -310.107325) (xy 278.854986 -310.135565) (xy 278.85517 -310.149748) (xy 278.85467 -310.174563)
			(xy 278.846634 -310.223539) (xy 278.83078 -310.27057) (xy 278.807527 -310.314417) (xy 278.777487 -310.353924)
			(xy 278.741451 -310.388051) (xy 278.70037 -310.415899) (xy 278.655324 -310.436735) (xy 278.607501 -310.450009)
			(xy 278.558161 -310.455371) (xy 278.508603 -310.452681) (xy 278.460132 -310.44201) (xy 278.414027 -310.423638)
			(xy 278.371501 -310.398049) (xy 278.333675 -310.365918) (xy 278.301545 -310.32809) (xy 278.275958 -310.285564)
			(xy 278.257587 -310.239458) (xy 278.246917 -310.190988) (xy 278.244229 -310.141429) (xy 277.905043 -310.141429)
			(xy 277.90521 -310.149748) (xy 277.904715 -310.174355) (xy 277.89682 -310.222932) (xy 277.881236 -310.269613)
			(xy 277.858365 -310.31319) (xy 277.8288 -310.352534) (xy 277.793307 -310.386626) (xy 277.752804 -310.414582)
			(xy 277.708342 -310.43568) (xy 277.661071 -310.449372) (xy 277.612216 -310.455304) (xy 277.563041 -310.453323)
			(xy 277.514822 -310.443479) (xy 277.468806 -310.426027) (xy 277.426185 -310.40142) (xy 277.388064 -310.370295)
			(xy 277.355429 -310.333458) (xy 277.329126 -310.291862) (xy 277.309835 -310.246586) (xy 277.298058 -310.198802)
			(xy 277.294098 -310.149748) (xy 276.954996 -310.149748) (xy 276.954501 -310.174355) (xy 276.946606 -310.222932)
			(xy 276.931022 -310.269613) (xy 276.908151 -310.31319) (xy 276.878586 -310.352534) (xy 276.843093 -310.386626)
			(xy 276.80259 -310.414582) (xy 276.758128 -310.43568) (xy 276.710857 -310.449372) (xy 276.662002 -310.455304)
			(xy 276.612827 -310.453323) (xy 276.564608 -310.443479) (xy 276.518592 -310.426027) (xy 276.475971 -310.40142)
			(xy 276.43785 -310.370295) (xy 276.405215 -310.333458) (xy 276.378912 -310.291862) (xy 276.359621 -310.246586)
			(xy 276.347844 -310.198802) (xy 276.343884 -310.149748) (xy 276.005036 -310.149748) (xy 276.004541 -310.174355)
			(xy 275.996646 -310.222932) (xy 275.981062 -310.269613) (xy 275.958191 -310.31319) (xy 275.928626 -310.352534)
			(xy 275.893133 -310.386626) (xy 275.85263 -310.414582) (xy 275.808168 -310.43568) (xy 275.760897 -310.449372)
			(xy 275.712042 -310.455304) (xy 275.662867 -310.453323) (xy 275.614648 -310.443479) (xy 275.568632 -310.426027)
			(xy 275.526011 -310.40142) (xy 275.48789 -310.370295) (xy 275.455255 -310.333458) (xy 275.428952 -310.291862)
			(xy 275.409661 -310.246586) (xy 275.397884 -310.198802) (xy 275.393924 -310.149748) (xy 275.055076 -310.149748)
			(xy 275.054581 -310.174355) (xy 275.046686 -310.222932) (xy 275.031102 -310.269613) (xy 275.008231 -310.31319)
			(xy 274.978666 -310.352534) (xy 274.943173 -310.386626) (xy 274.90267 -310.414582) (xy 274.858208 -310.43568)
			(xy 274.810937 -310.449372) (xy 274.762082 -310.455304) (xy 274.712907 -310.453323) (xy 274.664688 -310.443479)
			(xy 274.618672 -310.426027) (xy 274.576051 -310.40142) (xy 274.53793 -310.370295) (xy 274.505295 -310.333458)
			(xy 274.478992 -310.291862) (xy 274.459701 -310.246586) (xy 274.447924 -310.198802) (xy 274.443964 -310.149748)
			(xy 274.105579 -310.149748) (xy 274.101413 -310.200029) (xy 274.089015 -310.248986) (xy 274.068729 -310.295234)
			(xy 274.041108 -310.337513) (xy 274.006904 -310.374669) (xy 273.967052 -310.405689) (xy 273.922637 -310.429726)
			(xy 273.874872 -310.446124) (xy 273.825059 -310.454438) (xy 273.799808 -310.455056) (xy 273.7993 -310.455056)
			(xy 273.774129 -310.454518) (xy 273.724474 -310.446217) (xy 273.700494 -310.438546) (xy 273.692874 -310.436514)
			(xy 273.689318 -310.436006) (xy 273.677099 -310.434706) (xy 273.65376 -310.442276) (xy 273.644614 -310.450484)
			(xy 273.63547 -310.459628) (xy 273.628612 -310.48325) (xy 273.632422 -310.503062) (xy 273.633946 -310.507126)
			(xy 273.641058 -310.527954) (xy 273.641058 -310.528462) (xy 273.644614 -310.540654) (xy 273.645884 -310.545988)
			(xy 273.645884 -310.546242) (xy 273.650336 -310.565495) (xy 273.655172 -310.604716) (xy 273.655536 -310.624474)
			(xy 273.655536 -310.69534) (xy 273.656103 -310.706029) (xy 273.664771 -310.725576) (xy 273.6723 -310.733186)
			(xy 273.728434 -310.783732) (xy 273.736653 -310.790522) (xy 273.756911 -310.797109) (xy 273.76755 -310.796432)
			(xy 273.767804 -310.796432) (xy 273.799808 -310.794654) (xy 273.825066 -310.795176) (xy 273.874893 -310.803492)
			(xy 273.922672 -310.819896) (xy 273.967099 -310.843939) (xy 274.006963 -310.874968) (xy 274.041176 -310.912134)
			(xy 274.068805 -310.954425) (xy 274.089097 -311.000686) (xy 274.101497 -311.049656) (xy 274.105666 -311.099962)
			(xy 274.443964 -311.099962) (xy 274.447924 -311.050908) (xy 274.459701 -311.003124) (xy 274.478992 -310.957848)
			(xy 274.505295 -310.916252) (xy 274.53793 -310.879415) (xy 274.576051 -310.84829) (xy 274.618672 -310.823683)
			(xy 274.664688 -310.806231) (xy 274.712907 -310.796387) (xy 274.762082 -310.794406) (xy 274.810937 -310.800338)
			(xy 274.858208 -310.81403) (xy 274.90267 -310.835128) (xy 274.943173 -310.863084) (xy 274.978666 -310.897176)
			(xy 275.008231 -310.93652) (xy 275.031102 -310.980097) (xy 275.046686 -311.026778) (xy 275.054581 -311.075355)
			(xy 275.055076 -311.099962) (xy 275.393924 -311.099962) (xy 275.397884 -311.050908) (xy 275.409661 -311.003124)
			(xy 275.428952 -310.957848) (xy 275.455255 -310.916252) (xy 275.48789 -310.879415) (xy 275.526011 -310.84829)
			(xy 275.568632 -310.823683) (xy 275.614648 -310.806231) (xy 275.662867 -310.796387) (xy 275.712042 -310.794406)
			(xy 275.760897 -310.800338) (xy 275.808168 -310.81403) (xy 275.85263 -310.835128) (xy 275.893133 -310.863084)
			(xy 275.928626 -310.897176) (xy 275.958191 -310.93652) (xy 275.981062 -310.980097) (xy 275.996646 -311.026778)
			(xy 276.004541 -311.075355) (xy 276.005036 -311.099962) (xy 276.343884 -311.099962) (xy 276.347844 -311.050908)
			(xy 276.359621 -311.003124) (xy 276.378912 -310.957848) (xy 276.405215 -310.916252) (xy 276.43785 -310.879415)
			(xy 276.475971 -310.84829) (xy 276.518592 -310.823683) (xy 276.564608 -310.806231) (xy 276.612827 -310.796387)
			(xy 276.662002 -310.794406) (xy 276.710857 -310.800338) (xy 276.758128 -310.81403) (xy 276.80259 -310.835128)
			(xy 276.843093 -310.863084) (xy 276.878586 -310.897176) (xy 276.908151 -310.93652) (xy 276.931022 -310.980097)
			(xy 276.946606 -311.026778) (xy 276.954501 -311.075355) (xy 276.954996 -311.099962) (xy 277.294098 -311.099962)
			(xy 277.298058 -311.050908) (xy 277.309835 -311.003124) (xy 277.329126 -310.957848) (xy 277.355429 -310.916252)
			(xy 277.388064 -310.879415) (xy 277.426185 -310.84829) (xy 277.468806 -310.823683) (xy 277.514822 -310.806231)
			(xy 277.563041 -310.796387) (xy 277.612216 -310.794406) (xy 277.661071 -310.800338) (xy 277.708342 -310.81403)
			(xy 277.752804 -310.835128) (xy 277.793307 -310.863084) (xy 277.8288 -310.897176) (xy 277.858365 -310.93652)
			(xy 277.881236 -310.980097) (xy 277.89682 -311.026778) (xy 277.904715 -311.075355) (xy 277.90521 -311.099962)
			(xy 278.244058 -311.099962) (xy 278.248018 -311.050908) (xy 278.259795 -311.003124) (xy 278.279086 -310.957848)
			(xy 278.305389 -310.916252) (xy 278.338024 -310.879415) (xy 278.376145 -310.84829) (xy 278.418766 -310.823683)
			(xy 278.464782 -310.806231) (xy 278.513001 -310.796387) (xy 278.562176 -310.794406) (xy 278.611031 -310.800338)
			(xy 278.658302 -310.81403) (xy 278.702764 -310.835128) (xy 278.743267 -310.863084) (xy 278.77876 -310.897176)
			(xy 278.808325 -310.93652) (xy 278.831196 -310.980097) (xy 278.84678 -311.026778) (xy 278.854675 -311.075355)
			(xy 278.85517 -311.099962) (xy 279.194018 -311.099962) (xy 279.197978 -311.050908) (xy 279.209755 -311.003124)
			(xy 279.229046 -310.957848) (xy 279.255349 -310.916252) (xy 279.287984 -310.879415) (xy 279.326105 -310.84829)
			(xy 279.368726 -310.823683) (xy 279.414742 -310.806231) (xy 279.462961 -310.796387) (xy 279.512136 -310.794406)
			(xy 279.560991 -310.800338) (xy 279.608262 -310.81403) (xy 279.652724 -310.835128) (xy 279.693227 -310.863084)
			(xy 279.72872 -310.897176) (xy 279.758285 -310.93652) (xy 279.781156 -310.980097) (xy 279.79674 -311.026778)
			(xy 279.804635 -311.075355) (xy 279.80513 -311.099962) (xy 280.143978 -311.099962) (xy 280.147938 -311.050908)
			(xy 280.159715 -311.003124) (xy 280.179006 -310.957848) (xy 280.205309 -310.916252) (xy 280.237944 -310.879415)
			(xy 280.276065 -310.84829) (xy 280.318686 -310.823683) (xy 280.364702 -310.806231) (xy 280.412921 -310.796387)
			(xy 280.462096 -310.794406) (xy 280.510951 -310.800338) (xy 280.558222 -310.81403) (xy 280.602684 -310.835128)
			(xy 280.643187 -310.863084) (xy 280.67868 -310.897176) (xy 280.708245 -310.93652) (xy 280.731116 -310.980097)
			(xy 280.7467 -311.026778) (xy 280.754595 -311.075355) (xy 280.75509 -311.099962) (xy 281.093938 -311.099962)
			(xy 281.097898 -311.050908) (xy 281.109675 -311.003124) (xy 281.128966 -310.957848) (xy 281.155269 -310.916252)
			(xy 281.187904 -310.879415) (xy 281.226025 -310.84829) (xy 281.268646 -310.823683) (xy 281.314662 -310.806231)
			(xy 281.362881 -310.796387) (xy 281.412056 -310.794406) (xy 281.460911 -310.800338) (xy 281.508182 -310.81403)
			(xy 281.552644 -310.835128) (xy 281.593147 -310.863084) (xy 281.62864 -310.897176) (xy 281.658205 -310.93652)
			(xy 281.681076 -310.980097) (xy 281.69666 -311.026778) (xy 281.704555 -311.075355) (xy 281.70505 -311.099962)
			(xy 282.043898 -311.099962) (xy 282.047858 -311.050908) (xy 282.059635 -311.003124) (xy 282.078926 -310.957848)
			(xy 282.105229 -310.916252) (xy 282.137864 -310.879415) (xy 282.175985 -310.84829) (xy 282.218606 -310.823683)
			(xy 282.264622 -310.806231) (xy 282.312841 -310.796387) (xy 282.362016 -310.794406) (xy 282.410871 -310.800338)
			(xy 282.458142 -310.81403) (xy 282.502604 -310.835128) (xy 282.543107 -310.863084) (xy 282.5786 -310.897176)
			(xy 282.608165 -310.93652) (xy 282.631036 -310.980097) (xy 282.64662 -311.026778) (xy 282.654515 -311.075355)
			(xy 282.65501 -311.099962) (xy 282.994112 -311.099962) (xy 282.998072 -311.050908) (xy 283.009849 -311.003124)
			(xy 283.02914 -310.957848) (xy 283.055443 -310.916252) (xy 283.088078 -310.879415) (xy 283.126199 -310.84829)
			(xy 283.16882 -310.823683) (xy 283.214836 -310.806231) (xy 283.263055 -310.796387) (xy 283.31223 -310.794406)
			(xy 283.361085 -310.800338) (xy 283.408356 -310.81403) (xy 283.452818 -310.835128) (xy 283.493321 -310.863084)
			(xy 283.528814 -310.897176) (xy 283.558379 -310.93652) (xy 283.58125 -310.980097) (xy 283.596834 -311.026778)
			(xy 283.604729 -311.075355) (xy 283.605224 -311.099962) (xy 283.944072 -311.099962) (xy 283.948032 -311.050908)
			(xy 283.959809 -311.003124) (xy 283.9791 -310.957848) (xy 284.005403 -310.916252) (xy 284.038038 -310.879415)
			(xy 284.076159 -310.84829) (xy 284.11878 -310.823683) (xy 284.164796 -310.806231) (xy 284.213015 -310.796387)
			(xy 284.26219 -310.794406) (xy 284.311045 -310.800338) (xy 284.358316 -310.81403) (xy 284.402778 -310.835128)
			(xy 284.443281 -310.863084) (xy 284.478774 -310.897176) (xy 284.508339 -310.93652) (xy 284.53121 -310.980097)
			(xy 284.546794 -311.026778) (xy 284.554689 -311.075355) (xy 284.555184 -311.099962) (xy 284.894032 -311.099962)
			(xy 284.897992 -311.050908) (xy 284.909769 -311.003124) (xy 284.92906 -310.957848) (xy 284.955363 -310.916252)
			(xy 284.987998 -310.879415) (xy 285.026119 -310.84829) (xy 285.06874 -310.823683) (xy 285.114756 -310.806231)
			(xy 285.162975 -310.796387) (xy 285.21215 -310.794406) (xy 285.261005 -310.800338) (xy 285.308276 -310.81403)
			(xy 285.352738 -310.835128) (xy 285.393241 -310.863084) (xy 285.428734 -310.897176) (xy 285.458299 -310.93652)
			(xy 285.48117 -310.980097) (xy 285.496754 -311.026778) (xy 285.504649 -311.075355) (xy 285.505144 -311.099962)
			(xy 285.843992 -311.099962) (xy 285.847952 -311.050908) (xy 285.859729 -311.003124) (xy 285.87902 -310.957848)
			(xy 285.905323 -310.916252) (xy 285.937958 -310.879415) (xy 285.976079 -310.84829) (xy 286.0187 -310.823683)
			(xy 286.064716 -310.806231) (xy 286.112935 -310.796387) (xy 286.16211 -310.794406) (xy 286.210965 -310.800338)
			(xy 286.258236 -310.81403) (xy 286.302698 -310.835128) (xy 286.343201 -310.863084) (xy 286.378694 -310.897176)
			(xy 286.408259 -310.93652) (xy 286.43113 -310.980097) (xy 286.446714 -311.026778) (xy 286.454609 -311.075355)
			(xy 286.455104 -311.099962) (xy 286.793952 -311.099962) (xy 286.797912 -311.050908) (xy 286.809689 -311.003124)
			(xy 286.82898 -310.957848) (xy 286.855283 -310.916252) (xy 286.887918 -310.879415) (xy 286.926039 -310.84829)
			(xy 286.96866 -310.823683) (xy 287.014676 -310.806231) (xy 287.062895 -310.796387) (xy 287.11207 -310.794406)
			(xy 287.160925 -310.800338) (xy 287.208196 -310.81403) (xy 287.252658 -310.835128) (xy 287.293161 -310.863084)
			(xy 287.328654 -310.897176) (xy 287.358219 -310.93652) (xy 287.38109 -310.980097) (xy 287.396674 -311.026778)
			(xy 287.404569 -311.075355) (xy 287.405064 -311.099962) (xy 287.743912 -311.099962) (xy 287.747872 -311.050908)
			(xy 287.759649 -311.003124) (xy 287.77894 -310.957848) (xy 287.805243 -310.916252) (xy 287.837878 -310.879415)
			(xy 287.875999 -310.84829) (xy 287.91862 -310.823683) (xy 287.964636 -310.806231) (xy 288.012855 -310.796387)
			(xy 288.06203 -310.794406) (xy 288.110885 -310.800338) (xy 288.158156 -310.81403) (xy 288.202618 -310.835128)
			(xy 288.243121 -310.863084) (xy 288.278614 -310.897176) (xy 288.308179 -310.93652) (xy 288.33105 -310.980097)
			(xy 288.346634 -311.026778) (xy 288.354529 -311.075355) (xy 288.355024 -311.099962) (xy 288.694126 -311.099962)
			(xy 288.698086 -311.050908) (xy 288.709863 -311.003124) (xy 288.729154 -310.957848) (xy 288.755457 -310.916252)
			(xy 288.788092 -310.879415) (xy 288.826213 -310.84829) (xy 288.868834 -310.823683) (xy 288.91485 -310.806231)
			(xy 288.963069 -310.796387) (xy 289.012244 -310.794406) (xy 289.061099 -310.800338) (xy 289.10837 -310.81403)
			(xy 289.152832 -310.835128) (xy 289.193335 -310.863084) (xy 289.228828 -310.897176) (xy 289.258393 -310.93652)
			(xy 289.281264 -310.980097) (xy 289.296848 -311.026778) (xy 289.304743 -311.075355) (xy 289.305238 -311.099962)
			(xy 289.644086 -311.099962) (xy 289.648046 -311.050908) (xy 289.659823 -311.003124) (xy 289.679114 -310.957848)
			(xy 289.705417 -310.916252) (xy 289.738052 -310.879415) (xy 289.776173 -310.84829) (xy 289.818794 -310.823683)
			(xy 289.86481 -310.806231) (xy 289.913029 -310.796387) (xy 289.962204 -310.794406) (xy 290.011059 -310.800338)
			(xy 290.05833 -310.81403) (xy 290.102792 -310.835128) (xy 290.143295 -310.863084) (xy 290.178788 -310.897176)
			(xy 290.208353 -310.93652) (xy 290.231224 -310.980097) (xy 290.246808 -311.026778) (xy 290.254703 -311.075355)
			(xy 290.255198 -311.099962) (xy 290.594046 -311.099962) (xy 290.598006 -311.050908) (xy 290.609783 -311.003124)
			(xy 290.629074 -310.957848) (xy 290.655377 -310.916252) (xy 290.688012 -310.879415) (xy 290.726133 -310.84829)
			(xy 290.768754 -310.823683) (xy 290.81477 -310.806231) (xy 290.862989 -310.796387) (xy 290.912164 -310.794406)
			(xy 290.961019 -310.800338) (xy 291.00829 -310.81403) (xy 291.052752 -310.835128) (xy 291.093255 -310.863084)
			(xy 291.128748 -310.897176) (xy 291.158313 -310.93652) (xy 291.181184 -310.980097) (xy 291.196768 -311.026778)
			(xy 291.204663 -311.075355) (xy 291.205158 -311.099962) (xy 291.544006 -311.099962) (xy 291.547966 -311.050908)
			(xy 291.559743 -311.003124) (xy 291.579034 -310.957848) (xy 291.605337 -310.916252) (xy 291.637972 -310.879415)
			(xy 291.676093 -310.84829) (xy 291.718714 -310.823683) (xy 291.76473 -310.806231) (xy 291.812949 -310.796387)
			(xy 291.862124 -310.794406) (xy 291.910979 -310.800338) (xy 291.95825 -310.81403) (xy 292.002712 -310.835128)
			(xy 292.043215 -310.863084) (xy 292.078708 -310.897176) (xy 292.108273 -310.93652) (xy 292.131144 -310.980097)
			(xy 292.146728 -311.026778) (xy 292.154623 -311.075355) (xy 292.155118 -311.099962) (xy 292.493966 -311.099962)
			(xy 292.497926 -311.050908) (xy 292.509703 -311.003124) (xy 292.528994 -310.957848) (xy 292.555297 -310.916252)
			(xy 292.587932 -310.879415) (xy 292.626053 -310.84829) (xy 292.668674 -310.823683) (xy 292.71469 -310.806231)
			(xy 292.762909 -310.796387) (xy 292.812084 -310.794406) (xy 292.860939 -310.800338) (xy 292.90821 -310.81403)
			(xy 292.952672 -310.835128) (xy 292.993175 -310.863084) (xy 293.028668 -310.897176) (xy 293.058233 -310.93652)
			(xy 293.081104 -310.980097) (xy 293.096688 -311.026778) (xy 293.104583 -311.075355) (xy 293.105078 -311.099962)
			(xy 293.443926 -311.099962) (xy 293.447886 -311.050908) (xy 293.459663 -311.003124) (xy 293.478954 -310.957848)
			(xy 293.505257 -310.916252) (xy 293.537892 -310.879415) (xy 293.576013 -310.84829) (xy 293.618634 -310.823683)
			(xy 293.66465 -310.806231) (xy 293.712869 -310.796387) (xy 293.762044 -310.794406) (xy 293.810899 -310.800338)
			(xy 293.85817 -310.81403) (xy 293.902632 -310.835128) (xy 293.943135 -310.863084) (xy 293.978628 -310.897176)
			(xy 294.008193 -310.93652) (xy 294.031064 -310.980097) (xy 294.046648 -311.026778) (xy 294.054543 -311.075355)
			(xy 294.055038 -311.099962) (xy 294.054543 -311.124569) (xy 294.046648 -311.173146) (xy 294.031064 -311.219827)
			(xy 294.008193 -311.263404) (xy 293.978628 -311.302748) (xy 293.943135 -311.33684) (xy 293.902632 -311.364796)
			(xy 293.85817 -311.385894) (xy 293.810899 -311.399586) (xy 293.762044 -311.405518) (xy 293.712869 -311.403537)
			(xy 293.66465 -311.393693) (xy 293.618634 -311.376241) (xy 293.576013 -311.351634) (xy 293.537892 -311.320509)
			(xy 293.505257 -311.283672) (xy 293.478954 -311.242076) (xy 293.459663 -311.1968) (xy 293.447886 -311.149016)
			(xy 293.443926 -311.099962) (xy 293.105078 -311.099962) (xy 293.104583 -311.124569) (xy 293.096688 -311.173146)
			(xy 293.081104 -311.219827) (xy 293.058233 -311.263404) (xy 293.028668 -311.302748) (xy 292.993175 -311.33684)
			(xy 292.952672 -311.364796) (xy 292.90821 -311.385894) (xy 292.860939 -311.399586) (xy 292.812084 -311.405518)
			(xy 292.762909 -311.403537) (xy 292.71469 -311.393693) (xy 292.668674 -311.376241) (xy 292.626053 -311.351634)
			(xy 292.587932 -311.320509) (xy 292.555297 -311.283672) (xy 292.528994 -311.242076) (xy 292.509703 -311.1968)
			(xy 292.497926 -311.149016) (xy 292.493966 -311.099962) (xy 292.155118 -311.099962) (xy 292.154623 -311.124569)
			(xy 292.146728 -311.173146) (xy 292.131144 -311.219827) (xy 292.108273 -311.263404) (xy 292.078708 -311.302748)
			(xy 292.043215 -311.33684) (xy 292.002712 -311.364796) (xy 291.95825 -311.385894) (xy 291.910979 -311.399586)
			(xy 291.862124 -311.405518) (xy 291.812949 -311.403537) (xy 291.76473 -311.393693) (xy 291.718714 -311.376241)
			(xy 291.676093 -311.351634) (xy 291.637972 -311.320509) (xy 291.605337 -311.283672) (xy 291.579034 -311.242076)
			(xy 291.559743 -311.1968) (xy 291.547966 -311.149016) (xy 291.544006 -311.099962) (xy 291.205158 -311.099962)
			(xy 291.204663 -311.124569) (xy 291.196768 -311.173146) (xy 291.181184 -311.219827) (xy 291.158313 -311.263404)
			(xy 291.128748 -311.302748) (xy 291.093255 -311.33684) (xy 291.052752 -311.364796) (xy 291.00829 -311.385894)
			(xy 290.961019 -311.399586) (xy 290.912164 -311.405518) (xy 290.862989 -311.403537) (xy 290.81477 -311.393693)
			(xy 290.768754 -311.376241) (xy 290.726133 -311.351634) (xy 290.688012 -311.320509) (xy 290.655377 -311.283672)
			(xy 290.629074 -311.242076) (xy 290.609783 -311.1968) (xy 290.598006 -311.149016) (xy 290.594046 -311.099962)
			(xy 290.255198 -311.099962) (xy 290.254703 -311.124569) (xy 290.246808 -311.173146) (xy 290.231224 -311.219827)
			(xy 290.208353 -311.263404) (xy 290.178788 -311.302748) (xy 290.143295 -311.33684) (xy 290.102792 -311.364796)
			(xy 290.05833 -311.385894) (xy 290.011059 -311.399586) (xy 289.962204 -311.405518) (xy 289.913029 -311.403537)
			(xy 289.86481 -311.393693) (xy 289.818794 -311.376241) (xy 289.776173 -311.351634) (xy 289.738052 -311.320509)
			(xy 289.705417 -311.283672) (xy 289.679114 -311.242076) (xy 289.659823 -311.1968) (xy 289.648046 -311.149016)
			(xy 289.644086 -311.099962) (xy 289.305238 -311.099962) (xy 289.304743 -311.124569) (xy 289.296848 -311.173146)
			(xy 289.281264 -311.219827) (xy 289.258393 -311.263404) (xy 289.228828 -311.302748) (xy 289.193335 -311.33684)
			(xy 289.152832 -311.364796) (xy 289.10837 -311.385894) (xy 289.061099 -311.399586) (xy 289.012244 -311.405518)
			(xy 288.963069 -311.403537) (xy 288.91485 -311.393693) (xy 288.868834 -311.376241) (xy 288.826213 -311.351634)
			(xy 288.788092 -311.320509) (xy 288.755457 -311.283672) (xy 288.729154 -311.242076) (xy 288.709863 -311.1968)
			(xy 288.698086 -311.149016) (xy 288.694126 -311.099962) (xy 288.355024 -311.099962) (xy 288.354529 -311.124569)
			(xy 288.346634 -311.173146) (xy 288.33105 -311.219827) (xy 288.308179 -311.263404) (xy 288.278614 -311.302748)
			(xy 288.243121 -311.33684) (xy 288.202618 -311.364796) (xy 288.158156 -311.385894) (xy 288.110885 -311.399586)
			(xy 288.06203 -311.405518) (xy 288.012855 -311.403537) (xy 287.964636 -311.393693) (xy 287.91862 -311.376241)
			(xy 287.875999 -311.351634) (xy 287.837878 -311.320509) (xy 287.805243 -311.283672) (xy 287.77894 -311.242076)
			(xy 287.759649 -311.1968) (xy 287.747872 -311.149016) (xy 287.743912 -311.099962) (xy 287.405064 -311.099962)
			(xy 287.404569 -311.124569) (xy 287.396674 -311.173146) (xy 287.38109 -311.219827) (xy 287.358219 -311.263404)
			(xy 287.328654 -311.302748) (xy 287.293161 -311.33684) (xy 287.252658 -311.364796) (xy 287.208196 -311.385894)
			(xy 287.160925 -311.399586) (xy 287.11207 -311.405518) (xy 287.062895 -311.403537) (xy 287.014676 -311.393693)
			(xy 286.96866 -311.376241) (xy 286.926039 -311.351634) (xy 286.887918 -311.320509) (xy 286.855283 -311.283672)
			(xy 286.82898 -311.242076) (xy 286.809689 -311.1968) (xy 286.797912 -311.149016) (xy 286.793952 -311.099962)
			(xy 286.455104 -311.099962) (xy 286.454609 -311.124569) (xy 286.446714 -311.173146) (xy 286.43113 -311.219827)
			(xy 286.408259 -311.263404) (xy 286.378694 -311.302748) (xy 286.343201 -311.33684) (xy 286.302698 -311.364796)
			(xy 286.258236 -311.385894) (xy 286.210965 -311.399586) (xy 286.16211 -311.405518) (xy 286.112935 -311.403537)
			(xy 286.064716 -311.393693) (xy 286.0187 -311.376241) (xy 285.976079 -311.351634) (xy 285.937958 -311.320509)
			(xy 285.905323 -311.283672) (xy 285.87902 -311.242076) (xy 285.859729 -311.1968) (xy 285.847952 -311.149016)
			(xy 285.843992 -311.099962) (xy 285.505144 -311.099962) (xy 285.504649 -311.124569) (xy 285.496754 -311.173146)
			(xy 285.48117 -311.219827) (xy 285.458299 -311.263404) (xy 285.428734 -311.302748) (xy 285.393241 -311.33684)
			(xy 285.352738 -311.364796) (xy 285.308276 -311.385894) (xy 285.261005 -311.399586) (xy 285.21215 -311.405518)
			(xy 285.162975 -311.403537) (xy 285.114756 -311.393693) (xy 285.06874 -311.376241) (xy 285.026119 -311.351634)
			(xy 284.987998 -311.320509) (xy 284.955363 -311.283672) (xy 284.92906 -311.242076) (xy 284.909769 -311.1968)
			(xy 284.897992 -311.149016) (xy 284.894032 -311.099962) (xy 284.555184 -311.099962) (xy 284.554689 -311.124569)
			(xy 284.546794 -311.173146) (xy 284.53121 -311.219827) (xy 284.508339 -311.263404) (xy 284.478774 -311.302748)
			(xy 284.443281 -311.33684) (xy 284.402778 -311.364796) (xy 284.358316 -311.385894) (xy 284.311045 -311.399586)
			(xy 284.26219 -311.405518) (xy 284.213015 -311.403537) (xy 284.164796 -311.393693) (xy 284.11878 -311.376241)
			(xy 284.076159 -311.351634) (xy 284.038038 -311.320509) (xy 284.005403 -311.283672) (xy 283.9791 -311.242076)
			(xy 283.959809 -311.1968) (xy 283.948032 -311.149016) (xy 283.944072 -311.099962) (xy 283.605224 -311.099962)
			(xy 283.604729 -311.124569) (xy 283.596834 -311.173146) (xy 283.58125 -311.219827) (xy 283.558379 -311.263404)
			(xy 283.528814 -311.302748) (xy 283.493321 -311.33684) (xy 283.452818 -311.364796) (xy 283.408356 -311.385894)
			(xy 283.361085 -311.399586) (xy 283.31223 -311.405518) (xy 283.263055 -311.403537) (xy 283.214836 -311.393693)
			(xy 283.16882 -311.376241) (xy 283.126199 -311.351634) (xy 283.088078 -311.320509) (xy 283.055443 -311.283672)
			(xy 283.02914 -311.242076) (xy 283.009849 -311.1968) (xy 282.998072 -311.149016) (xy 282.994112 -311.099962)
			(xy 282.65501 -311.099962) (xy 282.654515 -311.124569) (xy 282.64662 -311.173146) (xy 282.631036 -311.219827)
			(xy 282.608165 -311.263404) (xy 282.5786 -311.302748) (xy 282.543107 -311.33684) (xy 282.502604 -311.364796)
			(xy 282.458142 -311.385894) (xy 282.410871 -311.399586) (xy 282.362016 -311.405518) (xy 282.312841 -311.403537)
			(xy 282.264622 -311.393693) (xy 282.218606 -311.376241) (xy 282.175985 -311.351634) (xy 282.137864 -311.320509)
			(xy 282.105229 -311.283672) (xy 282.078926 -311.242076) (xy 282.059635 -311.1968) (xy 282.047858 -311.149016)
			(xy 282.043898 -311.099962) (xy 281.70505 -311.099962) (xy 281.704555 -311.124569) (xy 281.69666 -311.173146)
			(xy 281.681076 -311.219827) (xy 281.658205 -311.263404) (xy 281.62864 -311.302748) (xy 281.593147 -311.33684)
			(xy 281.552644 -311.364796) (xy 281.508182 -311.385894) (xy 281.460911 -311.399586) (xy 281.412056 -311.405518)
			(xy 281.362881 -311.403537) (xy 281.314662 -311.393693) (xy 281.268646 -311.376241) (xy 281.226025 -311.351634)
			(xy 281.187904 -311.320509) (xy 281.155269 -311.283672) (xy 281.128966 -311.242076) (xy 281.109675 -311.1968)
			(xy 281.097898 -311.149016) (xy 281.093938 -311.099962) (xy 280.75509 -311.099962) (xy 280.754595 -311.124569)
			(xy 280.7467 -311.173146) (xy 280.731116 -311.219827) (xy 280.708245 -311.263404) (xy 280.67868 -311.302748)
			(xy 280.643187 -311.33684) (xy 280.602684 -311.364796) (xy 280.558222 -311.385894) (xy 280.510951 -311.399586)
			(xy 280.462096 -311.405518) (xy 280.412921 -311.403537) (xy 280.364702 -311.393693) (xy 280.318686 -311.376241)
			(xy 280.276065 -311.351634) (xy 280.237944 -311.320509) (xy 280.205309 -311.283672) (xy 280.179006 -311.242076)
			(xy 280.159715 -311.1968) (xy 280.147938 -311.149016) (xy 280.143978 -311.099962) (xy 279.80513 -311.099962)
			(xy 279.804635 -311.124569) (xy 279.79674 -311.173146) (xy 279.781156 -311.219827) (xy 279.758285 -311.263404)
			(xy 279.72872 -311.302748) (xy 279.693227 -311.33684) (xy 279.652724 -311.364796) (xy 279.608262 -311.385894)
			(xy 279.560991 -311.399586) (xy 279.512136 -311.405518) (xy 279.462961 -311.403537) (xy 279.414742 -311.393693)
			(xy 279.368726 -311.376241) (xy 279.326105 -311.351634) (xy 279.287984 -311.320509) (xy 279.255349 -311.283672)
			(xy 279.229046 -311.242076) (xy 279.209755 -311.1968) (xy 279.197978 -311.149016) (xy 279.194018 -311.099962)
			(xy 278.85517 -311.099962) (xy 278.854675 -311.124569) (xy 278.84678 -311.173146) (xy 278.831196 -311.219827)
			(xy 278.808325 -311.263404) (xy 278.77876 -311.302748) (xy 278.743267 -311.33684) (xy 278.702764 -311.364796)
			(xy 278.658302 -311.385894) (xy 278.611031 -311.399586) (xy 278.562176 -311.405518) (xy 278.513001 -311.403537)
			(xy 278.464782 -311.393693) (xy 278.418766 -311.376241) (xy 278.376145 -311.351634) (xy 278.338024 -311.320509)
			(xy 278.305389 -311.283672) (xy 278.279086 -311.242076) (xy 278.259795 -311.1968) (xy 278.248018 -311.149016)
			(xy 278.244058 -311.099962) (xy 277.90521 -311.099962) (xy 277.904715 -311.124569) (xy 277.89682 -311.173146)
			(xy 277.881236 -311.219827) (xy 277.858365 -311.263404) (xy 277.8288 -311.302748) (xy 277.793307 -311.33684)
			(xy 277.752804 -311.364796) (xy 277.708342 -311.385894) (xy 277.661071 -311.399586) (xy 277.612216 -311.405518)
			(xy 277.563041 -311.403537) (xy 277.514822 -311.393693) (xy 277.468806 -311.376241) (xy 277.426185 -311.351634)
			(xy 277.388064 -311.320509) (xy 277.355429 -311.283672) (xy 277.329126 -311.242076) (xy 277.309835 -311.1968)
			(xy 277.298058 -311.149016) (xy 277.294098 -311.099962) (xy 276.954996 -311.099962) (xy 276.954501 -311.124569)
			(xy 276.946606 -311.173146) (xy 276.931022 -311.219827) (xy 276.908151 -311.263404) (xy 276.878586 -311.302748)
			(xy 276.843093 -311.33684) (xy 276.80259 -311.364796) (xy 276.758128 -311.385894) (xy 276.710857 -311.399586)
			(xy 276.662002 -311.405518) (xy 276.612827 -311.403537) (xy 276.564608 -311.393693) (xy 276.518592 -311.376241)
			(xy 276.475971 -311.351634) (xy 276.43785 -311.320509) (xy 276.405215 -311.283672) (xy 276.378912 -311.242076)
			(xy 276.359621 -311.1968) (xy 276.347844 -311.149016) (xy 276.343884 -311.099962) (xy 276.005036 -311.099962)
			(xy 276.004541 -311.124569) (xy 275.996646 -311.173146) (xy 275.981062 -311.219827) (xy 275.958191 -311.263404)
			(xy 275.928626 -311.302748) (xy 275.893133 -311.33684) (xy 275.85263 -311.364796) (xy 275.808168 -311.385894)
			(xy 275.760897 -311.399586) (xy 275.712042 -311.405518) (xy 275.662867 -311.403537) (xy 275.614648 -311.393693)
			(xy 275.568632 -311.376241) (xy 275.526011 -311.351634) (xy 275.48789 -311.320509) (xy 275.455255 -311.283672)
			(xy 275.428952 -311.242076) (xy 275.409661 -311.1968) (xy 275.397884 -311.149016) (xy 275.393924 -311.099962)
			(xy 275.055076 -311.099962) (xy 275.054581 -311.124569) (xy 275.046686 -311.173146) (xy 275.031102 -311.219827)
			(xy 275.008231 -311.263404) (xy 274.978666 -311.302748) (xy 274.943173 -311.33684) (xy 274.90267 -311.364796)
			(xy 274.858208 -311.385894) (xy 274.810937 -311.399586) (xy 274.762082 -311.405518) (xy 274.712907 -311.403537)
			(xy 274.664688 -311.393693) (xy 274.618672 -311.376241) (xy 274.576051 -311.351634) (xy 274.53793 -311.320509)
			(xy 274.505295 -311.283672) (xy 274.478992 -311.242076) (xy 274.459701 -311.1968) (xy 274.447924 -311.149016)
			(xy 274.443964 -311.099962) (xy 274.105666 -311.099962) (xy 274.105669 -311.1) (xy 274.101497 -311.150344)
			(xy 274.089097 -311.199314) (xy 274.068805 -311.245575) (xy 274.041176 -311.287866) (xy 274.006963 -311.325032)
			(xy 273.967099 -311.356061) (xy 273.922672 -311.380104) (xy 273.874893 -311.396508) (xy 273.825066 -311.404824)
			(xy 273.799808 -311.40527) (xy 273.768058 -311.403492) (xy 273.76755 -311.403492) (xy 273.756927 -311.40297)
			(xy 273.736717 -311.409522) (xy 273.728434 -311.416192) (xy 273.6723 -311.466738) (xy 273.664651 -311.47426)
			(xy 273.655989 -311.493864) (xy 273.655536 -311.504584) (xy 273.655536 -311.574942) (xy 273.655361 -311.589756)
			(xy 273.652692 -311.619265) (xy 273.650202 -311.63387) (xy 273.650202 -311.634632) (xy 273.648932 -311.641236)
			(xy 273.656044 -311.663842) (xy 273.72056 -311.731406) (xy 273.729199 -311.739621) (xy 273.751593 -311.747711)
			(xy 273.763486 -311.7469) (xy 273.77253 -311.745852) (xy 273.790704 -311.744708) (xy 273.799808 -311.744614)
			(xy 273.825061 -311.745136) (xy 273.874878 -311.75345) (xy 273.922647 -311.769851) (xy 273.967066 -311.79389)
			(xy 274.006922 -311.824912) (xy 274.041128 -311.862071) (xy 274.068752 -311.904353) (xy 274.08904 -311.950606)
			(xy 274.101438 -311.999566) (xy 274.105609 -312.0499) (xy 274.105607 -312.049922) (xy 274.443964 -312.049922)
			(xy 274.447924 -312.000868) (xy 274.459701 -311.953084) (xy 274.478992 -311.907808) (xy 274.505295 -311.866212)
			(xy 274.53793 -311.829375) (xy 274.576051 -311.79825) (xy 274.618672 -311.773643) (xy 274.664688 -311.756191)
			(xy 274.712907 -311.746347) (xy 274.762082 -311.744366) (xy 274.810937 -311.750298) (xy 274.858208 -311.76399)
			(xy 274.90267 -311.785088) (xy 274.943173 -311.813044) (xy 274.978666 -311.847136) (xy 275.008231 -311.88648)
			(xy 275.031102 -311.930057) (xy 275.046686 -311.976738) (xy 275.054581 -312.025315) (xy 275.055076 -312.049922)
			(xy 275.393924 -312.049922) (xy 275.397884 -312.000868) (xy 275.409661 -311.953084) (xy 275.428952 -311.907808)
			(xy 275.455255 -311.866212) (xy 275.48789 -311.829375) (xy 275.526011 -311.79825) (xy 275.568632 -311.773643)
			(xy 275.614648 -311.756191) (xy 275.662867 -311.746347) (xy 275.712042 -311.744366) (xy 275.760897 -311.750298)
			(xy 275.808168 -311.76399) (xy 275.85263 -311.785088) (xy 275.893133 -311.813044) (xy 275.928626 -311.847136)
			(xy 275.958191 -311.88648) (xy 275.981062 -311.930057) (xy 275.996646 -311.976738) (xy 276.004541 -312.025315)
			(xy 276.005036 -312.049922) (xy 276.343884 -312.049922) (xy 276.347844 -312.000868) (xy 276.359621 -311.953084)
			(xy 276.378912 -311.907808) (xy 276.405215 -311.866212) (xy 276.43785 -311.829375) (xy 276.475971 -311.79825)
			(xy 276.518592 -311.773643) (xy 276.564608 -311.756191) (xy 276.612827 -311.746347) (xy 276.662002 -311.744366)
			(xy 276.710857 -311.750298) (xy 276.758128 -311.76399) (xy 276.80259 -311.785088) (xy 276.843093 -311.813044)
			(xy 276.878586 -311.847136) (xy 276.908151 -311.88648) (xy 276.931022 -311.930057) (xy 276.946606 -311.976738)
			(xy 276.954501 -312.025315) (xy 276.954996 -312.049922) (xy 277.294098 -312.049922) (xy 277.298058 -312.000868)
			(xy 277.309835 -311.953084) (xy 277.329126 -311.907808) (xy 277.355429 -311.866212) (xy 277.388064 -311.829375)
			(xy 277.426185 -311.79825) (xy 277.468806 -311.773643) (xy 277.514822 -311.756191) (xy 277.563041 -311.746347)
			(xy 277.612216 -311.744366) (xy 277.661071 -311.750298) (xy 277.708342 -311.76399) (xy 277.752804 -311.785088)
			(xy 277.793307 -311.813044) (xy 277.8288 -311.847136) (xy 277.858365 -311.88648) (xy 277.881236 -311.930057)
			(xy 277.89682 -311.976738) (xy 277.904715 -312.025315) (xy 277.90521 -312.049922) (xy 278.244058 -312.049922)
			(xy 278.248018 -312.000868) (xy 278.259795 -311.953084) (xy 278.279086 -311.907808) (xy 278.305389 -311.866212)
			(xy 278.338024 -311.829375) (xy 278.376145 -311.79825) (xy 278.418766 -311.773643) (xy 278.464782 -311.756191)
			(xy 278.513001 -311.746347) (xy 278.562176 -311.744366) (xy 278.611031 -311.750298) (xy 278.658302 -311.76399)
			(xy 278.702764 -311.785088) (xy 278.743267 -311.813044) (xy 278.77876 -311.847136) (xy 278.808325 -311.88648)
			(xy 278.831196 -311.930057) (xy 278.84678 -311.976738) (xy 278.854675 -312.025315) (xy 278.85517 -312.049922)
			(xy 279.194018 -312.049922) (xy 279.197978 -312.000868) (xy 279.209755 -311.953084) (xy 279.229046 -311.907808)
			(xy 279.255349 -311.866212) (xy 279.287984 -311.829375) (xy 279.326105 -311.79825) (xy 279.368726 -311.773643)
			(xy 279.414742 -311.756191) (xy 279.462961 -311.746347) (xy 279.512136 -311.744366) (xy 279.560991 -311.750298)
			(xy 279.608262 -311.76399) (xy 279.652724 -311.785088) (xy 279.693227 -311.813044) (xy 279.72872 -311.847136)
			(xy 279.758285 -311.88648) (xy 279.781156 -311.930057) (xy 279.79674 -311.976738) (xy 279.804635 -312.025315)
			(xy 279.80513 -312.049922) (xy 280.143978 -312.049922) (xy 280.147938 -312.000868) (xy 280.159715 -311.953084)
			(xy 280.179006 -311.907808) (xy 280.205309 -311.866212) (xy 280.237944 -311.829375) (xy 280.276065 -311.79825)
			(xy 280.318686 -311.773643) (xy 280.364702 -311.756191) (xy 280.412921 -311.746347) (xy 280.462096 -311.744366)
			(xy 280.510951 -311.750298) (xy 280.558222 -311.76399) (xy 280.602684 -311.785088) (xy 280.643187 -311.813044)
			(xy 280.67868 -311.847136) (xy 280.708245 -311.88648) (xy 280.731116 -311.930057) (xy 280.7467 -311.976738)
			(xy 280.754595 -312.025315) (xy 280.75509 -312.049922) (xy 281.093938 -312.049922) (xy 281.097898 -312.000868)
			(xy 281.109675 -311.953084) (xy 281.128966 -311.907808) (xy 281.155269 -311.866212) (xy 281.187904 -311.829375)
			(xy 281.226025 -311.79825) (xy 281.268646 -311.773643) (xy 281.314662 -311.756191) (xy 281.362881 -311.746347)
			(xy 281.412056 -311.744366) (xy 281.460911 -311.750298) (xy 281.508182 -311.76399) (xy 281.552644 -311.785088)
			(xy 281.593147 -311.813044) (xy 281.62864 -311.847136) (xy 281.658205 -311.88648) (xy 281.681076 -311.930057)
			(xy 281.69666 -311.976738) (xy 281.704555 -312.025315) (xy 281.70505 -312.049922) (xy 282.043898 -312.049922)
			(xy 282.047858 -312.000868) (xy 282.059635 -311.953084) (xy 282.078926 -311.907808) (xy 282.105229 -311.866212)
			(xy 282.137864 -311.829375) (xy 282.175985 -311.79825) (xy 282.218606 -311.773643) (xy 282.264622 -311.756191)
			(xy 282.312841 -311.746347) (xy 282.362016 -311.744366) (xy 282.410871 -311.750298) (xy 282.458142 -311.76399)
			(xy 282.502604 -311.785088) (xy 282.543107 -311.813044) (xy 282.5786 -311.847136) (xy 282.608165 -311.88648)
			(xy 282.631036 -311.930057) (xy 282.64662 -311.976738) (xy 282.654515 -312.025315) (xy 282.65501 -312.049922)
			(xy 282.994112 -312.049922) (xy 282.998072 -312.000868) (xy 283.009849 -311.953084) (xy 283.02914 -311.907808)
			(xy 283.055443 -311.866212) (xy 283.088078 -311.829375) (xy 283.126199 -311.79825) (xy 283.16882 -311.773643)
			(xy 283.214836 -311.756191) (xy 283.263055 -311.746347) (xy 283.31223 -311.744366) (xy 283.361085 -311.750298)
			(xy 283.408356 -311.76399) (xy 283.452818 -311.785088) (xy 283.493321 -311.813044) (xy 283.528814 -311.847136)
			(xy 283.558379 -311.88648) (xy 283.58125 -311.930057) (xy 283.596834 -311.976738) (xy 283.604729 -312.025315)
			(xy 283.605224 -312.049922) (xy 283.944072 -312.049922) (xy 283.948032 -312.000868) (xy 283.959809 -311.953084)
			(xy 283.9791 -311.907808) (xy 284.005403 -311.866212) (xy 284.038038 -311.829375) (xy 284.076159 -311.79825)
			(xy 284.11878 -311.773643) (xy 284.164796 -311.756191) (xy 284.213015 -311.746347) (xy 284.26219 -311.744366)
			(xy 284.311045 -311.750298) (xy 284.358316 -311.76399) (xy 284.402778 -311.785088) (xy 284.443281 -311.813044)
			(xy 284.478774 -311.847136) (xy 284.508339 -311.88648) (xy 284.53121 -311.930057) (xy 284.546794 -311.976738)
			(xy 284.554689 -312.025315) (xy 284.555184 -312.049922) (xy 284.894032 -312.049922) (xy 284.897992 -312.000868)
			(xy 284.909769 -311.953084) (xy 284.92906 -311.907808) (xy 284.955363 -311.866212) (xy 284.987998 -311.829375)
			(xy 285.026119 -311.79825) (xy 285.06874 -311.773643) (xy 285.114756 -311.756191) (xy 285.162975 -311.746347)
			(xy 285.21215 -311.744366) (xy 285.261005 -311.750298) (xy 285.308276 -311.76399) (xy 285.352738 -311.785088)
			(xy 285.393241 -311.813044) (xy 285.428734 -311.847136) (xy 285.458299 -311.88648) (xy 285.48117 -311.930057)
			(xy 285.496754 -311.976738) (xy 285.504649 -312.025315) (xy 285.505144 -312.049922) (xy 285.843992 -312.049922)
			(xy 285.847952 -312.000868) (xy 285.859729 -311.953084) (xy 285.87902 -311.907808) (xy 285.905323 -311.866212)
			(xy 285.937958 -311.829375) (xy 285.976079 -311.79825) (xy 286.0187 -311.773643) (xy 286.064716 -311.756191)
			(xy 286.112935 -311.746347) (xy 286.16211 -311.744366) (xy 286.210965 -311.750298) (xy 286.258236 -311.76399)
			(xy 286.302698 -311.785088) (xy 286.343201 -311.813044) (xy 286.378694 -311.847136) (xy 286.408259 -311.88648)
			(xy 286.43113 -311.930057) (xy 286.446714 -311.976738) (xy 286.454609 -312.025315) (xy 286.455104 -312.049922)
			(xy 286.793952 -312.049922) (xy 286.797912 -312.000868) (xy 286.809689 -311.953084) (xy 286.82898 -311.907808)
			(xy 286.855283 -311.866212) (xy 286.887918 -311.829375) (xy 286.926039 -311.79825) (xy 286.96866 -311.773643)
			(xy 287.014676 -311.756191) (xy 287.062895 -311.746347) (xy 287.11207 -311.744366) (xy 287.160925 -311.750298)
			(xy 287.208196 -311.76399) (xy 287.252658 -311.785088) (xy 287.293161 -311.813044) (xy 287.328654 -311.847136)
			(xy 287.358219 -311.88648) (xy 287.38109 -311.930057) (xy 287.396674 -311.976738) (xy 287.404569 -312.025315)
			(xy 287.405064 -312.049922) (xy 287.743912 -312.049922) (xy 287.747872 -312.000868) (xy 287.759649 -311.953084)
			(xy 287.77894 -311.907808) (xy 287.805243 -311.866212) (xy 287.837878 -311.829375) (xy 287.875999 -311.79825)
			(xy 287.91862 -311.773643) (xy 287.964636 -311.756191) (xy 288.012855 -311.746347) (xy 288.06203 -311.744366)
			(xy 288.110885 -311.750298) (xy 288.158156 -311.76399) (xy 288.202618 -311.785088) (xy 288.243121 -311.813044)
			(xy 288.278614 -311.847136) (xy 288.308179 -311.88648) (xy 288.33105 -311.930057) (xy 288.346634 -311.976738)
			(xy 288.354529 -312.025315) (xy 288.355024 -312.049922) (xy 288.694126 -312.049922) (xy 288.698086 -312.000868)
			(xy 288.709863 -311.953084) (xy 288.729154 -311.907808) (xy 288.755457 -311.866212) (xy 288.788092 -311.829375)
			(xy 288.826213 -311.79825) (xy 288.868834 -311.773643) (xy 288.91485 -311.756191) (xy 288.963069 -311.746347)
			(xy 289.012244 -311.744366) (xy 289.061099 -311.750298) (xy 289.10837 -311.76399) (xy 289.152832 -311.785088)
			(xy 289.193335 -311.813044) (xy 289.228828 -311.847136) (xy 289.258393 -311.88648) (xy 289.281264 -311.930057)
			(xy 289.296848 -311.976738) (xy 289.304743 -312.025315) (xy 289.305238 -312.049922) (xy 289.644086 -312.049922)
			(xy 289.648046 -312.000868) (xy 289.659823 -311.953084) (xy 289.679114 -311.907808) (xy 289.705417 -311.866212)
			(xy 289.738052 -311.829375) (xy 289.776173 -311.79825) (xy 289.818794 -311.773643) (xy 289.86481 -311.756191)
			(xy 289.913029 -311.746347) (xy 289.962204 -311.744366) (xy 290.011059 -311.750298) (xy 290.05833 -311.76399)
			(xy 290.102792 -311.785088) (xy 290.143295 -311.813044) (xy 290.178788 -311.847136) (xy 290.208353 -311.88648)
			(xy 290.231224 -311.930057) (xy 290.246808 -311.976738) (xy 290.254703 -312.025315) (xy 290.255198 -312.049922)
			(xy 290.594046 -312.049922) (xy 290.598006 -312.000868) (xy 290.609783 -311.953084) (xy 290.629074 -311.907808)
			(xy 290.655377 -311.866212) (xy 290.688012 -311.829375) (xy 290.726133 -311.79825) (xy 290.768754 -311.773643)
			(xy 290.81477 -311.756191) (xy 290.862989 -311.746347) (xy 290.912164 -311.744366) (xy 290.961019 -311.750298)
			(xy 291.00829 -311.76399) (xy 291.052752 -311.785088) (xy 291.093255 -311.813044) (xy 291.128748 -311.847136)
			(xy 291.158313 -311.88648) (xy 291.181184 -311.930057) (xy 291.196768 -311.976738) (xy 291.204663 -312.025315)
			(xy 291.205158 -312.049922) (xy 291.544006 -312.049922) (xy 291.547966 -312.000868) (xy 291.559743 -311.953084)
			(xy 291.579034 -311.907808) (xy 291.605337 -311.866212) (xy 291.637972 -311.829375) (xy 291.676093 -311.79825)
			(xy 291.718714 -311.773643) (xy 291.76473 -311.756191) (xy 291.812949 -311.746347) (xy 291.862124 -311.744366)
			(xy 291.910979 -311.750298) (xy 291.95825 -311.76399) (xy 292.002712 -311.785088) (xy 292.043215 -311.813044)
			(xy 292.078708 -311.847136) (xy 292.108273 -311.88648) (xy 292.131144 -311.930057) (xy 292.146728 -311.976738)
			(xy 292.154623 -312.025315) (xy 292.155118 -312.049922) (xy 292.493966 -312.049922) (xy 292.497926 -312.000868)
			(xy 292.509703 -311.953084) (xy 292.528994 -311.907808) (xy 292.555297 -311.866212) (xy 292.587932 -311.829375)
			(xy 292.626053 -311.79825) (xy 292.668674 -311.773643) (xy 292.71469 -311.756191) (xy 292.762909 -311.746347)
			(xy 292.812084 -311.744366) (xy 292.860939 -311.750298) (xy 292.90821 -311.76399) (xy 292.952672 -311.785088)
			(xy 292.993175 -311.813044) (xy 293.028668 -311.847136) (xy 293.058233 -311.88648) (xy 293.081104 -311.930057)
			(xy 293.096688 -311.976738) (xy 293.104583 -312.025315) (xy 293.105078 -312.049922) (xy 293.443926 -312.049922)
			(xy 293.447886 -312.000868) (xy 293.459663 -311.953084) (xy 293.478954 -311.907808) (xy 293.505257 -311.866212)
			(xy 293.537892 -311.829375) (xy 293.576013 -311.79825) (xy 293.618634 -311.773643) (xy 293.66465 -311.756191)
			(xy 293.712869 -311.746347) (xy 293.762044 -311.744366) (xy 293.810899 -311.750298) (xy 293.85817 -311.76399)
			(xy 293.902632 -311.785088) (xy 293.943135 -311.813044) (xy 293.978628 -311.847136) (xy 294.008193 -311.88648)
			(xy 294.031064 -311.930057) (xy 294.046648 -311.976738) (xy 294.054543 -312.025315) (xy 294.055038 -312.049922)
			(xy 294.054543 -312.074529) (xy 294.046648 -312.123106) (xy 294.031064 -312.169787) (xy 294.008193 -312.213364)
			(xy 293.978628 -312.252708) (xy 293.943135 -312.2868) (xy 293.902632 -312.314756) (xy 293.85817 -312.335854)
			(xy 293.810899 -312.349546) (xy 293.762044 -312.355478) (xy 293.712869 -312.353497) (xy 293.66465 -312.343653)
			(xy 293.618634 -312.326201) (xy 293.576013 -312.301594) (xy 293.537892 -312.270469) (xy 293.505257 -312.233632)
			(xy 293.478954 -312.192036) (xy 293.459663 -312.14676) (xy 293.447886 -312.098976) (xy 293.443926 -312.049922)
			(xy 293.105078 -312.049922) (xy 293.104583 -312.074529) (xy 293.096688 -312.123106) (xy 293.081104 -312.169787)
			(xy 293.058233 -312.213364) (xy 293.028668 -312.252708) (xy 292.993175 -312.2868) (xy 292.952672 -312.314756)
			(xy 292.90821 -312.335854) (xy 292.860939 -312.349546) (xy 292.812084 -312.355478) (xy 292.762909 -312.353497)
			(xy 292.71469 -312.343653) (xy 292.668674 -312.326201) (xy 292.626053 -312.301594) (xy 292.587932 -312.270469)
			(xy 292.555297 -312.233632) (xy 292.528994 -312.192036) (xy 292.509703 -312.14676) (xy 292.497926 -312.098976)
			(xy 292.493966 -312.049922) (xy 292.155118 -312.049922) (xy 292.154623 -312.074529) (xy 292.146728 -312.123106)
			(xy 292.131144 -312.169787) (xy 292.108273 -312.213364) (xy 292.078708 -312.252708) (xy 292.043215 -312.2868)
			(xy 292.002712 -312.314756) (xy 291.95825 -312.335854) (xy 291.910979 -312.349546) (xy 291.862124 -312.355478)
			(xy 291.812949 -312.353497) (xy 291.76473 -312.343653) (xy 291.718714 -312.326201) (xy 291.676093 -312.301594)
			(xy 291.637972 -312.270469) (xy 291.605337 -312.233632) (xy 291.579034 -312.192036) (xy 291.559743 -312.14676)
			(xy 291.547966 -312.098976) (xy 291.544006 -312.049922) (xy 291.205158 -312.049922) (xy 291.204663 -312.074529)
			(xy 291.196768 -312.123106) (xy 291.181184 -312.169787) (xy 291.158313 -312.213364) (xy 291.128748 -312.252708)
			(xy 291.093255 -312.2868) (xy 291.052752 -312.314756) (xy 291.00829 -312.335854) (xy 290.961019 -312.349546)
			(xy 290.912164 -312.355478) (xy 290.862989 -312.353497) (xy 290.81477 -312.343653) (xy 290.768754 -312.326201)
			(xy 290.726133 -312.301594) (xy 290.688012 -312.270469) (xy 290.655377 -312.233632) (xy 290.629074 -312.192036)
			(xy 290.609783 -312.14676) (xy 290.598006 -312.098976) (xy 290.594046 -312.049922) (xy 290.255198 -312.049922)
			(xy 290.254703 -312.074529) (xy 290.246808 -312.123106) (xy 290.231224 -312.169787) (xy 290.208353 -312.213364)
			(xy 290.178788 -312.252708) (xy 290.143295 -312.2868) (xy 290.102792 -312.314756) (xy 290.05833 -312.335854)
			(xy 290.011059 -312.349546) (xy 289.962204 -312.355478) (xy 289.913029 -312.353497) (xy 289.86481 -312.343653)
			(xy 289.818794 -312.326201) (xy 289.776173 -312.301594) (xy 289.738052 -312.270469) (xy 289.705417 -312.233632)
			(xy 289.679114 -312.192036) (xy 289.659823 -312.14676) (xy 289.648046 -312.098976) (xy 289.644086 -312.049922)
			(xy 289.305238 -312.049922) (xy 289.304743 -312.074529) (xy 289.296848 -312.123106) (xy 289.281264 -312.169787)
			(xy 289.258393 -312.213364) (xy 289.228828 -312.252708) (xy 289.193335 -312.2868) (xy 289.152832 -312.314756)
			(xy 289.10837 -312.335854) (xy 289.061099 -312.349546) (xy 289.012244 -312.355478) (xy 288.963069 -312.353497)
			(xy 288.91485 -312.343653) (xy 288.868834 -312.326201) (xy 288.826213 -312.301594) (xy 288.788092 -312.270469)
			(xy 288.755457 -312.233632) (xy 288.729154 -312.192036) (xy 288.709863 -312.14676) (xy 288.698086 -312.098976)
			(xy 288.694126 -312.049922) (xy 288.355024 -312.049922) (xy 288.354529 -312.074529) (xy 288.346634 -312.123106)
			(xy 288.33105 -312.169787) (xy 288.308179 -312.213364) (xy 288.278614 -312.252708) (xy 288.243121 -312.2868)
			(xy 288.202618 -312.314756) (xy 288.158156 -312.335854) (xy 288.110885 -312.349546) (xy 288.06203 -312.355478)
			(xy 288.012855 -312.353497) (xy 287.964636 -312.343653) (xy 287.91862 -312.326201) (xy 287.875999 -312.301594)
			(xy 287.837878 -312.270469) (xy 287.805243 -312.233632) (xy 287.77894 -312.192036) (xy 287.759649 -312.14676)
			(xy 287.747872 -312.098976) (xy 287.743912 -312.049922) (xy 287.405064 -312.049922) (xy 287.404569 -312.074529)
			(xy 287.396674 -312.123106) (xy 287.38109 -312.169787) (xy 287.358219 -312.213364) (xy 287.328654 -312.252708)
			(xy 287.293161 -312.2868) (xy 287.252658 -312.314756) (xy 287.208196 -312.335854) (xy 287.160925 -312.349546)
			(xy 287.11207 -312.355478) (xy 287.062895 -312.353497) (xy 287.014676 -312.343653) (xy 286.96866 -312.326201)
			(xy 286.926039 -312.301594) (xy 286.887918 -312.270469) (xy 286.855283 -312.233632) (xy 286.82898 -312.192036)
			(xy 286.809689 -312.14676) (xy 286.797912 -312.098976) (xy 286.793952 -312.049922) (xy 286.455104 -312.049922)
			(xy 286.454609 -312.074529) (xy 286.446714 -312.123106) (xy 286.43113 -312.169787) (xy 286.408259 -312.213364)
			(xy 286.378694 -312.252708) (xy 286.343201 -312.2868) (xy 286.302698 -312.314756) (xy 286.258236 -312.335854)
			(xy 286.210965 -312.349546) (xy 286.16211 -312.355478) (xy 286.112935 -312.353497) (xy 286.064716 -312.343653)
			(xy 286.0187 -312.326201) (xy 285.976079 -312.301594) (xy 285.937958 -312.270469) (xy 285.905323 -312.233632)
			(xy 285.87902 -312.192036) (xy 285.859729 -312.14676) (xy 285.847952 -312.098976) (xy 285.843992 -312.049922)
			(xy 285.505144 -312.049922) (xy 285.504649 -312.074529) (xy 285.496754 -312.123106) (xy 285.48117 -312.169787)
			(xy 285.458299 -312.213364) (xy 285.428734 -312.252708) (xy 285.393241 -312.2868) (xy 285.352738 -312.314756)
			(xy 285.308276 -312.335854) (xy 285.261005 -312.349546) (xy 285.21215 -312.355478) (xy 285.162975 -312.353497)
			(xy 285.114756 -312.343653) (xy 285.06874 -312.326201) (xy 285.026119 -312.301594) (xy 284.987998 -312.270469)
			(xy 284.955363 -312.233632) (xy 284.92906 -312.192036) (xy 284.909769 -312.14676) (xy 284.897992 -312.098976)
			(xy 284.894032 -312.049922) (xy 284.555184 -312.049922) (xy 284.554689 -312.074529) (xy 284.546794 -312.123106)
			(xy 284.53121 -312.169787) (xy 284.508339 -312.213364) (xy 284.478774 -312.252708) (xy 284.443281 -312.2868)
			(xy 284.402778 -312.314756) (xy 284.358316 -312.335854) (xy 284.311045 -312.349546) (xy 284.26219 -312.355478)
			(xy 284.213015 -312.353497) (xy 284.164796 -312.343653) (xy 284.11878 -312.326201) (xy 284.076159 -312.301594)
			(xy 284.038038 -312.270469) (xy 284.005403 -312.233632) (xy 283.9791 -312.192036) (xy 283.959809 -312.14676)
			(xy 283.948032 -312.098976) (xy 283.944072 -312.049922) (xy 283.605224 -312.049922) (xy 283.604729 -312.074529)
			(xy 283.596834 -312.123106) (xy 283.58125 -312.169787) (xy 283.558379 -312.213364) (xy 283.528814 -312.252708)
			(xy 283.493321 -312.2868) (xy 283.452818 -312.314756) (xy 283.408356 -312.335854) (xy 283.361085 -312.349546)
			(xy 283.31223 -312.355478) (xy 283.263055 -312.353497) (xy 283.214836 -312.343653) (xy 283.16882 -312.326201)
			(xy 283.126199 -312.301594) (xy 283.088078 -312.270469) (xy 283.055443 -312.233632) (xy 283.02914 -312.192036)
			(xy 283.009849 -312.14676) (xy 282.998072 -312.098976) (xy 282.994112 -312.049922) (xy 282.65501 -312.049922)
			(xy 282.654515 -312.074529) (xy 282.64662 -312.123106) (xy 282.631036 -312.169787) (xy 282.608165 -312.213364)
			(xy 282.5786 -312.252708) (xy 282.543107 -312.2868) (xy 282.502604 -312.314756) (xy 282.458142 -312.335854)
			(xy 282.410871 -312.349546) (xy 282.362016 -312.355478) (xy 282.312841 -312.353497) (xy 282.264622 -312.343653)
			(xy 282.218606 -312.326201) (xy 282.175985 -312.301594) (xy 282.137864 -312.270469) (xy 282.105229 -312.233632)
			(xy 282.078926 -312.192036) (xy 282.059635 -312.14676) (xy 282.047858 -312.098976) (xy 282.043898 -312.049922)
			(xy 281.70505 -312.049922) (xy 281.704555 -312.074529) (xy 281.69666 -312.123106) (xy 281.681076 -312.169787)
			(xy 281.658205 -312.213364) (xy 281.62864 -312.252708) (xy 281.593147 -312.2868) (xy 281.552644 -312.314756)
			(xy 281.508182 -312.335854) (xy 281.460911 -312.349546) (xy 281.412056 -312.355478) (xy 281.362881 -312.353497)
			(xy 281.314662 -312.343653) (xy 281.268646 -312.326201) (xy 281.226025 -312.301594) (xy 281.187904 -312.270469)
			(xy 281.155269 -312.233632) (xy 281.128966 -312.192036) (xy 281.109675 -312.14676) (xy 281.097898 -312.098976)
			(xy 281.093938 -312.049922) (xy 280.75509 -312.049922) (xy 280.754595 -312.074529) (xy 280.7467 -312.123106)
			(xy 280.731116 -312.169787) (xy 280.708245 -312.213364) (xy 280.67868 -312.252708) (xy 280.643187 -312.2868)
			(xy 280.602684 -312.314756) (xy 280.558222 -312.335854) (xy 280.510951 -312.349546) (xy 280.462096 -312.355478)
			(xy 280.412921 -312.353497) (xy 280.364702 -312.343653) (xy 280.318686 -312.326201) (xy 280.276065 -312.301594)
			(xy 280.237944 -312.270469) (xy 280.205309 -312.233632) (xy 280.179006 -312.192036) (xy 280.159715 -312.14676)
			(xy 280.147938 -312.098976) (xy 280.143978 -312.049922) (xy 279.80513 -312.049922) (xy 279.804635 -312.074529)
			(xy 279.79674 -312.123106) (xy 279.781156 -312.169787) (xy 279.758285 -312.213364) (xy 279.72872 -312.252708)
			(xy 279.693227 -312.2868) (xy 279.652724 -312.314756) (xy 279.608262 -312.335854) (xy 279.560991 -312.349546)
			(xy 279.512136 -312.355478) (xy 279.462961 -312.353497) (xy 279.414742 -312.343653) (xy 279.368726 -312.326201)
			(xy 279.326105 -312.301594) (xy 279.287984 -312.270469) (xy 279.255349 -312.233632) (xy 279.229046 -312.192036)
			(xy 279.209755 -312.14676) (xy 279.197978 -312.098976) (xy 279.194018 -312.049922) (xy 278.85517 -312.049922)
			(xy 278.854675 -312.074529) (xy 278.84678 -312.123106) (xy 278.831196 -312.169787) (xy 278.808325 -312.213364)
			(xy 278.77876 -312.252708) (xy 278.743267 -312.2868) (xy 278.702764 -312.314756) (xy 278.658302 -312.335854)
			(xy 278.611031 -312.349546) (xy 278.562176 -312.355478) (xy 278.513001 -312.353497) (xy 278.464782 -312.343653)
			(xy 278.418766 -312.326201) (xy 278.376145 -312.301594) (xy 278.338024 -312.270469) (xy 278.305389 -312.233632)
			(xy 278.279086 -312.192036) (xy 278.259795 -312.14676) (xy 278.248018 -312.098976) (xy 278.244058 -312.049922)
			(xy 277.90521 -312.049922) (xy 277.904715 -312.074529) (xy 277.89682 -312.123106) (xy 277.881236 -312.169787)
			(xy 277.858365 -312.213364) (xy 277.8288 -312.252708) (xy 277.793307 -312.2868) (xy 277.752804 -312.314756)
			(xy 277.708342 -312.335854) (xy 277.661071 -312.349546) (xy 277.612216 -312.355478) (xy 277.563041 -312.353497)
			(xy 277.514822 -312.343653) (xy 277.468806 -312.326201) (xy 277.426185 -312.301594) (xy 277.388064 -312.270469)
			(xy 277.355429 -312.233632) (xy 277.329126 -312.192036) (xy 277.309835 -312.14676) (xy 277.298058 -312.098976)
			(xy 277.294098 -312.049922) (xy 276.954996 -312.049922) (xy 276.954501 -312.074529) (xy 276.946606 -312.123106)
			(xy 276.931022 -312.169787) (xy 276.908151 -312.213364) (xy 276.878586 -312.252708) (xy 276.843093 -312.2868)
			(xy 276.80259 -312.314756) (xy 276.758128 -312.335854) (xy 276.710857 -312.349546) (xy 276.662002 -312.355478)
			(xy 276.612827 -312.353497) (xy 276.564608 -312.343653) (xy 276.518592 -312.326201) (xy 276.475971 -312.301594)
			(xy 276.43785 -312.270469) (xy 276.405215 -312.233632) (xy 276.378912 -312.192036) (xy 276.359621 -312.14676)
			(xy 276.347844 -312.098976) (xy 276.343884 -312.049922) (xy 276.005036 -312.049922) (xy 276.004541 -312.074529)
			(xy 275.996646 -312.123106) (xy 275.981062 -312.169787) (xy 275.958191 -312.213364) (xy 275.928626 -312.252708)
			(xy 275.893133 -312.2868) (xy 275.85263 -312.314756) (xy 275.808168 -312.335854) (xy 275.760897 -312.349546)
			(xy 275.712042 -312.355478) (xy 275.662867 -312.353497) (xy 275.614648 -312.343653) (xy 275.568632 -312.326201)
			(xy 275.526011 -312.301594) (xy 275.48789 -312.270469) (xy 275.455255 -312.233632) (xy 275.428952 -312.192036)
			(xy 275.409661 -312.14676) (xy 275.397884 -312.098976) (xy 275.393924 -312.049922) (xy 275.055076 -312.049922)
			(xy 275.054581 -312.074529) (xy 275.046686 -312.123106) (xy 275.031102 -312.169787) (xy 275.008231 -312.213364)
			(xy 274.978666 -312.252708) (xy 274.943173 -312.2868) (xy 274.90267 -312.314756) (xy 274.858208 -312.335854)
			(xy 274.810937 -312.349546) (xy 274.762082 -312.355478) (xy 274.712907 -312.353497) (xy 274.664688 -312.343653)
			(xy 274.618672 -312.326201) (xy 274.576051 -312.301594) (xy 274.53793 -312.270469) (xy 274.505295 -312.233632)
			(xy 274.478992 -312.192036) (xy 274.459701 -312.14676) (xy 274.447924 -312.098976) (xy 274.443964 -312.049922)
			(xy 274.105607 -312.049922) (xy 274.101438 -312.100234) (xy 274.08904 -312.149194) (xy 274.068752 -312.195447)
			(xy 274.041128 -312.237729) (xy 274.006922 -312.274888) (xy 273.967066 -312.30591) (xy 273.922647 -312.329949)
			(xy 273.874878 -312.34635) (xy 273.825061 -312.354664) (xy 273.799808 -312.35523) (xy 273.785753 -312.355022)
			(xy 273.757769 -312.35235) (xy 273.743928 -312.349896) (xy 273.74342 -312.349896) (xy 273.731189 -312.348405)
			(xy 273.707701 -312.355713) (xy 273.698462 -312.363866) (xy 273.629882 -312.432446) (xy 273.622516 -312.456068)
			(xy 273.623278 -312.46064) (xy 273.627301 -312.480886) (xy 273.630506 -312.52204) (xy 273.62815 -312.563251)
			(xy 273.624548 -312.583576) (xy 273.623532 -312.593228) (xy 273.623532 -312.600086) (xy 273.631152 -312.618628)
			(xy 273.698462 -312.685938) (xy 273.707701 -312.69409) (xy 273.731191 -312.701401) (xy 273.74342 -312.699908)
			(xy 273.743674 -312.699908) (xy 273.757576 -312.69743) (xy 273.785688 -312.694755) (xy 273.799808 -312.694574)
			(xy 273.823799 -312.695045) (xy 273.871191 -312.702552) (xy 273.916825 -312.71738) (xy 273.959578 -312.739164)
			(xy 273.998397 -312.767367) (xy 274.032327 -312.801295) (xy 274.060531 -312.840113) (xy 274.082316 -312.882866)
			(xy 274.097145 -312.928499) (xy 274.104654 -312.975891) (xy 274.105116 -312.999882) (xy 274.105077 -313.008983)
			(xy 274.104062 -313.027156) (xy 274.103084 -313.036204) (xy 274.10156 -313.048142) (xy 274.109688 -313.070494)
			(xy 274.185634 -313.143392) (xy 274.20824 -313.150504) (xy 274.220178 -313.148472) (xy 274.233604 -313.146356)
			(xy 274.260689 -313.144071) (xy 274.27428 -313.1439) (xy 274.274534 -313.1439) (xy 274.288124 -313.14407)
			(xy 274.315209 -313.146362) (xy 274.328636 -313.148472) (xy 274.329144 -313.148472) (xy 274.340883 -313.149765)
			(xy 274.363405 -313.14275) (xy 274.372324 -313.13501) (xy 274.431506 -313.078622) (xy 274.439584 -313.069986)
			(xy 274.447547 -313.047747) (xy 274.446746 -313.03595) (xy 274.446746 -313.035696) (xy 274.445721 -313.026841)
			(xy 274.44458 -313.009049) (xy 274.44446 -313.000136) (xy 274.44446 -312.999628) (xy 274.444951 -312.97565)
			(xy 274.452491 -312.928289) (xy 274.467342 -312.882689) (xy 274.489139 -312.839972) (xy 274.517347 -312.801188)
			(xy 274.551271 -312.76729) (xy 274.590077 -312.739113) (xy 274.632811 -312.71735) (xy 274.678423 -312.702534)
			(xy 274.725789 -312.695032) (xy 274.749768 -312.694574) (xy 274.775029 -312.695064) (xy 274.824862 -312.703375)
			(xy 274.872648 -312.719776) (xy 274.917082 -312.743818) (xy 274.956953 -312.774847) (xy 274.991172 -312.812015)
			(xy 275.018807 -312.854309) (xy 275.039102 -312.900575) (xy 275.051506 -312.949551) (xy 275.055678 -312.9999)
			(xy 275.051506 -313.050249) (xy 275.039102 -313.099225) (xy 275.018807 -313.145491) (xy 274.991172 -313.187785)
			(xy 274.956953 -313.224953) (xy 274.917082 -313.255982) (xy 274.872648 -313.280024) (xy 274.824862 -313.296425)
			(xy 274.775029 -313.304736) (xy 274.749768 -313.30519) (xy 274.740664 -313.305093) (xy 274.722491 -313.303949)
			(xy 274.713446 -313.302904) (xy 274.713192 -313.302904) (xy 274.701392 -313.302098) (xy 274.679152 -313.310057)
			(xy 274.67052 -313.318144) (xy 274.606004 -313.385962) (xy 274.598892 -313.408822) (xy 274.5994 -313.41187)
			(xy 274.602248 -313.427462) (xy 274.605305 -313.459013) (xy 274.605496 -313.474862) (xy 274.605496 -313.54522)
			(xy 274.606059 -313.555912) (xy 274.614716 -313.575469) (xy 274.62226 -313.583066) (xy 274.678394 -313.633612)
			(xy 274.686615 -313.640394) (xy 274.706871 -313.646959) (xy 274.71751 -313.646312) (xy 274.717764 -313.646312)
			(xy 274.749768 -313.644534) (xy 274.773762 -313.644978) (xy 274.821158 -313.652481) (xy 274.866798 -313.667307)
			(xy 274.909555 -313.689091) (xy 274.948378 -313.717297) (xy 274.982309 -313.75123) (xy 275.010514 -313.790053)
			(xy 275.032297 -313.832812) (xy 275.047121 -313.878451) (xy 275.054623 -313.925848) (xy 275.055076 -313.949842)
			(xy 275.05487 -313.963897) (xy 275.052203 -313.991882) (xy 275.049742 -314.005722) (xy 275.049742 -314.00623)
			(xy 275.048239 -314.018464) (xy 275.055536 -314.041965) (xy 275.063712 -314.051188) (xy 275.132292 -314.119768)
			(xy 275.155914 -314.127134) (xy 275.164042 -314.12561) (xy 275.1941 -314.120262) (xy 275.255142 -314.120262)
			(xy 275.2852 -314.12561) (xy 275.285962 -314.12561) (xy 275.293582 -314.127134) (xy 275.317204 -314.119768)
			(xy 275.385784 -314.051188) (xy 275.393932 -314.041949) (xy 275.401229 -314.018461) (xy 275.399754 -314.00623)
			(xy 275.399754 -314.005722) (xy 275.397286 -313.991883) (xy 275.394612 -313.963898) (xy 275.39442 -313.949842)
			(xy 275.394863 -313.925847) (xy 275.402365 -313.878449) (xy 275.41719 -313.832807) (xy 275.438974 -313.790047)
			(xy 275.467179 -313.751222) (xy 275.501111 -313.717288) (xy 275.539935 -313.689081) (xy 275.582694 -313.667295)
			(xy 275.628335 -313.652468) (xy 275.675734 -313.644964) (xy 275.699728 -313.644534) (xy 275.731478 -313.646312)
			(xy 275.731986 -313.646312) (xy 275.742606 -313.646827) (xy 275.762807 -313.640265) (xy 275.771102 -313.633612)
			(xy 275.827236 -313.583066) (xy 275.834893 -313.575548) (xy 275.843568 -313.555943) (xy 275.844 -313.54522)
			(xy 275.844 -313.474862) (xy 275.84415 -313.459533) (xy 275.84695 -313.429003) (xy 275.849588 -313.413902)
			(xy 275.849588 -313.41314) (xy 275.85035 -313.408568) (xy 275.843492 -313.385962) (xy 275.778976 -313.318398)
			(xy 275.770333 -313.310195) (xy 275.747943 -313.302132) (xy 275.73605 -313.302904) (xy 275.727006 -313.303953)
			(xy 275.708832 -313.305099) (xy 275.699728 -313.30519) (xy 275.674908 -313.304706) (xy 275.625922 -313.29668)
			(xy 275.57888 -313.280835) (xy 275.535022 -313.257587) (xy 275.495502 -313.22755) (xy 275.461362 -313.191515)
			(xy 275.433501 -313.150432) (xy 275.412655 -313.105382) (xy 275.399371 -313.057554) (xy 275.394 -313.008206)
			(xy 275.396683 -312.958639) (xy 275.40735 -312.91016) (xy 275.42572 -312.864045) (xy 275.451308 -312.821509)
			(xy 275.483441 -312.783674) (xy 275.521272 -312.751535) (xy 275.563804 -312.725941) (xy 275.609916 -312.707564)
			(xy 275.658394 -312.696889) (xy 275.70796 -312.694199) (xy 275.757308 -312.699562) (xy 275.805139 -312.712839)
			(xy 275.850192 -312.733679) (xy 275.891279 -312.761533) (xy 275.927319 -312.795667) (xy 275.957362 -312.835183)
			(xy 275.980616 -312.879038) (xy 275.996469 -312.926078) (xy 276.004503 -312.975062) (xy 276.005036 -312.999882)
			(xy 276.004937 -313.008986) (xy 276.003791 -313.027159) (xy 276.00275 -313.036204) (xy 276.001951 -313.048098)
			(xy 276.01003 -313.070492) (xy 276.018244 -313.07913) (xy 276.085808 -313.143646) (xy 276.108414 -313.150504)
			(xy 276.113494 -313.149742) (xy 276.128659 -313.147103) (xy 276.159316 -313.144306) (xy 276.174708 -313.144154)
			(xy 276.190037 -313.144303) (xy 276.220567 -313.1471) (xy 276.235668 -313.149742) (xy 276.23643 -313.149742)
			(xy 276.241002 -313.150504) (xy 276.263608 -313.143646) (xy 276.331172 -313.07913) (xy 276.33939 -313.070492)
			(xy 276.347481 -313.048098) (xy 276.346666 -313.036204) (xy 276.345618 -313.02716) (xy 276.344476 -313.008986)
			(xy 276.34438 -312.999882) (xy 276.344867 -312.97506) (xy 276.352902 -312.926071) (xy 276.368756 -312.879027)
			(xy 276.392011 -312.835168) (xy 276.422057 -312.795649) (xy 276.458099 -312.761511) (xy 276.49919 -312.733654)
			(xy 276.544247 -312.712812) (xy 276.592081 -312.699534) (xy 276.641434 -312.694169) (xy 276.691005 -312.696859)
			(xy 276.739487 -312.707533) (xy 276.785603 -312.725911) (xy 276.82814 -312.751507) (xy 276.865974 -312.783647)
			(xy 276.898111 -312.821485) (xy 276.923703 -312.864023) (xy 276.942075 -312.910142) (xy 276.952745 -312.958625)
			(xy 276.95543 -313.008196) (xy 276.950061 -313.057548) (xy 276.936778 -313.105382) (xy 276.915931 -313.150436)
			(xy 276.88807 -313.191524) (xy 276.853929 -313.227563) (xy 276.814407 -313.257605) (xy 276.770545 -313.280856)
			(xy 276.7235 -313.296706) (xy 276.67451 -313.304735) (xy 276.649688 -313.30519) (xy 276.640584 -313.305093)
			(xy 276.62241 -313.303951) (xy 276.613366 -313.302904) (xy 276.601476 -313.302112) (xy 276.579097 -313.310207)
			(xy 276.57044 -313.318398) (xy 276.505924 -313.385962) (xy 276.499066 -313.408568) (xy 276.499828 -313.413648)
			(xy 276.502469 -313.428813) (xy 276.505271 -313.45947) (xy 276.505416 -313.474862) (xy 276.505416 -313.54522)
			(xy 276.505979 -313.555912) (xy 276.514639 -313.575466) (xy 276.52218 -313.583066) (xy 276.578314 -313.633612)
			(xy 276.586532 -313.640408) (xy 276.606791 -313.647005) (xy 276.61743 -313.646312) (xy 276.617684 -313.646312)
			(xy 276.649688 -313.644534) (xy 276.673681 -313.644979) (xy 276.721075 -313.652485) (xy 276.766712 -313.667313)
			(xy 276.809466 -313.689098) (xy 276.848286 -313.717304) (xy 276.882215 -313.751237) (xy 276.910417 -313.790059)
			(xy 276.932199 -313.832816) (xy 276.947022 -313.878454) (xy 276.954523 -313.925849) (xy 276.954996 -313.949842)
			(xy 276.954796 -313.963961) (xy 276.952125 -313.992072) (xy 276.949662 -314.005976) (xy 276.949662 -314.006484)
			(xy 276.948171 -314.018713) (xy 276.955488 -314.042195) (xy 276.963632 -314.051442) (xy 277.023322 -314.110878)
			(xy 277.032561 -314.119025) (xy 277.056049 -314.126318) (xy 277.06828 -314.124848) (xy 277.068534 -314.124848)
			(xy 277.082436 -314.122373) (xy 277.110549 -314.119704) (xy 277.124668 -314.119514) (xy 277.125176 -314.119514)
			(xy 277.13929 -314.119637) (xy 277.167402 -314.122185) (xy 277.18131 -314.124594) (xy 277.193502 -314.12688)
			(xy 277.217632 -314.119514) (xy 277.285958 -314.051188) (xy 277.294097 -314.041945) (xy 277.301383 -314.018461)
			(xy 277.299928 -314.00623) (xy 277.299928 -314.005722) (xy 277.29746 -313.991883) (xy 277.294786 -313.963898)
			(xy 277.294594 -313.949842) (xy 277.295037 -313.925847) (xy 277.302539 -313.878446) (xy 277.317363 -313.832803)
			(xy 277.339147 -313.790041) (xy 277.367352 -313.751214) (xy 277.401284 -313.717278) (xy 277.440107 -313.689068)
			(xy 277.482866 -313.667279) (xy 277.528507 -313.652448) (xy 277.575907 -313.64494) (xy 277.599902 -313.644534)
			(xy 277.631398 -313.646312) (xy 277.631906 -313.646312) (xy 277.642525 -313.646823) (xy 277.66272 -313.640255)
			(xy 277.671022 -313.633612) (xy 277.727156 -313.583066) (xy 277.734811 -313.575547) (xy 277.743482 -313.555942)
			(xy 277.74392 -313.54522) (xy 277.74392 -313.474862) (xy 277.74407 -313.459533) (xy 277.74687 -313.429003)
			(xy 277.749508 -313.413902) (xy 277.749508 -313.41314) (xy 277.75027 -313.408568) (xy 277.743412 -313.385962)
			(xy 277.670514 -313.309762) (xy 277.648162 -313.301634) (xy 277.636224 -313.303158) (xy 277.627177 -313.304146)
			(xy 277.609003 -313.305161) (xy 277.599902 -313.30519) (xy 277.574646 -313.304698) (xy 277.524822 -313.296384)
			(xy 277.477046 -313.279983) (xy 277.432621 -313.255941) (xy 277.39276 -313.224916) (xy 277.358548 -313.187753)
			(xy 277.33092 -313.145465) (xy 277.31063 -313.099207) (xy 277.298229 -313.05024) (xy 277.294058 -312.9999)
			(xy 277.298229 -312.94956) (xy 277.31063 -312.900593) (xy 277.33092 -312.854335) (xy 277.358548 -312.812047)
			(xy 277.39276 -312.774884) (xy 277.432621 -312.743859) (xy 277.477046 -312.719817) (xy 277.524822 -312.703416)
			(xy 277.574646 -312.695102) (xy 277.599902 -312.694574) (xy 277.623881 -312.695044) (xy 277.671249 -312.702542)
			(xy 277.716862 -312.717354) (xy 277.759599 -312.739115) (xy 277.798408 -312.76729) (xy 277.832334 -312.801187)
			(xy 277.860543 -312.839971) (xy 277.882342 -312.882688) (xy 277.897195 -312.928288) (xy 277.904735 -312.975649)
			(xy 277.90521 -312.999628) (xy 277.90521 -313.000136) (xy 277.903178 -313.033156) (xy 277.902924 -313.03595)
			(xy 277.902924 -313.036712) (xy 277.902216 -313.048385) (xy 277.910158 -313.070352) (xy 277.918164 -313.078876)
			(xy 277.985728 -313.143392) (xy 278.008588 -313.150504) (xy 278.020272 -313.148472) (xy 278.033639 -313.146424)
			(xy 278.060597 -313.144263) (xy 278.07412 -313.144154) (xy 278.074628 -313.144154) (xy 278.088218 -313.144324)
			(xy 278.115303 -313.146615) (xy 278.12873 -313.148726) (xy 278.129238 -313.148726) (xy 278.140947 -313.150069)
			(xy 278.163452 -313.14317) (xy 278.172418 -313.135518) (xy 278.231346 -313.07913) (xy 278.239567 -313.070493)
			(xy 278.247663 -313.048098) (xy 278.24684 -313.036204) (xy 278.245792 -313.02716) (xy 278.24465 -313.008986)
			(xy 278.244554 -312.999882) (xy 278.245041 -312.975058) (xy 278.253077 -312.926064) (xy 278.268933 -312.879015)
			(xy 278.292191 -312.835152) (xy 278.32224 -312.795629) (xy 278.358287 -312.761488) (xy 278.399383 -312.733629)
			(xy 278.444444 -312.712785) (xy 278.492284 -312.699507) (xy 278.541642 -312.694143) (xy 278.591217 -312.696834)
			(xy 278.639704 -312.707511) (xy 278.685825 -312.725892) (xy 278.728365 -312.751493) (xy 278.766202 -312.783638)
			(xy 278.79834 -312.821481) (xy 278.823933 -312.864025) (xy 278.842305 -312.910149) (xy 278.852973 -312.958638)
			(xy 278.855656 -313.008214) (xy 278.850283 -313.057571) (xy 278.836995 -313.105409) (xy 278.816144 -313.150466)
			(xy 278.788277 -313.191557) (xy 278.75413 -313.227597) (xy 278.714601 -313.257639) (xy 278.670733 -313.28089)
			(xy 278.623682 -313.296737) (xy 278.574686 -313.304763) (xy 278.549862 -313.30519) (xy 278.540694 -313.305096)
			(xy 278.522394 -313.30395) (xy 278.513286 -313.302904) (xy 278.513032 -313.302904) (xy 278.501229 -313.302089)
			(xy 278.478976 -313.310036) (xy 278.47036 -313.318144) (xy 278.406098 -313.385708) (xy 278.398986 -313.408568)
			(xy 278.401018 -313.420252) (xy 278.403091 -313.433808) (xy 278.40525 -313.461149) (xy 278.405336 -313.474862)
			(xy 278.405336 -313.54522) (xy 278.4059 -313.555911) (xy 278.414562 -313.575463) (xy 278.4221 -313.583066)
			(xy 278.478488 -313.633612) (xy 278.486774 -313.640284) (xy 278.506981 -313.646865) (xy 278.517604 -313.646312)
			(xy 278.517858 -313.646312) (xy 278.549862 -313.644534) (xy 278.573856 -313.644977) (xy 278.621254 -313.65248)
			(xy 278.666894 -313.667305) (xy 278.709652 -313.689089) (xy 278.748475 -313.717295) (xy 278.782408 -313.751228)
			(xy 278.810613 -313.790051) (xy 278.832396 -313.83281) (xy 278.847221 -313.87845) (xy 278.854723 -313.925848)
			(xy 278.85517 -313.949842) (xy 278.854964 -313.963897) (xy 278.852297 -313.991882) (xy 278.849836 -314.005722)
			(xy 278.849836 -314.00623) (xy 278.848333 -314.018464) (xy 278.855629 -314.041966) (xy 278.863806 -314.051188)
			(xy 278.932132 -314.119514) (xy 278.956262 -314.12688) (xy 278.968454 -314.124594) (xy 278.982363 -314.122197)
			(xy 279.010475 -314.119655) (xy 279.024588 -314.119514) (xy 279.025096 -314.119514) (xy 279.039211 -314.119633)
			(xy 279.067324 -314.122174) (xy 279.08123 -314.124594) (xy 279.093422 -314.12688) (xy 279.117552 -314.119514)
			(xy 279.185878 -314.051188) (xy 279.194027 -314.041949) (xy 279.201325 -314.018461) (xy 279.199848 -314.00623)
			(xy 279.199848 -314.005722) (xy 279.19738 -313.991883) (xy 279.194706 -313.963898) (xy 279.194514 -313.949842)
			(xy 279.194957 -313.925847) (xy 279.202459 -313.878448) (xy 279.217284 -313.832806) (xy 279.239067 -313.790046)
			(xy 279.267273 -313.75122) (xy 279.301205 -313.717286) (xy 279.340029 -313.689078) (xy 279.382788 -313.667292)
			(xy 279.428429 -313.652463) (xy 279.475827 -313.644959) (xy 279.499822 -313.644534) (xy 279.531318 -313.646312)
			(xy 279.531826 -313.646312) (xy 279.542443 -313.646819) (xy 279.562633 -313.640245) (xy 279.570942 -313.633612)
			(xy 279.627076 -313.583066) (xy 279.634729 -313.575546) (xy 279.643396 -313.555941) (xy 279.64384 -313.54522)
			(xy 279.64384 -313.474862) (xy 279.64399 -313.459533) (xy 279.64679 -313.429003) (xy 279.649428 -313.413902)
			(xy 279.649428 -313.41314) (xy 279.65019 -313.408568) (xy 279.643332 -313.385962) (xy 279.570434 -313.309762)
			(xy 279.548082 -313.301634) (xy 279.536144 -313.303158) (xy 279.527097 -313.304147) (xy 279.508923 -313.305163)
			(xy 279.499822 -313.30519) (xy 279.474565 -313.304699) (xy 279.424738 -313.296388) (xy 279.37696 -313.279988)
			(xy 279.332532 -313.255948) (xy 279.292667 -313.224923) (xy 279.258453 -313.187759) (xy 279.230823 -313.145471)
			(xy 279.210531 -313.099211) (xy 279.19813 -313.050242) (xy 279.193958 -312.9999) (xy 279.19813 -312.949558)
			(xy 279.210531 -312.900589) (xy 279.230823 -312.854329) (xy 279.258453 -312.812041) (xy 279.292667 -312.774877)
			(xy 279.332532 -312.743852) (xy 279.37696 -312.719812) (xy 279.424738 -312.703412) (xy 279.474565 -312.695101)
			(xy 279.499822 -312.694574) (xy 279.5238 -312.695045) (xy 279.571166 -312.702546) (xy 279.616776 -312.71736)
			(xy 279.65951 -312.739122) (xy 279.698316 -312.767298) (xy 279.73224 -312.801194) (xy 279.760447 -312.839977)
			(xy 279.782244 -312.882693) (xy 279.797095 -312.928291) (xy 279.804635 -312.97565) (xy 279.80513 -312.999628)
			(xy 279.80513 -313.000136) (xy 279.803098 -313.033156) (xy 279.802844 -313.03595) (xy 279.802844 -313.036712)
			(xy 279.802136 -313.048384) (xy 279.810081 -313.07035) (xy 279.818084 -313.078876) (xy 279.885648 -313.143392)
			(xy 279.908508 -313.150504) (xy 279.920192 -313.148472) (xy 279.933559 -313.146425) (xy 279.960517 -313.144266)
			(xy 279.97404 -313.144154) (xy 279.974548 -313.144154) (xy 279.988138 -313.144325) (xy 280.015223 -313.146617)
			(xy 280.02865 -313.148726) (xy 280.029158 -313.148726) (xy 280.040873 -313.150087) (xy 280.063403 -313.143213)
			(xy 280.072338 -313.135518) (xy 280.131266 -313.07913) (xy 280.139485 -313.070492) (xy 280.147577 -313.048098)
			(xy 280.14676 -313.036204) (xy 280.145712 -313.02716) (xy 280.14457 -313.008986) (xy 280.144474 -312.999882)
			(xy 280.144961 -312.97506) (xy 280.152996 -312.92607) (xy 280.16885 -312.879025) (xy 280.192107 -312.835164)
			(xy 280.222153 -312.795644) (xy 280.258197 -312.761506) (xy 280.299289 -312.733648) (xy 280.344346 -312.712806)
			(xy 280.392182 -312.699527) (xy 280.441536 -312.694163) (xy 280.491107 -312.696853) (xy 280.539591 -312.707528)
			(xy 280.585708 -312.725906) (xy 280.628245 -312.751503) (xy 280.666081 -312.783645) (xy 280.698218 -312.821484)
			(xy 280.72381 -312.864024) (xy 280.742182 -312.910144) (xy 280.752852 -312.958628) (xy 280.755536 -313.0082)
			(xy 280.750166 -313.057554) (xy 280.736882 -313.105388) (xy 280.716034 -313.150443) (xy 280.688172 -313.191532)
			(xy 280.654029 -313.227571) (xy 280.614505 -313.257613) (xy 280.570642 -313.280864) (xy 280.523595 -313.296713)
			(xy 280.474604 -313.304742) (xy 280.449782 -313.30519) (xy 280.440614 -313.305097) (xy 280.422314 -313.303952)
			(xy 280.413206 -313.302904) (xy 280.412952 -313.302904) (xy 280.401147 -313.302084) (xy 280.378887 -313.310025)
			(xy 280.37028 -313.318144) (xy 280.306018 -313.385708) (xy 280.298906 -313.408568) (xy 280.300938 -313.420252)
			(xy 280.303011 -313.433808) (xy 280.30517 -313.461149) (xy 280.305256 -313.474862) (xy 280.305256 -313.54522)
			(xy 280.30582 -313.555911) (xy 280.314485 -313.575461) (xy 280.32202 -313.583066) (xy 280.378408 -313.633612)
			(xy 280.386695 -313.640281) (xy 280.406902 -313.646854) (xy 280.417524 -313.646312) (xy 280.417778 -313.646312)
			(xy 280.449782 -313.644534) (xy 280.473775 -313.644979) (xy 280.52117 -313.652484) (xy 280.566807 -313.667311)
			(xy 280.609563 -313.689096) (xy 280.648384 -313.717302) (xy 280.682313 -313.751235) (xy 280.710516 -313.790057)
			(xy 280.732298 -313.832815) (xy 280.747122 -313.878453) (xy 280.754623 -313.925849) (xy 280.75509 -313.949842)
			(xy 280.754884 -313.963897) (xy 280.752216 -313.991882) (xy 280.749756 -314.005722) (xy 280.749756 -314.00623)
			(xy 280.748252 -314.018464) (xy 280.755551 -314.041964) (xy 280.763726 -314.051188) (xy 280.832306 -314.119768)
			(xy 280.855928 -314.127134) (xy 280.864056 -314.12561) (xy 280.894114 -314.120262) (xy 280.955156 -314.120262)
			(xy 280.985214 -314.12561) (xy 280.985976 -314.12561) (xy 280.993596 -314.127134) (xy 281.017218 -314.119768)
			(xy 281.085798 -314.051188) (xy 281.093944 -314.041948) (xy 281.101239 -314.018461) (xy 281.099768 -314.00623)
			(xy 281.099768 -314.005722) (xy 281.0973 -313.991883) (xy 281.094625 -313.963898) (xy 281.094434 -313.949842)
			(xy 281.094877 -313.925848) (xy 281.102379 -313.87845) (xy 281.117204 -313.832809) (xy 281.138988 -313.79005)
			(xy 281.167194 -313.751226) (xy 281.201126 -313.717294) (xy 281.23995 -313.689088) (xy 281.282709 -313.667304)
			(xy 281.32835 -313.652479) (xy 281.375748 -313.644977) (xy 281.399742 -313.644534) (xy 281.431238 -313.646312)
			(xy 281.431746 -313.646312) (xy 281.442369 -313.646835) (xy 281.46258 -313.640284) (xy 281.470862 -313.633612)
			(xy 281.526996 -313.583066) (xy 281.534646 -313.575545) (xy 281.54331 -313.55594) (xy 281.54376 -313.54522)
			(xy 281.54376 -313.474862) (xy 281.543917 -313.459596) (xy 281.546716 -313.429194) (xy 281.549348 -313.414156)
			(xy 281.549602 -313.412632) (xy 281.550364 -313.408568) (xy 281.543252 -313.385962) (xy 281.470354 -313.309762)
			(xy 281.448002 -313.301634) (xy 281.436064 -313.303158) (xy 281.427017 -313.304147) (xy 281.408843 -313.305165)
			(xy 281.399742 -313.30519) (xy 281.374922 -313.304708) (xy 281.325935 -313.296683) (xy 281.278892 -313.28084)
			(xy 281.235032 -313.257594) (xy 281.19551 -313.227558) (xy 281.161369 -313.191524) (xy 281.133507 -313.150441)
			(xy 281.112658 -313.105392) (xy 281.099373 -313.057563) (xy 281.094 -313.008215) (xy 281.096682 -312.958648)
			(xy 281.107348 -312.910168) (xy 281.125717 -312.864052) (xy 281.151304 -312.821515) (xy 281.183436 -312.783679)
			(xy 281.221267 -312.751539) (xy 281.263798 -312.725943) (xy 281.309911 -312.707565) (xy 281.358389 -312.69689)
			(xy 281.407955 -312.694198) (xy 281.457304 -312.699561) (xy 281.505136 -312.712837) (xy 281.550189 -312.733677)
			(xy 281.591277 -312.761531) (xy 281.627318 -312.795666) (xy 281.657361 -312.835181) (xy 281.680616 -312.879037)
			(xy 281.696469 -312.926077) (xy 281.704503 -312.975062) (xy 281.70505 -312.999882) (xy 281.705011 -313.008983)
			(xy 281.703996 -313.027156) (xy 281.703018 -313.036204) (xy 281.701494 -313.048142) (xy 281.709622 -313.070494)
			(xy 281.785822 -313.143392) (xy 281.808428 -313.150504) (xy 281.813254 -313.149742) (xy 281.828475 -313.147017)
			(xy 281.85926 -313.144094) (xy 281.874722 -313.1439) (xy 281.889988 -313.144056) (xy 281.920391 -313.146853)
			(xy 281.935428 -313.149488) (xy 281.936952 -313.149742) (xy 281.941016 -313.150504) (xy 281.963622 -313.143392)
			(xy 282.039822 -313.070494) (xy 282.04795 -313.048142) (xy 282.046426 -313.036204) (xy 282.045438 -313.027157)
			(xy 282.044424 -313.008983) (xy 282.044394 -312.999882) (xy 282.044881 -312.975062) (xy 282.052915 -312.926075)
			(xy 282.068768 -312.879034) (xy 282.092022 -312.835177) (xy 282.122066 -312.79566) (xy 282.158106 -312.761524)
			(xy 282.199194 -312.733668) (xy 282.244248 -312.712826) (xy 282.29208 -312.699548) (xy 282.34143 -312.694183)
			(xy 282.390998 -312.696872) (xy 282.439477 -312.707545) (xy 282.485592 -312.72592) (xy 282.528126 -312.751514)
			(xy 282.565959 -312.783652) (xy 282.598095 -312.821487) (xy 282.623687 -312.864023) (xy 282.64206 -312.910138)
			(xy 282.65273 -312.958618) (xy 282.654967 -312.999882) (xy 282.994112 -312.999882) (xy 282.998072 -312.950828)
			(xy 283.009849 -312.903044) (xy 283.02914 -312.857768) (xy 283.055443 -312.816172) (xy 283.088078 -312.779335)
			(xy 283.126199 -312.74821) (xy 283.16882 -312.723603) (xy 283.214836 -312.706151) (xy 283.263055 -312.696307)
			(xy 283.31223 -312.694326) (xy 283.361085 -312.700258) (xy 283.408356 -312.71395) (xy 283.452818 -312.735048)
			(xy 283.493321 -312.763004) (xy 283.528814 -312.797096) (xy 283.558379 -312.83644) (xy 283.58125 -312.880017)
			(xy 283.596834 -312.926698) (xy 283.604729 -312.975275) (xy 283.605224 -312.999882) (xy 283.944072 -312.999882)
			(xy 283.948032 -312.950828) (xy 283.959809 -312.903044) (xy 283.9791 -312.857768) (xy 284.005403 -312.816172)
			(xy 284.038038 -312.779335) (xy 284.076159 -312.74821) (xy 284.11878 -312.723603) (xy 284.164796 -312.706151)
			(xy 284.213015 -312.696307) (xy 284.26219 -312.694326) (xy 284.311045 -312.700258) (xy 284.358316 -312.71395)
			(xy 284.402778 -312.735048) (xy 284.443281 -312.763004) (xy 284.478774 -312.797096) (xy 284.508339 -312.83644)
			(xy 284.53121 -312.880017) (xy 284.546794 -312.926698) (xy 284.554689 -312.975275) (xy 284.555184 -312.999882)
			(xy 284.894032 -312.999882) (xy 284.897992 -312.950828) (xy 284.909769 -312.903044) (xy 284.92906 -312.857768)
			(xy 284.955363 -312.816172) (xy 284.987998 -312.779335) (xy 285.026119 -312.74821) (xy 285.06874 -312.723603)
			(xy 285.114756 -312.706151) (xy 285.162975 -312.696307) (xy 285.21215 -312.694326) (xy 285.261005 -312.700258)
			(xy 285.308276 -312.71395) (xy 285.352738 -312.735048) (xy 285.393241 -312.763004) (xy 285.428734 -312.797096)
			(xy 285.458299 -312.83644) (xy 285.48117 -312.880017) (xy 285.496754 -312.926698) (xy 285.504649 -312.975275)
			(xy 285.505144 -312.999882) (xy 285.843992 -312.999882) (xy 285.847952 -312.950828) (xy 285.859729 -312.903044)
			(xy 285.87902 -312.857768) (xy 285.905323 -312.816172) (xy 285.937958 -312.779335) (xy 285.976079 -312.74821)
			(xy 286.0187 -312.723603) (xy 286.064716 -312.706151) (xy 286.112935 -312.696307) (xy 286.16211 -312.694326)
			(xy 286.210965 -312.700258) (xy 286.258236 -312.71395) (xy 286.302698 -312.735048) (xy 286.343201 -312.763004)
			(xy 286.378694 -312.797096) (xy 286.408259 -312.83644) (xy 286.43113 -312.880017) (xy 286.446714 -312.926698)
			(xy 286.454609 -312.975275) (xy 286.455104 -312.999882) (xy 286.793952 -312.999882) (xy 286.797912 -312.950828)
			(xy 286.809689 -312.903044) (xy 286.82898 -312.857768) (xy 286.855283 -312.816172) (xy 286.887918 -312.779335)
			(xy 286.926039 -312.74821) (xy 286.96866 -312.723603) (xy 287.014676 -312.706151) (xy 287.062895 -312.696307)
			(xy 287.11207 -312.694326) (xy 287.160925 -312.700258) (xy 287.208196 -312.71395) (xy 287.252658 -312.735048)
			(xy 287.293161 -312.763004) (xy 287.328654 -312.797096) (xy 287.358219 -312.83644) (xy 287.38109 -312.880017)
			(xy 287.396674 -312.926698) (xy 287.404569 -312.975275) (xy 287.405064 -312.999882) (xy 287.743912 -312.999882)
			(xy 287.747872 -312.950828) (xy 287.759649 -312.903044) (xy 287.77894 -312.857768) (xy 287.805243 -312.816172)
			(xy 287.837878 -312.779335) (xy 287.875999 -312.74821) (xy 287.91862 -312.723603) (xy 287.964636 -312.706151)
			(xy 288.012855 -312.696307) (xy 288.06203 -312.694326) (xy 288.110885 -312.700258) (xy 288.158156 -312.71395)
			(xy 288.202618 -312.735048) (xy 288.243121 -312.763004) (xy 288.278614 -312.797096) (xy 288.308179 -312.83644)
			(xy 288.33105 -312.880017) (xy 288.346634 -312.926698) (xy 288.354529 -312.975275) (xy 288.355024 -312.999882)
			(xy 288.354529 -313.024489) (xy 288.346634 -313.073066) (xy 288.33105 -313.119747) (xy 288.308179 -313.163324)
			(xy 288.278614 -313.202668) (xy 288.243121 -313.23676) (xy 288.202618 -313.264716) (xy 288.158156 -313.285814)
			(xy 288.110885 -313.299506) (xy 288.06203 -313.305438) (xy 288.012855 -313.303457) (xy 287.964636 -313.293613)
			(xy 287.91862 -313.276161) (xy 287.875999 -313.251554) (xy 287.837878 -313.220429) (xy 287.805243 -313.183592)
			(xy 287.77894 -313.141996) (xy 287.759649 -313.09672) (xy 287.747872 -313.048936) (xy 287.743912 -312.999882)
			(xy 287.405064 -312.999882) (xy 287.404569 -313.024489) (xy 287.396674 -313.073066) (xy 287.38109 -313.119747)
			(xy 287.358219 -313.163324) (xy 287.328654 -313.202668) (xy 287.293161 -313.23676) (xy 287.252658 -313.264716)
			(xy 287.208196 -313.285814) (xy 287.160925 -313.299506) (xy 287.11207 -313.305438) (xy 287.062895 -313.303457)
			(xy 287.014676 -313.293613) (xy 286.96866 -313.276161) (xy 286.926039 -313.251554) (xy 286.887918 -313.220429)
			(xy 286.855283 -313.183592) (xy 286.82898 -313.141996) (xy 286.809689 -313.09672) (xy 286.797912 -313.048936)
			(xy 286.793952 -312.999882) (xy 286.455104 -312.999882) (xy 286.454609 -313.024489) (xy 286.446714 -313.073066)
			(xy 286.43113 -313.119747) (xy 286.408259 -313.163324) (xy 286.378694 -313.202668) (xy 286.343201 -313.23676)
			(xy 286.302698 -313.264716) (xy 286.258236 -313.285814) (xy 286.210965 -313.299506) (xy 286.16211 -313.305438)
			(xy 286.112935 -313.303457) (xy 286.064716 -313.293613) (xy 286.0187 -313.276161) (xy 285.976079 -313.251554)
			(xy 285.937958 -313.220429) (xy 285.905323 -313.183592) (xy 285.87902 -313.141996) (xy 285.859729 -313.09672)
			(xy 285.847952 -313.048936) (xy 285.843992 -312.999882) (xy 285.505144 -312.999882) (xy 285.504649 -313.024489)
			(xy 285.496754 -313.073066) (xy 285.48117 -313.119747) (xy 285.458299 -313.163324) (xy 285.428734 -313.202668)
			(xy 285.393241 -313.23676) (xy 285.352738 -313.264716) (xy 285.308276 -313.285814) (xy 285.261005 -313.299506)
			(xy 285.21215 -313.305438) (xy 285.162975 -313.303457) (xy 285.114756 -313.293613) (xy 285.06874 -313.276161)
			(xy 285.026119 -313.251554) (xy 284.987998 -313.220429) (xy 284.955363 -313.183592) (xy 284.92906 -313.141996)
			(xy 284.909769 -313.09672) (xy 284.897992 -313.048936) (xy 284.894032 -312.999882) (xy 284.555184 -312.999882)
			(xy 284.554689 -313.024489) (xy 284.546794 -313.073066) (xy 284.53121 -313.119747) (xy 284.508339 -313.163324)
			(xy 284.478774 -313.202668) (xy 284.443281 -313.23676) (xy 284.402778 -313.264716) (xy 284.358316 -313.285814)
			(xy 284.311045 -313.299506) (xy 284.26219 -313.305438) (xy 284.213015 -313.303457) (xy 284.164796 -313.293613)
			(xy 284.11878 -313.276161) (xy 284.076159 -313.251554) (xy 284.038038 -313.220429) (xy 284.005403 -313.183592)
			(xy 283.9791 -313.141996) (xy 283.959809 -313.09672) (xy 283.948032 -313.048936) (xy 283.944072 -312.999882)
			(xy 283.605224 -312.999882) (xy 283.604729 -313.024489) (xy 283.596834 -313.073066) (xy 283.58125 -313.119747)
			(xy 283.558379 -313.163324) (xy 283.528814 -313.202668) (xy 283.493321 -313.23676) (xy 283.452818 -313.264716)
			(xy 283.408356 -313.285814) (xy 283.361085 -313.299506) (xy 283.31223 -313.305438) (xy 283.263055 -313.303457)
			(xy 283.214836 -313.293613) (xy 283.16882 -313.276161) (xy 283.126199 -313.251554) (xy 283.088078 -313.220429)
			(xy 283.055443 -313.183592) (xy 283.02914 -313.141996) (xy 283.009849 -313.09672) (xy 282.998072 -313.048936)
			(xy 282.994112 -312.999882) (xy 282.654967 -312.999882) (xy 282.655417 -313.008186) (xy 282.650049 -313.057536)
			(xy 282.636768 -313.105367) (xy 282.615924 -313.150419) (xy 282.588066 -313.191506) (xy 282.553928 -313.227545)
			(xy 282.514409 -313.257586) (xy 282.470551 -313.280838) (xy 282.423509 -313.296689) (xy 282.374522 -313.30472)
			(xy 282.349702 -313.30519) (xy 282.340601 -313.305151) (xy 282.322428 -313.304134) (xy 282.31338 -313.303158)
			(xy 282.301442 -313.301634) (xy 282.27909 -313.309762) (xy 282.206192 -313.385962) (xy 282.19908 -313.408568)
			(xy 282.199842 -313.413394) (xy 282.20257 -313.428615) (xy 282.205499 -313.4594) (xy 282.205684 -313.474862)
			(xy 282.205684 -313.54522) (xy 282.206246 -313.555913) (xy 282.214902 -313.57547) (xy 282.222448 -313.583066)
			(xy 282.278582 -313.633612) (xy 282.286803 -313.640396) (xy 282.307059 -313.646966) (xy 282.317698 -313.646312)
			(xy 282.317952 -313.646312) (xy 282.349702 -313.644534) (xy 282.374954 -313.645056) (xy 282.424768 -313.653368)
			(xy 282.472535 -313.669767) (xy 282.516952 -313.693804) (xy 282.556806 -313.724824) (xy 282.591011 -313.761981)
			(xy 282.618634 -313.804261) (xy 282.638921 -313.850511) (xy 282.651318 -313.899469) (xy 282.655489 -313.9498)
			(xy 282.655486 -313.949842) (xy 282.994112 -313.949842) (xy 282.998072 -313.900788) (xy 283.009849 -313.853004)
			(xy 283.02914 -313.807728) (xy 283.055443 -313.766132) (xy 283.088078 -313.729295) (xy 283.126199 -313.69817)
			(xy 283.16882 -313.673563) (xy 283.214836 -313.656111) (xy 283.263055 -313.646267) (xy 283.31223 -313.644286)
			(xy 283.361085 -313.650218) (xy 283.408356 -313.66391) (xy 283.452818 -313.685008) (xy 283.493321 -313.712964)
			(xy 283.528814 -313.747056) (xy 283.558379 -313.7864) (xy 283.58125 -313.829977) (xy 283.596834 -313.876658)
			(xy 283.604729 -313.925235) (xy 283.605224 -313.949842) (xy 283.944072 -313.949842) (xy 283.948032 -313.900788)
			(xy 283.959809 -313.853004) (xy 283.9791 -313.807728) (xy 284.005403 -313.766132) (xy 284.038038 -313.729295)
			(xy 284.076159 -313.69817) (xy 284.11878 -313.673563) (xy 284.164796 -313.656111) (xy 284.213015 -313.646267)
			(xy 284.26219 -313.644286) (xy 284.311045 -313.650218) (xy 284.358316 -313.66391) (xy 284.402778 -313.685008)
			(xy 284.443281 -313.712964) (xy 284.478774 -313.747056) (xy 284.508339 -313.7864) (xy 284.53121 -313.829977)
			(xy 284.546794 -313.876658) (xy 284.554689 -313.925235) (xy 284.555184 -313.949842) (xy 284.894032 -313.949842)
			(xy 284.897992 -313.900788) (xy 284.909769 -313.853004) (xy 284.92906 -313.807728) (xy 284.955363 -313.766132)
			(xy 284.987998 -313.729295) (xy 285.026119 -313.69817) (xy 285.06874 -313.673563) (xy 285.114756 -313.656111)
			(xy 285.162975 -313.646267) (xy 285.21215 -313.644286) (xy 285.261005 -313.650218) (xy 285.308276 -313.66391)
			(xy 285.352738 -313.685008) (xy 285.393241 -313.712964) (xy 285.428734 -313.747056) (xy 285.458299 -313.7864)
			(xy 285.48117 -313.829977) (xy 285.496754 -313.876658) (xy 285.504649 -313.925235) (xy 285.505144 -313.949842)
			(xy 285.843992 -313.949842) (xy 285.847952 -313.900788) (xy 285.859729 -313.853004) (xy 285.87902 -313.807728)
			(xy 285.905323 -313.766132) (xy 285.937958 -313.729295) (xy 285.976079 -313.69817) (xy 286.0187 -313.673563)
			(xy 286.064716 -313.656111) (xy 286.112935 -313.646267) (xy 286.16211 -313.644286) (xy 286.210965 -313.650218)
			(xy 286.258236 -313.66391) (xy 286.302698 -313.685008) (xy 286.343201 -313.712964) (xy 286.378694 -313.747056)
			(xy 286.408259 -313.7864) (xy 286.43113 -313.829977) (xy 286.446714 -313.876658) (xy 286.454609 -313.925235)
			(xy 286.455104 -313.949842) (xy 286.793952 -313.949842) (xy 286.797912 -313.900788) (xy 286.809689 -313.853004)
			(xy 286.82898 -313.807728) (xy 286.855283 -313.766132) (xy 286.887918 -313.729295) (xy 286.926039 -313.69817)
			(xy 286.96866 -313.673563) (xy 287.014676 -313.656111) (xy 287.062895 -313.646267) (xy 287.11207 -313.644286)
			(xy 287.160925 -313.650218) (xy 287.208196 -313.66391) (xy 287.252658 -313.685008) (xy 287.293161 -313.712964)
			(xy 287.328654 -313.747056) (xy 287.358219 -313.7864) (xy 287.38109 -313.829977) (xy 287.396674 -313.876658)
			(xy 287.404569 -313.925235) (xy 287.405064 -313.949842) (xy 287.743912 -313.949842) (xy 287.747872 -313.900788)
			(xy 287.759649 -313.853004) (xy 287.77894 -313.807728) (xy 287.805243 -313.766132) (xy 287.837878 -313.729295)
			(xy 287.875999 -313.69817) (xy 287.91862 -313.673563) (xy 287.964636 -313.656111) (xy 288.012855 -313.646267)
			(xy 288.06203 -313.644286) (xy 288.110885 -313.650218) (xy 288.158156 -313.66391) (xy 288.202618 -313.685008)
			(xy 288.243121 -313.712964) (xy 288.278614 -313.747056) (xy 288.308179 -313.7864) (xy 288.33105 -313.829977)
			(xy 288.346634 -313.876658) (xy 288.354529 -313.925235) (xy 288.355024 -313.949842) (xy 288.354529 -313.974449)
			(xy 288.346634 -314.023026) (xy 288.33105 -314.069707) (xy 288.308179 -314.113284) (xy 288.278614 -314.152628)
			(xy 288.243121 -314.18672) (xy 288.202618 -314.214676) (xy 288.158156 -314.235774) (xy 288.110885 -314.249466)
			(xy 288.06203 -314.255398) (xy 288.012855 -314.253417) (xy 287.964636 -314.243573) (xy 287.91862 -314.226121)
			(xy 287.875999 -314.201514) (xy 287.837878 -314.170389) (xy 287.805243 -314.133552) (xy 287.77894 -314.091956)
			(xy 287.759649 -314.04668) (xy 287.747872 -313.998896) (xy 287.743912 -313.949842) (xy 287.405064 -313.949842)
			(xy 287.404569 -313.974449) (xy 287.396674 -314.023026) (xy 287.38109 -314.069707) (xy 287.358219 -314.113284)
			(xy 287.328654 -314.152628) (xy 287.293161 -314.18672) (xy 287.252658 -314.214676) (xy 287.208196 -314.235774)
			(xy 287.160925 -314.249466) (xy 287.11207 -314.255398) (xy 287.062895 -314.253417) (xy 287.014676 -314.243573)
			(xy 286.96866 -314.226121) (xy 286.926039 -314.201514) (xy 286.887918 -314.170389) (xy 286.855283 -314.133552)
			(xy 286.82898 -314.091956) (xy 286.809689 -314.04668) (xy 286.797912 -313.998896) (xy 286.793952 -313.949842)
			(xy 286.455104 -313.949842) (xy 286.454609 -313.974449) (xy 286.446714 -314.023026) (xy 286.43113 -314.069707)
			(xy 286.408259 -314.113284) (xy 286.378694 -314.152628) (xy 286.343201 -314.18672) (xy 286.302698 -314.214676)
			(xy 286.258236 -314.235774) (xy 286.210965 -314.249466) (xy 286.16211 -314.255398) (xy 286.112935 -314.253417)
			(xy 286.064716 -314.243573) (xy 286.0187 -314.226121) (xy 285.976079 -314.201514) (xy 285.937958 -314.170389)
			(xy 285.905323 -314.133552) (xy 285.87902 -314.091956) (xy 285.859729 -314.04668) (xy 285.847952 -313.998896)
			(xy 285.843992 -313.949842) (xy 285.505144 -313.949842) (xy 285.504649 -313.974449) (xy 285.496754 -314.023026)
			(xy 285.48117 -314.069707) (xy 285.458299 -314.113284) (xy 285.428734 -314.152628) (xy 285.393241 -314.18672)
			(xy 285.352738 -314.214676) (xy 285.308276 -314.235774) (xy 285.261005 -314.249466) (xy 285.21215 -314.255398)
			(xy 285.162975 -314.253417) (xy 285.114756 -314.243573) (xy 285.06874 -314.226121) (xy 285.026119 -314.201514)
			(xy 284.987998 -314.170389) (xy 284.955363 -314.133552) (xy 284.92906 -314.091956) (xy 284.909769 -314.04668)
			(xy 284.897992 -313.998896) (xy 284.894032 -313.949842) (xy 284.555184 -313.949842) (xy 284.554689 -313.974449)
			(xy 284.546794 -314.023026) (xy 284.53121 -314.069707) (xy 284.508339 -314.113284) (xy 284.478774 -314.152628)
			(xy 284.443281 -314.18672) (xy 284.402778 -314.214676) (xy 284.358316 -314.235774) (xy 284.311045 -314.249466)
			(xy 284.26219 -314.255398) (xy 284.213015 -314.253417) (xy 284.164796 -314.243573) (xy 284.11878 -314.226121)
			(xy 284.076159 -314.201514) (xy 284.038038 -314.170389) (xy 284.005403 -314.133552) (xy 283.9791 -314.091956)
			(xy 283.959809 -314.04668) (xy 283.948032 -313.998896) (xy 283.944072 -313.949842) (xy 283.605224 -313.949842)
			(xy 283.604729 -313.974449) (xy 283.596834 -314.023026) (xy 283.58125 -314.069707) (xy 283.558379 -314.113284)
			(xy 283.528814 -314.152628) (xy 283.493321 -314.18672) (xy 283.452818 -314.214676) (xy 283.408356 -314.235774)
			(xy 283.361085 -314.249466) (xy 283.31223 -314.255398) (xy 283.263055 -314.253417) (xy 283.214836 -314.243573)
			(xy 283.16882 -314.226121) (xy 283.126199 -314.201514) (xy 283.088078 -314.170389) (xy 283.055443 -314.133552)
			(xy 283.02914 -314.091956) (xy 283.009849 -314.04668) (xy 282.998072 -313.998896) (xy 282.994112 -313.949842)
			(xy 282.655486 -313.949842) (xy 282.651318 -314.000131) (xy 282.638921 -314.049089) (xy 282.618634 -314.095339)
			(xy 282.591011 -314.137619) (xy 282.556806 -314.174776) (xy 282.516952 -314.205796) (xy 282.472535 -314.229833)
			(xy 282.424768 -314.246232) (xy 282.374954 -314.254544) (xy 282.349702 -314.25515) (xy 282.318206 -314.253372)
			(xy 282.317698 -314.253372) (xy 282.307079 -314.252859) (xy 282.286881 -314.259425) (xy 282.278582 -314.266072)
			(xy 282.222448 -314.316618) (xy 282.21479 -314.324136) (xy 282.206112 -314.343741) (xy 282.205684 -314.354464)
			(xy 282.205684 -314.424822) (xy 282.205528 -314.440088) (xy 282.202731 -314.470491) (xy 282.200096 -314.485528)
			(xy 282.199842 -314.487052) (xy 282.19908 -314.491116) (xy 282.206192 -314.513722) (xy 282.27909 -314.589922)
			(xy 282.301442 -314.59805) (xy 282.31338 -314.596526) (xy 282.322427 -314.595538) (xy 282.340601 -314.594523)
			(xy 282.349702 -314.594494) (xy 282.373693 -314.594965) (xy 282.421084 -314.602471) (xy 282.466718 -314.617299)
			(xy 282.50947 -314.639082) (xy 282.548288 -314.667286) (xy 282.582217 -314.701215) (xy 282.61042 -314.740033)
			(xy 282.632203 -314.782786) (xy 282.64703 -314.828419) (xy 282.654536 -314.875811) (xy 282.65501 -314.899802)
			(xy 282.654248 -314.920884) (xy 282.65396 -314.931397) (xy 282.6609 -314.951225) (xy 282.66771 -314.959238)
			(xy 282.71851 -315.01334) (xy 282.725983 -315.020671) (xy 282.745138 -315.029059) (xy 282.755594 -315.029596)
			(xy 282.894024 -315.029596) (xy 282.904473 -315.029036) (xy 282.92362 -315.020648) (xy 282.931108 -315.01334)
			(xy 282.981908 -314.959238) (xy 282.988648 -314.951184) (xy 282.995583 -314.931385) (xy 282.99537 -314.920884)
			(xy 282.994608 -314.899802) (xy 282.99513 -314.874547) (xy 283.003443 -314.824725) (xy 283.019844 -314.776951)
			(xy 283.043885 -314.732528) (xy 283.074909 -314.692668) (xy 283.112071 -314.658458) (xy 283.154357 -314.630832)
			(xy 283.200613 -314.610542) (xy 283.249578 -314.598142) (xy 283.299916 -314.593971) (xy 283.350254 -314.598142)
			(xy 283.399219 -314.610542) (xy 283.445475 -314.630832) (xy 283.487761 -314.658458) (xy 283.524923 -314.692668)
			(xy 283.555947 -314.732528) (xy 283.579988 -314.776951) (xy 283.596389 -314.824725) (xy 283.604702 -314.874547)
			(xy 283.605224 -314.899802) (xy 283.605224 -314.900056) (xy 283.605007 -314.916834) (xy 283.601318 -314.950186)
			(xy 283.597858 -314.966604) (xy 283.597096 -314.969398) (xy 283.596334 -314.976002) (xy 283.595765 -314.985199)
			(xy 283.600429 -315.003012) (xy 283.611074 -315.018037) (xy 283.626333 -315.028344) (xy 283.635196 -315.030866)
			(xy 283.642056 -315.032718) (xy 283.654439 -315.039677) (xy 283.65958 -315.044582) (xy 283.675328 -315.06033)
			(xy 283.680916 -315.065156) (xy 283.684364 -315.067599) (xy 283.691897 -315.071426) (xy 283.695902 -315.072776)
			(xy 283.707332 -315.076332) (xy 283.719778 -315.074046) (xy 283.746198 -315.069829) (xy 283.799696 -315.069609)
			(xy 283.852417 -315.078697) (xy 283.877766 -315.087254) (xy 283.886985 -315.090128) (xy 283.90627 -315.089506)
			(xy 283.923971 -315.081825) (xy 283.931106 -315.075316) (xy 283.961078 -315.04509) (xy 283.967428 -315.016642)
			(xy 283.962348 -315.002672) (xy 283.954072 -314.977894) (xy 283.94513 -314.926428) (xy 283.944568 -314.90031)
			(xy 283.944568 -314.899802) (xy 283.94509 -314.874547) (xy 283.953403 -314.824725) (xy 283.969804 -314.776951)
			(xy 283.993845 -314.732528) (xy 284.024869 -314.692668) (xy 284.062031 -314.658458) (xy 284.104317 -314.630832)
			(xy 284.150573 -314.610542) (xy 284.199538 -314.598142) (xy 284.249876 -314.593971) (xy 284.300214 -314.598142)
			(xy 284.349179 -314.610542) (xy 284.395435 -314.630832) (xy 284.437721 -314.658458) (xy 284.474883 -314.692668)
			(xy 284.505907 -314.732528) (xy 284.529948 -314.776951) (xy 284.546349 -314.824725) (xy 284.554662 -314.874547)
			(xy 284.555184 -314.899802) (xy 284.554784 -314.921411) (xy 284.548648 -314.964191) (xy 284.536556 -315.005683)
			(xy 284.528006 -315.025532) (xy 284.525974 -315.030104) (xy 284.523942 -315.039502) (xy 284.522343 -315.047926)
			(xy 284.524223 -315.06496) (xy 284.531614 -315.080421) (xy 284.537404 -315.086746) (xy 284.546802 -315.096144)
			(xy 284.571694 -315.103256) (xy 284.592776 -315.09843) (xy 284.597348 -315.096398) (xy 284.61208 -315.090302)
			(xy 284.612588 -315.090302) (xy 284.628028 -315.084564) (xy 284.659848 -315.076039) (xy 284.676088 -315.073284)
			(xy 284.676342 -315.073284) (xy 284.680152 -315.072776) (xy 284.691201 -315.071243) (xy 284.713448 -315.06959)
			(xy 284.724602 -315.069474) (xy 284.731206 -315.069474) (xy 284.749195 -315.070108) (xy 284.78485 -315.075068)
			(xy 284.802326 -315.07938) (xy 284.815092 -315.082873) (xy 284.84002 -315.091773) (xy 284.85211 -315.09716)
			(xy 284.856682 -315.099192) (xy 284.865572 -315.101224) (xy 284.873937 -315.102826) (xy 284.890862 -315.101006)
			(xy 284.906255 -315.09374) (xy 284.912562 -315.088016) (xy 284.92196 -315.078618) (xy 284.929326 -315.053472)
			(xy 284.9245 -315.031882) (xy 284.922214 -315.026802) (xy 284.922214 -315.026548) (xy 284.913499 -315.006564)
			(xy 284.901182 -314.964745) (xy 284.894931 -314.921599) (xy 284.894528 -314.899802) (xy 284.89505 -314.874547)
			(xy 284.903363 -314.824725) (xy 284.919764 -314.776951) (xy 284.943805 -314.732528) (xy 284.974829 -314.692668)
			(xy 285.011991 -314.658458) (xy 285.054277 -314.630832) (xy 285.100533 -314.610542) (xy 285.149498 -314.598142)
			(xy 285.199836 -314.593971) (xy 285.250174 -314.598142) (xy 285.299139 -314.610542) (xy 285.345395 -314.630832)
			(xy 285.387681 -314.658458) (xy 285.424843 -314.692668) (xy 285.455867 -314.732528) (xy 285.479908 -314.776951)
			(xy 285.496309 -314.824725) (xy 285.504622 -314.874547) (xy 285.505144 -314.899802) (xy 285.504711 -314.92249)
			(xy 285.497945 -314.967361) (xy 285.484595 -315.01073) (xy 285.475172 -315.031374) (xy 285.471063 -315.041057)
			(xy 285.47025 -315.062053) (xy 285.477912 -315.081618) (xy 285.492768 -315.096479) (xy 285.51233 -315.104147)
			(xy 285.533327 -315.103341) (xy 285.54299 -315.099192) (xy 285.543244 -315.099192) (xy 285.549086 -315.096398)
			(xy 285.570644 -315.087115) (xy 285.615864 -315.074548) (xy 285.662478 -315.069066) (xy 285.70938 -315.070798)
			(xy 285.755462 -315.079705) (xy 285.777686 -315.087254) (xy 285.786909 -315.090144) (xy 285.806211 -315.089548)
			(xy 285.823936 -315.081882) (xy 285.831026 -315.075316) (xy 285.860998 -315.04509) (xy 285.867348 -315.016642)
			(xy 285.862268 -315.002672) (xy 285.853991 -314.977894) (xy 285.845049 -314.926428) (xy 285.844488 -314.90031)
			(xy 285.844488 -314.899802) (xy 285.84501 -314.874547) (xy 285.853323 -314.824725) (xy 285.869724 -314.776951)
			(xy 285.893765 -314.732528) (xy 285.924789 -314.692668) (xy 285.961951 -314.658458) (xy 286.004237 -314.630832)
			(xy 286.050493 -314.610542) (xy 286.099458 -314.598142) (xy 286.149796 -314.593971) (xy 286.200134 -314.598142)
			(xy 286.249099 -314.610542) (xy 286.295355 -314.630832) (xy 286.337641 -314.658458) (xy 286.374803 -314.692668)
			(xy 286.405827 -314.732528) (xy 286.429868 -314.776951) (xy 286.446269 -314.824725) (xy 286.454582 -314.874547)
			(xy 286.455104 -314.899802) (xy 286.454704 -314.921411) (xy 286.448569 -314.964191) (xy 286.436477 -315.005683)
			(xy 286.427926 -315.025532) (xy 286.425894 -315.030104) (xy 286.423862 -315.039502) (xy 286.422262 -315.047926)
			(xy 286.424143 -315.064959) (xy 286.431536 -315.080418) (xy 286.437324 -315.086746) (xy 286.446722 -315.096144)
			(xy 286.471614 -315.103256) (xy 286.492696 -315.09843) (xy 286.497268 -315.096398) (xy 286.512 -315.090302)
			(xy 286.512508 -315.090302) (xy 286.527949 -315.084565) (xy 286.559768 -315.076042) (xy 286.576008 -315.073284)
			(xy 286.576262 -315.073284) (xy 286.580072 -315.072776) (xy 286.591121 -315.071244) (xy 286.613368 -315.069592)
			(xy 286.624522 -315.069474) (xy 286.631126 -315.069474) (xy 286.649115 -315.070109) (xy 286.684769 -315.075071)
			(xy 286.702246 -315.07938) (xy 286.715012 -315.082874) (xy 286.739939 -315.091775) (xy 286.75203 -315.09716)
			(xy 286.756602 -315.099192) (xy 286.765492 -315.101224) (xy 286.773856 -315.102822) (xy 286.790777 -315.100997)
			(xy 286.806165 -315.093728) (xy 286.812482 -315.088016) (xy 286.82188 -315.078618) (xy 286.829246 -315.053472)
			(xy 286.82442 -315.031882) (xy 286.822134 -315.026802) (xy 286.822134 -315.026548) (xy 286.813418 -315.006565)
			(xy 286.801101 -314.964745) (xy 286.79485 -314.921599) (xy 286.794448 -314.899802) (xy 286.79497 -314.874547)
			(xy 286.803283 -314.824725) (xy 286.819684 -314.776951) (xy 286.843725 -314.732528) (xy 286.874749 -314.692668)
			(xy 286.911911 -314.658458) (xy 286.954197 -314.630832) (xy 287.000453 -314.610542) (xy 287.049418 -314.598142)
			(xy 287.099756 -314.593971) (xy 287.150094 -314.598142) (xy 287.199059 -314.610542) (xy 287.245315 -314.630832)
			(xy 287.287601 -314.658458) (xy 287.324763 -314.692668) (xy 287.355787 -314.732528) (xy 287.379828 -314.776951)
			(xy 287.396229 -314.824725) (xy 287.404542 -314.874547) (xy 287.405064 -314.899802) (xy 287.40465 -314.922534)
			(xy 287.397904 -314.967494) (xy 287.384547 -315.010952) (xy 287.375092 -315.031628) (xy 287.371054 -315.041251)
			(xy 287.370294 -315.062084) (xy 287.377882 -315.081501) (xy 287.392566 -315.0963) (xy 287.411924 -315.104038)
			(xy 287.432762 -315.103439) (xy 287.442402 -315.099446) (xy 287.449006 -315.096652) (xy 287.449514 -315.096144)
			(xy 287.473285 -315.086044) (xy 287.523277 -315.073086) (xy 287.574736 -315.068725) (xy 287.626195 -315.073086)
			(xy 287.676187 -315.086044) (xy 287.699958 -315.096144) (xy 287.700466 -315.096652) (xy 287.70707 -315.099446)
			(xy 287.716716 -315.10336) (xy 287.737506 -315.103892) (xy 287.756805 -315.096144) (xy 287.771456 -315.081384)
			(xy 287.779059 -315.062027) (xy 287.778371 -315.041242) (xy 287.77438 -315.031628) (xy 287.764943 -315.010945)
			(xy 287.751601 -314.967486) (xy 287.744833 -314.922532) (xy 287.744408 -314.899802) (xy 287.74493 -314.874547)
			(xy 287.753243 -314.824725) (xy 287.769644 -314.776951) (xy 287.793685 -314.732528) (xy 287.824709 -314.692668)
			(xy 287.861871 -314.658458) (xy 287.904157 -314.630832) (xy 287.950413 -314.610542) (xy 287.999378 -314.598142)
			(xy 288.049716 -314.593971) (xy 288.100054 -314.598142) (xy 288.149019 -314.610542) (xy 288.195275 -314.630832)
			(xy 288.237561 -314.658458) (xy 288.274723 -314.692668) (xy 288.305747 -314.732528) (xy 288.329788 -314.776951)
			(xy 288.346189 -314.824725) (xy 288.354502 -314.874547) (xy 288.355024 -314.899802) (xy 288.354856 -314.912824)
			(xy 288.352566 -314.938768) (xy 288.350452 -314.951618) (xy 288.34969 -314.955936) (xy 288.34969 -314.95619)
			(xy 288.348201 -314.96842) (xy 288.355512 -314.991905) (xy 288.36366 -315.001148) (xy 288.422588 -315.060584)
			(xy 288.431792 -315.068804) (xy 288.455285 -315.07622) (xy 288.467546 -315.074808) (xy 288.478214 -315.07303)
			(xy 288.48177 -315.072522) (xy 288.492445 -315.071103) (xy 288.513928 -315.069578) (xy 288.524696 -315.069474)
			(xy 288.52495 -315.069474) (xy 288.539972 -315.06964) (xy 288.569872 -315.072562) (xy 288.58464 -315.075316)
			(xy 288.585148 -315.075316) (xy 288.59353 -315.07684) (xy 288.61766 -315.069474) (xy 288.685986 -315.001148)
			(xy 288.694146 -314.991912) (xy 288.70147 -314.968419) (xy 288.699956 -314.95619) (xy 288.699956 -314.955682)
			(xy 288.697489 -314.941843) (xy 288.694819 -314.913858) (xy 288.694622 -314.899802) (xy 288.695068 -314.87581)
			(xy 288.702575 -314.828416) (xy 288.717403 -314.78278) (xy 288.739189 -314.740025) (xy 288.767395 -314.701206)
			(xy 288.801327 -314.667277) (xy 288.840149 -314.639075) (xy 288.882906 -314.617293) (xy 288.928543 -314.602468)
			(xy 288.975938 -314.594966) (xy 288.99993 -314.594494) (xy 289.009031 -314.594534) (xy 289.027203 -314.595552)
			(xy 289.036252 -314.596526) (xy 289.04819 -314.59805) (xy 289.070542 -314.589922) (xy 289.14344 -314.513722)
			(xy 289.150552 -314.491116) (xy 289.14979 -314.48629) (xy 289.147063 -314.471069) (xy 289.144135 -314.440284)
			(xy 289.143948 -314.424822) (xy 289.143948 -314.354464) (xy 289.143381 -314.343775) (xy 289.134712 -314.324229)
			(xy 289.127184 -314.316618) (xy 289.07105 -314.266072) (xy 289.06283 -314.259284) (xy 289.042573 -314.252703)
			(xy 289.031934 -314.253372) (xy 289.03168 -314.253372) (xy 288.99993 -314.25515) (xy 288.974667 -314.25466)
			(xy 288.92483 -314.246348) (xy 288.877041 -314.229946) (xy 288.832603 -314.205901) (xy 288.79273 -314.17487)
			(xy 288.758508 -314.137699) (xy 288.730872 -314.095402) (xy 288.710575 -314.049132) (xy 288.698171 -314.000153)
			(xy 288.693998 -313.9498) (xy 288.698171 -313.899447) (xy 288.710575 -313.850468) (xy 288.730872 -313.804198)
			(xy 288.758508 -313.761901) (xy 288.79273 -313.72473) (xy 288.832603 -313.693699) (xy 288.877041 -313.669654)
			(xy 288.92483 -313.653252) (xy 288.974667 -313.64494) (xy 288.99993 -313.644534) (xy 289.031426 -313.646312)
			(xy 289.031934 -313.646312) (xy 289.042551 -313.646818) (xy 289.062739 -313.640241) (xy 289.07105 -313.633612)
			(xy 289.127184 -313.583066) (xy 289.134836 -313.575546) (xy 289.143502 -313.555941) (xy 289.143948 -313.54522)
			(xy 289.143948 -313.474862) (xy 289.144105 -313.459596) (xy 289.146904 -313.429194) (xy 289.149536 -313.414156)
			(xy 289.14979 -313.412632) (xy 289.150552 -313.408568) (xy 289.14344 -313.385962) (xy 289.070542 -313.309762)
			(xy 289.04819 -313.301634) (xy 289.036252 -313.303158) (xy 289.027205 -313.304147) (xy 289.009031 -313.305164)
			(xy 288.99993 -313.30519) (xy 288.97511 -313.304707) (xy 288.926124 -313.296681) (xy 288.879082 -313.280835)
			(xy 288.835223 -313.257588) (xy 288.795703 -313.227551) (xy 288.761563 -313.191517) (xy 288.733702 -313.150433)
			(xy 288.712855 -313.105384) (xy 288.699571 -313.057555) (xy 288.6942 -313.008207) (xy 288.696883 -312.958641)
			(xy 288.70755 -312.910161) (xy 288.72592 -312.864046) (xy 288.751508 -312.82151) (xy 288.783641 -312.783675)
			(xy 288.821471 -312.751536) (xy 288.864003 -312.725941) (xy 288.910115 -312.707564) (xy 288.958593 -312.69689)
			(xy 289.008159 -312.694199) (xy 289.057508 -312.699562) (xy 289.105339 -312.712839) (xy 289.150391 -312.733678)
			(xy 289.191479 -312.761533) (xy 289.227519 -312.795667) (xy 289.257562 -312.835183) (xy 289.280816 -312.879038)
			(xy 289.296669 -312.926078) (xy 289.304703 -312.975062) (xy 289.305238 -312.999882) (xy 289.305199 -313.008983)
			(xy 289.304184 -313.027156) (xy 289.303206 -313.036204) (xy 289.301682 -313.048142) (xy 289.30981 -313.070494)
			(xy 289.38601 -313.143392) (xy 289.408616 -313.150504) (xy 289.413442 -313.149742) (xy 289.428663 -313.147017)
			(xy 289.459448 -313.144092) (xy 289.47491 -313.1439) (xy 289.490176 -313.144055) (xy 289.520579 -313.146852)
			(xy 289.535616 -313.149488) (xy 289.53714 -313.149742) (xy 289.541204 -313.150504) (xy 289.56381 -313.143392)
			(xy 289.64001 -313.070494) (xy 289.648138 -313.048142) (xy 289.646614 -313.036204) (xy 289.645626 -313.027157)
			(xy 289.644612 -313.008983) (xy 289.644582 -312.999882) (xy 289.645069 -312.975061) (xy 289.653104 -312.926072)
			(xy 289.668957 -312.879028) (xy 289.692213 -312.835169) (xy 289.722258 -312.795651) (xy 289.7583 -312.761513)
			(xy 289.799391 -312.733656) (xy 289.844447 -312.712814) (xy 289.892281 -312.699536) (xy 289.941633 -312.694171)
			(xy 289.991204 -312.696861) (xy 290.039685 -312.707535) (xy 290.085802 -312.725912) (xy 290.128338 -312.751508)
			(xy 290.166172 -312.783648) (xy 290.198309 -312.821485) (xy 290.2239 -312.864023) (xy 290.242273 -312.910141)
			(xy 290.252943 -312.958624) (xy 290.255179 -312.999882) (xy 290.594046 -312.999882) (xy 290.598006 -312.950828)
			(xy 290.609783 -312.903044) (xy 290.629074 -312.857768) (xy 290.655377 -312.816172) (xy 290.688012 -312.779335)
			(xy 290.726133 -312.74821) (xy 290.768754 -312.723603) (xy 290.81477 -312.706151) (xy 290.862989 -312.696307)
			(xy 290.912164 -312.694326) (xy 290.961019 -312.700258) (xy 291.00829 -312.71395) (xy 291.052752 -312.735048)
			(xy 291.093255 -312.763004) (xy 291.128748 -312.797096) (xy 291.158313 -312.83644) (xy 291.181184 -312.880017)
			(xy 291.196768 -312.926698) (xy 291.204663 -312.975275) (xy 291.205158 -312.999882) (xy 291.204663 -313.024489)
			(xy 291.196768 -313.073066) (xy 291.181184 -313.119747) (xy 291.158313 -313.163324) (xy 291.128748 -313.202668)
			(xy 291.093255 -313.23676) (xy 291.052752 -313.264716) (xy 291.00829 -313.285814) (xy 290.961019 -313.299506)
			(xy 290.912164 -313.305438) (xy 290.862989 -313.303457) (xy 290.81477 -313.293613) (xy 290.768754 -313.276161)
			(xy 290.726133 -313.251554) (xy 290.688012 -313.220429) (xy 290.655377 -313.183592) (xy 290.629074 -313.141996)
			(xy 290.609783 -313.09672) (xy 290.598006 -313.048936) (xy 290.594046 -312.999882) (xy 290.255179 -312.999882)
			(xy 290.255629 -313.008195) (xy 290.250259 -313.057546) (xy 290.236976 -313.105379) (xy 290.21613 -313.150433)
			(xy 290.188269 -313.191521) (xy 290.154128 -313.227561) (xy 290.114607 -313.257602) (xy 290.070746 -313.280854)
			(xy 290.023701 -313.296703) (xy 289.974712 -313.304733) (xy 289.94989 -313.30519) (xy 289.940789 -313.30515)
			(xy 289.922616 -313.304133) (xy 289.913568 -313.303158) (xy 289.90163 -313.301634) (xy 289.879278 -313.309762)
			(xy 289.80638 -313.385962) (xy 289.799268 -313.408568) (xy 289.80003 -313.413394) (xy 289.802758 -313.428615)
			(xy 289.805687 -313.4594) (xy 289.805872 -313.474862) (xy 289.805872 -313.54522) (xy 289.806434 -313.555913)
			(xy 289.815088 -313.575472) (xy 289.822636 -313.583066) (xy 289.87877 -313.633612) (xy 289.88699 -313.640398)
			(xy 289.907247 -313.646974) (xy 289.917886 -313.646312) (xy 289.91814 -313.646312) (xy 289.94989 -313.644534)
			(xy 289.973882 -313.644979) (xy 290.021277 -313.652485) (xy 290.066913 -313.667313) (xy 290.109667 -313.689099)
			(xy 290.148487 -313.717305) (xy 290.182416 -313.751237) (xy 290.210618 -313.79006) (xy 290.232399 -313.832817)
			(xy 290.247222 -313.878454) (xy 290.254723 -313.925849) (xy 290.255198 -313.949842) (xy 290.254992 -313.963897)
			(xy 290.252324 -313.991882) (xy 290.249864 -314.005722) (xy 290.249864 -314.00623) (xy 290.24836 -314.018464)
			(xy 290.25566 -314.041963) (xy 290.263834 -314.051188) (xy 290.33216 -314.119768) (xy 290.355782 -314.127134)
			(xy 290.364164 -314.12561) (xy 290.379178 -314.122753) (xy 290.409588 -314.119697) (xy 290.42487 -314.119514)
			(xy 290.427918 -314.119514) (xy 290.440627 -314.119787) (xy 290.465934 -314.122201) (xy 290.478464 -314.12434)
			(xy 290.478972 -314.12434) (xy 290.48837 -314.126118) (xy 290.49345 -314.127134) (xy 290.51758 -314.119768)
			(xy 290.594796 -314.042552) (xy 290.602162 -314.01893) (xy 290.600384 -314.008516) (xy 290.60013 -314.008008)
			(xy 290.599876 -314.005468) (xy 290.597424 -313.991691) (xy 290.594756 -313.963834) (xy 290.594542 -313.949842)
			(xy 290.595024 -313.925025) (xy 290.603047 -313.876045) (xy 290.618889 -313.829007) (xy 290.642131 -313.785152)
			(xy 290.672162 -313.745635) (xy 290.708191 -313.711498) (xy 290.749268 -313.683638) (xy 290.794311 -313.662791)
			(xy 290.842133 -313.649506) (xy 290.891475 -313.644132) (xy 290.941036 -313.646812) (xy 290.98951 -313.657475)
			(xy 291.035621 -313.675839) (xy 291.078154 -313.701421) (xy 291.115987 -313.733548) (xy 291.148125 -313.771371)
			(xy 291.17372 -313.813896) (xy 291.192098 -313.860002) (xy 291.202775 -313.908473) (xy 291.20547 -313.958033)
			(xy 291.200112 -314.007376) (xy 291.186841 -314.055202) (xy 291.166007 -314.100252) (xy 291.13816 -314.141337)
			(xy 291.104033 -314.177376) (xy 291.064525 -314.207419) (xy 291.020677 -314.230675) (xy 290.973645 -314.24653)
			(xy 290.924667 -314.254568) (xy 290.89985 -314.25515) (xy 290.877161 -314.25472) (xy 290.832287 -314.247963)
			(xy 290.788914 -314.234619) (xy 290.768278 -314.225178) (xy 290.758601 -314.22108) (xy 290.737625 -314.220281)
			(xy 290.718082 -314.227944) (xy 290.70324 -314.242789) (xy 290.695579 -314.262333) (xy 290.696382 -314.28331)
			(xy 290.70046 -314.292996) (xy 290.704655 -314.301925) (xy 290.712028 -314.320227) (xy 290.715192 -314.329572)
			(xy 290.717732 -314.3377) (xy 290.71951 -314.34405) (xy 290.723738 -314.360141) (xy 290.729087 -314.39298)
			(xy 290.730178 -314.409582) (xy 290.730178 -314.41009) (xy 290.730686 -314.418218) (xy 290.735512 -314.431172)
			(xy 290.747196 -314.44819) (xy 290.748212 -314.449714) (xy 290.757102 -314.462414) (xy 290.764976 -314.470034)
			(xy 290.769294 -314.47359) (xy 290.777676 -314.476892) (xy 290.822085 -314.494972) (xy 290.907414 -314.538719)
			(xy 290.987975 -314.590725) (xy 291.025834 -314.620148) (xy 291.034978 -314.62599) (xy 291.05715 -314.637491)
			(xy 291.097739 -314.666594) (xy 291.133051 -314.701914) (xy 291.162145 -314.74251) (xy 291.173662 -314.764674)
			(xy 291.179504 -314.773818) (xy 291.193314 -314.791377) (xy 291.219488 -314.827586) (xy 291.231828 -314.846208)
			(xy 291.255527 -314.883332) (xy 291.29683 -314.961129) (xy 291.330873 -315.042365) (xy 291.357376 -315.126365)
			(xy 291.36721 -315.169296) (xy 291.367464 -315.170058) (xy 291.367718 -315.171074) (xy 291.369496 -315.177678)
			(xy 291.372008 -315.183831) (xy 291.37973 -315.194642) (xy 291.384736 -315.199014) (xy 291.39134 -315.204348)
			(xy 291.399214 -315.207142) (xy 291.403392 -315.208554) (xy 291.412077 -315.210092) (xy 291.416486 -315.21019)
		)
		(stroke
			(width 0)
			(type solid)
		)
		(fill yes)
		(layer "In5.Cu")
		(net "P1V8_VDDA_PEX2")
	)
	(gr_poly
		(pts
			(xy 124.0282 -330.059538) (xy 124.028708 -330.059538) (xy 124.043186 -330.060046) (xy 147.430236 -330.060046)
			(xy 147.437647 -330.059786) (xy 147.45184 -330.055517) (xy 147.458176 -330.051664) (xy 162.414204 -320.131186)
			(xy 162.422209 -320.125356) (xy 162.433389 -320.109034) (xy 162.437574 -320.089698) (xy 162.436302 -320.079878)
			(xy 162.419538 -319.98793) (xy 162.417318 -319.978314) (xy 162.406738 -319.961675) (xy 162.390678 -319.950235)
			(xy 162.381184 -319.947544) (xy 162.356312 -319.94125) (xy 162.308968 -319.921496) (xy 162.265591 -319.894107)
			(xy 162.227403 -319.859853) (xy 162.195476 -319.819698) (xy 162.17071 -319.774772) (xy 162.153801 -319.726338)
			(xy 162.145226 -319.67576) (xy 162.14471 -319.65011) (xy 162.145155 -319.626117) (xy 162.152661 -319.578721)
			(xy 162.167489 -319.533083) (xy 162.189274 -319.490327) (xy 162.21748 -319.451506) (xy 162.251412 -319.417575)
			(xy 162.290234 -319.38937) (xy 162.332991 -319.367586) (xy 162.378629 -319.352759) (xy 162.426025 -319.345255)
			(xy 162.450018 -319.344802) (xy 162.459059 -319.344908) (xy 162.477104 -319.346053) (xy 162.486086 -319.347088)
			(xy 162.486594 -319.347088) (xy 162.498278 -319.348358) (xy 162.52063 -319.34023) (xy 162.593528 -319.26403)
			(xy 162.60064 -319.241424) (xy 162.59937 -319.233804) (xy 162.59688 -319.219199) (xy 162.594209 -319.189691)
			(xy 162.594036 -319.174876) (xy 162.594215 -319.160062) (xy 162.596889 -319.130554) (xy 162.59937 -319.115948)
			(xy 162.59937 -319.115186) (xy 162.60064 -319.108582) (xy 162.593528 -319.085976) (xy 162.528758 -319.018412)
			(xy 162.520265 -319.010341) (xy 162.498294 -319.002279) (xy 162.486594 -319.002918) (xy 162.48634 -319.002918)
			(xy 162.477296 -319.003967) (xy 162.459122 -319.005112) (xy 162.450018 -319.005204) (xy 162.42476 -319.004713)
			(xy 162.374932 -318.996401) (xy 162.327151 -318.98) (xy 162.282722 -318.955959) (xy 162.242856 -318.924932)
			(xy 162.208641 -318.887767) (xy 162.18101 -318.845476) (xy 162.160717 -318.799215) (xy 162.148316 -318.750244)
			(xy 162.144144 -318.6999) (xy 162.148316 -318.649556) (xy 162.160717 -318.600585) (xy 162.18101 -318.554324)
			(xy 162.208641 -318.512033) (xy 162.242856 -318.474868) (xy 162.282722 -318.443841) (xy 162.327151 -318.4198)
			(xy 162.374932 -318.403399) (xy 162.42476 -318.395087) (xy 162.450018 -318.394588) (xy 162.459059 -318.394694)
			(xy 162.477104 -318.395839) (xy 162.486086 -318.396874) (xy 162.486594 -318.396874) (xy 162.498278 -318.398144)
			(xy 162.52063 -318.390016) (xy 162.593528 -318.313816) (xy 162.60064 -318.29121) (xy 162.59937 -318.284098)
			(xy 162.596868 -318.269431) (xy 162.594198 -318.239794) (xy 162.594036 -318.224916) (xy 162.594213 -318.210102)
			(xy 162.596883 -318.180593) (xy 162.59937 -318.165988) (xy 162.59937 -318.165226) (xy 162.60064 -318.158622)
			(xy 162.593528 -318.136016) (xy 162.528758 -318.068452) (xy 162.520267 -318.060376) (xy 162.498295 -318.052307)
			(xy 162.486594 -318.052958) (xy 162.48634 -318.052958) (xy 162.477296 -318.054007) (xy 162.459122 -318.055152)
			(xy 162.450018 -318.055244) (xy 162.424756 -318.054753) (xy 162.374922 -318.046439) (xy 162.327135 -318.030037)
			(xy 162.2827 -318.005992) (xy 162.242829 -317.974961) (xy 162.20861 -317.937791) (xy 162.180975 -317.895495)
			(xy 162.16068 -317.849228) (xy 162.148276 -317.800251) (xy 162.144104 -317.7499) (xy 162.148276 -317.699549)
			(xy 162.16068 -317.650572) (xy 162.180975 -317.604305) (xy 162.20861 -317.562009) (xy 162.242829 -317.524839)
			(xy 162.2827 -317.493808) (xy 162.327135 -317.469763) (xy 162.374922 -317.453361) (xy 162.424756 -317.445047)
			(xy 162.450018 -317.444628) (xy 162.458992 -317.444668) (xy 162.476911 -317.445683) (xy 162.485832 -317.44666)
			(xy 162.497516 -317.448184) (xy 162.520376 -317.440056) (xy 162.592766 -317.363856) (xy 162.599624 -317.34125)
			(xy 162.598354 -317.332868) (xy 162.595997 -317.318634) (xy 162.593456 -317.289891) (xy 162.593274 -317.275464)
			(xy 162.593274 -317.204598) (xy 162.592714 -317.193905) (xy 162.584058 -317.174346) (xy 162.57651 -317.166752)
			(xy 162.52063 -317.11646) (xy 162.51237 -317.109723) (xy 162.492161 -317.10302) (xy 162.481514 -317.103506)
			(xy 162.48126 -317.103506) (xy 162.450018 -317.10503) (xy 162.424757 -317.104539) (xy 162.374925 -317.096226)
			(xy 162.327141 -317.079824) (xy 162.282708 -317.05578) (xy 162.242839 -317.024751) (xy 162.208621 -316.987583)
			(xy 162.180988 -316.945289) (xy 162.160693 -316.899023) (xy 162.14829 -316.850048) (xy 162.144118 -316.7997)
			(xy 162.14829 -316.749352) (xy 162.160693 -316.700377) (xy 162.180988 -316.654111) (xy 162.208621 -316.611817)
			(xy 162.242839 -316.574649) (xy 162.282708 -316.54362) (xy 162.327141 -316.519576) (xy 162.374925 -316.503174)
			(xy 162.424757 -316.494861) (xy 162.450018 -316.494414) (xy 162.48126 -316.495938) (xy 162.481514 -316.495938)
			(xy 162.492182 -316.496557) (xy 162.512456 -316.489864) (xy 162.52063 -316.482984) (xy 162.57651 -316.432692)
			(xy 162.584163 -316.425172) (xy 162.592834 -316.405568) (xy 162.593274 -316.394846) (xy 162.593274 -316.324742)
			(xy 162.593421 -316.309413) (xy 162.596218 -316.278882) (xy 162.598862 -316.263782) (xy 162.599116 -316.262258)
			(xy 162.599878 -316.258448) (xy 162.592766 -316.235842) (xy 162.528504 -316.168532) (xy 162.519865 -316.160319)
			(xy 162.497472 -316.152238) (xy 162.485578 -316.153038) (xy 162.476719 -316.153993) (xy 162.458928 -316.155008)
			(xy 162.450018 -316.15507) (xy 162.424762 -316.154579) (xy 162.37494 -316.146268) (xy 162.327165 -316.129869)
			(xy 162.282741 -316.10583) (xy 162.242879 -316.074807) (xy 162.208668 -316.037646) (xy 162.18104 -315.99536)
			(xy 162.16075 -315.949104) (xy 162.148349 -315.900139) (xy 162.144178 -315.8498) (xy 162.148349 -315.799461)
			(xy 162.16075 -315.750496) (xy 162.18104 -315.70424) (xy 162.208668 -315.661954) (xy 162.242879 -315.624793)
			(xy 162.282741 -315.59377) (xy 162.327165 -315.569731) (xy 162.37494 -315.553332) (xy 162.424762 -315.545021)
			(xy 162.450018 -315.544454) (xy 162.459059 -315.54456) (xy 162.477104 -315.545705) (xy 162.486086 -315.54674)
			(xy 162.486594 -315.54674) (xy 162.498278 -315.54801) (xy 162.52063 -315.539882) (xy 162.593528 -315.463682)
			(xy 162.60064 -315.441076) (xy 162.59937 -315.433964) (xy 162.596869 -315.419297) (xy 162.594202 -315.38966)
			(xy 162.594036 -315.374782) (xy 162.594232 -315.359771) (xy 162.597026 -315.329878) (xy 162.599624 -315.315092)
			(xy 162.599624 -315.314076) (xy 162.60064 -315.308488) (xy 162.593528 -315.285882) (xy 162.52063 -315.209682)
			(xy 162.498278 -315.201554) (xy 162.48634 -315.203078) (xy 162.477293 -315.204067) (xy 162.459119 -315.205083)
			(xy 162.450018 -315.20511) (xy 162.425197 -315.204626) (xy 162.376207 -315.196597) (xy 162.329162 -315.180749)
			(xy 162.285301 -315.157498) (xy 162.24578 -315.127457) (xy 162.211639 -315.091419) (xy 162.183778 -315.050331)
			(xy 162.162931 -315.005277) (xy 162.149649 -314.957445) (xy 162.144279 -314.908093) (xy 162.146965 -314.858523)
			(xy 162.157635 -314.810041) (xy 162.176009 -314.763923) (xy 162.201601 -314.721386) (xy 162.233738 -314.683549)
			(xy 162.271573 -314.65141) (xy 162.314109 -314.625816) (xy 162.360225 -314.60744) (xy 162.408707 -314.596767)
			(xy 162.458277 -314.594079) (xy 162.507629 -314.599446) (xy 162.555462 -314.612726) (xy 162.600517 -314.63357)
			(xy 162.641606 -314.661429) (xy 162.677647 -314.695568) (xy 162.707689 -314.735088) (xy 162.730942 -314.778948)
			(xy 162.746793 -314.825992) (xy 162.754824 -314.874981) (xy 162.755326 -314.899802) (xy 162.755221 -314.908843)
			(xy 162.754076 -314.926888) (xy 162.75304 -314.93587) (xy 162.75304 -314.936632) (xy 162.752337 -314.948302)
			(xy 162.760286 -314.970262) (xy 162.76828 -314.978796) (xy 162.835844 -315.043566) (xy 162.85845 -315.050678)
			(xy 162.863276 -315.049916) (xy 162.878497 -315.047187) (xy 162.909282 -315.04426) (xy 162.924744 -315.044074)
			(xy 162.937499 -315.044221) (xy 162.962928 -315.046257) (xy 162.975544 -315.048138) (xy 162.976306 -315.048138)
			(xy 162.988127 -315.04925) (xy 163.010655 -315.041847) (xy 163.019486 -315.033914) (xy 163.089844 -314.963556)
			(xy 163.097464 -314.941966) (xy 163.096194 -314.93079) (xy 163.09467 -314.899802) (xy 163.09514 -314.87581)
			(xy 163.102646 -314.828417) (xy 163.117473 -314.782781) (xy 163.139256 -314.740027) (xy 163.167459 -314.701206)
			(xy 163.201388 -314.667275) (xy 163.240206 -314.639069) (xy 163.282959 -314.617282) (xy 163.328593 -314.602452)
			(xy 163.375986 -314.594942) (xy 163.399978 -314.594494) (xy 163.430966 -314.596018) (xy 163.442142 -314.597288)
			(xy 163.463732 -314.589668) (xy 163.478718 -314.574682) (xy 163.481544 -314.571894) (xy 163.48793 -314.56718)
			(xy 163.491418 -314.565284) (xy 163.494466 -314.56376) (xy 163.500241 -314.56001) (xy 163.509644 -314.549956)
			(xy 163.513008 -314.543948) (xy 163.524946 -314.521596) (xy 163.54044 -314.492132) (xy 163.542143 -314.488879)
			(xy 163.544694 -314.481994) (xy 163.54552 -314.478416) (xy 163.54679 -314.471558) (xy 163.545774 -314.463176)
			(xy 163.544713 -314.453623) (xy 163.543568 -314.434434) (xy 163.543488 -314.424822) (xy 163.543488 -314.354464)
			(xy 163.542922 -314.343774) (xy 163.534258 -314.324224) (xy 163.526724 -314.316618) (xy 163.462716 -314.25896)
			(xy 163.441888 -314.252356) (xy 163.431474 -314.253626) (xy 163.399978 -314.25515) (xy 163.37472 -314.254627)
			(xy 163.324895 -314.246309) (xy 163.277117 -314.229904) (xy 163.232692 -314.205859) (xy 163.192829 -314.17483)
			(xy 163.158618 -314.137664) (xy 163.130989 -314.095373) (xy 163.110699 -314.049112) (xy 163.098298 -314.000143)
			(xy 163.094127 -313.9498) (xy 163.098298 -313.899457) (xy 163.110699 -313.850488) (xy 163.130989 -313.804227)
			(xy 163.158618 -313.761936) (xy 163.192829 -313.72477) (xy 163.232692 -313.693741) (xy 163.277117 -313.669696)
			(xy 163.324895 -313.653291) (xy 163.37472 -313.644973) (xy 163.399978 -313.644534) (xy 163.431474 -313.646058)
			(xy 163.441888 -313.647328) (xy 163.462716 -313.640724) (xy 163.526724 -313.583066) (xy 163.534383 -313.575549)
			(xy 163.54306 -313.555943) (xy 163.543488 -313.54522) (xy 163.543488 -313.474862) (xy 163.543678 -313.459788)
			(xy 163.546481 -313.429769) (xy 163.549076 -313.414918) (xy 163.549076 -313.413902) (xy 163.550092 -313.408568)
			(xy 163.54298 -313.385962) (xy 163.470082 -313.309762) (xy 163.44773 -313.301634) (xy 163.435792 -313.303158)
			(xy 163.42687 -313.304119) (xy 163.408952 -313.305134) (xy 163.399978 -313.30519) (xy 163.375159 -313.304702)
			(xy 163.326176 -313.296669) (xy 163.279138 -313.280816) (xy 163.235284 -313.257563) (xy 163.19577 -313.227522)
			(xy 163.161636 -313.191484) (xy 163.133782 -313.150398) (xy 163.112942 -313.105348) (xy 163.099664 -313.057519)
			(xy 163.094299 -313.008172) (xy 163.096988 -312.958608) (xy 163.107659 -312.910131) (xy 163.126033 -312.864019)
			(xy 163.151624 -312.821488) (xy 163.183759 -312.783656) (xy 163.221591 -312.751522) (xy 163.264123 -312.725931)
			(xy 163.310235 -312.707558) (xy 163.358712 -312.696887) (xy 163.408276 -312.694199) (xy 163.457623 -312.699565)
			(xy 163.505451 -312.712843) (xy 163.550502 -312.733684) (xy 163.591587 -312.761539) (xy 163.627625 -312.795673)
			(xy 163.657665 -312.835188) (xy 163.680918 -312.879042) (xy 163.69677 -312.92608) (xy 163.704803 -312.975063)
			(xy 163.705286 -312.999882) (xy 163.705239 -313.008919) (xy 163.704222 -313.026965) (xy 163.703254 -313.03595)
			(xy 163.703254 -313.036204) (xy 163.702447 -313.048003) (xy 163.710411 -313.07024) (xy 163.718494 -313.078876)
			(xy 163.785804 -313.143138) (xy 163.808664 -313.15025) (xy 163.820602 -313.148218) (xy 163.833969 -313.14617)
			(xy 163.860927 -313.144007) (xy 163.87445 -313.1439) (xy 163.888878 -313.144062) (xy 163.917622 -313.146604)
			(xy 163.931854 -313.14898) (xy 163.932616 -313.14898) (xy 163.941252 -313.150504) (xy 163.963858 -313.143392)
			(xy 164.031422 -313.078622) (xy 164.039501 -313.07013) (xy 164.047584 -313.048158) (xy 164.046916 -313.036458)
			(xy 164.046916 -313.036204) (xy 164.045868 -313.02716) (xy 164.044726 -313.008986) (xy 164.04463 -312.999882)
			(xy 164.045117 -312.975065) (xy 164.05315 -312.926086) (xy 164.069 -312.879051) (xy 164.09225 -312.8352)
			(xy 164.122289 -312.795688) (xy 164.158323 -312.761556) (xy 164.199405 -312.733703) (xy 164.244452 -312.712863)
			(xy 164.292276 -312.699585) (xy 164.341619 -312.694219) (xy 164.39118 -312.696906) (xy 164.439653 -312.707575)
			(xy 164.485762 -312.725946) (xy 164.528291 -312.751534) (xy 164.566121 -312.783665) (xy 164.598255 -312.821492)
			(xy 164.623845 -312.86402) (xy 164.642219 -312.910128) (xy 164.652891 -312.9586) (xy 164.655581 -313.008161)
			(xy 164.650218 -313.057504) (xy 164.636944 -313.105329) (xy 164.616107 -313.150377) (xy 164.588256 -313.191461)
			(xy 164.554127 -313.227498) (xy 164.514617 -313.257539) (xy 164.470767 -313.280792) (xy 164.423734 -313.296646)
			(xy 164.374755 -313.304681) (xy 164.349938 -313.30519) (xy 164.34077 -313.305099) (xy 164.32247 -313.303957)
			(xy 164.313362 -313.302904) (xy 164.301424 -313.30138) (xy 164.279072 -313.309508) (xy 164.206174 -313.385708)
			(xy 164.199062 -313.408568) (xy 164.201094 -313.420506) (xy 164.202862 -313.431733) (xy 164.205025 -313.454359)
			(xy 164.205412 -313.465718) (xy 164.205412 -313.54522) (xy 164.205975 -313.555912) (xy 164.214634 -313.575467)
			(xy 164.222176 -313.583066) (xy 164.286692 -313.640724) (xy 164.307012 -313.647328) (xy 164.31768 -313.646312)
			(xy 164.349938 -313.644534) (xy 164.373928 -313.644983) (xy 164.421316 -313.652495) (xy 164.466946 -313.667327)
			(xy 164.509694 -313.689115) (xy 164.548507 -313.717322) (xy 164.58243 -313.751254) (xy 164.610627 -313.790074)
			(xy 164.632403 -313.832828) (xy 164.647224 -313.878461) (xy 164.654723 -313.925852) (xy 164.655246 -313.949842)
			(xy 164.65471 -313.976025) (xy 164.645777 -314.027624) (xy 164.637466 -314.052458) (xy 164.63466 -314.061611)
			(xy 164.63533 -314.080731) (xy 164.642942 -314.098283) (xy 164.656442 -314.111838) (xy 164.673962 -314.119522)
			(xy 164.693079 -314.120272) (xy 164.702236 -314.117482) (xy 164.712999 -314.113323) (xy 164.734989 -314.10633)
			(xy 164.746178 -314.103512) (xy 164.76896 -314.098385) (xy 164.815433 -314.093832) (xy 164.862086 -314.095842)
			(xy 164.885116 -314.099702) (xy 164.886132 -314.099702) (xy 164.891212 -314.100718) (xy 164.913818 -314.093606)
			(xy 164.981382 -314.02909) (xy 164.989591 -314.020449) (xy 164.997663 -313.998057) (xy 164.996876 -313.986164)
			(xy 164.995826 -313.97712) (xy 164.99468 -313.958946) (xy 164.99459 -313.949842) (xy 164.995033 -313.925847)
			(xy 165.002535 -313.878446) (xy 165.017359 -313.832803) (xy 165.039142 -313.79004) (xy 165.067347 -313.751213)
			(xy 165.101279 -313.717276) (xy 165.140103 -313.689065) (xy 165.182862 -313.667276) (xy 165.228503 -313.652445)
			(xy 165.275903 -313.644937) (xy 165.299898 -313.644534) (xy 165.331648 -313.646058) (xy 165.342062 -313.647328)
			(xy 165.36289 -313.64047) (xy 165.426898 -313.582812) (xy 165.434555 -313.575293) (xy 165.443237 -313.555689)
			(xy 165.443662 -313.544966) (xy 165.443662 -313.473846) (xy 165.443916 -313.47156) (xy 165.443916 -313.468004)
			(xy 165.446202 -313.433968) (xy 165.446456 -313.43219) (xy 165.44671 -313.431174) (xy 165.448234 -313.420506)
			(xy 165.450266 -313.408822) (xy 165.443154 -313.385962) (xy 165.378892 -313.318398) (xy 165.370254 -313.310325)
			(xy 165.348016 -313.302375) (xy 165.33622 -313.303158) (xy 165.335966 -313.303158) (xy 165.326982 -313.304142)
			(xy 165.308936 -313.305161) (xy 165.299898 -313.30519) (xy 165.275079 -313.304704) (xy 165.226095 -313.296673)
			(xy 165.179055 -313.280824) (xy 165.135199 -313.257573) (xy 165.095683 -313.227533) (xy 165.061546 -313.191496)
			(xy 165.03369 -313.150412) (xy 165.012847 -313.105361) (xy 164.999567 -313.057533) (xy 164.994199 -313.008186)
			(xy 164.996886 -312.95862) (xy 165.007556 -312.910143) (xy 165.025928 -312.86403) (xy 165.051518 -312.821496)
			(xy 165.083652 -312.783663) (xy 165.121483 -312.751527) (xy 165.164015 -312.725935) (xy 165.210127 -312.70756)
			(xy 165.258605 -312.696888) (xy 165.30817 -312.694199) (xy 165.357517 -312.699564) (xy 165.405346 -312.712841)
			(xy 165.450398 -312.733682) (xy 165.491484 -312.761536) (xy 165.527522 -312.795671) (xy 165.557564 -312.835186)
			(xy 165.580817 -312.87904) (xy 165.596669 -312.926079) (xy 165.604703 -312.975063) (xy 165.605206 -312.999882)
			(xy 165.605167 -313.008983) (xy 165.604152 -313.027156) (xy 165.603174 -313.036204) (xy 165.60165 -313.048142)
			(xy 165.609778 -313.070494) (xy 165.685724 -313.143392) (xy 165.70833 -313.150504) (xy 165.713156 -313.149742)
			(xy 165.728376 -313.147012) (xy 165.759162 -313.144083) (xy 165.774624 -313.1439) (xy 165.789184 -313.144116)
			(xy 165.818181 -313.14679) (xy 165.832536 -313.149234) (xy 165.833552 -313.149234) (xy 165.841172 -313.150504)
			(xy 165.863778 -313.143392) (xy 165.931342 -313.078622) (xy 165.939431 -313.070135) (xy 165.947528 -313.04816)
			(xy 165.946836 -313.036458) (xy 165.946836 -313.036204) (xy 165.945788 -313.02716) (xy 165.944646 -313.008986)
			(xy 165.94455 -312.999882) (xy 165.945038 -312.975057) (xy 165.953073 -312.926063) (xy 165.968929 -312.879013)
			(xy 165.992188 -312.835149) (xy 166.022237 -312.795626) (xy 166.058285 -312.761484) (xy 166.099381 -312.733625)
			(xy 166.144444 -312.712781) (xy 166.192284 -312.699502) (xy 166.241643 -312.694138) (xy 166.291219 -312.696831)
			(xy 166.339707 -312.707508) (xy 166.385828 -312.725889) (xy 166.428368 -312.75149) (xy 166.466206 -312.783636)
			(xy 166.498345 -312.82148) (xy 166.523937 -312.864025) (xy 166.54231 -312.91015) (xy 166.552977 -312.95864)
			(xy 166.55566 -313.008217) (xy 166.550286 -313.057575) (xy 166.536998 -313.105413) (xy 166.516146 -313.150471)
			(xy 166.488278 -313.191562) (xy 166.45413 -313.227603) (xy 166.4146 -313.257644) (xy 166.370732 -313.280895)
			(xy 166.323679 -313.296742) (xy 166.274683 -313.304767) (xy 166.249858 -313.30519) (xy 166.240757 -313.305149)
			(xy 166.222585 -313.30413) (xy 166.213536 -313.303158) (xy 166.201598 -313.301634) (xy 166.179246 -313.309762)
			(xy 166.106348 -313.385962) (xy 166.099236 -313.408568) (xy 166.100252 -313.414664) (xy 166.102853 -313.429578)
			(xy 166.105652 -313.459724) (xy 166.10584 -313.474862) (xy 166.10584 -313.54522) (xy 166.106404 -313.555911)
			(xy 166.115067 -313.575463) (xy 166.122604 -313.583066) (xy 166.178738 -313.633612) (xy 166.186957 -313.640404)
			(xy 166.207215 -313.646992) (xy 166.217854 -313.646312) (xy 166.218108 -313.646312) (xy 166.249858 -313.644534)
			(xy 166.273852 -313.644977) (xy 166.32125 -313.652479) (xy 166.366891 -313.667304) (xy 166.40965 -313.689088)
			(xy 166.448474 -313.717294) (xy 166.482406 -313.751226) (xy 166.510612 -313.79005) (xy 166.532396 -313.832809)
			(xy 166.547221 -313.87845) (xy 166.554723 -313.925848) (xy 166.555166 -313.949842) (xy 166.555068 -313.958946)
			(xy 166.553924 -313.977119) (xy 166.55288 -313.986164) (xy 166.552072 -313.998061) (xy 166.560143 -314.020465)
			(xy 166.568374 -314.02909) (xy 166.635938 -314.093606) (xy 166.658544 -314.100718) (xy 166.664132 -314.099702)
			(xy 166.69033 -314.095347) (xy 166.743419 -314.094071) (xy 166.769796 -314.097162) (xy 166.78402 -314.099448)
			(xy 166.784528 -314.099448) (xy 166.791386 -314.100718) (xy 166.813992 -314.093606) (xy 166.881556 -314.02909)
			(xy 166.889768 -314.020451) (xy 166.897845 -313.998058) (xy 166.89705 -313.986164) (xy 166.896 -313.97712)
			(xy 166.894854 -313.958946) (xy 166.894764 -313.949842) (xy 166.895207 -313.925846) (xy 166.902708 -313.878444)
			(xy 166.917533 -313.832799) (xy 166.939316 -313.790035) (xy 166.96752 -313.751205) (xy 167.001452 -313.717265)
			(xy 167.040275 -313.689052) (xy 167.083034 -313.66726) (xy 167.128675 -313.652425) (xy 167.176076 -313.644913)
			(xy 167.200072 -313.644534) (xy 167.231568 -313.646058) (xy 167.241982 -313.647328) (xy 167.26281 -313.64047)
			(xy 167.326818 -313.582812) (xy 167.334485 -313.575298) (xy 167.343181 -313.555693) (xy 167.343582 -313.544966)
			(xy 167.343582 -313.474862) (xy 167.343772 -313.459788) (xy 167.346575 -313.429769) (xy 167.34917 -313.414918)
			(xy 167.34917 -313.413902) (xy 167.350186 -313.408568) (xy 167.343074 -313.385962) (xy 167.270176 -313.309762)
			(xy 167.247824 -313.301634) (xy 167.235886 -313.303158) (xy 167.226964 -313.304119) (xy 167.209046 -313.305134)
			(xy 167.200072 -313.30519) (xy 167.175253 -313.304702) (xy 167.126271 -313.296667) (xy 167.079233 -313.280814)
			(xy 167.03538 -313.25756) (xy 166.995866 -313.227518) (xy 166.961733 -313.19148) (xy 166.93388 -313.150394)
			(xy 166.91304 -313.105343) (xy 166.899763 -313.057515) (xy 166.894399 -313.008168) (xy 166.897088 -312.958604)
			(xy 166.90776 -312.910128) (xy 166.926134 -312.864016) (xy 166.951726 -312.821485) (xy 166.983861 -312.783654)
			(xy 167.021693 -312.75152) (xy 167.064225 -312.72593) (xy 167.110337 -312.707557) (xy 167.158814 -312.696887)
			(xy 167.208378 -312.694199) (xy 167.257725 -312.699565) (xy 167.305553 -312.712844) (xy 167.350603 -312.733685)
			(xy 167.391688 -312.761539) (xy 167.427725 -312.795674) (xy 167.457766 -312.835188) (xy 167.481018 -312.879042)
			(xy 167.49687 -312.926081) (xy 167.504903 -312.975063) (xy 167.50538 -312.999882) (xy 167.505333 -313.008919)
			(xy 167.504316 -313.026965) (xy 167.503348 -313.03595) (xy 167.503348 -313.036204) (xy 167.502541 -313.048003)
			(xy 167.510504 -313.070241) (xy 167.518588 -313.078876) (xy 167.585898 -313.143138) (xy 167.608758 -313.15025)
			(xy 167.620696 -313.148218) (xy 167.634063 -313.14617) (xy 167.661021 -313.144006) (xy 167.674544 -313.1439)
			(xy 167.682926 -313.1439) (xy 167.687498 -313.144154) (xy 167.687752 -313.144154) (xy 167.69925 -313.144717)
			(xy 167.722132 -313.147256) (xy 167.733472 -313.149234) (xy 167.734488 -313.149234) (xy 167.741346 -313.150504)
			(xy 167.763952 -313.143392) (xy 167.831516 -313.078622) (xy 167.839595 -313.070131) (xy 167.84768 -313.048159)
			(xy 167.84701 -313.036458) (xy 167.84701 -313.036204) (xy 167.845962 -313.02716) (xy 167.844819 -313.008986)
			(xy 167.844724 -312.999882) (xy 167.845211 -312.975065) (xy 167.853244 -312.926084) (xy 167.869095 -312.879048)
			(xy 167.892346 -312.835196) (xy 167.922385 -312.795684) (xy 167.958421 -312.761551) (xy 167.999503 -312.733697)
			(xy 168.044551 -312.712857) (xy 168.092377 -312.699579) (xy 168.141721 -312.694213) (xy 168.191283 -312.6969)
			(xy 168.239757 -312.70757) (xy 168.285867 -312.725942) (xy 168.328397 -312.75153) (xy 168.366228 -312.783662)
			(xy 168.398361 -312.821491) (xy 168.423952 -312.864021) (xy 168.442326 -312.910129) (xy 168.452998 -312.958603)
			(xy 168.455687 -313.008165) (xy 168.450323 -313.057509) (xy 168.437048 -313.105336) (xy 168.416209 -313.150384)
			(xy 168.388358 -313.191469) (xy 168.354227 -313.227506) (xy 168.314715 -313.257547) (xy 168.270865 -313.2808)
			(xy 168.223829 -313.296653) (xy 168.174849 -313.304688) (xy 168.150032 -313.30519) (xy 168.140928 -313.305091)
			(xy 168.122755 -313.303946) (xy 168.11371 -313.302904) (xy 168.101816 -313.302103) (xy 168.079422 -313.310183)
			(xy 168.070784 -313.318398) (xy 168.006268 -313.385962) (xy 167.99941 -313.408568) (xy 168.000426 -313.415426)
			(xy 168.002913 -313.430031) (xy 168.005584 -313.45954) (xy 168.00576 -313.474354) (xy 168.00576 -313.54522)
			(xy 168.006324 -313.555911) (xy 168.01499 -313.57546) (xy 168.022524 -313.583066) (xy 168.078658 -313.633612)
			(xy 168.086878 -313.6404) (xy 168.107135 -313.64698) (xy 168.117774 -313.646312) (xy 168.118028 -313.646312)
			(xy 168.150032 -313.644534) (xy 168.174022 -313.644983) (xy 168.221411 -313.652494) (xy 168.267042 -313.667326)
			(xy 168.309791 -313.689113) (xy 168.348605 -313.71732) (xy 168.382528 -313.751252) (xy 168.410726 -313.790072)
			(xy 168.432503 -313.832826) (xy 168.447324 -313.878461) (xy 168.454823 -313.925852) (xy 168.45534 -313.949842)
			(xy 168.455237 -313.958883) (xy 168.454095 -313.976929) (xy 168.453054 -313.98591) (xy 168.453054 -313.986672)
			(xy 168.452338 -313.998347) (xy 168.460271 -314.020325) (xy 168.468294 -314.028836) (xy 168.535858 -314.093606)
			(xy 168.558464 -314.100718) (xy 168.563036 -314.099956) (xy 168.589472 -314.09544) (xy 168.64308 -314.094034)
			(xy 168.669716 -314.097162) (xy 168.68394 -314.099448) (xy 168.684448 -314.099448) (xy 168.691306 -314.100718)
			(xy 168.713912 -314.093606) (xy 168.781476 -314.02909) (xy 168.789685 -314.020449) (xy 168.797759 -313.998058)
			(xy 168.79697 -313.986164) (xy 168.79592 -313.97712) (xy 168.794774 -313.958946) (xy 168.794684 -313.949842)
			(xy 168.795127 -313.925846) (xy 168.802628 -313.878445) (xy 168.817453 -313.832802) (xy 168.839236 -313.790039)
			(xy 168.867441 -313.751211) (xy 168.901373 -313.717274) (xy 168.940196 -313.689062) (xy 168.982955 -313.667272)
			(xy 169.028597 -313.65244) (xy 169.075997 -313.644931) (xy 169.099992 -313.644534) (xy 169.131488 -313.646058)
			(xy 169.141902 -313.647328) (xy 169.16273 -313.64047) (xy 169.226738 -313.582812) (xy 169.234403 -313.575297)
			(xy 169.243095 -313.555692) (xy 169.243502 -313.544966) (xy 169.243502 -313.474862) (xy 169.243692 -313.459788)
			(xy 169.246495 -313.429769) (xy 169.24909 -313.414918) (xy 169.24909 -313.413902) (xy 169.250106 -313.408568)
			(xy 169.242994 -313.385962) (xy 169.170096 -313.309762) (xy 169.147744 -313.301634) (xy 169.135806 -313.303158)
			(xy 169.126884 -313.30412) (xy 169.108966 -313.305136) (xy 169.099992 -313.30519) (xy 169.075173 -313.304704)
			(xy 169.026189 -313.296672) (xy 168.97915 -313.280821) (xy 168.935295 -313.25757) (xy 168.895779 -313.22753)
			(xy 168.861643 -313.191493) (xy 168.833788 -313.150408) (xy 168.812945 -313.105357) (xy 168.799666 -313.057529)
			(xy 168.794299 -313.008182) (xy 168.796986 -312.958617) (xy 168.807657 -312.910139) (xy 168.826029 -312.864027)
			(xy 168.85162 -312.821494) (xy 168.883754 -312.783661) (xy 168.921586 -312.751526) (xy 168.964118 -312.725934)
			(xy 169.01023 -312.70756) (xy 169.058707 -312.696888) (xy 169.108272 -312.694199) (xy 169.157619 -312.699564)
			(xy 169.205448 -312.712842) (xy 169.250499 -312.733683) (xy 169.291585 -312.761537) (xy 169.327623 -312.795671)
			(xy 169.357665 -312.835186) (xy 169.380918 -312.879041) (xy 169.396769 -312.92608) (xy 169.404803 -312.975063)
			(xy 169.4053 -312.999882) (xy 169.405253 -313.008919) (xy 169.404236 -313.026965) (xy 169.403268 -313.03595)
			(xy 169.403268 -313.036204) (xy 169.402461 -313.048003) (xy 169.410427 -313.070238) (xy 169.418508 -313.078876)
			(xy 169.485818 -313.143138) (xy 169.508678 -313.15025) (xy 169.520616 -313.148218) (xy 169.533983 -313.146171)
			(xy 169.560941 -313.144009) (xy 169.574464 -313.1439) (xy 169.582846 -313.1439) (xy 169.587418 -313.144154)
			(xy 169.587672 -313.144154) (xy 169.59917 -313.144718) (xy 169.622051 -313.147258) (xy 169.633392 -313.149234)
			(xy 169.634408 -313.149234) (xy 169.641266 -313.150504) (xy 169.663872 -313.143392) (xy 169.731436 -313.078622)
			(xy 169.739525 -313.070135) (xy 169.747624 -313.04816) (xy 169.74693 -313.036458) (xy 169.74693 -313.036204)
			(xy 169.745882 -313.02716) (xy 169.74474 -313.008986) (xy 169.744644 -312.999882) (xy 169.745131 -312.975057)
			(xy 169.753167 -312.926061) (xy 169.769023 -312.87901) (xy 169.792283 -312.835145) (xy 169.822333 -312.795621)
			(xy 169.858382 -312.761479) (xy 169.899479 -312.733619) (xy 169.944543 -312.712775) (xy 169.992385 -312.699496)
			(xy 170.041745 -312.694132) (xy 170.091322 -312.696825) (xy 170.139811 -312.707503) (xy 170.185934 -312.725885)
			(xy 170.228474 -312.751487) (xy 170.266313 -312.783634) (xy 170.298452 -312.821479) (xy 170.324045 -312.864026)
			(xy 170.342417 -312.910152) (xy 170.353084 -312.958643) (xy 170.355766 -313.008221) (xy 170.350392 -313.05758)
			(xy 170.337103 -313.105419) (xy 170.316249 -313.150478) (xy 170.28838 -313.19157) (xy 170.25423 -313.227611)
			(xy 170.214699 -313.257653) (xy 170.170829 -313.280903) (xy 170.123775 -313.296749) (xy 170.074777 -313.304774)
			(xy 170.049952 -313.30519) (xy 170.040848 -313.305092) (xy 170.022675 -313.303948) (xy 170.01363 -313.302904)
			(xy 170.001734 -313.302098) (xy 169.979334 -313.310173) (xy 169.970704 -313.318398) (xy 169.906188 -313.385962)
			(xy 169.89933 -313.408568) (xy 169.900346 -313.415426) (xy 169.902833 -313.430031) (xy 169.905505 -313.45954)
			(xy 169.90568 -313.474354) (xy 169.90568 -313.54522) (xy 169.906242 -313.555913) (xy 169.914898 -313.575471)
			(xy 169.922444 -313.583066) (xy 169.978578 -313.633612) (xy 169.986799 -313.640396) (xy 170.007055 -313.646968)
			(xy 170.017694 -313.646312) (xy 170.017948 -313.646312) (xy 170.049952 -313.644534) (xy 170.073946 -313.644977)
			(xy 170.121345 -313.652478) (xy 170.166987 -313.667303) (xy 170.209746 -313.689086) (xy 170.248571 -313.717291)
			(xy 170.282505 -313.751224) (xy 170.310711 -313.790048) (xy 170.332495 -313.832808) (xy 170.347321 -313.878449)
			(xy 170.354823 -313.925848) (xy 170.35526 -313.949842) (xy 170.355157 -313.958883) (xy 170.354016 -313.976929)
			(xy 170.352974 -313.98591) (xy 170.352974 -313.986672) (xy 170.352258 -313.998347) (xy 170.360193 -314.020323)
			(xy 170.368214 -314.028836) (xy 170.435778 -314.093606) (xy 170.458384 -314.100718) (xy 170.462956 -314.099956)
			(xy 170.489392 -314.095441) (xy 170.543 -314.094039) (xy 170.569636 -314.097162) (xy 170.58386 -314.099448)
			(xy 170.584368 -314.099448) (xy 170.591226 -314.100718) (xy 170.613832 -314.093606) (xy 170.681396 -314.02909)
			(xy 170.689603 -314.020448) (xy 170.697673 -313.998057) (xy 170.69689 -313.986164) (xy 170.69584 -313.97712)
			(xy 170.694694 -313.958946) (xy 170.694604 -313.949842) (xy 170.695047 -313.925847) (xy 170.702549 -313.878447)
			(xy 170.717374 -313.832805) (xy 170.739157 -313.790044) (xy 170.767362 -313.751217) (xy 170.801294 -313.717282)
			(xy 170.840118 -313.689073) (xy 170.882877 -313.667285) (xy 170.928518 -313.652456) (xy 170.975917 -313.644949)
			(xy 170.999912 -313.644534) (xy 171.031662 -313.646058) (xy 171.042076 -313.647328) (xy 171.062904 -313.640724)
			(xy 171.126912 -313.583066) (xy 171.13456 -313.575544) (xy 171.143221 -313.55594) (xy 171.143676 -313.54522)
			(xy 171.143676 -313.474862) (xy 171.145454 -313.441588) (xy 171.148248 -313.420506) (xy 171.15028 -313.408568)
			(xy 171.143168 -313.385962) (xy 171.07027 -313.309762) (xy 171.047918 -313.301634) (xy 171.03598 -313.303158)
			(xy 171.026996 -313.304139) (xy 171.00895 -313.305153) (xy 170.999912 -313.30519) (xy 170.975093 -313.304705)
			(xy 170.926108 -313.296676) (xy 170.879067 -313.280829) (xy 170.83521 -313.257579) (xy 170.795691 -313.227541)
			(xy 170.761554 -313.191505) (xy 170.733695 -313.150421) (xy 170.712851 -313.105371) (xy 170.699569 -313.057543)
			(xy 170.6942 -313.008195) (xy 170.696885 -312.958629) (xy 170.707553 -312.910151) (xy 170.725924 -312.864037)
			(xy 170.751513 -312.821502) (xy 170.783647 -312.783668) (xy 170.821478 -312.751531) (xy 170.86401 -312.725937)
			(xy 170.910122 -312.707562) (xy 170.9586 -312.696889) (xy 171.008165 -312.694199) (xy 171.057513 -312.699563)
			(xy 171.105343 -312.71284) (xy 171.150395 -312.73368) (xy 171.191482 -312.761535) (xy 171.227521 -312.795669)
			(xy 171.257563 -312.835184) (xy 171.280817 -312.879039) (xy 171.296669 -312.926079) (xy 171.304703 -312.975063)
			(xy 171.30522 -312.999882) (xy 171.305181 -313.008983) (xy 171.304165 -313.027156) (xy 171.303188 -313.036204)
			(xy 171.301664 -313.048142) (xy 171.309792 -313.070494) (xy 171.385738 -313.143392) (xy 171.408344 -313.150504)
			(xy 171.41317 -313.149742) (xy 171.42839 -313.147013) (xy 171.459176 -313.144085) (xy 171.474638 -313.1439)
			(xy 171.4754 -313.1439) (xy 171.489764 -313.144071) (xy 171.518381 -313.146614) (xy 171.53255 -313.14898)
			(xy 171.533058 -313.14898) (xy 171.541186 -313.15025) (xy 171.563792 -313.143392) (xy 171.631356 -313.078622)
			(xy 171.639443 -313.070134) (xy 171.647537 -313.04816) (xy 171.64685 -313.036458) (xy 171.64685 -313.036204)
			(xy 171.645802 -313.02716) (xy 171.64466 -313.008986) (xy 171.644564 -312.999882) (xy 171.645051 -312.975059)
			(xy 171.653086 -312.926067) (xy 171.668941 -312.87902) (xy 171.692199 -312.835158) (xy 171.722246 -312.795637)
			(xy 171.758292 -312.761497) (xy 171.799386 -312.733639) (xy 171.844445 -312.712796) (xy 171.892283 -312.699517)
			(xy 171.941639 -312.694153) (xy 171.991212 -312.696844) (xy 172.039698 -312.70752) (xy 172.085817 -312.725899)
			(xy 172.128355 -312.751498) (xy 172.166191 -312.783641) (xy 172.198329 -312.821483) (xy 172.223921 -312.864025)
			(xy 172.242294 -312.910146) (xy 172.252962 -312.958633) (xy 172.255646 -313.008207) (xy 172.250274 -313.057562)
			(xy 172.236989 -313.105398) (xy 172.216139 -313.150455) (xy 172.188274 -313.191544) (xy 172.154129 -313.227584)
			(xy 172.114603 -313.257626) (xy 172.070738 -313.280877) (xy 172.023689 -313.296725) (xy 171.974695 -313.304752)
			(xy 171.949872 -313.30519) (xy 171.940768 -313.305093) (xy 171.922595 -313.30395) (xy 171.91355 -313.302904)
			(xy 171.913296 -313.302904) (xy 171.901496 -313.302097) (xy 171.879254 -313.310054) (xy 171.870624 -313.318144)
			(xy 171.806108 -313.385708) (xy 171.798996 -313.408314) (xy 171.800012 -313.414918) (xy 171.802596 -313.42977)
			(xy 171.805394 -313.459788) (xy 171.8056 -313.474862) (xy 171.8056 -313.54522) (xy 171.806163 -313.555912)
			(xy 171.814821 -313.575468) (xy 171.822364 -313.583066) (xy 171.878498 -313.633612) (xy 171.88672 -313.640393)
			(xy 171.906975 -313.646957) (xy 171.917614 -313.646312) (xy 171.917868 -313.646312) (xy 171.949872 -313.644534)
			(xy 171.973865 -313.644978) (xy 172.021262 -313.652482) (xy 172.066901 -313.667308) (xy 172.109657 -313.689093)
			(xy 172.14848 -313.717299) (xy 172.18241 -313.751231) (xy 172.210615 -313.790054) (xy 172.232397 -313.832812)
			(xy 172.247222 -313.878452) (xy 172.254723 -313.925849) (xy 172.25518 -313.949842) (xy 172.255077 -313.958883)
			(xy 172.253936 -313.976929) (xy 172.252894 -313.98591) (xy 172.252894 -313.986672) (xy 172.252177 -313.998349)
			(xy 172.260103 -314.020332) (xy 172.268134 -314.028836) (xy 172.335698 -314.093606) (xy 172.358304 -314.100718)
			(xy 172.36313 -314.099956) (xy 172.378351 -314.09723) (xy 172.409136 -314.094307) (xy 172.424598 -314.094114)
			(xy 172.439026 -314.094278) (xy 172.467769 -314.096824) (xy 172.482002 -314.099194) (xy 172.482764 -314.099194)
			(xy 172.4914 -314.100718) (xy 172.514006 -314.093606) (xy 172.59046 -314.020962) (xy 172.598588 -313.998102)
			(xy 172.597064 -313.986418) (xy 172.596009 -313.97731) (xy 172.594865 -313.95901) (xy 172.594778 -313.949842)
			(xy 172.595221 -313.925846) (xy 172.602722 -313.878445) (xy 172.617547 -313.832801) (xy 172.63933 -313.790038)
			(xy 172.667535 -313.751209) (xy 172.701467 -313.717271) (xy 172.74029 -313.689059) (xy 172.783049 -313.667269)
			(xy 172.82869 -313.652436) (xy 172.87609 -313.644925) (xy 172.900086 -313.644534) (xy 172.931582 -313.646312)
			(xy 172.93209 -313.646312) (xy 172.94271 -313.646827) (xy 172.96291 -313.640263) (xy 172.971206 -313.633612)
			(xy 173.02734 -313.583066) (xy 173.034997 -313.575548) (xy 173.043671 -313.555943) (xy 173.044104 -313.54522)
			(xy 173.044104 -313.48299) (xy 173.04385 -313.482482) (xy 173.04385 -313.474862) (xy 173.045882 -313.438794)
			(xy 173.04639 -313.434222) (xy 173.04639 -313.433968) (xy 173.049438 -313.415172) (xy 173.049438 -313.413902)
			(xy 173.050454 -313.408568) (xy 173.043342 -313.385962) (xy 172.970444 -313.309762) (xy 172.948092 -313.301634)
			(xy 172.936154 -313.303158) (xy 172.92717 -313.304141) (xy 172.909124 -313.30516) (xy 172.900086 -313.30519)
			(xy 172.875267 -313.304703) (xy 172.826284 -313.296671) (xy 172.779245 -313.280819) (xy 172.73539 -313.257567)
			(xy 172.695875 -313.227526) (xy 172.66174 -313.191489) (xy 172.633885 -313.150403) (xy 172.613044 -313.105353)
			(xy 172.599765 -313.057524) (xy 172.594399 -313.008178) (xy 172.597087 -312.958613) (xy 172.607758 -312.910136)
			(xy 172.626131 -312.864024) (xy 172.651722 -312.821491) (xy 172.683856 -312.783659) (xy 172.721688 -312.751524)
			(xy 172.76422 -312.725932) (xy 172.810332 -312.707559) (xy 172.858809 -312.696887) (xy 172.908374 -312.694199)
			(xy 172.957721 -312.699564) (xy 173.005549 -312.712842) (xy 173.0506 -312.733683) (xy 173.091686 -312.761538)
			(xy 173.127724 -312.795672) (xy 173.157765 -312.835187) (xy 173.181018 -312.879041) (xy 173.19687 -312.92608)
			(xy 173.204903 -312.975063) (xy 173.205394 -312.999882) (xy 173.205355 -313.008983) (xy 173.20434 -313.027156)
			(xy 173.203362 -313.036204) (xy 173.201838 -313.048142) (xy 173.209966 -313.070494) (xy 173.285912 -313.143392)
			(xy 173.308518 -313.150504) (xy 173.31309 -313.149742) (xy 173.328374 -313.147005) (xy 173.359286 -313.144076)
			(xy 173.374812 -313.1439) (xy 173.389372 -313.144116) (xy 173.41837 -313.146788) (xy 173.432724 -313.149234)
			(xy 173.43374 -313.149234) (xy 173.44136 -313.150504) (xy 173.463966 -313.143392) (xy 173.53153 -313.078622)
			(xy 173.53962 -313.070135) (xy 173.547719 -313.04816) (xy 173.547024 -313.036458) (xy 173.547024 -313.036204)
			(xy 173.545976 -313.02716) (xy 173.544834 -313.008986) (xy 173.544738 -312.999882) (xy 173.545225 -312.975066)
			(xy 173.553257 -312.926088) (xy 173.569107 -312.879055) (xy 173.592357 -312.835205) (xy 173.622394 -312.795695)
			(xy 173.658427 -312.761563) (xy 173.699508 -312.733711) (xy 173.744553 -312.712872) (xy 173.792376 -312.699594)
			(xy 173.841717 -312.694227) (xy 173.891276 -312.696914) (xy 173.939748 -312.707582) (xy 173.985855 -312.725951)
			(xy 174.028384 -312.751538) (xy 174.066213 -312.783667) (xy 174.098346 -312.821494) (xy 174.123936 -312.86402)
			(xy 174.14231 -312.910125) (xy 174.152983 -312.958596) (xy 174.155225 -312.999882) (xy 174.494202 -312.999882)
			(xy 174.498162 -312.950828) (xy 174.509939 -312.903044) (xy 174.52923 -312.857768) (xy 174.555533 -312.816172)
			(xy 174.588168 -312.779335) (xy 174.626289 -312.74821) (xy 174.66891 -312.723603) (xy 174.714926 -312.706151)
			(xy 174.763145 -312.696307) (xy 174.81232 -312.694326) (xy 174.861175 -312.700258) (xy 174.908446 -312.71395)
			(xy 174.952908 -312.735048) (xy 174.993411 -312.763004) (xy 175.028904 -312.797096) (xy 175.058469 -312.83644)
			(xy 175.08134 -312.880017) (xy 175.096924 -312.926698) (xy 175.104819 -312.975275) (xy 175.105314 -312.999882)
			(xy 175.104819 -313.024489) (xy 175.096924 -313.073066) (xy 175.08134 -313.119747) (xy 175.058469 -313.163324)
			(xy 175.028904 -313.202668) (xy 174.993411 -313.23676) (xy 174.952908 -313.264716) (xy 174.908446 -313.285814)
			(xy 174.861175 -313.299506) (xy 174.81232 -313.305438) (xy 174.763145 -313.303457) (xy 174.714926 -313.293613)
			(xy 174.66891 -313.276161) (xy 174.626289 -313.251554) (xy 174.588168 -313.220429) (xy 174.555533 -313.183592)
			(xy 174.52923 -313.141996) (xy 174.509939 -313.09672) (xy 174.498162 -313.048936) (xy 174.494202 -312.999882)
			(xy 174.155225 -312.999882) (xy 174.155674 -313.008155) (xy 174.150312 -313.057497) (xy 174.137038 -313.105321)
			(xy 174.116203 -313.150368) (xy 174.088354 -313.191451) (xy 174.054226 -313.227487) (xy 174.014718 -313.257528)
			(xy 173.970871 -313.280782) (xy 173.923839 -313.296636) (xy 173.874862 -313.304673) (xy 173.850046 -313.30519)
			(xy 173.840945 -313.305152) (xy 173.822772 -313.304138) (xy 173.813724 -313.303158) (xy 173.801786 -313.301634)
			(xy 173.779434 -313.309762) (xy 173.706536 -313.385962) (xy 173.699424 -313.408568) (xy 173.70044 -313.414664)
			(xy 173.703041 -313.429578) (xy 173.70584 -313.459724) (xy 173.706028 -313.474862) (xy 173.706028 -313.54522)
			(xy 173.706591 -313.555911) (xy 173.715253 -313.575464) (xy 173.722792 -313.583066) (xy 173.778926 -313.633612)
			(xy 173.787144 -313.640406) (xy 173.807403 -313.646999) (xy 173.818042 -313.646312) (xy 173.818296 -313.646312)
			(xy 173.850046 -313.644534) (xy 173.874034 -313.645008) (xy 173.921417 -313.65252) (xy 173.967043 -313.667352)
			(xy 174.009786 -313.689139) (xy 174.048595 -313.717344) (xy 174.082513 -313.751272) (xy 174.110707 -313.790089)
			(xy 174.132482 -313.832839) (xy 174.1473 -313.878468) (xy 174.154799 -313.925854) (xy 174.155354 -313.949842)
			(xy 174.154818 -313.976025) (xy 174.145885 -314.027624) (xy 174.137574 -314.052458) (xy 174.134768 -314.061611)
			(xy 174.135438 -314.080729) (xy 174.143049 -314.09828) (xy 174.156549 -314.111834) (xy 174.174069 -314.119516)
			(xy 174.193184 -314.120263) (xy 174.202344 -314.117482) (xy 174.213107 -314.113324) (xy 174.235097 -314.106331)
			(xy 174.246286 -314.103512) (xy 174.269068 -314.098386) (xy 174.315541 -314.093834) (xy 174.362193 -314.095845)
			(xy 174.385224 -314.099702) (xy 174.38624 -314.099702) (xy 174.39132 -314.100718) (xy 174.413926 -314.093606)
			(xy 174.48149 -314.02909) (xy 174.489698 -314.020449) (xy 174.497768 -313.998057) (xy 174.496984 -313.986164)
			(xy 174.495934 -313.97712) (xy 174.494788 -313.958946) (xy 174.494698 -313.949842) (xy 174.49518 -313.925021)
			(xy 174.503205 -313.876032) (xy 174.51905 -313.828986) (xy 174.542297 -313.785124) (xy 174.572334 -313.745601)
			(xy 174.60837 -313.711458) (xy 174.649455 -313.683595) (xy 174.694507 -313.662746) (xy 174.742338 -313.64946)
			(xy 174.791688 -313.644088) (xy 174.841258 -313.646771) (xy 174.88974 -313.657438) (xy 174.935858 -313.675808)
			(xy 174.978396 -313.701398) (xy 175.016234 -313.733532) (xy 175.048374 -313.771365) (xy 175.073971 -313.813899)
			(xy 175.092348 -313.860014) (xy 175.103023 -313.908495) (xy 175.105713 -313.958064) (xy 175.100349 -314.007415)
			(xy 175.087071 -314.055248) (xy 175.066229 -314.100303) (xy 175.038372 -314.141392) (xy 175.004235 -314.177434)
			(xy 174.964716 -314.207477) (xy 174.920858 -314.230731) (xy 174.873815 -314.246583) (xy 174.824827 -314.254616)
			(xy 174.800006 -314.25515) (xy 174.790838 -314.255058) (xy 174.772538 -314.253914) (xy 174.76343 -314.252864)
			(xy 174.751492 -314.25134) (xy 174.72914 -314.259468) (xy 174.656242 -314.335668) (xy 174.64913 -314.358528)
			(xy 174.651162 -314.370466) (xy 174.652674 -314.379996) (xy 174.654709 -314.399185) (xy 174.655226 -314.40882)
			(xy 174.655734 -314.418726) (xy 174.65929 -314.427108) (xy 174.661416 -314.431479) (xy 174.667043 -314.439405)
			(xy 174.670466 -314.442856) (xy 174.693326 -314.465208) (xy 174.69358 -314.465462) (xy 174.701962 -314.47359)
			(xy 174.721266 -314.492132) (xy 174.728618 -314.498612) (xy 174.746781 -314.505922) (xy 174.756572 -314.506356)
			(xy 175.792892 -314.506356) (xy 175.797718 -314.506102) (xy 175.806216 -314.504964) (xy 175.821802 -314.49784)
			(xy 175.828198 -314.492132) (xy 175.84674 -314.474352) (xy 175.880014 -314.442348) (xy 175.885962 -314.43558)
			(xy 175.893124 -314.419059) (xy 175.893984 -314.41009) (xy 175.893984 -314.354464) (xy 175.893418 -314.343774)
			(xy 175.884754 -314.324224) (xy 175.87722 -314.316618) (xy 175.821086 -314.266072) (xy 175.812868 -314.259278)
			(xy 175.792609 -314.252682) (xy 175.78197 -314.253372) (xy 175.781716 -314.253372) (xy 175.749966 -314.25515)
			(xy 175.724709 -314.254626) (xy 175.674885 -314.246306) (xy 175.627109 -314.2299) (xy 175.582685 -314.205855)
			(xy 175.542825 -314.174826) (xy 175.508614 -314.13766) (xy 175.480988 -314.09537) (xy 175.460698 -314.04911)
			(xy 175.448298 -314.000142) (xy 175.444127 -313.9498) (xy 175.448298 -313.899458) (xy 175.460698 -313.85049)
			(xy 175.480988 -313.80423) (xy 175.508614 -313.76194) (xy 175.542825 -313.724774) (xy 175.582685 -313.693745)
			(xy 175.627109 -313.6697) (xy 175.674885 -313.653294) (xy 175.724709 -313.644974) (xy 175.749966 -313.644534)
			(xy 175.781462 -313.646312) (xy 175.78197 -313.646312) (xy 175.792592 -313.646831) (xy 175.812796 -313.640272)
			(xy 175.821086 -313.633612) (xy 175.87722 -313.583066) (xy 175.884879 -313.575549) (xy 175.893557 -313.555944)
			(xy 175.893984 -313.54522) (xy 175.893984 -313.474862) (xy 175.894174 -313.459788) (xy 175.896977 -313.429769)
			(xy 175.899572 -313.414918) (xy 175.899572 -313.413902) (xy 175.900588 -313.408568) (xy 175.893476 -313.385962)
			(xy 175.820578 -313.309762) (xy 175.798226 -313.301634) (xy 175.786288 -313.303158) (xy 175.777241 -313.304148)
			(xy 175.759067 -313.305167) (xy 175.749966 -313.30519) (xy 175.725148 -313.304701) (xy 175.676165 -313.296666)
			(xy 175.629128 -313.280812) (xy 175.585276 -313.257558) (xy 175.545762 -313.227515) (xy 175.51163 -313.191476)
			(xy 175.483778 -313.15039) (xy 175.462939 -313.105339) (xy 175.449663 -313.057511) (xy 175.444299 -313.008164)
			(xy 175.446989 -312.9586) (xy 175.457661 -312.910124) (xy 175.476036 -312.864013) (xy 175.501628 -312.821482)
			(xy 175.533763 -312.783652) (xy 175.571595 -312.751518) (xy 175.614128 -312.725929) (xy 175.660239 -312.707557)
			(xy 175.708716 -312.696886) (xy 175.75828 -312.694199) (xy 175.807626 -312.699566) (xy 175.855454 -312.712844)
			(xy 175.900504 -312.733685) (xy 175.941589 -312.76154) (xy 175.977626 -312.795674) (xy 176.007666 -312.835189)
			(xy 176.030918 -312.879043) (xy 176.04677 -312.926081) (xy 176.054803 -312.975064) (xy 176.055274 -312.999882)
			(xy 176.055235 -313.008983) (xy 176.05422 -313.027156) (xy 176.053242 -313.036204) (xy 176.051718 -313.048142)
			(xy 176.059846 -313.070494) (xy 176.136046 -313.143392) (xy 176.158652 -313.15025) (xy 176.165256 -313.149234)
			(xy 176.176975 -313.147219) (xy 176.20062 -313.144676) (xy 176.2125 -313.144154) (xy 176.22266 -313.1439)
			(xy 176.225454 -313.1439) (xy 176.245993 -313.144206) (xy 176.286753 -313.149295) (xy 176.306734 -313.15406)
			(xy 176.317207 -313.156828) (xy 176.337799 -313.163563) (xy 176.347882 -313.167522) (xy 176.358428 -313.170589)
			(xy 176.380261 -313.16843) (xy 176.399209 -313.157369) (xy 176.411823 -313.139418) (xy 176.41581 -313.117843)
			(xy 176.413668 -313.10707) (xy 176.412398 -313.102498) (xy 176.404104 -313.077659) (xy 176.395173 -313.026063)
			(xy 176.394618 -312.999882) (xy 176.395066 -312.975891) (xy 176.402575 -312.928499) (xy 176.417405 -312.882865)
			(xy 176.439192 -312.840113) (xy 176.467398 -312.801296) (xy 176.50133 -312.76737) (xy 176.540151 -312.739169)
			(xy 176.582906 -312.717388) (xy 176.628542 -312.702564) (xy 176.675934 -312.695062) (xy 176.699926 -312.694574)
			(xy 176.708963 -312.694619) (xy 176.727009 -312.695633) (xy 176.735994 -312.696606) (xy 176.736248 -312.696606)
			(xy 176.748053 -312.697426) (xy 176.770314 -312.689487) (xy 176.77892 -312.681366) (xy 176.843182 -312.613802)
			(xy 176.850294 -312.590942) (xy 176.848262 -312.579258) (xy 176.844328 -312.552219) (xy 176.844327 -312.497584)
			(xy 176.848262 -312.470546) (xy 176.850294 -312.458862) (xy 176.843182 -312.436002) (xy 176.77892 -312.368438)
			(xy 176.770281 -312.360367) (xy 176.748044 -312.352415) (xy 176.736248 -312.353198) (xy 176.735994 -312.353198)
			(xy 176.72701 -312.354179) (xy 176.708964 -312.355194) (xy 176.699926 -312.35523) (xy 176.674665 -312.354739)
			(xy 176.624832 -312.346427) (xy 176.577046 -312.330026) (xy 176.532612 -312.305983) (xy 176.492742 -312.274954)
			(xy 176.458523 -312.237785) (xy 176.430889 -312.195491) (xy 176.410593 -312.149225) (xy 176.39819 -312.100249)
			(xy 176.394018 -312.0499) (xy 176.39819 -311.999551) (xy 176.410593 -311.950575) (xy 176.430889 -311.904309)
			(xy 176.458523 -311.862015) (xy 176.492742 -311.824846) (xy 176.532612 -311.793817) (xy 176.577046 -311.769774)
			(xy 176.624832 -311.753373) (xy 176.674665 -311.745061) (xy 176.699926 -311.744614) (xy 176.709027 -311.744654)
			(xy 176.727199 -311.745672) (xy 176.736248 -311.746646) (xy 176.748186 -311.74817) (xy 176.770538 -311.740042)
			(xy 176.843436 -311.663842) (xy 176.850548 -311.641236) (xy 176.849532 -311.63514) (xy 176.846936 -311.620225)
			(xy 176.844134 -311.59008) (xy 176.843944 -311.574942) (xy 176.843944 -311.504584) (xy 176.84338 -311.493893)
			(xy 176.834717 -311.474342) (xy 176.82718 -311.466738) (xy 176.771046 -311.416192) (xy 176.762827 -311.409403)
			(xy 176.742569 -311.40282) (xy 176.73193 -311.403492) (xy 176.731676 -311.403492) (xy 176.699926 -311.40527)
			(xy 176.67467 -311.40478) (xy 176.624846 -311.396469) (xy 176.57707 -311.380071) (xy 176.532645 -311.356033)
			(xy 176.492782 -311.32501) (xy 176.45857 -311.287848) (xy 176.430941 -311.245562) (xy 176.41065 -311.199305)
			(xy 176.398249 -311.150339) (xy 176.394078 -311.1) (xy 176.398249 -311.049661) (xy 176.41065 -311.000695)
			(xy 176.430941 -310.954438) (xy 176.45857 -310.912152) (xy 176.492782 -310.87499) (xy 176.532645 -310.843967)
			(xy 176.57707 -310.819929) (xy 176.624846 -310.803531) (xy 176.67467 -310.79522) (xy 176.699926 -310.794654)
			(xy 176.731422 -310.796432) (xy 176.73193 -310.796432) (xy 176.742548 -310.796939) (xy 176.762738 -310.790365)
			(xy 176.771046 -310.783732) (xy 176.82718 -310.733186) (xy 176.834835 -310.725667) (xy 176.84351 -310.706062)
			(xy 176.843944 -310.69534) (xy 176.843944 -310.624728) (xy 176.844043 -310.612041) (xy 176.845949 -310.58674)
			(xy 176.847754 -310.574182) (xy 176.847754 -310.573674) (xy 176.848262 -310.570372) (xy 176.850294 -310.558688)
			(xy 176.843182 -310.535828) (xy 176.77892 -310.468264) (xy 176.770282 -310.46019) (xy 176.748044 -310.452233)
			(xy 176.736248 -310.453024) (xy 176.735994 -310.453024) (xy 176.72701 -310.454006) (xy 176.708964 -310.455021)
			(xy 176.699926 -310.455056) (xy 176.674663 -310.454565) (xy 176.624825 -310.446253) (xy 176.577036 -310.42985)
			(xy 176.532598 -310.405805) (xy 176.492724 -310.374773) (xy 176.458502 -310.337601) (xy 176.430866 -310.295303)
			(xy 176.410569 -310.249033) (xy 176.398165 -310.200054) (xy 176.393992 -310.1497) (xy 176.398165 -310.099346)
			(xy 176.410569 -310.050367) (xy 176.430866 -310.004097) (xy 176.458502 -309.961799) (xy 176.492724 -309.924627)
			(xy 176.532598 -309.893595) (xy 176.577036 -309.86955) (xy 176.624825 -309.853147) (xy 176.674663 -309.844835)
			(xy 176.699926 -309.84444) (xy 176.709027 -309.84448) (xy 176.727199 -309.845498) (xy 176.736248 -309.846472)
			(xy 176.748186 -309.847996) (xy 176.770538 -309.839868) (xy 176.843436 -309.763668) (xy 176.850548 -309.741062)
			(xy 176.849786 -309.73649) (xy 176.846493 -309.717818) (xy 176.843694 -309.680005) (xy 176.844198 -309.661052)
			(xy 176.844657 -309.650844) (xy 176.84669 -309.630509) (xy 176.848262 -309.620412) (xy 176.850294 -309.608474)
			(xy 176.843182 -309.585614) (xy 176.77892 -309.518304) (xy 176.770284 -309.510225) (xy 176.748045 -309.502261)
			(xy 176.736248 -309.503064) (xy 176.735994 -309.503064) (xy 176.72701 -309.504046) (xy 176.708964 -309.505061)
			(xy 176.699926 -309.505096) (xy 176.675932 -309.504652) (xy 176.628534 -309.497148) (xy 176.582894 -309.482322)
			(xy 176.540135 -309.460538) (xy 176.50131 -309.432332) (xy 176.467377 -309.3984) (xy 176.43917 -309.359577)
			(xy 176.417384 -309.316819) (xy 176.402555 -309.27118) (xy 176.395049 -309.223782) (xy 176.394618 -309.199788)
			(xy 176.394805 -309.185606) (xy 176.39748 -309.157367) (xy 176.399952 -309.1434) (xy 176.402238 -309.130954)
			(xy 176.394872 -309.107332) (xy 176.317402 -309.029862) (xy 176.29378 -309.022496) (xy 176.281334 -309.024782)
			(xy 176.267369 -309.027265) (xy 176.239129 -309.029932) (xy 176.224946 -309.030116) (xy 176.200123 -309.029634)
			(xy 176.151131 -309.021609) (xy 176.104083 -309.005764) (xy 176.060218 -308.982516) (xy 176.020693 -308.952477)
			(xy 175.986547 -308.916439) (xy 175.958683 -308.875352) (xy 175.937832 -308.830298) (xy 175.924546 -308.782464)
			(xy 175.919174 -308.73311) (xy 175.921857 -308.683538) (xy 175.932525 -308.635053) (xy 175.950897 -308.588933)
			(xy 175.976489 -308.546392) (xy 176.008626 -308.508553) (xy 176.046461 -308.476411) (xy 176.088998 -308.450814)
			(xy 176.135117 -308.432436) (xy 176.1836 -308.421762) (xy 176.233172 -308.419073) (xy 176.282526 -308.424439)
			(xy 176.330362 -308.437719) (xy 176.375419 -308.458564) (xy 176.416509 -308.486424) (xy 176.452552 -308.520564)
			(xy 176.482595 -308.560086) (xy 176.505849 -308.603948) (xy 176.5217 -308.650995) (xy 176.529731 -308.699986)
			(xy 176.530254 -308.724808) (xy 176.530067 -308.73899) (xy 176.527393 -308.76723) (xy 176.52492 -308.781196)
			(xy 176.522634 -308.793642) (xy 176.53 -308.817264) (xy 176.60747 -308.894734) (xy 176.631092 -308.9021)
			(xy 176.643538 -308.899814) (xy 176.657503 -308.89733) (xy 176.685743 -308.89466) (xy 176.699926 -308.89448)
			(xy 176.708963 -308.894525) (xy 176.727009 -308.895539) (xy 176.735994 -308.896512) (xy 176.736248 -308.896512)
			(xy 176.748053 -308.897332) (xy 176.770315 -308.889393) (xy 176.77892 -308.881272) (xy 176.843182 -308.813708)
			(xy 176.850294 -308.790848) (xy 176.848262 -308.779164) (xy 176.844624 -308.754655) (xy 176.843861 -308.705113)
			(xy 176.850499 -308.656012) (xy 176.86439 -308.608451) (xy 176.885222 -308.563495) (xy 176.912528 -308.522151)
			(xy 176.945699 -308.485344) (xy 176.98399 -308.453899) (xy 177.026544 -308.42852) (xy 177.072409 -308.409774)
			(xy 177.120557 -308.398082) (xy 177.145188 -308.39537) (xy 177.16754 -308.3941) (xy 177.169826 -308.3941)
			(xy 177.178285 -308.393273) (xy 177.193984 -308.386785) (xy 177.20056 -308.3814) (xy 177.255424 -308.325774)
			(xy 177.260686 -308.319364) (xy 177.267032 -308.304053) (xy 177.26787 -308.295802) (xy 177.268124 -308.293516)
			(xy 177.268124 -308.207156) (xy 177.26787 -308.201314) (xy 177.266647 -308.193444) (xy 177.260043 -308.178961)
			(xy 177.254916 -308.172866) (xy 177.203608 -308.120796) (xy 177.20004 -308.11739) (xy 177.191857 -308.111882)
			(xy 177.187352 -308.109874) (xy 177.177954 -308.10581) (xy 177.168048 -308.105556) (xy 177.141112 -308.104485)
			(xy 177.088105 -308.094687) (xy 177.037386 -308.076432) (xy 176.990293 -308.050203) (xy 176.94807 -308.016693)
			(xy 176.911833 -307.976786) (xy 176.896776 -307.954426) (xy 176.883547 -307.933096) (xy 176.862988 -307.88731)
			(xy 176.849583 -307.838944) (xy 176.843638 -307.789108) (xy 176.84529 -307.738946) (xy 176.854501 -307.689609)
			(xy 176.87106 -307.642229) (xy 176.894587 -307.597896) (xy 176.924541 -307.557625) (xy 176.960236 -307.522342)
			(xy 177.00085 -307.492856) (xy 177.045454 -307.469844) (xy 177.093022 -307.453835) (xy 177.142462 -307.445196)
			(xy 177.16754 -307.44414) (xy 177.169826 -307.44414) (xy 177.178284 -307.443311) (xy 177.193979 -307.436818)
			(xy 177.20056 -307.43144) (xy 177.255424 -307.375814) (xy 177.260691 -307.369406) (xy 177.26705 -307.354096)
			(xy 177.26787 -307.345842) (xy 177.268124 -307.343556) (xy 177.268124 -307.257196) (xy 177.26787 -307.251354)
			(xy 177.266653 -307.243481) (xy 177.260057 -307.228991) (xy 177.254916 -307.222906) (xy 177.203608 -307.170836)
			(xy 177.200041 -307.167427) (xy 177.191861 -307.161916) (xy 177.187352 -307.159914) (xy 177.177954 -307.15585)
			(xy 177.168048 -307.155596) (xy 177.142401 -307.154603) (xy 177.09186 -307.14567) (xy 177.043307 -307.129035)
			(xy 176.997907 -307.105097) (xy 176.956751 -307.074433) (xy 176.920827 -307.037778) (xy 176.890999 -306.996012)
			(xy 176.867981 -306.950139) (xy 176.852328 -306.90126) (xy 176.844415 -306.85055) (xy 176.843944 -306.824888)
			(xy 176.844454 -306.7989) (xy 176.852586 -306.747564) (xy 176.868648 -306.698132) (xy 176.892243 -306.651821)
			(xy 176.922792 -306.60977) (xy 176.959543 -306.573016) (xy 177.00159 -306.542462) (xy 177.047899 -306.518861)
			(xy 177.097329 -306.502795) (xy 177.148664 -306.494657) (xy 177.174652 -306.49418) (xy 177.183815 -306.494242)
			(xy 177.202114 -306.495257) (xy 177.211228 -306.496212) (xy 177.213514 -306.496466) (xy 177.217324 -306.496466)
			(xy 177.22734 -306.496042) (xy 177.245842 -306.488366) (xy 177.259999 -306.474194) (xy 177.267653 -306.455682)
			(xy 177.268124 -306.445666) (xy 177.268124 -306.433728) (xy 177.268886 -306.413154) (xy 177.268886 -306.412646)
			(xy 177.270223 -306.392645) (xy 177.276588 -306.353065) (xy 177.281586 -306.333652) (xy 177.28819 -306.310538)
			(xy 177.284634 -306.304188) (xy 177.259488 -306.272184) (xy 177.255932 -306.267612) (xy 177.255932 -306.267104)
			(xy 177.22215 -306.224686) (xy 177.218398 -306.220263) (xy 177.20929 -306.213085) (xy 177.204116 -306.210462)
			(xy 177.193448 -306.205382) (xy 177.18151 -306.205636) (xy 177.174652 -306.205636) (xy 177.148665 -306.205123)
			(xy 177.097332 -306.196986) (xy 177.047904 -306.180919) (xy 177.001597 -306.157319) (xy 176.959552 -306.126765)
			(xy 176.922803 -306.090012) (xy 176.892256 -306.047962) (xy 176.868663 -306.001652) (xy 176.852603 -305.952221)
			(xy 176.844473 -305.900887) (xy 176.844473 -305.848913) (xy 176.852603 -305.797579) (xy 176.868663 -305.748148)
			(xy 176.892256 -305.701838) (xy 176.922803 -305.659788) (xy 176.959552 -305.623035) (xy 177.001597 -305.592481)
			(xy 177.047904 -305.568881) (xy 177.097332 -305.552814) (xy 177.148665 -305.544677) (xy 177.174652 -305.54422)
			(xy 177.187402 -305.544313) (xy 177.21283 -305.546222) (xy 177.225452 -305.54803) (xy 177.250251 -305.552365)
			(xy 177.298248 -305.567551) (xy 177.343389 -305.589835) (xy 177.384633 -305.6187) (xy 177.421027 -305.653482)
			(xy 177.45173 -305.693376) (xy 177.476035 -305.737462) (xy 177.493379 -305.784722) (xy 177.503362 -305.834064)
			(xy 177.505106 -305.85918) (xy 177.505614 -305.87188) (xy 177.511456 -305.88204) (xy 177.514556 -305.887061)
			(xy 177.522636 -305.895657) (xy 177.527458 -305.899058) (xy 177.596546 -305.944778) (xy 177.601605 -305.947868)
			(xy 177.612772 -305.951839) (xy 177.618644 -305.952652) (xy 177.630836 -305.954176) (xy 177.642266 -305.949858)
			(xy 177.677318 -305.938428) (xy 177.68749 -305.935705) (xy 177.708077 -305.931258) (xy 177.718466 -305.929538)
			(xy 177.719228 -305.929538) (xy 177.722784 -305.928776) (xy 177.735484 -305.924712) (xy 177.740564 -305.922426)
			(xy 177.75174 -305.916838) (xy 177.755705 -305.914685) (xy 177.762866 -305.909196) (xy 177.765964 -305.905916)
			(xy 177.768504 -305.903122) (xy 177.776632 -305.893724) (xy 177.782982 -305.884326) (xy 177.794158 -305.858672)
			(xy 177.79492 -305.850036) (xy 177.79492 -305.849782) (xy 177.797264 -305.825167) (xy 177.808331 -305.776979)
			(xy 177.826448 -305.730975) (xy 177.851212 -305.68818) (xy 177.88207 -305.649549) (xy 177.918336 -305.615941)
			(xy 177.9592 -305.588107) (xy 178.003752 -305.566667) (xy 178.051 -305.552098) (xy 178.099891 -305.544724)
			(xy 178.124612 -305.54422) (xy 178.152765 -305.544785) (xy 178.208259 -305.55431) (xy 178.261343 -305.573084)
			(xy 178.310487 -305.600565) (xy 178.354275 -305.635962) (xy 178.373278 -305.656742) (xy 178.374294 -305.658012)
			(xy 178.377596 -305.661314) (xy 178.380748 -305.664326) (xy 178.387902 -305.669307) (xy 178.39182 -305.67122)
			(xy 178.410616 -305.680364) (xy 178.421538 -305.684174) (xy 178.432206 -305.68519) (xy 178.76139 -305.68519)
			(xy 178.770026 -305.684428) (xy 178.78171 -305.681888) (xy 178.782218 -305.681888) (xy 178.792886 -305.678332)
			(xy 178.807364 -305.671474) (xy 178.807618 -305.67122) (xy 178.812952 -305.67122) (xy 178.828192 -305.654202)
			(xy 178.845545 -305.635533) (xy 178.88497 -305.60323) (xy 178.928881 -305.577353) (xy 178.97624 -305.558515)
			(xy 179.025928 -305.547162) (xy 179.076769 -305.54356) (xy 179.127562 -305.547796) (xy 179.177104 -305.55977)
			(xy 179.224224 -305.579197) (xy 179.267809 -305.60562) (xy 179.306828 -305.638413) (xy 179.324 -305.65725)
			(xy 179.325016 -305.65852) (xy 179.329588 -305.663092) (xy 179.340764 -305.670458) (xy 179.36337 -305.681126)
			(xy 179.368051 -305.682971) (xy 179.3779 -305.68502) (xy 179.382928 -305.68519) (xy 179.71135 -305.68519)
			(xy 179.719986 -305.684428) (xy 179.73167 -305.681888) (xy 179.732178 -305.681888) (xy 179.742846 -305.678332)
			(xy 179.757324 -305.671474) (xy 179.757578 -305.67122) (xy 179.762912 -305.67122) (xy 179.778152 -305.654202)
			(xy 179.795505 -305.635529) (xy 179.834931 -305.60322) (xy 179.878844 -305.577338) (xy 179.926206 -305.558495)
			(xy 179.975898 -305.547136) (xy 180.026743 -305.54353) (xy 180.07754 -305.547762) (xy 180.127088 -305.559733)
			(xy 180.174214 -305.579159) (xy 180.217805 -305.60558) (xy 180.25683 -305.638373) (xy 180.27396 -305.65725)
			(xy 180.274976 -305.65852) (xy 180.279548 -305.663092) (xy 180.290724 -305.670458) (xy 180.31333 -305.681126)
			(xy 180.318012 -305.682966) (xy 180.327861 -305.685003) (xy 180.332888 -305.68519) (xy 180.66131 -305.68519)
			(xy 180.669946 -305.684428) (xy 180.68163 -305.681888) (xy 180.682138 -305.681888) (xy 180.692806 -305.678332)
			(xy 180.707284 -305.671474) (xy 180.707538 -305.67122) (xy 180.712872 -305.67122) (xy 180.728112 -305.654202)
			(xy 180.745465 -305.635526) (xy 180.784892 -305.603211) (xy 180.828807 -305.577323) (xy 180.876172 -305.558474)
			(xy 180.925867 -305.54711) (xy 180.976717 -305.5435) (xy 181.027519 -305.547729) (xy 181.077072 -305.559697)
			(xy 181.124204 -305.57912) (xy 181.167801 -305.605541) (xy 181.206832 -305.638333) (xy 181.22392 -305.65725)
			(xy 181.224936 -305.65852) (xy 181.229508 -305.663092) (xy 181.240684 -305.670458) (xy 181.26329 -305.681126)
			(xy 181.267971 -305.68297) (xy 181.27782 -305.685015) (xy 181.282848 -305.68519) (xy 181.61127 -305.68519)
			(xy 181.619906 -305.684428) (xy 181.63159 -305.681888) (xy 181.632098 -305.681888) (xy 181.642766 -305.678332)
			(xy 181.657244 -305.671474) (xy 181.657498 -305.67122) (xy 181.662832 -305.67122) (xy 181.678072 -305.654202)
			(xy 181.695425 -305.635531) (xy 181.73485 -305.603225) (xy 181.778762 -305.577346) (xy 181.826123 -305.558505)
			(xy 181.875813 -305.547149) (xy 181.926656 -305.543545) (xy 181.977451 -305.547779) (xy 182.026996 -305.559751)
			(xy 182.074119 -305.579178) (xy 182.117707 -305.6056) (xy 182.156729 -305.638393) (xy 182.17388 -305.65725)
			(xy 182.174896 -305.65852) (xy 182.179468 -305.663092) (xy 182.190644 -305.670458) (xy 182.21325 -305.681126)
			(xy 182.21793 -305.682973) (xy 182.227779 -305.685026) (xy 182.232808 -305.68519) (xy 182.56123 -305.68519)
			(xy 182.569866 -305.684428) (xy 182.58155 -305.681888) (xy 182.582058 -305.681888) (xy 182.592726 -305.678332)
			(xy 182.607204 -305.671474) (xy 182.607458 -305.67122) (xy 182.612792 -305.67122) (xy 182.628032 -305.654202)
			(xy 182.645385 -305.635528) (xy 182.684811 -305.603216) (xy 182.728725 -305.577331) (xy 182.776089 -305.558485)
			(xy 182.825782 -305.547123) (xy 182.87663 -305.543515) (xy 182.927429 -305.547746) (xy 182.97698 -305.559715)
			(xy 183.024109 -305.57914) (xy 183.067703 -305.605561) (xy 183.106731 -305.638353) (xy 183.12384 -305.65725)
			(xy 183.124856 -305.65852) (xy 183.129428 -305.663092) (xy 183.140604 -305.670458) (xy 183.16321 -305.681126)
			(xy 183.167891 -305.682968) (xy 183.17774 -305.685009) (xy 183.182768 -305.68519) (xy 183.51119 -305.68519)
			(xy 183.519826 -305.684428) (xy 183.53151 -305.681888) (xy 183.532018 -305.681888) (xy 183.542686 -305.678332)
			(xy 183.557164 -305.671474) (xy 183.557418 -305.67122) (xy 183.562752 -305.67122) (xy 183.577992 -305.654202)
			(xy 183.595345 -305.635533) (xy 183.63477 -305.60323) (xy 183.678681 -305.577353) (xy 183.72604 -305.558515)
			(xy 183.775728 -305.547162) (xy 183.826569 -305.54356) (xy 183.877362 -305.547796) (xy 183.926904 -305.55977)
			(xy 183.974024 -305.579197) (xy 184.017609 -305.60562) (xy 184.056628 -305.638413) (xy 184.0738 -305.65725)
			(xy 184.074816 -305.65852) (xy 184.079388 -305.663092) (xy 184.090564 -305.670458) (xy 184.11317 -305.681126)
			(xy 184.117851 -305.682971) (xy 184.1277 -305.68502) (xy 184.132728 -305.68519) (xy 184.471818 -305.68519)
			(xy 184.483502 -305.682904) (xy 184.514744 -305.668172) (xy 184.521094 -305.661314) (xy 184.52592 -305.656488)
			(xy 184.526936 -305.655472) (xy 184.528714 -305.65344) (xy 184.545824 -305.635199) (xy 184.584562 -305.603571)
			(xy 184.627616 -305.578129) (xy 184.650634 -305.56835) (xy 184.65165 -305.567842) (xy 184.660794 -305.564032)
			(xy 184.677304 -305.538886) (xy 184.677304 -305.517296) (xy 184.678057 -305.475167) (xy 184.690175 -305.391784)
			(xy 184.701434 -305.35118) (xy 184.701434 -305.350672) (xy 184.70357 -305.341782) (xy 184.702123 -305.323568)
			(xy 184.69864 -305.315112) (xy 184.66181 -305.236118) (xy 184.651904 -305.2318) (xy 184.628669 -305.222006)
			(xy 184.585229 -305.196408) (xy 184.546178 -305.164513) (xy 184.512421 -305.127059) (xy 184.484741 -305.084915)
			(xy 184.46378 -305.039057) (xy 184.450022 -304.990549) (xy 184.443788 -304.940515) (xy 184.445221 -304.890114)
			(xy 184.454288 -304.840515) (xy 184.47078 -304.792867) (xy 184.494313 -304.748275) (xy 184.524342 -304.707772)
			(xy 184.560172 -304.672296) (xy 184.600972 -304.642671) (xy 184.645797 -304.619583) (xy 184.693606 -304.603566)
			(xy 184.743293 -304.594993) (xy 184.76849 -304.594006) (xy 184.769252 -304.594006) (xy 184.779 -304.593268)
			(xy 184.796887 -304.585421) (xy 184.80405 -304.578766) (xy 184.853834 -304.527966) (xy 184.860421 -304.520587)
			(xy 184.867881 -304.502288) (xy 184.868312 -304.492406) (xy 184.868312 -304.400204) (xy 184.868058 -304.397918)
			(xy 184.868058 -304.397664) (xy 184.867804 -304.395124) (xy 184.866558 -304.385163) (xy 184.857551 -304.367243)
			(xy 184.850278 -304.360326) (xy 184.838848 -304.350674) (xy 184.835292 -304.347372) (xy 184.821322 -304.332894)
			(xy 184.805066 -304.31613) (xy 184.804812 -304.315876) (xy 184.801252 -304.312411) (xy 184.793067 -304.306782)
			(xy 184.788556 -304.3047) (xy 184.779412 -304.30089) (xy 184.76976 -304.300382) (xy 184.769252 -304.300382)
			(xy 184.743819 -304.299109) (xy 184.693772 -304.289716) (xy 184.645756 -304.272761) (xy 184.600907 -304.248645)
			(xy 184.560286 -304.217939) (xy 184.524853 -304.181367) (xy 184.495445 -304.139796) (xy 184.472758 -304.094208)
			(xy 184.457329 -304.045681) (xy 184.449522 -303.995361) (xy 184.449522 -303.94444) (xy 184.457329 -303.894121)
			(xy 184.472758 -303.845594) (xy 184.495444 -303.800005) (xy 184.524851 -303.758434) (xy 184.560285 -303.721863)
			(xy 184.600906 -303.691156) (xy 184.645754 -303.66704) (xy 184.69377 -303.650085) (xy 184.743817 -303.640692)
			(xy 184.769252 -303.639474) (xy 184.76976 -303.639474) (xy 184.779412 -303.638966) (xy 184.788556 -303.635156)
			(xy 184.79308 -303.633097) (xy 184.801274 -303.627471) (xy 184.804812 -303.62398) (xy 184.805066 -303.623726)
			(xy 184.821322 -303.606962) (xy 184.855866 -303.570894) (xy 184.861178 -303.564366) (xy 184.86754 -303.548794)
			(xy 184.868312 -303.540414) (xy 184.868312 -303.473104) (xy 184.868566 -303.463198) (xy 184.868566 -303.46269)
			(xy 184.86882 -303.448974) (xy 184.863232 -303.436782) (xy 184.861595 -303.433488) (xy 184.857515 -303.427368)
			(xy 184.855104 -303.42459) (xy 184.845706 -303.414938) (xy 184.845706 -303.41443) (xy 184.803542 -303.36998)
			(xy 184.798555 -303.365392) (xy 184.786706 -303.358829) (xy 184.780174 -303.357026) (xy 184.77865 -303.356772)
			(xy 184.77738 -303.356518) (xy 184.772808 -303.355502) (xy 184.767982 -303.355502) (xy 184.742333 -303.354511)
			(xy 184.691788 -303.345582) (xy 184.64323 -303.32895) (xy 184.597825 -303.305015) (xy 184.556664 -303.274351)
			(xy 184.520735 -303.237695) (xy 184.490902 -303.195928) (xy 184.467881 -303.150053) (xy 184.452225 -303.101171)
			(xy 184.44431 -303.050458) (xy 184.443878 -303.024794) (xy 184.444388 -302.998807) (xy 184.452519 -302.947472)
			(xy 184.468581 -302.898042) (xy 184.492176 -302.851732) (xy 184.522726 -302.809683) (xy 184.559477 -302.772931)
			(xy 184.601525 -302.742381) (xy 184.647834 -302.718784) (xy 184.697264 -302.702721) (xy 184.748599 -302.694589)
			(xy 184.774586 -302.694086) (xy 184.798841 -302.694517) (xy 184.846831 -302.701607) (xy 184.893273 -302.715624)
			(xy 184.937172 -302.736268) (xy 184.977589 -302.763096) (xy 185.01366 -302.795534) (xy 185.044611 -302.832888)
			(xy 185.069781 -302.874358) (xy 185.07964 -302.896524) (xy 185.081926 -302.901858) (xy 185.090308 -302.913288)
			(xy 185.092594 -302.916336) (xy 185.097958 -302.922274) (xy 185.111557 -302.930694) (xy 185.119264 -302.932846)
			(xy 185.177176 -302.94453) (xy 185.203846 -302.949864) (xy 185.215338 -302.951107) (xy 185.237422 -302.944357)
			(xy 185.246264 -302.93691) (xy 185.273188 -302.910494) (xy 185.273188 -302.91024) (xy 185.305192 -302.878236)
			(xy 185.310176 -302.872736) (xy 185.317012 -302.859567) (xy 185.318654 -302.852328) (xy 185.31967 -302.842676)
			(xy 185.31967 -282.05557) (xy 185.319183 -282.046124) (xy 185.31228 -282.028532) (xy 185.306208 -282.02128)
			(xy 185.259472 -281.97048) (xy 185.252695 -281.963704) (xy 185.235461 -281.955357) (xy 185.225944 -281.954224)
			(xy 185.200749 -281.951725) (xy 185.151632 -281.939448) (xy 185.105213 -281.919236) (xy 185.062765 -281.891643)
			(xy 185.025451 -281.857425) (xy 184.994293 -281.817521) (xy 184.970145 -281.773023) (xy 184.953669 -281.725151)
			(xy 184.945316 -281.675217) (xy 184.945316 -281.624589) (xy 184.953668 -281.574654) (xy 184.970143 -281.526782)
			(xy 184.99429 -281.482283) (xy 185.025448 -281.442378) (xy 185.062761 -281.40816) (xy 185.105209 -281.380567)
			(xy 185.151627 -281.360354) (xy 185.200744 -281.348076) (xy 185.225944 -281.34564) (xy 185.235458 -281.344509)
			(xy 185.252679 -281.336143) (xy 185.259472 -281.329384) (xy 185.306208 -281.278584) (xy 185.312361 -281.27138)
			(xy 185.319281 -281.253759) (xy 185.31967 -281.244294) (xy 185.31967 -281.105356) (xy 185.31918 -281.095911)
			(xy 185.312274 -281.078322) (xy 185.306208 -281.071066) (xy 185.259472 -281.020266) (xy 185.252694 -281.013492)
			(xy 185.23546 -281.005147) (xy 185.225944 -281.00401) (xy 185.20075 -281.001511) (xy 185.151635 -280.989234)
			(xy 185.105219 -280.969023) (xy 185.062773 -280.941431) (xy 185.025461 -280.907215) (xy 184.994304 -280.867312)
			(xy 184.970158 -280.822816) (xy 184.953682 -280.774946) (xy 184.94533 -280.725014) (xy 184.94533 -280.674389)
			(xy 184.953682 -280.624456) (xy 184.970156 -280.576586) (xy 184.994303 -280.53209) (xy 185.025459 -280.492187)
			(xy 185.062771 -280.45797) (xy 185.105217 -280.430378) (xy 185.151633 -280.410167) (xy 185.200747 -280.397889)
			(xy 185.225944 -280.395426) (xy 185.235461 -280.394298) (xy 185.252691 -280.385942) (xy 185.259472 -280.37917)
			(xy 185.306208 -280.32837) (xy 185.312359 -280.321166) (xy 185.319274 -280.303545) (xy 185.31967 -280.29408)
			(xy 185.31967 -280.155396) (xy 185.319187 -280.145948) (xy 185.312291 -280.12835) (xy 185.306208 -280.121106)
			(xy 185.259472 -280.070306) (xy 185.252691 -280.063538) (xy 185.235457 -280.055203) (xy 185.225944 -280.05405)
			(xy 185.200755 -280.051551) (xy 185.15165 -280.039276) (xy 185.105243 -280.019068) (xy 185.062806 -279.991481)
			(xy 185.025502 -279.957271) (xy 184.994352 -279.917375) (xy 184.970211 -279.872888) (xy 184.95374 -279.825027)
			(xy 184.94539 -279.775105) (xy 184.945391 -279.724489) (xy 184.953741 -279.674567) (xy 184.970213 -279.626706)
			(xy 184.994356 -279.582219) (xy 185.025506 -279.542324) (xy 185.062812 -279.508115) (xy 185.105249 -279.480529)
			(xy 185.151657 -279.460322) (xy 185.200761 -279.448048) (xy 185.225944 -279.445466) (xy 185.235459 -279.444335)
			(xy 185.252683 -279.435973) (xy 185.259472 -279.42921) (xy 185.306208 -279.37841) (xy 185.312364 -279.371207)
			(xy 185.319294 -279.353587) (xy 185.31967 -279.34412) (xy 185.31967 -279.205436) (xy 185.319177 -279.195993)
			(xy 185.312265 -279.178408) (xy 185.306208 -279.171146) (xy 185.252614 -279.11298) (xy 185.235596 -279.104852)
			(xy 185.225944 -279.10409) (xy 185.200735 -279.101613) (xy 185.151584 -279.089373) (xy 185.105129 -279.069186)
			(xy 185.062643 -279.041608) (xy 185.025293 -279.007395) (xy 184.994104 -278.967485) (xy 184.96993 -278.922973)
			(xy 184.953436 -278.875082) (xy 184.945075 -278.825126) (xy 184.945075 -278.774474) (xy 184.953437 -278.724517)
			(xy 184.96993 -278.676626) (xy 184.994104 -278.632115) (xy 185.025293 -278.592205) (xy 185.062643 -278.557992)
			(xy 185.105129 -278.530413) (xy 185.151585 -278.510227) (xy 185.200735 -278.497986) (xy 185.225944 -278.495506)
			(xy 185.235596 -278.494744) (xy 185.252614 -278.486616) (xy 185.306208 -278.42845) (xy 185.312355 -278.421244)
			(xy 185.319263 -278.403624) (xy 185.31967 -278.39416) (xy 185.31967 -278.255476) (xy 185.319184 -278.24603)
			(xy 185.312282 -278.228436) (xy 185.306208 -278.221186) (xy 185.252614 -278.16302) (xy 185.235596 -278.154892)
			(xy 185.225944 -278.15413) (xy 185.200736 -278.151647) (xy 185.151589 -278.139396) (xy 185.105136 -278.119204)
			(xy 185.062653 -278.091624) (xy 185.025302 -278.057413) (xy 184.994108 -278.017507) (xy 184.969926 -277.973002)
			(xy 184.953418 -277.925116) (xy 184.945038 -277.875163) (xy 184.944512 -277.849838) (xy 184.944512 -277.84933)
			(xy 184.945064 -277.823211) (xy 184.953999 -277.771742) (xy 184.962292 -277.746968) (xy 184.965155 -277.737919)
			(xy 184.96468 -277.718958) (xy 184.957337 -277.701471) (xy 184.944135 -277.687854) (xy 184.926882 -277.679976)
			(xy 184.907945 -277.678915) (xy 184.898792 -277.681436) (xy 184.879488 -277.688548) (xy 184.854051 -277.696462)
			(xy 184.801474 -277.705011) (xy 184.77484 -277.705566) (xy 184.774586 -277.705566) (xy 184.75932 -277.70541)
			(xy 184.728917 -277.702614) (xy 184.71388 -277.699978) (xy 184.712356 -277.699724) (xy 184.708292 -277.698962)
			(xy 184.685686 -277.706074) (xy 184.618122 -277.770844) (xy 184.610116 -277.779369) (xy 184.602162 -277.801336)
			(xy 184.602882 -277.813008) (xy 184.602882 -277.813516) (xy 184.603929 -277.82256) (xy 184.60507 -277.840734)
			(xy 184.605168 -277.849838) (xy 184.604719 -277.873828) (xy 184.597207 -277.921217) (xy 184.582375 -277.966847)
			(xy 184.560587 -278.009595) (xy 184.53238 -278.048408) (xy 184.498448 -278.082331) (xy 184.459628 -278.110528)
			(xy 184.416874 -278.132305) (xy 184.371241 -278.147125) (xy 184.32385 -278.154625) (xy 184.29986 -278.155146)
			(xy 184.26811 -278.153368) (xy 184.267602 -278.153368) (xy 184.256982 -278.152855) (xy 184.236783 -278.159419)
			(xy 184.228486 -278.166068) (xy 184.172352 -278.216614) (xy 184.164693 -278.224131) (xy 184.156012 -278.243736)
			(xy 184.155588 -278.25446) (xy 184.155588 -278.299926) (xy 184.155588 -278.307292) (xy 184.155588 -278.324818)
			(xy 184.15537 -278.339702) (xy 184.152572 -278.369339) (xy 184.15 -278.384) (xy 184.15 -278.385524)
			(xy 184.148984 -278.391366) (xy 184.156096 -278.413972) (xy 184.220612 -278.481536) (xy 184.229252 -278.489604)
			(xy 184.251488 -278.497547) (xy 184.263284 -278.496776) (xy 184.263538 -278.496776) (xy 184.272582 -278.495726)
			(xy 184.290756 -278.49458) (xy 184.29986 -278.49449) (xy 184.324682 -278.494973) (xy 184.373672 -278.502998)
			(xy 184.420719 -278.518843) (xy 184.464582 -278.542092) (xy 184.504107 -278.57213) (xy 184.53825 -278.608168)
			(xy 184.566114 -278.649254) (xy 184.586963 -278.694307) (xy 184.600248 -278.74214) (xy 184.60562 -278.791492)
			(xy 184.602937 -278.841063) (xy 184.592269 -278.889547) (xy 184.573897 -278.935666) (xy 184.548306 -278.978205)
			(xy 184.51617 -279.016043) (xy 184.478336 -279.048184) (xy 184.4358 -279.07378) (xy 184.389683 -279.092157)
			(xy 184.341201 -279.102831) (xy 184.29163 -279.105521) (xy 184.242277 -279.100156) (xy 184.194443 -279.086876)
			(xy 184.149387 -279.066032) (xy 184.108297 -279.038174) (xy 184.072256 -279.004035) (xy 184.042212 -278.964514)
			(xy 184.018958 -278.920654) (xy 184.003107 -278.873609) (xy 183.995076 -278.82462) (xy 183.994552 -278.799798)
			(xy 183.994657 -278.790757) (xy 183.995802 -278.772712) (xy 183.996838 -278.76373) (xy 183.996838 -278.763222)
			(xy 183.998108 -278.751538) (xy 183.98998 -278.729186) (xy 183.91378 -278.656288) (xy 183.891174 -278.64943)
			(xy 183.882792 -278.6507) (xy 183.868558 -278.653058) (xy 183.839815 -278.655601) (xy 183.825388 -278.65578)
			(xy 183.824626 -278.65578) (xy 183.809551 -278.655592) (xy 183.779531 -278.652795) (xy 183.764682 -278.650192)
			(xy 183.763666 -278.650192) (xy 183.758332 -278.649176) (xy 183.735726 -278.656288) (xy 183.659526 -278.729186)
			(xy 183.651398 -278.751538) (xy 183.652922 -278.763476) (xy 183.65391 -278.772523) (xy 183.654925 -278.790697)
			(xy 183.654954 -278.799798) (xy 183.654469 -278.824623) (xy 183.646436 -278.87362) (xy 183.630582 -278.920672)
			(xy 183.607325 -278.964539) (xy 183.577277 -279.004065) (xy 183.54123 -279.038209) (xy 183.500134 -279.066072)
			(xy 183.455071 -279.086918) (xy 183.407229 -279.1002) (xy 183.357869 -279.105566) (xy 183.308291 -279.102875)
			(xy 183.259802 -279.092199) (xy 183.213678 -279.073819) (xy 183.171136 -279.048218) (xy 183.133296 -279.016072)
			(xy 183.101156 -278.978228) (xy 183.075562 -278.935682) (xy 183.057188 -278.889556) (xy 183.046519 -278.841065)
			(xy 183.043835 -278.791487) (xy 183.049209 -278.742127) (xy 183.062497 -278.694288) (xy 183.08335 -278.649228)
			(xy 183.111218 -278.608136) (xy 183.145368 -278.572094) (xy 183.184898 -278.542051) (xy 183.228768 -278.5188)
			(xy 183.275822 -278.502953) (xy 183.32482 -278.494928) (xy 183.349646 -278.49449) (xy 183.358747 -278.494531)
			(xy 183.376919 -278.49555) (xy 183.385968 -278.496522) (xy 183.397906 -278.498046) (xy 183.420258 -278.489918)
			(xy 183.493156 -278.413718) (xy 183.500268 -278.391112) (xy 183.499252 -278.38527) (xy 183.496646 -278.370293)
			(xy 183.493849 -278.340019) (xy 183.493664 -278.324818) (xy 183.493664 -278.25446) (xy 183.493097 -278.243771)
			(xy 183.484429 -278.224224) (xy 183.4769 -278.216614) (xy 183.420766 -278.166068) (xy 183.412547 -278.159278)
			(xy 183.392289 -278.152691) (xy 183.38165 -278.153368) (xy 183.381396 -278.153368) (xy 183.349646 -278.155146)
			(xy 183.325649 -278.154703) (xy 183.278246 -278.147203) (xy 183.2326 -278.132378) (xy 183.189835 -278.110596)
			(xy 183.151003 -278.082392) (xy 183.117063 -278.048461) (xy 183.088848 -278.009637) (xy 183.067054 -277.966878)
			(xy 183.052217 -277.921236) (xy 183.044703 -277.873834) (xy 183.044338 -277.849838) (xy 183.044436 -277.840734)
			(xy 183.045581 -277.822561) (xy 183.046624 -277.813516) (xy 183.047427 -277.801621) (xy 183.039351 -277.779223)
			(xy 183.03113 -277.77059) (xy 182.963566 -277.706074) (xy 182.94096 -277.699216) (xy 182.93588 -277.699978)
			(xy 182.921532 -277.702502) (xy 182.892533 -277.705301) (xy 182.877968 -277.705566) (xy 182.863555 -277.705594)
			(xy 182.83481 -277.703436) (xy 182.820564 -277.701248) (xy 182.808626 -277.699216) (xy 182.785766 -277.706328)
			(xy 182.718202 -277.771098) (xy 182.710208 -277.779627) (xy 182.702282 -277.801591) (xy 182.702962 -277.813262)
			(xy 182.702962 -277.813516) (xy 182.704009 -277.82256) (xy 182.70515 -277.840734) (xy 182.705248 -277.849838)
			(xy 182.704775 -277.873828) (xy 182.697264 -277.921218) (xy 182.682434 -277.966849) (xy 182.660649 -278.0096)
			(xy 182.632445 -278.048416) (xy 182.598518 -278.082344) (xy 182.559701 -278.110548) (xy 182.516951 -278.132333)
			(xy 182.47132 -278.147164) (xy 182.42393 -278.154674) (xy 182.39994 -278.155146) (xy 182.36819 -278.153368)
			(xy 182.367682 -278.153368) (xy 182.357064 -278.152859) (xy 182.33687 -278.159429) (xy 182.328566 -278.166068)
			(xy 182.272432 -278.216614) (xy 182.264775 -278.224132) (xy 182.256099 -278.243737) (xy 182.255668 -278.25446)
			(xy 182.255668 -278.324818) (xy 182.255468 -278.339829) (xy 182.252668 -278.369721) (xy 182.25008 -278.384508)
			(xy 182.25008 -278.385524) (xy 182.249064 -278.391112) (xy 182.256176 -278.413718) (xy 182.320692 -278.481282)
			(xy 182.329332 -278.489494) (xy 182.351724 -278.497575) (xy 182.363618 -278.496776) (xy 182.372662 -278.495729)
			(xy 182.390836 -278.494587) (xy 182.39994 -278.49449) (xy 182.42476 -278.494979) (xy 182.473746 -278.503016)
			(xy 182.520786 -278.518872) (xy 182.564642 -278.54213) (xy 182.604157 -278.572175) (xy 182.638291 -278.608218)
			(xy 182.666144 -278.649308) (xy 182.686983 -278.694363) (xy 182.700259 -278.742196) (xy 182.705622 -278.791546)
			(xy 182.70293 -278.841114) (xy 182.692254 -278.889593) (xy 182.673877 -278.935706) (xy 182.648281 -278.978239)
			(xy 182.616142 -279.016071) (xy 182.578305 -279.048206) (xy 182.535769 -279.073795) (xy 182.489653 -279.092167)
			(xy 182.441172 -279.102835) (xy 182.391604 -279.10552) (xy 182.342254 -279.100151) (xy 182.294423 -279.086869)
			(xy 182.249372 -279.066024) (xy 182.208285 -279.038165) (xy 182.172247 -279.004026) (xy 182.142207 -278.964506)
			(xy 182.118956 -278.920648) (xy 182.103106 -278.873605) (xy 182.095076 -278.824618) (xy 182.094632 -278.799798)
			(xy 182.094737 -278.790757) (xy 182.095882 -278.772712) (xy 182.096918 -278.76373) (xy 182.096918 -278.763222)
			(xy 182.098188 -278.751538) (xy 182.09006 -278.729186) (xy 182.01386 -278.656288) (xy 181.991254 -278.649176)
			(xy 181.983634 -278.650446) (xy 181.969029 -278.652937) (xy 181.939521 -278.655611) (xy 181.924706 -278.65578)
			(xy 181.924452 -278.65578) (xy 181.909186 -278.655623) (xy 181.878784 -278.652825) (xy 181.863746 -278.650192)
			(xy 181.862222 -278.649938) (xy 181.858158 -278.649176) (xy 181.835552 -278.656288) (xy 181.759606 -278.729186)
			(xy 181.751478 -278.751538) (xy 181.753002 -278.763476) (xy 181.75399 -278.772523) (xy 181.755005 -278.790697)
			(xy 181.755034 -278.799798) (xy 181.754548 -278.824621) (xy 181.746516 -278.873614) (xy 181.730664 -278.920662)
			(xy 181.707409 -278.964526) (xy 181.677364 -279.004049) (xy 181.64132 -279.038191) (xy 181.600227 -279.066052)
			(xy 181.555169 -279.086897) (xy 181.507331 -279.100178) (xy 181.457975 -279.105545) (xy 181.408401 -279.102856)
			(xy 181.359915 -279.092182) (xy 181.313795 -279.073804) (xy 181.271256 -279.048207) (xy 181.233418 -279.016065)
			(xy 181.201279 -278.978225) (xy 181.175685 -278.935683) (xy 181.157311 -278.889562) (xy 181.146641 -278.841075)
			(xy 181.143956 -278.791501) (xy 181.149326 -278.742145) (xy 181.162611 -278.694309) (xy 181.18346 -278.649252)
			(xy 181.211324 -278.608161) (xy 181.245469 -278.57212) (xy 181.284994 -278.542078) (xy 181.32886 -278.518826)
			(xy 181.375909 -278.502978) (xy 181.424903 -278.49495) (xy 181.449726 -278.49449) (xy 181.458827 -278.49453)
			(xy 181.476999 -278.495548) (xy 181.486048 -278.496522) (xy 181.497986 -278.498046) (xy 181.520338 -278.489918)
			(xy 181.593236 -278.413972) (xy 181.600348 -278.391366) (xy 181.599586 -278.38654) (xy 181.596871 -278.371382)
			(xy 181.593943 -278.340724) (xy 181.593744 -278.325326) (xy 181.593744 -278.25446) (xy 181.593176 -278.243771)
			(xy 181.584506 -278.224227) (xy 181.57698 -278.216614) (xy 181.520846 -278.166068) (xy 181.512626 -278.159281)
			(xy 181.492369 -278.152702) (xy 181.48173 -278.153368) (xy 181.481476 -278.153368) (xy 181.449726 -278.155146)
			(xy 181.425732 -278.154677) (xy 181.378335 -278.147175) (xy 181.332695 -278.13235) (xy 181.289936 -278.110569)
			(xy 181.251111 -278.082366) (xy 181.217175 -278.048438) (xy 181.188965 -278.009618) (xy 181.167174 -277.966864)
			(xy 181.15234 -277.921227) (xy 181.144828 -277.873832) (xy 181.144418 -277.849838) (xy 181.144516 -277.840734)
			(xy 181.145661 -277.822561) (xy 181.146704 -277.813516) (xy 181.147507 -277.801621) (xy 181.139429 -277.779225)
			(xy 181.13121 -277.77059) (xy 181.063646 -277.706074) (xy 181.04104 -277.699216) (xy 181.03596 -277.699978)
			(xy 181.021612 -277.702501) (xy 180.992613 -277.705298) (xy 180.978048 -277.705566) (xy 180.963635 -277.705593)
			(xy 180.934891 -277.703433) (xy 180.920644 -277.701248) (xy 180.908706 -277.699216) (xy 180.885846 -277.706328)
			(xy 180.818282 -277.771098) (xy 180.810291 -277.779628) (xy 180.802367 -277.801592) (xy 180.803042 -277.813262)
			(xy 180.803042 -277.813516) (xy 180.804089 -277.82256) (xy 180.805231 -277.840734) (xy 180.805328 -277.849838)
			(xy 180.804855 -277.873828) (xy 180.797344 -277.921216) (xy 180.782513 -277.966846) (xy 180.760728 -278.009595)
			(xy 180.732524 -278.04841) (xy 180.698597 -278.082336) (xy 180.65978 -278.110538) (xy 180.61703 -278.13232)
			(xy 180.571399 -278.147148) (xy 180.52401 -278.154656) (xy 180.50002 -278.155146) (xy 180.46827 -278.153368)
			(xy 180.467762 -278.153368) (xy 180.457138 -278.152843) (xy 180.436923 -278.159389) (xy 180.428646 -278.166068)
			(xy 180.372512 -278.216614) (xy 180.364858 -278.224134) (xy 180.356185 -278.243738) (xy 180.355748 -278.25446)
			(xy 180.355748 -278.324818) (xy 180.355548 -278.339829) (xy 180.352748 -278.369721) (xy 180.35016 -278.384508)
			(xy 180.35016 -278.385524) (xy 180.349144 -278.391112) (xy 180.356256 -278.413718) (xy 180.420772 -278.481282)
			(xy 180.429411 -278.489498) (xy 180.451804 -278.497587) (xy 180.463698 -278.496776) (xy 180.472742 -278.495728)
			(xy 180.490916 -278.494586) (xy 180.50002 -278.49449) (xy 180.524841 -278.494977) (xy 180.573828 -278.503012)
			(xy 180.620869 -278.518865) (xy 180.664727 -278.54212) (xy 180.704244 -278.572164) (xy 180.738381 -278.608206)
			(xy 180.766237 -278.649295) (xy 180.787078 -278.694349) (xy 180.800356 -278.742182) (xy 180.805721 -278.791532)
			(xy 180.803031 -278.841101) (xy 180.792358 -278.889581) (xy 180.773982 -278.935696) (xy 180.748387 -278.978231)
			(xy 180.716249 -279.016064) (xy 180.678413 -279.0482) (xy 180.635876 -279.073792) (xy 180.58976 -279.092164)
			(xy 180.541279 -279.102834) (xy 180.49171 -279.105521) (xy 180.44236 -279.100152) (xy 180.394528 -279.086871)
			(xy 180.349475 -279.066026) (xy 180.308388 -279.038167) (xy 180.272349 -279.004028) (xy 180.242308 -278.964508)
			(xy 180.219056 -278.920649) (xy 180.203206 -278.873606) (xy 180.195176 -278.824619) (xy 180.194712 -278.799798)
			(xy 180.194817 -278.790757) (xy 180.195962 -278.772712) (xy 180.196998 -278.76373) (xy 180.196998 -278.763222)
			(xy 180.198268 -278.751538) (xy 180.19014 -278.729186) (xy 180.11394 -278.656288) (xy 180.091334 -278.649176)
			(xy 180.083714 -278.650446) (xy 180.069109 -278.652936) (xy 180.039601 -278.655608) (xy 180.024786 -278.65578)
			(xy 180.024532 -278.65578) (xy 180.009266 -278.655622) (xy 179.978864 -278.652822) (xy 179.963826 -278.650192)
			(xy 179.962302 -278.649938) (xy 179.958238 -278.649176) (xy 179.935632 -278.656288) (xy 179.859686 -278.729186)
			(xy 179.851558 -278.751538) (xy 179.853082 -278.763476) (xy 179.85407 -278.772523) (xy 179.855086 -278.790697)
			(xy 179.855114 -278.799798) (xy 179.854628 -278.824619) (xy 179.846597 -278.873609) (xy 179.830746 -278.920653)
			(xy 179.807493 -278.964513) (xy 179.777451 -279.004034) (xy 179.74141 -279.038173) (xy 179.700321 -279.066032)
			(xy 179.655267 -279.086877) (xy 179.607433 -279.100158) (xy 179.558081 -279.105525) (xy 179.508511 -279.102837)
			(xy 179.460029 -279.092165) (xy 179.413912 -279.07379) (xy 179.371375 -279.048196) (xy 179.333539 -279.016058)
			(xy 179.301401 -278.978222) (xy 179.275808 -278.935685) (xy 179.257434 -278.889567) (xy 179.246762 -278.841085)
			(xy 179.244075 -278.791515) (xy 179.249443 -278.742163) (xy 179.262725 -278.69433) (xy 179.28357 -278.649275)
			(xy 179.311429 -278.608187) (xy 179.345569 -278.572147) (xy 179.38509 -278.542105) (xy 179.428951 -278.518852)
			(xy 179.475995 -278.503002) (xy 179.524985 -278.494971) (xy 179.549806 -278.49449) (xy 179.558907 -278.494529)
			(xy 179.57708 -278.495546) (xy 179.586128 -278.496522) (xy 179.598066 -278.498046) (xy 179.620418 -278.489918)
			(xy 179.693316 -278.413972) (xy 179.700428 -278.391366) (xy 179.699666 -278.38654) (xy 179.696952 -278.371382)
			(xy 179.694023 -278.340724) (xy 179.693824 -278.325326) (xy 179.693824 -278.25446) (xy 179.693258 -278.243769)
			(xy 179.684598 -278.224216) (xy 179.67706 -278.216614) (xy 179.620926 -278.166068) (xy 179.612705 -278.159285)
			(xy 179.592449 -278.152714) (xy 179.58181 -278.153368) (xy 179.581556 -278.153368) (xy 179.549806 -278.155146)
			(xy 179.525813 -278.154676) (xy 179.478419 -278.147171) (xy 179.432781 -278.132344) (xy 179.390025 -278.110562)
			(xy 179.351203 -278.082359) (xy 179.31727 -278.048431) (xy 179.289061 -278.009612) (xy 179.267273 -277.966859)
			(xy 179.25244 -277.921224) (xy 179.244928 -277.873831) (xy 179.244498 -277.849838) (xy 179.244596 -277.840734)
			(xy 179.245741 -277.822561) (xy 179.246784 -277.813516) (xy 179.247588 -277.80162) (xy 179.239519 -277.779216)
			(xy 179.23129 -277.77059) (xy 179.163726 -277.706074) (xy 179.14112 -277.699216) (xy 179.13604 -277.699978)
			(xy 179.105761 -277.704974) (xy 179.044399 -277.704974) (xy 179.01412 -277.699978) (xy 179.013104 -277.699978)
			(xy 179.008532 -277.699216) (xy 178.985926 -277.706074) (xy 178.918362 -277.77059) (xy 178.910144 -277.779227)
			(xy 178.902055 -277.801622) (xy 178.902868 -277.813516) (xy 178.903915 -277.82256) (xy 178.905056 -277.840734)
			(xy 178.905154 -277.849838) (xy 178.904681 -277.873829) (xy 178.89717 -277.921218) (xy 178.88234 -277.96685)
			(xy 178.860555 -278.009601) (xy 178.832352 -278.048418) (xy 178.798424 -278.082347) (xy 178.759608 -278.110551)
			(xy 178.716858 -278.132337) (xy 178.671226 -278.147168) (xy 178.623837 -278.15468) (xy 178.599846 -278.155146)
			(xy 178.56835 -278.153368) (xy 178.567842 -278.153368) (xy 178.557219 -278.152847) (xy 178.53701 -278.159399)
			(xy 178.528726 -278.166068) (xy 178.472592 -278.216614) (xy 178.46494 -278.224135) (xy 178.45627 -278.243739)
			(xy 178.455828 -278.25446) (xy 178.455828 -278.299418) (xy 178.455828 -278.301704) (xy 178.455828 -278.324818)
			(xy 178.455638 -278.339893) (xy 178.452838 -278.369912) (xy 178.45024 -278.384762) (xy 178.45024 -278.385778)
			(xy 178.449224 -278.391112) (xy 178.456336 -278.413718) (xy 178.529234 -278.489918) (xy 178.551586 -278.498046)
			(xy 178.563524 -278.496522) (xy 178.572571 -278.495532) (xy 178.590745 -278.494514) (xy 178.599846 -278.49449)
			(xy 178.624666 -278.49498) (xy 178.673652 -278.503018) (xy 178.720691 -278.518875) (xy 178.764546 -278.542133)
			(xy 178.804061 -278.572179) (xy 178.838194 -278.608222) (xy 178.866047 -278.649312) (xy 178.886885 -278.694367)
			(xy 178.90016 -278.7422) (xy 178.905522 -278.79155) (xy 178.902829 -278.841117) (xy 178.892153 -278.889596)
			(xy 178.873775 -278.935709) (xy 178.848179 -278.978242) (xy 178.81604 -279.016074) (xy 178.778203 -279.048207)
			(xy 178.735666 -279.073797) (xy 178.68955 -279.092167) (xy 178.64107 -279.102836) (xy 178.591502 -279.10552)
			(xy 178.542153 -279.100151) (xy 178.494322 -279.086868) (xy 178.44927 -279.066023) (xy 178.408184 -279.038164)
			(xy 178.372147 -279.004025) (xy 178.342107 -278.964506) (xy 178.318856 -278.920647) (xy 178.303006 -278.873605)
			(xy 178.294976 -278.824618) (xy 178.294538 -278.799798) (xy 178.294577 -278.790697) (xy 178.295594 -278.772524)
			(xy 178.29657 -278.763476) (xy 178.298094 -278.751538) (xy 178.289966 -278.729186) (xy 178.213766 -278.656288)
			(xy 178.19116 -278.649176) (xy 178.185318 -278.650192) (xy 178.170341 -278.652799) (xy 178.140067 -278.655601)
			(xy 178.124866 -278.65578) (xy 178.109861 -278.655633) (xy 178.07997 -278.65296) (xy 178.065176 -278.650446)
			(xy 178.064668 -278.650446) (xy 178.058318 -278.64943) (xy 178.035712 -278.656288) (xy 177.968148 -278.721058)
			(xy 177.960075 -278.72955) (xy 177.952014 -278.751522) (xy 177.952654 -278.763222) (xy 177.952654 -278.763476)
			(xy 177.953702 -278.77252) (xy 177.954846 -278.790694) (xy 177.95494 -278.799798) (xy 177.954454 -278.824622)
			(xy 177.946422 -278.873616) (xy 177.930569 -278.920665) (xy 177.907314 -278.96453) (xy 177.877267 -279.004054)
			(xy 177.841223 -279.038197) (xy 177.800129 -279.066058) (xy 177.755069 -279.086903) (xy 177.707231 -279.100185)
			(xy 177.657873 -279.105551) (xy 177.608298 -279.102862) (xy 177.559811 -279.092187) (xy 177.51369 -279.073809)
			(xy 177.47115 -279.04821) (xy 177.433312 -279.016067) (xy 177.401172 -278.978226) (xy 177.375578 -278.935683)
			(xy 177.357204 -278.88956) (xy 177.346534 -278.841072) (xy 177.34385 -278.791497) (xy 177.349221 -278.74214)
			(xy 177.362507 -278.694302) (xy 177.383357 -278.649245) (xy 177.411222 -278.608154) (xy 177.445368 -278.572112)
			(xy 177.484896 -278.54207) (xy 177.528762 -278.518819) (xy 177.575813 -278.502971) (xy 177.624808 -278.494943)
			(xy 177.649632 -278.49449) (xy 177.658736 -278.494587) (xy 177.676909 -278.49573) (xy 177.685954 -278.496776)
			(xy 177.686208 -278.496776) (xy 177.698007 -278.497583) (xy 177.720246 -278.489621) (xy 177.72888 -278.481536)
			(xy 177.793396 -278.413972) (xy 177.800508 -278.391366) (xy 177.799492 -278.384762) (xy 177.796909 -278.36991)
			(xy 177.794112 -278.339892) (xy 177.793904 -278.324818) (xy 177.793904 -278.25446) (xy 177.793337 -278.24377)
			(xy 177.784675 -278.224219) (xy 177.77714 -278.216614) (xy 177.721006 -278.166068) (xy 177.712784 -278.159289)
			(xy 177.692529 -278.152726) (xy 177.68189 -278.153368) (xy 177.681636 -278.153368) (xy 177.649632 -278.155146)
			(xy 177.625638 -278.154678) (xy 177.57824 -278.147176) (xy 177.5326 -278.132352) (xy 177.48984 -278.110571)
			(xy 177.451014 -278.082368) (xy 177.417077 -278.04844) (xy 177.388866 -278.00962) (xy 177.367075 -277.966865)
			(xy 177.35224 -277.921228) (xy 177.344728 -277.873832) (xy 177.344324 -277.849838) (xy 177.344422 -277.840734)
			(xy 177.345567 -277.822561) (xy 177.34661 -277.813516) (xy 177.347413 -277.801621) (xy 177.339336 -277.779224)
			(xy 177.331116 -277.77059) (xy 177.263552 -277.706074) (xy 177.240946 -277.699216) (xy 177.235866 -277.699978)
			(xy 177.221518 -277.702501) (xy 177.192519 -277.705299) (xy 177.177954 -277.705566) (xy 177.163541 -277.705593)
			(xy 177.134797 -277.703434) (xy 177.12055 -277.701248) (xy 177.108612 -277.699216) (xy 177.085752 -277.706328)
			(xy 177.018188 -277.771098) (xy 177.010196 -277.779628) (xy 177.002272 -277.801591) (xy 177.002948 -277.813262)
			(xy 177.002948 -277.813516) (xy 177.003995 -277.82256) (xy 177.005137 -277.840734) (xy 177.005234 -277.849838)
			(xy 177.004761 -277.873828) (xy 176.99725 -277.921217) (xy 176.982419 -277.966847) (xy 176.960634 -278.009597)
			(xy 176.932431 -278.048412) (xy 176.898503 -278.082339) (xy 176.859686 -278.110541) (xy 176.816936 -278.132324)
			(xy 176.771305 -278.147153) (xy 176.723916 -278.154662) (xy 176.699926 -278.155146) (xy 176.668176 -278.153368)
			(xy 176.667668 -278.153368) (xy 176.657051 -278.152861) (xy 176.636861 -278.159436) (xy 176.628552 -278.166068)
			(xy 176.572418 -278.216614) (xy 176.564763 -278.224133) (xy 176.556089 -278.243738) (xy 176.555654 -278.25446)
			(xy 176.555654 -278.324818) (xy 176.555454 -278.339829) (xy 176.552654 -278.369721) (xy 176.550066 -278.384508)
			(xy 176.550066 -278.385524) (xy 176.54905 -278.391112) (xy 176.556162 -278.413718) (xy 176.620678 -278.481282)
			(xy 176.629317 -278.489497) (xy 176.65171 -278.497583) (xy 176.663604 -278.496776) (xy 176.672648 -278.495728)
			(xy 176.690822 -278.494586) (xy 176.699926 -278.49449) (xy 176.724747 -278.494978) (xy 176.773733 -278.503013)
			(xy 176.820775 -278.518867) (xy 176.864631 -278.542123) (xy 176.904148 -278.572168) (xy 176.938284 -278.608209)
			(xy 176.966139 -278.649299) (xy 176.98698 -278.694353) (xy 177.000257 -278.742186) (xy 177.005621 -278.791536)
			(xy 177.002931 -278.841105) (xy 176.992257 -278.889585) (xy 176.97388 -278.935699) (xy 176.948285 -278.978233)
			(xy 176.916147 -279.016067) (xy 176.878311 -279.048202) (xy 176.835774 -279.073793) (xy 176.789658 -279.092165)
			(xy 176.741177 -279.102835) (xy 176.691608 -279.105521) (xy 176.642258 -279.100152) (xy 176.594427 -279.08687)
			(xy 176.549374 -279.066025) (xy 176.508287 -279.038166) (xy 176.472249 -279.004027) (xy 176.442208 -278.964508)
			(xy 176.418956 -278.920649) (xy 176.403106 -278.873606) (xy 176.395076 -278.824619) (xy 176.394618 -278.799798)
			(xy 176.394723 -278.790757) (xy 176.395868 -278.772712) (xy 176.396904 -278.76373) (xy 176.396904 -278.763222)
			(xy 176.398174 -278.751538) (xy 176.390046 -278.729186) (xy 176.313846 -278.656288) (xy 176.29124 -278.649176)
			(xy 176.284128 -278.650446) (xy 176.270151 -278.652836) (xy 176.241918 -278.655508) (xy 176.22774 -278.65578)
			(xy 176.224438 -278.65578) (xy 176.209109 -278.655633) (xy 176.178578 -278.652835) (xy 176.163478 -278.650192)
			(xy 176.161954 -278.649938) (xy 176.158144 -278.649176) (xy 176.135538 -278.656288) (xy 176.059592 -278.729186)
			(xy 176.051464 -278.751538) (xy 176.052988 -278.763476) (xy 176.053976 -278.772523) (xy 176.054992 -278.790697)
			(xy 176.05502 -278.799798) (xy 176.054534 -278.82462) (xy 176.046503 -278.87361) (xy 176.030652 -278.920656)
			(xy 176.007398 -278.964517) (xy 175.977355 -279.004038) (xy 175.941313 -279.038179) (xy 175.900223 -279.066038)
			(xy 175.855167 -279.086883) (xy 175.807333 -279.100164) (xy 175.757979 -279.105531) (xy 175.708408 -279.102843)
			(xy 175.659925 -279.09217) (xy 175.613807 -279.073794) (xy 175.571269 -279.0482) (xy 175.533433 -279.01606)
			(xy 175.501295 -278.978223) (xy 175.475701 -278.935684) (xy 175.457327 -278.889566) (xy 175.446656 -278.841082)
			(xy 175.443969 -278.791511) (xy 175.449338 -278.742158) (xy 175.462621 -278.694323) (xy 175.483467 -278.649268)
			(xy 175.511328 -278.608179) (xy 175.545469 -278.572139) (xy 175.584991 -278.542097) (xy 175.628853 -278.518844)
			(xy 175.675899 -278.502995) (xy 175.72489 -278.494965) (xy 175.749712 -278.49449) (xy 175.758749 -278.494538)
			(xy 175.776794 -278.495557) (xy 175.78578 -278.496522) (xy 175.797718 -278.498046) (xy 175.82007 -278.489918)
			(xy 175.892968 -278.413718) (xy 175.90008 -278.391112) (xy 175.899064 -278.38527) (xy 175.896458 -278.370293)
			(xy 175.893661 -278.340019) (xy 175.893476 -278.324818) (xy 175.893476 -278.25446) (xy 175.892909 -278.24377)
			(xy 175.884243 -278.224223) (xy 175.876712 -278.216614) (xy 175.812704 -278.158956) (xy 175.791876 -278.152352)
			(xy 175.781462 -278.153622) (xy 175.749712 -278.155146) (xy 175.725719 -278.154676) (xy 175.678324 -278.147172)
			(xy 175.632686 -278.132346) (xy 175.589929 -278.110564) (xy 175.551105 -278.082361) (xy 175.517171 -278.048433)
			(xy 175.488962 -278.009614) (xy 175.467173 -277.966861) (xy 175.45234 -277.921225) (xy 175.444828 -277.873831)
			(xy 175.444404 -277.849838) (xy 175.444884 -277.825149) (xy 175.452841 -277.776415) (xy 175.468537 -277.729597)
			(xy 175.491563 -277.685916) (xy 175.521319 -277.64651) (xy 175.55703 -277.612406) (xy 175.597763 -277.584494)
			(xy 175.642457 -277.563501) (xy 175.689947 -277.549975) (xy 175.714406 -277.546562) (xy 175.72863 -277.545038)
			(xy 175.75149 -277.52675) (xy 175.786542 -277.42642) (xy 175.789259 -277.41729) (xy 175.788461 -277.398272)
			(xy 175.780809 -277.380842) (xy 175.77435 -277.373842) (xy 175.276002 -276.875494) (xy 175.269017 -276.869)
			(xy 175.251585 -276.861298) (xy 175.232543 -276.860515) (xy 175.223424 -276.863302) (xy 175.123094 -276.898354)
			(xy 175.104806 -276.921214) (xy 175.103282 -276.935438) (xy 175.099937 -276.959895) (xy 175.086377 -277.007358)
			(xy 175.065358 -277.052019) (xy 175.037425 -277.092717) (xy 175.003309 -277.128391) (xy 174.963897 -277.15811)
			(xy 174.920217 -277.1811) (xy 174.873407 -277.196763) (xy 174.824687 -277.204691) (xy 174.800006 -277.205186)
			(xy 174.776013 -277.20474) (xy 174.728618 -277.197234) (xy 174.682981 -277.182406) (xy 174.640226 -277.16062)
			(xy 174.601405 -277.132415) (xy 174.567475 -277.098483) (xy 174.539271 -277.05966) (xy 174.517488 -277.016904)
			(xy 174.502662 -276.971266) (xy 174.495159 -276.923871) (xy 174.494698 -276.899878) (xy 174.494791 -276.89071)
			(xy 174.495936 -276.87241) (xy 174.496984 -276.863302) (xy 174.498508 -276.851618) (xy 174.49038 -276.828758)
			(xy 174.413926 -276.756114) (xy 174.39132 -276.749256) (xy 174.383192 -276.750526) (xy 174.368706 -276.752922)
			(xy 174.339454 -276.75547) (xy 174.324772 -276.755606) (xy 174.309506 -276.75545) (xy 174.279103 -276.752654)
			(xy 174.264066 -276.750018) (xy 174.262542 -276.749764) (xy 174.258478 -276.749002) (xy 174.235872 -276.756114)
			(xy 174.168308 -276.820884) (xy 174.160311 -276.829412) (xy 174.152377 -276.851377) (xy 174.153068 -276.863048)
			(xy 174.153068 -276.863556) (xy 174.154117 -276.8726) (xy 174.155262 -276.890774) (xy 174.155354 -276.899878)
			(xy 174.15487 -276.924704) (xy 174.146841 -276.973702) (xy 174.130989 -277.020755) (xy 174.107734 -277.064624)
			(xy 174.077688 -277.104153) (xy 174.041642 -277.138299) (xy 174.000547 -277.166164) (xy 173.955485 -277.187013)
			(xy 173.907643 -277.200297) (xy 173.858283 -277.205665) (xy 173.808704 -277.202977) (xy 173.760213 -277.192303)
			(xy 173.714088 -277.173924) (xy 173.671545 -277.148325) (xy 173.633703 -277.11618) (xy 173.601561 -277.078336)
			(xy 173.575965 -277.03579) (xy 173.55759 -276.989664) (xy 173.54692 -276.941172) (xy 173.544235 -276.891593)
			(xy 173.549608 -276.842233) (xy 173.562895 -276.794393) (xy 173.583748 -276.749332) (xy 173.611616 -276.708239)
			(xy 173.645765 -276.672196) (xy 173.685296 -276.642153) (xy 173.729167 -276.618901) (xy 173.776221 -276.603054)
			(xy 173.82522 -276.595028) (xy 173.850046 -276.59457) (xy 173.859147 -276.594611) (xy 173.877319 -276.59563)
			(xy 173.886368 -276.596602) (xy 173.898306 -276.598126) (xy 173.920658 -276.589998) (xy 173.993556 -276.513798)
			(xy 174.000668 -276.491192) (xy 173.999652 -276.485096) (xy 173.997058 -276.470181) (xy 173.994261 -276.440035)
			(xy 173.994064 -276.424898) (xy 173.994064 -276.424644) (xy 173.994221 -276.409378) (xy 173.99702 -276.378976)
			(xy 173.999652 -276.363938) (xy 173.999652 -276.363176) (xy 174.000414 -276.358604) (xy 173.993556 -276.335998)
			(xy 173.920658 -276.259798) (xy 173.898306 -276.25167) (xy 173.886368 -276.253194) (xy 173.877321 -276.254184)
			(xy 173.859147 -276.255202) (xy 173.850046 -276.255226) (xy 173.824784 -276.254737) (xy 173.774949 -276.246428)
			(xy 173.727161 -276.230029) (xy 173.682725 -276.205987) (xy 173.642852 -276.174958) (xy 173.608631 -276.137789)
			(xy 173.580995 -276.095495) (xy 173.560698 -276.049228) (xy 173.548295 -276.000251) (xy 173.544122 -275.9499)
			(xy 173.548295 -275.899549) (xy 173.560698 -275.850572) (xy 173.580995 -275.804305) (xy 173.608631 -275.762011)
			(xy 173.642852 -275.724842) (xy 173.682725 -275.693813) (xy 173.727161 -275.669771) (xy 173.774949 -275.653372)
			(xy 173.824784 -275.645063) (xy 173.850046 -275.64461) (xy 173.85902 -275.644651) (xy 173.876939 -275.645667)
			(xy 173.88586 -275.646642) (xy 173.897757 -275.647451) (xy 173.920166 -275.639385) (xy 173.928786 -275.631148)
			(xy 173.993048 -275.563838) (xy 174.00016 -275.541232) (xy 173.99889 -275.533866) (xy 173.996403 -275.519261)
			(xy 173.993732 -275.489752) (xy 173.993556 -275.474938) (xy 173.993556 -275.40458) (xy 173.992992 -275.393889)
			(xy 173.984329 -275.374338) (xy 173.976792 -275.366734) (xy 173.912784 -275.309076) (xy 173.891956 -275.302472)
			(xy 173.881542 -275.303742) (xy 173.850046 -275.305266) (xy 173.824789 -275.304777) (xy 173.774964 -275.29647)
			(xy 173.727185 -275.280074) (xy 173.682758 -275.256037) (xy 173.642893 -275.225014) (xy 173.608679 -275.187853)
			(xy 173.581048 -275.145566) (xy 173.560755 -275.099308) (xy 173.548354 -275.050341) (xy 173.544182 -275)
			(xy 173.548354 -274.949659) (xy 173.560755 -274.900692) (xy 173.581048 -274.854434) (xy 173.608679 -274.812147)
			(xy 173.642893 -274.774986) (xy 173.682758 -274.743964) (xy 173.727185 -274.719926) (xy 173.774964 -274.70353)
			(xy 173.824789 -274.695223) (xy 173.850046 -274.69465) (xy 173.881542 -274.696174) (xy 173.891956 -274.697444)
			(xy 173.912784 -274.69084) (xy 173.976792 -274.633182) (xy 173.984445 -274.625662) (xy 173.993116 -274.606058)
			(xy 173.993556 -274.595336) (xy 173.993556 -274.524724) (xy 173.993743 -274.509649) (xy 173.996538 -274.479629)
			(xy 173.999144 -274.46478) (xy 173.999144 -274.463764) (xy 174.00016 -274.45843) (xy 173.993048 -274.435824)
			(xy 173.92015 -274.359624) (xy 173.897798 -274.351496) (xy 173.88586 -274.35302) (xy 173.876938 -274.353984)
			(xy 173.85902 -274.355003) (xy 173.850046 -274.355052) (xy 173.824782 -274.354563) (xy 173.774943 -274.346253)
			(xy 173.727151 -274.329852) (xy 173.682711 -274.305808) (xy 173.642835 -274.274777) (xy 173.608611 -274.237605)
			(xy 173.580972 -274.195307) (xy 173.560674 -274.149036) (xy 173.548269 -274.100055) (xy 173.544096 -274.0497)
			(xy 173.548269 -273.999345) (xy 173.560674 -273.950364) (xy 173.580972 -273.904093) (xy 173.608611 -273.861795)
			(xy 173.642835 -273.824623) (xy 173.682711 -273.793591) (xy 173.727151 -273.769548) (xy 173.774943 -273.753147)
			(xy 173.824782 -273.744837) (xy 173.850046 -273.744436) (xy 173.859147 -273.744477) (xy 173.877319 -273.745496)
			(xy 173.886368 -273.746468) (xy 173.898306 -273.747992) (xy 173.920658 -273.739864) (xy 173.993556 -273.663664)
			(xy 174.000414 -273.641058) (xy 173.999652 -273.635724) (xy 173.997034 -273.620684) (xy 173.994234 -273.590283)
			(xy 173.994064 -273.575018) (xy 173.994064 -273.57451) (xy 173.994246 -273.559372) (xy 173.997045 -273.529225)
			(xy 173.999652 -273.514312) (xy 173.999652 -273.513296) (xy 174.000414 -273.50847) (xy 173.993556 -273.485864)
			(xy 173.920658 -273.409664) (xy 173.898306 -273.401536) (xy 173.886368 -273.40306) (xy 173.877321 -273.40405)
			(xy 173.859147 -273.405067) (xy 173.850046 -273.405092) (xy 173.824787 -273.404603) (xy 173.774957 -273.396295)
			(xy 173.727175 -273.379897) (xy 173.682744 -273.355858) (xy 173.642875 -273.324833) (xy 173.608658 -273.287669)
			(xy 173.581025 -273.245378) (xy 173.560731 -273.199117) (xy 173.548328 -273.150145) (xy 173.544156 -273.0998)
			(xy 173.548328 -273.049455) (xy 173.560731 -273.000483) (xy 173.581025 -272.954222) (xy 173.608658 -272.911931)
			(xy 173.642875 -272.874767) (xy 173.682744 -272.843742) (xy 173.727175 -272.819703) (xy 173.774957 -272.803305)
			(xy 173.824787 -272.794997) (xy 173.850046 -272.794476) (xy 173.859147 -272.794517) (xy 173.877319 -272.795536)
			(xy 173.886368 -272.796508) (xy 173.898306 -272.798032) (xy 173.920658 -272.789904) (xy 173.993556 -272.713704)
			(xy 174.000414 -272.691098) (xy 173.999652 -272.685764) (xy 173.997037 -272.670724) (xy 173.994243 -272.640323)
			(xy 173.994064 -272.625058) (xy 173.994064 -272.62455) (xy 173.994271 -272.609927) (xy 173.996943 -272.580801)
			(xy 173.999398 -272.566384) (xy 173.999398 -272.565368) (xy 174.000668 -272.558256) (xy 173.993556 -272.53565)
			(xy 173.920912 -272.459196) (xy 173.898052 -272.451068) (xy 173.886368 -272.452592) (xy 173.87726 -272.453645)
			(xy 173.85896 -272.454786) (xy 173.849792 -272.454878) (xy 173.82454 -272.454356) (xy 173.774724 -272.446042)
			(xy 173.726956 -272.429642) (xy 173.682538 -272.405604) (xy 173.642684 -272.374582) (xy 173.608478 -272.337424)
			(xy 173.580855 -272.295143) (xy 173.560568 -272.248892) (xy 173.54817 -272.199932) (xy 173.543999 -272.1496)
			(xy 173.54817 -272.099268) (xy 173.560568 -272.050308) (xy 173.580855 -272.004057) (xy 173.608478 -271.961776)
			(xy 173.642684 -271.924618) (xy 173.682538 -271.893596) (xy 173.726956 -271.869558) (xy 173.774724 -271.853158)
			(xy 173.82454 -271.844844) (xy 173.849792 -271.844262) (xy 173.876356 -271.844836) (xy 173.92868 -271.854038)
			(xy 173.978619 -271.872165) (xy 174.001938 -271.884902) (xy 174.0027 -271.88541) (xy 174.008424 -271.888368)
			(xy 174.020897 -271.891581) (xy 174.027338 -271.89176) (xy 174.027592 -271.89176) (xy 174.037611 -271.891341)
			(xy 174.056124 -271.883671) (xy 174.070289 -271.869497) (xy 174.077947 -271.85098) (xy 174.078392 -271.84096)
			(xy 174.078392 -271.833594) (xy 174.077916 -271.823627) (xy 174.070343 -271.805188) (xy 174.06366 -271.79778)
			(xy 173.810168 -271.544288) (xy 173.807315 -271.541586) (xy 173.800933 -271.537) (xy 173.797468 -271.535144)
			(xy 173.792042 -271.532558) (xy 173.780362 -271.529729) (xy 173.774354 -271.529556) (xy 150.5331 -271.529556)
			(xy 150.523956 -271.530318) (xy 150.510494 -271.532858) (xy 150.508462 -271.53362) (xy 150.504743 -271.53528)
			(xy 150.497851 -271.539621) (xy 150.494746 -271.542256) (xy 150.494746 -271.54251) (xy 150.489167 -271.547684)
			(xy 150.481161 -271.560614) (xy 150.478998 -271.56791) (xy 150.478236 -271.57172) (xy 150.477982 -271.573498)
			(xy 150.463721 -271.670089) (xy 150.428299 -271.862123) (xy 150.385057 -272.052548) (xy 150.358813 -272.14957)
			(xy 160.243786 -272.14957) (xy 160.247746 -272.100516) (xy 160.259523 -272.052732) (xy 160.278814 -272.007456)
			(xy 160.305117 -271.96586) (xy 160.337752 -271.929023) (xy 160.375873 -271.897898) (xy 160.418494 -271.873291)
			(xy 160.46451 -271.855839) (xy 160.512729 -271.845995) (xy 160.561904 -271.844014) (xy 160.610759 -271.849946)
			(xy 160.65803 -271.863638) (xy 160.702492 -271.884736) (xy 160.742995 -271.912692) (xy 160.778488 -271.946784)
			(xy 160.808053 -271.986128) (xy 160.830924 -272.029705) (xy 160.846508 -272.076386) (xy 160.854403 -272.124963)
			(xy 160.854898 -272.14957) (xy 162.14396 -272.14957) (xy 162.14792 -272.100516) (xy 162.159697 -272.052732)
			(xy 162.178988 -272.007456) (xy 162.205291 -271.96586) (xy 162.237926 -271.929023) (xy 162.276047 -271.897898)
			(xy 162.318668 -271.873291) (xy 162.364684 -271.855839) (xy 162.412903 -271.845995) (xy 162.462078 -271.844014)
			(xy 162.510933 -271.849946) (xy 162.558204 -271.863638) (xy 162.602666 -271.884736) (xy 162.643169 -271.912692)
			(xy 162.678662 -271.946784) (xy 162.708227 -271.986128) (xy 162.731098 -272.029705) (xy 162.746682 -272.076386)
			(xy 162.754577 -272.124963) (xy 162.755072 -272.14957) (xy 164.04388 -272.14957) (xy 164.04784 -272.100516)
			(xy 164.059617 -272.052732) (xy 164.078908 -272.007456) (xy 164.105211 -271.96586) (xy 164.137846 -271.929023)
			(xy 164.175967 -271.897898) (xy 164.218588 -271.873291) (xy 164.264604 -271.855839) (xy 164.312823 -271.845995)
			(xy 164.361998 -271.844014) (xy 164.410853 -271.849946) (xy 164.458124 -271.863638) (xy 164.502586 -271.884736)
			(xy 164.543089 -271.912692) (xy 164.578582 -271.946784) (xy 164.608147 -271.986128) (xy 164.631018 -272.029705)
			(xy 164.646602 -272.076386) (xy 164.654497 -272.124963) (xy 164.654992 -272.14957) (xy 165.9438 -272.14957)
			(xy 165.94776 -272.100516) (xy 165.959537 -272.052732) (xy 165.978828 -272.007456) (xy 166.005131 -271.96586)
			(xy 166.037766 -271.929023) (xy 166.075887 -271.897898) (xy 166.118508 -271.873291) (xy 166.164524 -271.855839)
			(xy 166.212743 -271.845995) (xy 166.261918 -271.844014) (xy 166.310773 -271.849946) (xy 166.358044 -271.863638)
			(xy 166.402506 -271.884736) (xy 166.443009 -271.912692) (xy 166.478502 -271.946784) (xy 166.508067 -271.986128)
			(xy 166.530938 -272.029705) (xy 166.546522 -272.076386) (xy 166.554417 -272.124963) (xy 166.554912 -272.14957)
			(xy 167.843974 -272.14957) (xy 167.847934 -272.100516) (xy 167.859711 -272.052732) (xy 167.879002 -272.007456)
			(xy 167.905305 -271.96586) (xy 167.93794 -271.929023) (xy 167.976061 -271.897898) (xy 168.018682 -271.873291)
			(xy 168.064698 -271.855839) (xy 168.112917 -271.845995) (xy 168.162092 -271.844014) (xy 168.210947 -271.849946)
			(xy 168.258218 -271.863638) (xy 168.30268 -271.884736) (xy 168.343183 -271.912692) (xy 168.378676 -271.946784)
			(xy 168.408241 -271.986128) (xy 168.431112 -272.029705) (xy 168.446696 -272.076386) (xy 168.454591 -272.124963)
			(xy 168.455086 -272.14957) (xy 169.743894 -272.14957) (xy 169.747854 -272.100516) (xy 169.759631 -272.052732)
			(xy 169.778922 -272.007456) (xy 169.805225 -271.96586) (xy 169.83786 -271.929023) (xy 169.875981 -271.897898)
			(xy 169.918602 -271.873291) (xy 169.964618 -271.855839) (xy 170.012837 -271.845995) (xy 170.062012 -271.844014)
			(xy 170.110867 -271.849946) (xy 170.158138 -271.863638) (xy 170.2026 -271.884736) (xy 170.243103 -271.912692)
			(xy 170.278596 -271.946784) (xy 170.308161 -271.986128) (xy 170.331032 -272.029705) (xy 170.346616 -272.076386)
			(xy 170.354511 -272.124963) (xy 170.355006 -272.14957) (xy 171.643814 -272.14957) (xy 171.647774 -272.100516)
			(xy 171.659551 -272.052732) (xy 171.678842 -272.007456) (xy 171.705145 -271.96586) (xy 171.73778 -271.929023)
			(xy 171.775901 -271.897898) (xy 171.818522 -271.873291) (xy 171.864538 -271.855839) (xy 171.912757 -271.845995)
			(xy 171.961932 -271.844014) (xy 172.010787 -271.849946) (xy 172.058058 -271.863638) (xy 172.10252 -271.884736)
			(xy 172.143023 -271.912692) (xy 172.178516 -271.946784) (xy 172.208081 -271.986128) (xy 172.230952 -272.029705)
			(xy 172.246536 -272.076386) (xy 172.254431 -272.124963) (xy 172.254926 -272.14957) (xy 172.254431 -272.174177)
			(xy 172.246536 -272.222754) (xy 172.230952 -272.269435) (xy 172.208081 -272.313012) (xy 172.178516 -272.352356)
			(xy 172.143023 -272.386448) (xy 172.10252 -272.414404) (xy 172.058058 -272.435502) (xy 172.010787 -272.449194)
			(xy 171.961932 -272.455126) (xy 171.912757 -272.453145) (xy 171.864538 -272.443301) (xy 171.818522 -272.425849)
			(xy 171.775901 -272.401242) (xy 171.73778 -272.370117) (xy 171.705145 -272.33328) (xy 171.678842 -272.291684)
			(xy 171.659551 -272.246408) (xy 171.647774 -272.198624) (xy 171.643814 -272.14957) (xy 170.355006 -272.14957)
			(xy 170.354511 -272.174177) (xy 170.346616 -272.222754) (xy 170.331032 -272.269435) (xy 170.308161 -272.313012)
			(xy 170.278596 -272.352356) (xy 170.243103 -272.386448) (xy 170.2026 -272.414404) (xy 170.158138 -272.435502)
			(xy 170.110867 -272.449194) (xy 170.062012 -272.455126) (xy 170.012837 -272.453145) (xy 169.964618 -272.443301)
			(xy 169.918602 -272.425849) (xy 169.875981 -272.401242) (xy 169.83786 -272.370117) (xy 169.805225 -272.33328)
			(xy 169.778922 -272.291684) (xy 169.759631 -272.246408) (xy 169.747854 -272.198624) (xy 169.743894 -272.14957)
			(xy 168.455086 -272.14957) (xy 168.454591 -272.174177) (xy 168.446696 -272.222754) (xy 168.431112 -272.269435)
			(xy 168.408241 -272.313012) (xy 168.378676 -272.352356) (xy 168.343183 -272.386448) (xy 168.30268 -272.414404)
			(xy 168.258218 -272.435502) (xy 168.210947 -272.449194) (xy 168.162092 -272.455126) (xy 168.112917 -272.453145)
			(xy 168.064698 -272.443301) (xy 168.018682 -272.425849) (xy 167.976061 -272.401242) (xy 167.93794 -272.370117)
			(xy 167.905305 -272.33328) (xy 167.879002 -272.291684) (xy 167.859711 -272.246408) (xy 167.847934 -272.198624)
			(xy 167.843974 -272.14957) (xy 166.554912 -272.14957) (xy 166.554417 -272.174177) (xy 166.546522 -272.222754)
			(xy 166.530938 -272.269435) (xy 166.508067 -272.313012) (xy 166.478502 -272.352356) (xy 166.443009 -272.386448)
			(xy 166.402506 -272.414404) (xy 166.358044 -272.435502) (xy 166.310773 -272.449194) (xy 166.261918 -272.455126)
			(xy 166.212743 -272.453145) (xy 166.164524 -272.443301) (xy 166.118508 -272.425849) (xy 166.075887 -272.401242)
			(xy 166.037766 -272.370117) (xy 166.005131 -272.33328) (xy 165.978828 -272.291684) (xy 165.959537 -272.246408)
			(xy 165.94776 -272.198624) (xy 165.9438 -272.14957) (xy 164.654992 -272.14957) (xy 164.654497 -272.174177)
			(xy 164.646602 -272.222754) (xy 164.631018 -272.269435) (xy 164.608147 -272.313012) (xy 164.578582 -272.352356)
			(xy 164.543089 -272.386448) (xy 164.502586 -272.414404) (xy 164.458124 -272.435502) (xy 164.410853 -272.449194)
			(xy 164.361998 -272.455126) (xy 164.312823 -272.453145) (xy 164.264604 -272.443301) (xy 164.218588 -272.425849)
			(xy 164.175967 -272.401242) (xy 164.137846 -272.370117) (xy 164.105211 -272.33328) (xy 164.078908 -272.291684)
			(xy 164.059617 -272.246408) (xy 164.04784 -272.198624) (xy 164.04388 -272.14957) (xy 162.755072 -272.14957)
			(xy 162.754577 -272.174177) (xy 162.746682 -272.222754) (xy 162.731098 -272.269435) (xy 162.708227 -272.313012)
			(xy 162.678662 -272.352356) (xy 162.643169 -272.386448) (xy 162.602666 -272.414404) (xy 162.558204 -272.435502)
			(xy 162.510933 -272.449194) (xy 162.462078 -272.455126) (xy 162.412903 -272.453145) (xy 162.364684 -272.443301)
			(xy 162.318668 -272.425849) (xy 162.276047 -272.401242) (xy 162.237926 -272.370117) (xy 162.205291 -272.33328)
			(xy 162.178988 -272.291684) (xy 162.159697 -272.246408) (xy 162.14792 -272.198624) (xy 162.14396 -272.14957)
			(xy 160.854898 -272.14957) (xy 160.854403 -272.174177) (xy 160.846508 -272.222754) (xy 160.830924 -272.269435)
			(xy 160.808053 -272.313012) (xy 160.778488 -272.352356) (xy 160.742995 -272.386448) (xy 160.702492 -272.414404)
			(xy 160.65803 -272.435502) (xy 160.610759 -272.449194) (xy 160.561904 -272.455126) (xy 160.512729 -272.453145)
			(xy 160.46451 -272.443301) (xy 160.418494 -272.425849) (xy 160.375873 -272.401242) (xy 160.337752 -272.370117)
			(xy 160.305117 -272.33328) (xy 160.278814 -272.291684) (xy 160.259523 -272.246408) (xy 160.247746 -272.198624)
			(xy 160.243786 -272.14957) (xy 150.358813 -272.14957) (xy 150.334069 -272.241047) (xy 150.27542 -272.427305)
			(xy 150.209206 -272.61101) (xy 150.203587 -272.624804) (xy 154.0693 -272.624804) (xy 154.07326 -272.57575)
			(xy 154.085037 -272.527966) (xy 154.104328 -272.48269) (xy 154.130631 -272.441094) (xy 154.163266 -272.404257)
			(xy 154.201387 -272.373132) (xy 154.244008 -272.348525) (xy 154.290024 -272.331073) (xy 154.338243 -272.321229)
			(xy 154.387418 -272.319248) (xy 154.436273 -272.32518) (xy 154.483544 -272.338872) (xy 154.528006 -272.35997)
			(xy 154.568509 -272.387926) (xy 154.604002 -272.422018) (xy 154.633567 -272.461362) (xy 154.656438 -272.504939)
			(xy 154.672022 -272.55162) (xy 154.679917 -272.600197) (xy 154.680412 -272.624804) (xy 155.01926 -272.624804)
			(xy 155.02322 -272.57575) (xy 155.034997 -272.527966) (xy 155.054288 -272.48269) (xy 155.080591 -272.441094)
			(xy 155.113226 -272.404257) (xy 155.151347 -272.373132) (xy 155.193968 -272.348525) (xy 155.239984 -272.331073)
			(xy 155.288203 -272.321229) (xy 155.337378 -272.319248) (xy 155.386233 -272.32518) (xy 155.433504 -272.338872)
			(xy 155.477966 -272.35997) (xy 155.518469 -272.387926) (xy 155.553962 -272.422018) (xy 155.583527 -272.461362)
			(xy 155.606398 -272.504939) (xy 155.621982 -272.55162) (xy 155.629877 -272.600197) (xy 155.630372 -272.624804)
			(xy 155.96922 -272.624804) (xy 155.97318 -272.57575) (xy 155.984957 -272.527966) (xy 156.004248 -272.48269)
			(xy 156.030551 -272.441094) (xy 156.063186 -272.404257) (xy 156.101307 -272.373132) (xy 156.143928 -272.348525)
			(xy 156.189944 -272.331073) (xy 156.238163 -272.321229) (xy 156.287338 -272.319248) (xy 156.336193 -272.32518)
			(xy 156.383464 -272.338872) (xy 156.427926 -272.35997) (xy 156.468429 -272.387926) (xy 156.503922 -272.422018)
			(xy 156.533487 -272.461362) (xy 156.556358 -272.504939) (xy 156.571942 -272.55162) (xy 156.579837 -272.600197)
			(xy 156.580332 -272.624804) (xy 156.91918 -272.624804) (xy 156.92314 -272.57575) (xy 156.934917 -272.527966)
			(xy 156.954208 -272.48269) (xy 156.980511 -272.441094) (xy 157.013146 -272.404257) (xy 157.051267 -272.373132)
			(xy 157.093888 -272.348525) (xy 157.139904 -272.331073) (xy 157.188123 -272.321229) (xy 157.237298 -272.319248)
			(xy 157.286153 -272.32518) (xy 157.333424 -272.338872) (xy 157.377886 -272.35997) (xy 157.418389 -272.387926)
			(xy 157.453882 -272.422018) (xy 157.483447 -272.461362) (xy 157.506318 -272.504939) (xy 157.521902 -272.55162)
			(xy 157.529797 -272.600197) (xy 157.530292 -272.624804) (xy 157.86914 -272.624804) (xy 157.8731 -272.57575)
			(xy 157.884877 -272.527966) (xy 157.904168 -272.48269) (xy 157.930471 -272.441094) (xy 157.963106 -272.404257)
			(xy 158.001227 -272.373132) (xy 158.043848 -272.348525) (xy 158.089864 -272.331073) (xy 158.138083 -272.321229)
			(xy 158.187258 -272.319248) (xy 158.236113 -272.32518) (xy 158.283384 -272.338872) (xy 158.327846 -272.35997)
			(xy 158.368349 -272.387926) (xy 158.403842 -272.422018) (xy 158.433407 -272.461362) (xy 158.456278 -272.504939)
			(xy 158.471862 -272.55162) (xy 158.479757 -272.600197) (xy 158.480252 -272.624804) (xy 158.479757 -272.649411)
			(xy 158.471862 -272.697988) (xy 158.456278 -272.744669) (xy 158.433407 -272.788246) (xy 158.403842 -272.82759)
			(xy 158.368349 -272.861682) (xy 158.327846 -272.889638) (xy 158.283384 -272.910736) (xy 158.236113 -272.924428)
			(xy 158.187258 -272.93036) (xy 158.138083 -272.928379) (xy 158.089864 -272.918535) (xy 158.043848 -272.901083)
			(xy 158.001227 -272.876476) (xy 157.963106 -272.845351) (xy 157.930471 -272.808514) (xy 157.904168 -272.766918)
			(xy 157.884877 -272.721642) (xy 157.8731 -272.673858) (xy 157.86914 -272.624804) (xy 157.530292 -272.624804)
			(xy 157.529797 -272.649411) (xy 157.521902 -272.697988) (xy 157.506318 -272.744669) (xy 157.483447 -272.788246)
			(xy 157.453882 -272.82759) (xy 157.418389 -272.861682) (xy 157.377886 -272.889638) (xy 157.333424 -272.910736)
			(xy 157.286153 -272.924428) (xy 157.237298 -272.93036) (xy 157.188123 -272.928379) (xy 157.139904 -272.918535)
			(xy 157.093888 -272.901083) (xy 157.051267 -272.876476) (xy 157.013146 -272.845351) (xy 156.980511 -272.808514)
			(xy 156.954208 -272.766918) (xy 156.934917 -272.721642) (xy 156.92314 -272.673858) (xy 156.91918 -272.624804)
			(xy 156.580332 -272.624804) (xy 156.579837 -272.649411) (xy 156.571942 -272.697988) (xy 156.556358 -272.744669)
			(xy 156.533487 -272.788246) (xy 156.503922 -272.82759) (xy 156.468429 -272.861682) (xy 156.427926 -272.889638)
			(xy 156.383464 -272.910736) (xy 156.336193 -272.924428) (xy 156.287338 -272.93036) (xy 156.238163 -272.928379)
			(xy 156.189944 -272.918535) (xy 156.143928 -272.901083) (xy 156.101307 -272.876476) (xy 156.063186 -272.845351)
			(xy 156.030551 -272.808514) (xy 156.004248 -272.766918) (xy 155.984957 -272.721642) (xy 155.97318 -272.673858)
			(xy 155.96922 -272.624804) (xy 155.630372 -272.624804) (xy 155.629877 -272.649411) (xy 155.621982 -272.697988)
			(xy 155.606398 -272.744669) (xy 155.583527 -272.788246) (xy 155.553962 -272.82759) (xy 155.518469 -272.861682)
			(xy 155.477966 -272.889638) (xy 155.433504 -272.910736) (xy 155.386233 -272.924428) (xy 155.337378 -272.93036)
			(xy 155.288203 -272.928379) (xy 155.239984 -272.918535) (xy 155.193968 -272.901083) (xy 155.151347 -272.876476)
			(xy 155.113226 -272.845351) (xy 155.080591 -272.808514) (xy 155.054288 -272.766918) (xy 155.034997 -272.721642)
			(xy 155.02322 -272.673858) (xy 155.01926 -272.624804) (xy 154.680412 -272.624804) (xy 154.679917 -272.649411)
			(xy 154.672022 -272.697988) (xy 154.656438 -272.744669) (xy 154.633567 -272.788246) (xy 154.604002 -272.82759)
			(xy 154.568509 -272.861682) (xy 154.528006 -272.889638) (xy 154.483544 -272.910736) (xy 154.436273 -272.924428)
			(xy 154.387418 -272.93036) (xy 154.338243 -272.928379) (xy 154.290024 -272.918535) (xy 154.244008 -272.901083)
			(xy 154.201387 -272.876476) (xy 154.163266 -272.845351) (xy 154.130631 -272.808514) (xy 154.104328 -272.766918)
			(xy 154.085037 -272.721642) (xy 154.07326 -272.673858) (xy 154.0693 -272.624804) (xy 150.203587 -272.624804)
			(xy 150.13554 -272.791855) (xy 150.054544 -272.969538) (xy 149.966353 -273.143763) (xy 149.871116 -273.314237)
			(xy 149.76899 -273.480676) (xy 149.705824 -273.574764) (xy 153.119086 -273.574764) (xy 153.123046 -273.52571)
			(xy 153.134823 -273.477926) (xy 153.154114 -273.43265) (xy 153.180417 -273.391054) (xy 153.213052 -273.354217)
			(xy 153.251173 -273.323092) (xy 153.293794 -273.298485) (xy 153.33981 -273.281033) (xy 153.388029 -273.271189)
			(xy 153.437204 -273.269208) (xy 153.486059 -273.27514) (xy 153.53333 -273.288832) (xy 153.577792 -273.30993)
			(xy 153.618295 -273.337886) (xy 153.653788 -273.371978) (xy 153.683353 -273.411322) (xy 153.706224 -273.454899)
			(xy 153.721808 -273.50158) (xy 153.729703 -273.550157) (xy 153.730198 -273.574764) (xy 154.069046 -273.574764)
			(xy 154.073006 -273.52571) (xy 154.084783 -273.477926) (xy 154.104074 -273.43265) (xy 154.130377 -273.391054)
			(xy 154.163012 -273.354217) (xy 154.201133 -273.323092) (xy 154.243754 -273.298485) (xy 154.28977 -273.281033)
			(xy 154.337989 -273.271189) (xy 154.387164 -273.269208) (xy 154.436019 -273.27514) (xy 154.48329 -273.288832)
			(xy 154.527752 -273.30993) (xy 154.568255 -273.337886) (xy 154.603748 -273.371978) (xy 154.633313 -273.411322)
			(xy 154.656184 -273.454899) (xy 154.671768 -273.50158) (xy 154.679663 -273.550157) (xy 154.680158 -273.574764)
			(xy 155.01926 -273.574764) (xy 155.02322 -273.52571) (xy 155.034997 -273.477926) (xy 155.054288 -273.43265)
			(xy 155.080591 -273.391054) (xy 155.113226 -273.354217) (xy 155.151347 -273.323092) (xy 155.193968 -273.298485)
			(xy 155.239984 -273.281033) (xy 155.288203 -273.271189) (xy 155.337378 -273.269208) (xy 155.386233 -273.27514)
			(xy 155.433504 -273.288832) (xy 155.477966 -273.30993) (xy 155.518469 -273.337886) (xy 155.553962 -273.371978)
			(xy 155.583527 -273.411322) (xy 155.606398 -273.454899) (xy 155.621982 -273.50158) (xy 155.629877 -273.550157)
			(xy 155.630372 -273.574764) (xy 155.96922 -273.574764) (xy 155.97318 -273.52571) (xy 155.984957 -273.477926)
			(xy 156.004248 -273.43265) (xy 156.030551 -273.391054) (xy 156.063186 -273.354217) (xy 156.101307 -273.323092)
			(xy 156.143928 -273.298485) (xy 156.189944 -273.281033) (xy 156.238163 -273.271189) (xy 156.287338 -273.269208)
			(xy 156.336193 -273.27514) (xy 156.383464 -273.288832) (xy 156.427926 -273.30993) (xy 156.468429 -273.337886)
			(xy 156.503922 -273.371978) (xy 156.533487 -273.411322) (xy 156.556358 -273.454899) (xy 156.571942 -273.50158)
			(xy 156.579837 -273.550157) (xy 156.580332 -273.574764) (xy 156.91918 -273.574764) (xy 156.92314 -273.52571)
			(xy 156.934917 -273.477926) (xy 156.954208 -273.43265) (xy 156.980511 -273.391054) (xy 157.013146 -273.354217)
			(xy 157.051267 -273.323092) (xy 157.093888 -273.298485) (xy 157.139904 -273.281033) (xy 157.188123 -273.271189)
			(xy 157.237298 -273.269208) (xy 157.286153 -273.27514) (xy 157.333424 -273.288832) (xy 157.377886 -273.30993)
			(xy 157.418389 -273.337886) (xy 157.453882 -273.371978) (xy 157.483447 -273.411322) (xy 157.506318 -273.454899)
			(xy 157.521902 -273.50158) (xy 157.529797 -273.550157) (xy 157.530292 -273.574764) (xy 157.86914 -273.574764)
			(xy 157.8731 -273.52571) (xy 157.884877 -273.477926) (xy 157.904168 -273.43265) (xy 157.930471 -273.391054)
			(xy 157.963106 -273.354217) (xy 158.001227 -273.323092) (xy 158.043848 -273.298485) (xy 158.089864 -273.281033)
			(xy 158.138083 -273.271189) (xy 158.187258 -273.269208) (xy 158.236113 -273.27514) (xy 158.283384 -273.288832)
			(xy 158.327846 -273.30993) (xy 158.368349 -273.337886) (xy 158.403842 -273.371978) (xy 158.433407 -273.411322)
			(xy 158.456278 -273.454899) (xy 158.471862 -273.50158) (xy 158.479757 -273.550157) (xy 158.480252 -273.574764)
			(xy 158.480251 -273.5748) (xy 158.819004 -273.5748) (xy 158.823176 -273.524451) (xy 158.835579 -273.475475)
			(xy 158.855873 -273.429208) (xy 158.883506 -273.386913) (xy 158.917724 -273.349744) (xy 158.957593 -273.318713)
			(xy 159.002026 -273.294667) (xy 159.04981 -273.278264) (xy 159.099643 -273.269948) (xy 159.124904 -273.269456)
			(xy 159.139087 -273.269633) (xy 159.167327 -273.272305) (xy 159.181292 -273.27479) (xy 159.193738 -273.277076)
			(xy 159.21736 -273.26971) (xy 159.29483 -273.19224) (xy 159.302196 -273.168618) (xy 159.29991 -273.156172)
			(xy 159.297434 -273.142206) (xy 159.294762 -273.113967) (xy 159.294576 -273.099784) (xy 159.294751 -273.085601)
			(xy 159.297424 -273.057361) (xy 159.29991 -273.043396) (xy 159.302196 -273.03095) (xy 159.29483 -273.007328)
			(xy 159.21736 -272.929858) (xy 159.193738 -272.922492) (xy 159.181292 -272.924778) (xy 159.167326 -272.927251)
			(xy 159.139086 -272.929925) (xy 159.124904 -272.930112) (xy 159.100083 -272.929626) (xy 159.051094 -272.921596)
			(xy 159.00405 -272.905745) (xy 158.96019 -272.882493) (xy 158.920669 -272.852451) (xy 158.88653 -272.816411)
			(xy 158.858671 -272.775322) (xy 158.837826 -272.730268) (xy 158.824545 -272.682435) (xy 158.819177 -272.633083)
			(xy 158.821865 -272.583513) (xy 158.832536 -272.535031) (xy 158.850911 -272.488914) (xy 158.876504 -272.446378)
			(xy 158.908642 -272.408542) (xy 158.946478 -272.376404) (xy 158.989014 -272.350811) (xy 159.035131 -272.332436)
			(xy 159.083613 -272.321765) (xy 159.133183 -272.319077) (xy 159.182535 -272.324445) (xy 159.230368 -272.337726)
			(xy 159.275422 -272.358571) (xy 159.316511 -272.38643) (xy 159.352551 -272.420569) (xy 159.382593 -272.46009)
			(xy 159.405845 -272.50395) (xy 159.421696 -272.550994) (xy 159.429726 -272.599983) (xy 159.430212 -272.624804)
			(xy 159.430036 -272.638987) (xy 159.427363 -272.667227) (xy 159.424878 -272.681192) (xy 159.422592 -272.693638)
			(xy 159.429958 -272.71726) (xy 159.507428 -272.79473) (xy 159.53105 -272.802096) (xy 159.543496 -272.79981)
			(xy 159.557463 -272.797338) (xy 159.585702 -272.794663) (xy 159.599884 -272.794476) (xy 159.625141 -272.794999)
			(xy 159.674967 -272.803311) (xy 159.722745 -272.819711) (xy 159.767172 -272.843752) (xy 159.807036 -272.874778)
			(xy 159.84125 -272.911941) (xy 159.868879 -272.95423) (xy 159.889171 -273.000489) (xy 159.901572 -273.049458)
			(xy 159.905743 -273.099784) (xy 160.24404 -273.099784) (xy 160.248 -273.05073) (xy 160.259777 -273.002946)
			(xy 160.279068 -272.95767) (xy 160.305371 -272.916074) (xy 160.338006 -272.879237) (xy 160.376127 -272.848112)
			(xy 160.418748 -272.823505) (xy 160.464764 -272.806053) (xy 160.512983 -272.796209) (xy 160.562158 -272.794228)
			(xy 160.611013 -272.80016) (xy 160.658284 -272.813852) (xy 160.702746 -272.83495) (xy 160.743249 -272.862906)
			(xy 160.778742 -272.896998) (xy 160.808307 -272.936342) (xy 160.831178 -272.979919) (xy 160.846762 -273.0266)
			(xy 160.854657 -273.075177) (xy 160.855152 -273.099784) (xy 161.194254 -273.099784) (xy 161.198214 -273.05073)
			(xy 161.209991 -273.002946) (xy 161.229282 -272.95767) (xy 161.255585 -272.916074) (xy 161.28822 -272.879237)
			(xy 161.326341 -272.848112) (xy 161.368962 -272.823505) (xy 161.414978 -272.806053) (xy 161.463197 -272.796209)
			(xy 161.512372 -272.794228) (xy 161.561227 -272.80016) (xy 161.608498 -272.813852) (xy 161.65296 -272.83495)
			(xy 161.693463 -272.862906) (xy 161.728956 -272.896998) (xy 161.758521 -272.936342) (xy 161.781392 -272.979919)
			(xy 161.796976 -273.0266) (xy 161.804871 -273.075177) (xy 161.805366 -273.099784) (xy 162.144214 -273.099784)
			(xy 162.148174 -273.05073) (xy 162.159951 -273.002946) (xy 162.179242 -272.95767) (xy 162.205545 -272.916074)
			(xy 162.23818 -272.879237) (xy 162.276301 -272.848112) (xy 162.318922 -272.823505) (xy 162.364938 -272.806053)
			(xy 162.413157 -272.796209) (xy 162.462332 -272.794228) (xy 162.511187 -272.80016) (xy 162.558458 -272.813852)
			(xy 162.60292 -272.83495) (xy 162.643423 -272.862906) (xy 162.678916 -272.896998) (xy 162.708481 -272.936342)
			(xy 162.731352 -272.979919) (xy 162.746936 -273.0266) (xy 162.754831 -273.075177) (xy 162.755326 -273.099784)
			(xy 163.094174 -273.099784) (xy 163.098134 -273.05073) (xy 163.109911 -273.002946) (xy 163.129202 -272.95767)
			(xy 163.155505 -272.916074) (xy 163.18814 -272.879237) (xy 163.226261 -272.848112) (xy 163.268882 -272.823505)
			(xy 163.314898 -272.806053) (xy 163.363117 -272.796209) (xy 163.412292 -272.794228) (xy 163.461147 -272.80016)
			(xy 163.508418 -272.813852) (xy 163.55288 -272.83495) (xy 163.593383 -272.862906) (xy 163.628876 -272.896998)
			(xy 163.658441 -272.936342) (xy 163.681312 -272.979919) (xy 163.696896 -273.0266) (xy 163.704791 -273.075177)
			(xy 163.705286 -273.099784) (xy 164.044134 -273.099784) (xy 164.048094 -273.05073) (xy 164.059871 -273.002946)
			(xy 164.079162 -272.95767) (xy 164.105465 -272.916074) (xy 164.1381 -272.879237) (xy 164.176221 -272.848112)
			(xy 164.218842 -272.823505) (xy 164.264858 -272.806053) (xy 164.313077 -272.796209) (xy 164.362252 -272.794228)
			(xy 164.411107 -272.80016) (xy 164.458378 -272.813852) (xy 164.50284 -272.83495) (xy 164.543343 -272.862906)
			(xy 164.578836 -272.896998) (xy 164.608401 -272.936342) (xy 164.631272 -272.979919) (xy 164.646856 -273.0266)
			(xy 164.654751 -273.075177) (xy 164.655246 -273.099784) (xy 164.994094 -273.099784) (xy 164.998054 -273.05073)
			(xy 165.009831 -273.002946) (xy 165.029122 -272.95767) (xy 165.055425 -272.916074) (xy 165.08806 -272.879237)
			(xy 165.126181 -272.848112) (xy 165.168802 -272.823505) (xy 165.214818 -272.806053) (xy 165.263037 -272.796209)
			(xy 165.312212 -272.794228) (xy 165.361067 -272.80016) (xy 165.408338 -272.813852) (xy 165.4528 -272.83495)
			(xy 165.493303 -272.862906) (xy 165.528796 -272.896998) (xy 165.558361 -272.936342) (xy 165.581232 -272.979919)
			(xy 165.596816 -273.0266) (xy 165.604711 -273.075177) (xy 165.605206 -273.099784) (xy 165.944054 -273.099784)
			(xy 165.948014 -273.05073) (xy 165.959791 -273.002946) (xy 165.979082 -272.95767) (xy 166.005385 -272.916074)
			(xy 166.03802 -272.879237) (xy 166.076141 -272.848112) (xy 166.118762 -272.823505) (xy 166.164778 -272.806053)
			(xy 166.212997 -272.796209) (xy 166.262172 -272.794228) (xy 166.311027 -272.80016) (xy 166.358298 -272.813852)
			(xy 166.40276 -272.83495) (xy 166.443263 -272.862906) (xy 166.478756 -272.896998) (xy 166.508321 -272.936342)
			(xy 166.531192 -272.979919) (xy 166.546776 -273.0266) (xy 166.554671 -273.075177) (xy 166.555166 -273.099784)
			(xy 166.894268 -273.099784) (xy 166.898228 -273.05073) (xy 166.910005 -273.002946) (xy 166.929296 -272.95767)
			(xy 166.955599 -272.916074) (xy 166.988234 -272.879237) (xy 167.026355 -272.848112) (xy 167.068976 -272.823505)
			(xy 167.114992 -272.806053) (xy 167.163211 -272.796209) (xy 167.212386 -272.794228) (xy 167.261241 -272.80016)
			(xy 167.308512 -272.813852) (xy 167.352974 -272.83495) (xy 167.393477 -272.862906) (xy 167.42897 -272.896998)
			(xy 167.458535 -272.936342) (xy 167.481406 -272.979919) (xy 167.49699 -273.0266) (xy 167.504885 -273.075177)
			(xy 167.50538 -273.099784) (xy 167.844228 -273.099784) (xy 167.848188 -273.05073) (xy 167.859965 -273.002946)
			(xy 167.879256 -272.95767) (xy 167.905559 -272.916074) (xy 167.938194 -272.879237) (xy 167.976315 -272.848112)
			(xy 168.018936 -272.823505) (xy 168.064952 -272.806053) (xy 168.113171 -272.796209) (xy 168.162346 -272.794228)
			(xy 168.211201 -272.80016) (xy 168.258472 -272.813852) (xy 168.302934 -272.83495) (xy 168.343437 -272.862906)
			(xy 168.37893 -272.896998) (xy 168.408495 -272.936342) (xy 168.431366 -272.979919) (xy 168.44695 -273.0266)
			(xy 168.454845 -273.075177) (xy 168.45534 -273.099784) (xy 168.794188 -273.099784) (xy 168.798148 -273.05073)
			(xy 168.809925 -273.002946) (xy 168.829216 -272.95767) (xy 168.855519 -272.916074) (xy 168.888154 -272.879237)
			(xy 168.926275 -272.848112) (xy 168.968896 -272.823505) (xy 169.014912 -272.806053) (xy 169.063131 -272.796209)
			(xy 169.112306 -272.794228) (xy 169.161161 -272.80016) (xy 169.208432 -272.813852) (xy 169.252894 -272.83495)
			(xy 169.293397 -272.862906) (xy 169.32889 -272.896998) (xy 169.358455 -272.936342) (xy 169.381326 -272.979919)
			(xy 169.39691 -273.0266) (xy 169.404805 -273.075177) (xy 169.4053 -273.099784) (xy 169.744148 -273.099784)
			(xy 169.748108 -273.05073) (xy 169.759885 -273.002946) (xy 169.779176 -272.95767) (xy 169.805479 -272.916074)
			(xy 169.838114 -272.879237) (xy 169.876235 -272.848112) (xy 169.918856 -272.823505) (xy 169.964872 -272.806053)
			(xy 170.013091 -272.796209) (xy 170.062266 -272.794228) (xy 170.111121 -272.80016) (xy 170.158392 -272.813852)
			(xy 170.202854 -272.83495) (xy 170.243357 -272.862906) (xy 170.27885 -272.896998) (xy 170.308415 -272.936342)
			(xy 170.331286 -272.979919) (xy 170.34687 -273.0266) (xy 170.354765 -273.075177) (xy 170.35526 -273.099784)
			(xy 170.694108 -273.099784) (xy 170.698068 -273.05073) (xy 170.709845 -273.002946) (xy 170.729136 -272.95767)
			(xy 170.755439 -272.916074) (xy 170.788074 -272.879237) (xy 170.826195 -272.848112) (xy 170.868816 -272.823505)
			(xy 170.914832 -272.806053) (xy 170.963051 -272.796209) (xy 171.012226 -272.794228) (xy 171.061081 -272.80016)
			(xy 171.108352 -272.813852) (xy 171.152814 -272.83495) (xy 171.193317 -272.862906) (xy 171.22881 -272.896998)
			(xy 171.258375 -272.936342) (xy 171.281246 -272.979919) (xy 171.29683 -273.0266) (xy 171.304725 -273.075177)
			(xy 171.30522 -273.099784) (xy 171.644068 -273.099784) (xy 171.648028 -273.05073) (xy 171.659805 -273.002946)
			(xy 171.679096 -272.95767) (xy 171.705399 -272.916074) (xy 171.738034 -272.879237) (xy 171.776155 -272.848112)
			(xy 171.818776 -272.823505) (xy 171.864792 -272.806053) (xy 171.913011 -272.796209) (xy 171.962186 -272.794228)
			(xy 172.011041 -272.80016) (xy 172.058312 -272.813852) (xy 172.102774 -272.83495) (xy 172.143277 -272.862906)
			(xy 172.17877 -272.896998) (xy 172.208335 -272.936342) (xy 172.231206 -272.979919) (xy 172.24679 -273.0266)
			(xy 172.254685 -273.075177) (xy 172.25518 -273.099784) (xy 172.594282 -273.099784) (xy 172.598242 -273.05073)
			(xy 172.610019 -273.002946) (xy 172.62931 -272.95767) (xy 172.655613 -272.916074) (xy 172.688248 -272.879237)
			(xy 172.726369 -272.848112) (xy 172.76899 -272.823505) (xy 172.815006 -272.806053) (xy 172.863225 -272.796209)
			(xy 172.9124 -272.794228) (xy 172.961255 -272.80016) (xy 173.008526 -272.813852) (xy 173.052988 -272.83495)
			(xy 173.093491 -272.862906) (xy 173.128984 -272.896998) (xy 173.158549 -272.936342) (xy 173.18142 -272.979919)
			(xy 173.197004 -273.0266) (xy 173.204899 -273.075177) (xy 173.205394 -273.099784) (xy 173.204899 -273.124391)
			(xy 173.197004 -273.172968) (xy 173.18142 -273.219649) (xy 173.158549 -273.263226) (xy 173.128984 -273.30257)
			(xy 173.093491 -273.336662) (xy 173.052988 -273.364618) (xy 173.008526 -273.385716) (xy 172.961255 -273.399408)
			(xy 172.9124 -273.40534) (xy 172.863225 -273.403359) (xy 172.815006 -273.393515) (xy 172.76899 -273.376063)
			(xy 172.726369 -273.351456) (xy 172.688248 -273.320331) (xy 172.655613 -273.283494) (xy 172.62931 -273.241898)
			(xy 172.610019 -273.196622) (xy 172.598242 -273.148838) (xy 172.594282 -273.099784) (xy 172.25518 -273.099784)
			(xy 172.254685 -273.124391) (xy 172.24679 -273.172968) (xy 172.231206 -273.219649) (xy 172.208335 -273.263226)
			(xy 172.17877 -273.30257) (xy 172.143277 -273.336662) (xy 172.102774 -273.364618) (xy 172.058312 -273.385716)
			(xy 172.011041 -273.399408) (xy 171.962186 -273.40534) (xy 171.913011 -273.403359) (xy 171.864792 -273.393515)
			(xy 171.818776 -273.376063) (xy 171.776155 -273.351456) (xy 171.738034 -273.320331) (xy 171.705399 -273.283494)
			(xy 171.679096 -273.241898) (xy 171.659805 -273.196622) (xy 171.648028 -273.148838) (xy 171.644068 -273.099784)
			(xy 171.30522 -273.099784) (xy 171.304725 -273.124391) (xy 171.29683 -273.172968) (xy 171.281246 -273.219649)
			(xy 171.258375 -273.263226) (xy 171.22881 -273.30257) (xy 171.193317 -273.336662) (xy 171.152814 -273.364618)
			(xy 171.108352 -273.385716) (xy 171.061081 -273.399408) (xy 171.012226 -273.40534) (xy 170.963051 -273.403359)
			(xy 170.914832 -273.393515) (xy 170.868816 -273.376063) (xy 170.826195 -273.351456) (xy 170.788074 -273.320331)
			(xy 170.755439 -273.283494) (xy 170.729136 -273.241898) (xy 170.709845 -273.196622) (xy 170.698068 -273.148838)
			(xy 170.694108 -273.099784) (xy 170.35526 -273.099784) (xy 170.354765 -273.124391) (xy 170.34687 -273.172968)
			(xy 170.331286 -273.219649) (xy 170.308415 -273.263226) (xy 170.27885 -273.30257) (xy 170.243357 -273.336662)
			(xy 170.202854 -273.364618) (xy 170.158392 -273.385716) (xy 170.111121 -273.399408) (xy 170.062266 -273.40534)
			(xy 170.013091 -273.403359) (xy 169.964872 -273.393515) (xy 169.918856 -273.376063) (xy 169.876235 -273.351456)
			(xy 169.838114 -273.320331) (xy 169.805479 -273.283494) (xy 169.779176 -273.241898) (xy 169.759885 -273.196622)
			(xy 169.748108 -273.148838) (xy 169.744148 -273.099784) (xy 169.4053 -273.099784) (xy 169.404805 -273.124391)
			(xy 169.39691 -273.172968) (xy 169.381326 -273.219649) (xy 169.358455 -273.263226) (xy 169.32889 -273.30257)
			(xy 169.293397 -273.336662) (xy 169.252894 -273.364618) (xy 169.208432 -273.385716) (xy 169.161161 -273.399408)
			(xy 169.112306 -273.40534) (xy 169.063131 -273.403359) (xy 169.014912 -273.393515) (xy 168.968896 -273.376063)
			(xy 168.926275 -273.351456) (xy 168.888154 -273.320331) (xy 168.855519 -273.283494) (xy 168.829216 -273.241898)
			(xy 168.809925 -273.196622) (xy 168.798148 -273.148838) (xy 168.794188 -273.099784) (xy 168.45534 -273.099784)
			(xy 168.454845 -273.124391) (xy 168.44695 -273.172968) (xy 168.431366 -273.219649) (xy 168.408495 -273.263226)
			(xy 168.37893 -273.30257) (xy 168.343437 -273.336662) (xy 168.302934 -273.364618) (xy 168.258472 -273.385716)
			(xy 168.211201 -273.399408) (xy 168.162346 -273.40534) (xy 168.113171 -273.403359) (xy 168.064952 -273.393515)
			(xy 168.018936 -273.376063) (xy 167.976315 -273.351456) (xy 167.938194 -273.320331) (xy 167.905559 -273.283494)
			(xy 167.879256 -273.241898) (xy 167.859965 -273.196622) (xy 167.848188 -273.148838) (xy 167.844228 -273.099784)
			(xy 167.50538 -273.099784) (xy 167.504885 -273.124391) (xy 167.49699 -273.172968) (xy 167.481406 -273.219649)
			(xy 167.458535 -273.263226) (xy 167.42897 -273.30257) (xy 167.393477 -273.336662) (xy 167.352974 -273.364618)
			(xy 167.308512 -273.385716) (xy 167.261241 -273.399408) (xy 167.212386 -273.40534) (xy 167.163211 -273.403359)
			(xy 167.114992 -273.393515) (xy 167.068976 -273.376063) (xy 167.026355 -273.351456) (xy 166.988234 -273.320331)
			(xy 166.955599 -273.283494) (xy 166.929296 -273.241898) (xy 166.910005 -273.196622) (xy 166.898228 -273.148838)
			(xy 166.894268 -273.099784) (xy 166.555166 -273.099784) (xy 166.554671 -273.124391) (xy 166.546776 -273.172968)
			(xy 166.531192 -273.219649) (xy 166.508321 -273.263226) (xy 166.478756 -273.30257) (xy 166.443263 -273.336662)
			(xy 166.40276 -273.364618) (xy 166.358298 -273.385716) (xy 166.311027 -273.399408) (xy 166.262172 -273.40534)
			(xy 166.212997 -273.403359) (xy 166.164778 -273.393515) (xy 166.118762 -273.376063) (xy 166.076141 -273.351456)
			(xy 166.03802 -273.320331) (xy 166.005385 -273.283494) (xy 165.979082 -273.241898) (xy 165.959791 -273.196622)
			(xy 165.948014 -273.148838) (xy 165.944054 -273.099784) (xy 165.605206 -273.099784) (xy 165.604711 -273.124391)
			(xy 165.596816 -273.172968) (xy 165.581232 -273.219649) (xy 165.558361 -273.263226) (xy 165.528796 -273.30257)
			(xy 165.493303 -273.336662) (xy 165.4528 -273.364618) (xy 165.408338 -273.385716) (xy 165.361067 -273.399408)
			(xy 165.312212 -273.40534) (xy 165.263037 -273.403359) (xy 165.214818 -273.393515) (xy 165.168802 -273.376063)
			(xy 165.126181 -273.351456) (xy 165.08806 -273.320331) (xy 165.055425 -273.283494) (xy 165.029122 -273.241898)
			(xy 165.009831 -273.196622) (xy 164.998054 -273.148838) (xy 164.994094 -273.099784) (xy 164.655246 -273.099784)
			(xy 164.654751 -273.124391) (xy 164.646856 -273.172968) (xy 164.631272 -273.219649) (xy 164.608401 -273.263226)
			(xy 164.578836 -273.30257) (xy 164.543343 -273.336662) (xy 164.50284 -273.364618) (xy 164.458378 -273.385716)
			(xy 164.411107 -273.399408) (xy 164.362252 -273.40534) (xy 164.313077 -273.403359) (xy 164.264858 -273.393515)
			(xy 164.218842 -273.376063) (xy 164.176221 -273.351456) (xy 164.1381 -273.320331) (xy 164.105465 -273.283494)
			(xy 164.079162 -273.241898) (xy 164.059871 -273.196622) (xy 164.048094 -273.148838) (xy 164.044134 -273.099784)
			(xy 163.705286 -273.099784) (xy 163.704791 -273.124391) (xy 163.696896 -273.172968) (xy 163.681312 -273.219649)
			(xy 163.658441 -273.263226) (xy 163.628876 -273.30257) (xy 163.593383 -273.336662) (xy 163.55288 -273.364618)
			(xy 163.508418 -273.385716) (xy 163.461147 -273.399408) (xy 163.412292 -273.40534) (xy 163.363117 -273.403359)
			(xy 163.314898 -273.393515) (xy 163.268882 -273.376063) (xy 163.226261 -273.351456) (xy 163.18814 -273.320331)
			(xy 163.155505 -273.283494) (xy 163.129202 -273.241898) (xy 163.109911 -273.196622) (xy 163.098134 -273.148838)
			(xy 163.094174 -273.099784) (xy 162.755326 -273.099784) (xy 162.754831 -273.124391) (xy 162.746936 -273.172968)
			(xy 162.731352 -273.219649) (xy 162.708481 -273.263226) (xy 162.678916 -273.30257) (xy 162.643423 -273.336662)
			(xy 162.60292 -273.364618) (xy 162.558458 -273.385716) (xy 162.511187 -273.399408) (xy 162.462332 -273.40534)
			(xy 162.413157 -273.403359) (xy 162.364938 -273.393515) (xy 162.318922 -273.376063) (xy 162.276301 -273.351456)
			(xy 162.23818 -273.320331) (xy 162.205545 -273.283494) (xy 162.179242 -273.241898) (xy 162.159951 -273.196622)
			(xy 162.148174 -273.148838) (xy 162.144214 -273.099784) (xy 161.805366 -273.099784) (xy 161.804871 -273.124391)
			(xy 161.796976 -273.172968) (xy 161.781392 -273.219649) (xy 161.758521 -273.263226) (xy 161.728956 -273.30257)
			(xy 161.693463 -273.336662) (xy 161.65296 -273.364618) (xy 161.608498 -273.385716) (xy 161.561227 -273.399408)
			(xy 161.512372 -273.40534) (xy 161.463197 -273.403359) (xy 161.414978 -273.393515) (xy 161.368962 -273.376063)
			(xy 161.326341 -273.351456) (xy 161.28822 -273.320331) (xy 161.255585 -273.283494) (xy 161.229282 -273.241898)
			(xy 161.209991 -273.196622) (xy 161.198214 -273.148838) (xy 161.194254 -273.099784) (xy 160.855152 -273.099784)
			(xy 160.854657 -273.124391) (xy 160.846762 -273.172968) (xy 160.831178 -273.219649) (xy 160.808307 -273.263226)
			(xy 160.778742 -273.30257) (xy 160.743249 -273.336662) (xy 160.702746 -273.364618) (xy 160.658284 -273.385716)
			(xy 160.611013 -273.399408) (xy 160.562158 -273.40534) (xy 160.512983 -273.403359) (xy 160.464764 -273.393515)
			(xy 160.418748 -273.376063) (xy 160.376127 -273.351456) (xy 160.338006 -273.320331) (xy 160.305371 -273.283494)
			(xy 160.279068 -273.241898) (xy 160.259777 -273.196622) (xy 160.248 -273.148838) (xy 160.24404 -273.099784)
			(xy 159.905743 -273.099784) (xy 159.905744 -273.0998) (xy 159.901572 -273.150142) (xy 159.889171 -273.199111)
			(xy 159.868879 -273.24537) (xy 159.84125 -273.287659) (xy 159.807036 -273.324822) (xy 159.767172 -273.355848)
			(xy 159.722745 -273.379889) (xy 159.674967 -273.396289) (xy 159.625141 -273.404601) (xy 159.599884 -273.405092)
			(xy 159.585701 -273.404918) (xy 159.557461 -273.402244) (xy 159.543496 -273.399758) (xy 159.53105 -273.397472)
			(xy 159.507428 -273.404838) (xy 159.429958 -273.482308) (xy 159.422592 -273.50593) (xy 159.424878 -273.518376)
			(xy 159.427361 -273.532341) (xy 159.430028 -273.560581) (xy 159.430212 -273.574764) (xy 159.43003 -273.588947)
			(xy 159.427362 -273.617187) (xy 159.424878 -273.631152) (xy 159.422592 -273.643598) (xy 159.429958 -273.66722)
			(xy 159.507428 -273.74469) (xy 159.53105 -273.752056) (xy 159.543496 -273.74977) (xy 159.557463 -273.747298)
			(xy 159.585702 -273.744623) (xy 159.599884 -273.744436) (xy 159.625146 -273.74484) (xy 159.674982 -273.753153)
			(xy 159.722769 -273.769557) (xy 159.767205 -273.793602) (xy 159.807077 -273.824633) (xy 159.841297 -273.861805)
			(xy 159.868932 -273.904101) (xy 159.889228 -273.95037) (xy 159.901632 -273.999348) (xy 159.905804 -274.0497)
			(xy 159.9058 -274.049744) (xy 160.24404 -274.049744) (xy 160.248 -274.00069) (xy 160.259777 -273.952906)
			(xy 160.279068 -273.90763) (xy 160.305371 -273.866034) (xy 160.338006 -273.829197) (xy 160.376127 -273.798072)
			(xy 160.418748 -273.773465) (xy 160.464764 -273.756013) (xy 160.512983 -273.746169) (xy 160.562158 -273.744188)
			(xy 160.611013 -273.75012) (xy 160.658284 -273.763812) (xy 160.702746 -273.78491) (xy 160.743249 -273.812866)
			(xy 160.778742 -273.846958) (xy 160.808307 -273.886302) (xy 160.831178 -273.929879) (xy 160.846762 -273.97656)
			(xy 160.854657 -274.025137) (xy 160.855152 -274.049744) (xy 161.194254 -274.049744) (xy 161.198214 -274.00069)
			(xy 161.209991 -273.952906) (xy 161.229282 -273.90763) (xy 161.255585 -273.866034) (xy 161.28822 -273.829197)
			(xy 161.326341 -273.798072) (xy 161.368962 -273.773465) (xy 161.414978 -273.756013) (xy 161.463197 -273.746169)
			(xy 161.512372 -273.744188) (xy 161.561227 -273.75012) (xy 161.608498 -273.763812) (xy 161.65296 -273.78491)
			(xy 161.693463 -273.812866) (xy 161.728956 -273.846958) (xy 161.758521 -273.886302) (xy 161.781392 -273.929879)
			(xy 161.796976 -273.97656) (xy 161.804871 -274.025137) (xy 161.805366 -274.049744) (xy 162.144214 -274.049744)
			(xy 162.148174 -274.00069) (xy 162.159951 -273.952906) (xy 162.179242 -273.90763) (xy 162.205545 -273.866034)
			(xy 162.23818 -273.829197) (xy 162.276301 -273.798072) (xy 162.318922 -273.773465) (xy 162.364938 -273.756013)
			(xy 162.413157 -273.746169) (xy 162.462332 -273.744188) (xy 162.511187 -273.75012) (xy 162.558458 -273.763812)
			(xy 162.60292 -273.78491) (xy 162.643423 -273.812866) (xy 162.678916 -273.846958) (xy 162.708481 -273.886302)
			(xy 162.731352 -273.929879) (xy 162.746936 -273.97656) (xy 162.754831 -274.025137) (xy 162.755326 -274.049744)
			(xy 163.094174 -274.049744) (xy 163.098134 -274.00069) (xy 163.109911 -273.952906) (xy 163.129202 -273.90763)
			(xy 163.155505 -273.866034) (xy 163.18814 -273.829197) (xy 163.226261 -273.798072) (xy 163.268882 -273.773465)
			(xy 163.314898 -273.756013) (xy 163.363117 -273.746169) (xy 163.412292 -273.744188) (xy 163.461147 -273.75012)
			(xy 163.508418 -273.763812) (xy 163.55288 -273.78491) (xy 163.593383 -273.812866) (xy 163.628876 -273.846958)
			(xy 163.658441 -273.886302) (xy 163.681312 -273.929879) (xy 163.696896 -273.97656) (xy 163.704791 -274.025137)
			(xy 163.705286 -274.049744) (xy 164.044134 -274.049744) (xy 164.048094 -274.00069) (xy 164.059871 -273.952906)
			(xy 164.079162 -273.90763) (xy 164.105465 -273.866034) (xy 164.1381 -273.829197) (xy 164.176221 -273.798072)
			(xy 164.218842 -273.773465) (xy 164.264858 -273.756013) (xy 164.313077 -273.746169) (xy 164.362252 -273.744188)
			(xy 164.411107 -273.75012) (xy 164.458378 -273.763812) (xy 164.50284 -273.78491) (xy 164.543343 -273.812866)
			(xy 164.578836 -273.846958) (xy 164.608401 -273.886302) (xy 164.631272 -273.929879) (xy 164.646856 -273.97656)
			(xy 164.654751 -274.025137) (xy 164.655246 -274.049744) (xy 164.994094 -274.049744) (xy 164.998054 -274.00069)
			(xy 165.009831 -273.952906) (xy 165.029122 -273.90763) (xy 165.055425 -273.866034) (xy 165.08806 -273.829197)
			(xy 165.126181 -273.798072) (xy 165.168802 -273.773465) (xy 165.214818 -273.756013) (xy 165.263037 -273.746169)
			(xy 165.312212 -273.744188) (xy 165.361067 -273.75012) (xy 165.408338 -273.763812) (xy 165.4528 -273.78491)
			(xy 165.493303 -273.812866) (xy 165.528796 -273.846958) (xy 165.558361 -273.886302) (xy 165.581232 -273.929879)
			(xy 165.596816 -273.97656) (xy 165.604711 -274.025137) (xy 165.605206 -274.049744) (xy 165.944054 -274.049744)
			(xy 165.948014 -274.00069) (xy 165.959791 -273.952906) (xy 165.979082 -273.90763) (xy 166.005385 -273.866034)
			(xy 166.03802 -273.829197) (xy 166.076141 -273.798072) (xy 166.118762 -273.773465) (xy 166.164778 -273.756013)
			(xy 166.212997 -273.746169) (xy 166.262172 -273.744188) (xy 166.311027 -273.75012) (xy 166.358298 -273.763812)
			(xy 166.40276 -273.78491) (xy 166.443263 -273.812866) (xy 166.478756 -273.846958) (xy 166.508321 -273.886302)
			(xy 166.531192 -273.929879) (xy 166.546776 -273.97656) (xy 166.554671 -274.025137) (xy 166.555166 -274.049744)
			(xy 166.894268 -274.049744) (xy 166.898228 -274.00069) (xy 166.910005 -273.952906) (xy 166.929296 -273.90763)
			(xy 166.955599 -273.866034) (xy 166.988234 -273.829197) (xy 167.026355 -273.798072) (xy 167.068976 -273.773465)
			(xy 167.114992 -273.756013) (xy 167.163211 -273.746169) (xy 167.212386 -273.744188) (xy 167.261241 -273.75012)
			(xy 167.308512 -273.763812) (xy 167.352974 -273.78491) (xy 167.393477 -273.812866) (xy 167.42897 -273.846958)
			(xy 167.458535 -273.886302) (xy 167.481406 -273.929879) (xy 167.49699 -273.97656) (xy 167.504885 -274.025137)
			(xy 167.50538 -274.049744) (xy 167.844228 -274.049744) (xy 167.848188 -274.00069) (xy 167.859965 -273.952906)
			(xy 167.879256 -273.90763) (xy 167.905559 -273.866034) (xy 167.938194 -273.829197) (xy 167.976315 -273.798072)
			(xy 168.018936 -273.773465) (xy 168.064952 -273.756013) (xy 168.113171 -273.746169) (xy 168.162346 -273.744188)
			(xy 168.211201 -273.75012) (xy 168.258472 -273.763812) (xy 168.302934 -273.78491) (xy 168.343437 -273.812866)
			(xy 168.37893 -273.846958) (xy 168.408495 -273.886302) (xy 168.431366 -273.929879) (xy 168.44695 -273.97656)
			(xy 168.454845 -274.025137) (xy 168.45534 -274.049744) (xy 168.794188 -274.049744) (xy 168.798148 -274.00069)
			(xy 168.809925 -273.952906) (xy 168.829216 -273.90763) (xy 168.855519 -273.866034) (xy 168.888154 -273.829197)
			(xy 168.926275 -273.798072) (xy 168.968896 -273.773465) (xy 169.014912 -273.756013) (xy 169.063131 -273.746169)
			(xy 169.112306 -273.744188) (xy 169.161161 -273.75012) (xy 169.208432 -273.763812) (xy 169.252894 -273.78491)
			(xy 169.293397 -273.812866) (xy 169.32889 -273.846958) (xy 169.358455 -273.886302) (xy 169.381326 -273.929879)
			(xy 169.39691 -273.97656) (xy 169.404805 -274.025137) (xy 169.4053 -274.049744) (xy 169.744148 -274.049744)
			(xy 169.748108 -274.00069) (xy 169.759885 -273.952906) (xy 169.779176 -273.90763) (xy 169.805479 -273.866034)
			(xy 169.838114 -273.829197) (xy 169.876235 -273.798072) (xy 169.918856 -273.773465) (xy 169.964872 -273.756013)
			(xy 170.013091 -273.746169) (xy 170.062266 -273.744188) (xy 170.111121 -273.75012) (xy 170.158392 -273.763812)
			(xy 170.202854 -273.78491) (xy 170.243357 -273.812866) (xy 170.27885 -273.846958) (xy 170.308415 -273.886302)
			(xy 170.331286 -273.929879) (xy 170.34687 -273.97656) (xy 170.354765 -274.025137) (xy 170.35526 -274.049744)
			(xy 170.694108 -274.049744) (xy 170.698068 -274.00069) (xy 170.709845 -273.952906) (xy 170.729136 -273.90763)
			(xy 170.755439 -273.866034) (xy 170.788074 -273.829197) (xy 170.826195 -273.798072) (xy 170.868816 -273.773465)
			(xy 170.914832 -273.756013) (xy 170.963051 -273.746169) (xy 171.012226 -273.744188) (xy 171.061081 -273.75012)
			(xy 171.108352 -273.763812) (xy 171.152814 -273.78491) (xy 171.193317 -273.812866) (xy 171.22881 -273.846958)
			(xy 171.258375 -273.886302) (xy 171.281246 -273.929879) (xy 171.29683 -273.97656) (xy 171.304725 -274.025137)
			(xy 171.30522 -274.049744) (xy 171.644068 -274.049744) (xy 171.648028 -274.00069) (xy 171.659805 -273.952906)
			(xy 171.679096 -273.90763) (xy 171.705399 -273.866034) (xy 171.738034 -273.829197) (xy 171.776155 -273.798072)
			(xy 171.818776 -273.773465) (xy 171.864792 -273.756013) (xy 171.913011 -273.746169) (xy 171.962186 -273.744188)
			(xy 172.011041 -273.75012) (xy 172.058312 -273.763812) (xy 172.102774 -273.78491) (xy 172.143277 -273.812866)
			(xy 172.17877 -273.846958) (xy 172.208335 -273.886302) (xy 172.231206 -273.929879) (xy 172.24679 -273.97656)
			(xy 172.254685 -274.025137) (xy 172.25518 -274.049744) (xy 172.594282 -274.049744) (xy 172.598242 -274.00069)
			(xy 172.610019 -273.952906) (xy 172.62931 -273.90763) (xy 172.655613 -273.866034) (xy 172.688248 -273.829197)
			(xy 172.726369 -273.798072) (xy 172.76899 -273.773465) (xy 172.815006 -273.756013) (xy 172.863225 -273.746169)
			(xy 172.9124 -273.744188) (xy 172.961255 -273.75012) (xy 173.008526 -273.763812) (xy 173.052988 -273.78491)
			(xy 173.093491 -273.812866) (xy 173.128984 -273.846958) (xy 173.158549 -273.886302) (xy 173.18142 -273.929879)
			(xy 173.197004 -273.97656) (xy 173.204899 -274.025137) (xy 173.205394 -274.049744) (xy 173.204899 -274.074351)
			(xy 173.197004 -274.122928) (xy 173.18142 -274.169609) (xy 173.158549 -274.213186) (xy 173.128984 -274.25253)
			(xy 173.093491 -274.286622) (xy 173.052988 -274.314578) (xy 173.008526 -274.335676) (xy 172.961255 -274.349368)
			(xy 172.9124 -274.3553) (xy 172.863225 -274.353319) (xy 172.815006 -274.343475) (xy 172.76899 -274.326023)
			(xy 172.726369 -274.301416) (xy 172.688248 -274.270291) (xy 172.655613 -274.233454) (xy 172.62931 -274.191858)
			(xy 172.610019 -274.146582) (xy 172.598242 -274.098798) (xy 172.594282 -274.049744) (xy 172.25518 -274.049744)
			(xy 172.254685 -274.074351) (xy 172.24679 -274.122928) (xy 172.231206 -274.169609) (xy 172.208335 -274.213186)
			(xy 172.17877 -274.25253) (xy 172.143277 -274.286622) (xy 172.102774 -274.314578) (xy 172.058312 -274.335676)
			(xy 172.011041 -274.349368) (xy 171.962186 -274.3553) (xy 171.913011 -274.353319) (xy 171.864792 -274.343475)
			(xy 171.818776 -274.326023) (xy 171.776155 -274.301416) (xy 171.738034 -274.270291) (xy 171.705399 -274.233454)
			(xy 171.679096 -274.191858) (xy 171.659805 -274.146582) (xy 171.648028 -274.098798) (xy 171.644068 -274.049744)
			(xy 171.30522 -274.049744) (xy 171.304725 -274.074351) (xy 171.29683 -274.122928) (xy 171.281246 -274.169609)
			(xy 171.258375 -274.213186) (xy 171.22881 -274.25253) (xy 171.193317 -274.286622) (xy 171.152814 -274.314578)
			(xy 171.108352 -274.335676) (xy 171.061081 -274.349368) (xy 171.012226 -274.3553) (xy 170.963051 -274.353319)
			(xy 170.914832 -274.343475) (xy 170.868816 -274.326023) (xy 170.826195 -274.301416) (xy 170.788074 -274.270291)
			(xy 170.755439 -274.233454) (xy 170.729136 -274.191858) (xy 170.709845 -274.146582) (xy 170.698068 -274.098798)
			(xy 170.694108 -274.049744) (xy 170.35526 -274.049744) (xy 170.354765 -274.074351) (xy 170.34687 -274.122928)
			(xy 170.331286 -274.169609) (xy 170.308415 -274.213186) (xy 170.27885 -274.25253) (xy 170.243357 -274.286622)
			(xy 170.202854 -274.314578) (xy 170.158392 -274.335676) (xy 170.111121 -274.349368) (xy 170.062266 -274.3553)
			(xy 170.013091 -274.353319) (xy 169.964872 -274.343475) (xy 169.918856 -274.326023) (xy 169.876235 -274.301416)
			(xy 169.838114 -274.270291) (xy 169.805479 -274.233454) (xy 169.779176 -274.191858) (xy 169.759885 -274.146582)
			(xy 169.748108 -274.098798) (xy 169.744148 -274.049744) (xy 169.4053 -274.049744) (xy 169.404805 -274.074351)
			(xy 169.39691 -274.122928) (xy 169.381326 -274.169609) (xy 169.358455 -274.213186) (xy 169.32889 -274.25253)
			(xy 169.293397 -274.286622) (xy 169.252894 -274.314578) (xy 169.208432 -274.335676) (xy 169.161161 -274.349368)
			(xy 169.112306 -274.3553) (xy 169.063131 -274.353319) (xy 169.014912 -274.343475) (xy 168.968896 -274.326023)
			(xy 168.926275 -274.301416) (xy 168.888154 -274.270291) (xy 168.855519 -274.233454) (xy 168.829216 -274.191858)
			(xy 168.809925 -274.146582) (xy 168.798148 -274.098798) (xy 168.794188 -274.049744) (xy 168.45534 -274.049744)
			(xy 168.454845 -274.074351) (xy 168.44695 -274.122928) (xy 168.431366 -274.169609) (xy 168.408495 -274.213186)
			(xy 168.37893 -274.25253) (xy 168.343437 -274.286622) (xy 168.302934 -274.314578) (xy 168.258472 -274.335676)
			(xy 168.211201 -274.349368) (xy 168.162346 -274.3553) (xy 168.113171 -274.353319) (xy 168.064952 -274.343475)
			(xy 168.018936 -274.326023) (xy 167.976315 -274.301416) (xy 167.938194 -274.270291) (xy 167.905559 -274.233454)
			(xy 167.879256 -274.191858) (xy 167.859965 -274.146582) (xy 167.848188 -274.098798) (xy 167.844228 -274.049744)
			(xy 167.50538 -274.049744) (xy 167.504885 -274.074351) (xy 167.49699 -274.122928) (xy 167.481406 -274.169609)
			(xy 167.458535 -274.213186) (xy 167.42897 -274.25253) (xy 167.393477 -274.286622) (xy 167.352974 -274.314578)
			(xy 167.308512 -274.335676) (xy 167.261241 -274.349368) (xy 167.212386 -274.3553) (xy 167.163211 -274.353319)
			(xy 167.114992 -274.343475) (xy 167.068976 -274.326023) (xy 167.026355 -274.301416) (xy 166.988234 -274.270291)
			(xy 166.955599 -274.233454) (xy 166.929296 -274.191858) (xy 166.910005 -274.146582) (xy 166.898228 -274.098798)
			(xy 166.894268 -274.049744) (xy 166.555166 -274.049744) (xy 166.554671 -274.074351) (xy 166.546776 -274.122928)
			(xy 166.531192 -274.169609) (xy 166.508321 -274.213186) (xy 166.478756 -274.25253) (xy 166.443263 -274.286622)
			(xy 166.40276 -274.314578) (xy 166.358298 -274.335676) (xy 166.311027 -274.349368) (xy 166.262172 -274.3553)
			(xy 166.212997 -274.353319) (xy 166.164778 -274.343475) (xy 166.118762 -274.326023) (xy 166.076141 -274.301416)
			(xy 166.03802 -274.270291) (xy 166.005385 -274.233454) (xy 165.979082 -274.191858) (xy 165.959791 -274.146582)
			(xy 165.948014 -274.098798) (xy 165.944054 -274.049744) (xy 165.605206 -274.049744) (xy 165.604711 -274.074351)
			(xy 165.596816 -274.122928) (xy 165.581232 -274.169609) (xy 165.558361 -274.213186) (xy 165.528796 -274.25253)
			(xy 165.493303 -274.286622) (xy 165.4528 -274.314578) (xy 165.408338 -274.335676) (xy 165.361067 -274.349368)
			(xy 165.312212 -274.3553) (xy 165.263037 -274.353319) (xy 165.214818 -274.343475) (xy 165.168802 -274.326023)
			(xy 165.126181 -274.301416) (xy 165.08806 -274.270291) (xy 165.055425 -274.233454) (xy 165.029122 -274.191858)
			(xy 165.009831 -274.146582) (xy 164.998054 -274.098798) (xy 164.994094 -274.049744) (xy 164.655246 -274.049744)
			(xy 164.654751 -274.074351) (xy 164.646856 -274.122928) (xy 164.631272 -274.169609) (xy 164.608401 -274.213186)
			(xy 164.578836 -274.25253) (xy 164.543343 -274.286622) (xy 164.50284 -274.314578) (xy 164.458378 -274.335676)
			(xy 164.411107 -274.349368) (xy 164.362252 -274.3553) (xy 164.313077 -274.353319) (xy 164.264858 -274.343475)
			(xy 164.218842 -274.326023) (xy 164.176221 -274.301416) (xy 164.1381 -274.270291) (xy 164.105465 -274.233454)
			(xy 164.079162 -274.191858) (xy 164.059871 -274.146582) (xy 164.048094 -274.098798) (xy 164.044134 -274.049744)
			(xy 163.705286 -274.049744) (xy 163.704791 -274.074351) (xy 163.696896 -274.122928) (xy 163.681312 -274.169609)
			(xy 163.658441 -274.213186) (xy 163.628876 -274.25253) (xy 163.593383 -274.286622) (xy 163.55288 -274.314578)
			(xy 163.508418 -274.335676) (xy 163.461147 -274.349368) (xy 163.412292 -274.3553) (xy 163.363117 -274.353319)
			(xy 163.314898 -274.343475) (xy 163.268882 -274.326023) (xy 163.226261 -274.301416) (xy 163.18814 -274.270291)
			(xy 163.155505 -274.233454) (xy 163.129202 -274.191858) (xy 163.109911 -274.146582) (xy 163.098134 -274.098798)
			(xy 163.094174 -274.049744) (xy 162.755326 -274.049744) (xy 162.754831 -274.074351) (xy 162.746936 -274.122928)
			(xy 162.731352 -274.169609) (xy 162.708481 -274.213186) (xy 162.678916 -274.25253) (xy 162.643423 -274.286622)
			(xy 162.60292 -274.314578) (xy 162.558458 -274.335676) (xy 162.511187 -274.349368) (xy 162.462332 -274.3553)
			(xy 162.413157 -274.353319) (xy 162.364938 -274.343475) (xy 162.318922 -274.326023) (xy 162.276301 -274.301416)
			(xy 162.23818 -274.270291) (xy 162.205545 -274.233454) (xy 162.179242 -274.191858) (xy 162.159951 -274.146582)
			(xy 162.148174 -274.098798) (xy 162.144214 -274.049744) (xy 161.805366 -274.049744) (xy 161.804871 -274.074351)
			(xy 161.796976 -274.122928) (xy 161.781392 -274.169609) (xy 161.758521 -274.213186) (xy 161.728956 -274.25253)
			(xy 161.693463 -274.286622) (xy 161.65296 -274.314578) (xy 161.608498 -274.335676) (xy 161.561227 -274.349368)
			(xy 161.512372 -274.3553) (xy 161.463197 -274.353319) (xy 161.414978 -274.343475) (xy 161.368962 -274.326023)
			(xy 161.326341 -274.301416) (xy 161.28822 -274.270291) (xy 161.255585 -274.233454) (xy 161.229282 -274.191858)
			(xy 161.209991 -274.146582) (xy 161.198214 -274.098798) (xy 161.194254 -274.049744) (xy 160.855152 -274.049744)
			(xy 160.854657 -274.074351) (xy 160.846762 -274.122928) (xy 160.831178 -274.169609) (xy 160.808307 -274.213186)
			(xy 160.778742 -274.25253) (xy 160.743249 -274.286622) (xy 160.702746 -274.314578) (xy 160.658284 -274.335676)
			(xy 160.611013 -274.349368) (xy 160.562158 -274.3553) (xy 160.512983 -274.353319) (xy 160.464764 -274.343475)
			(xy 160.418748 -274.326023) (xy 160.376127 -274.301416) (xy 160.338006 -274.270291) (xy 160.305371 -274.233454)
			(xy 160.279068 -274.191858) (xy 160.259777 -274.146582) (xy 160.248 -274.098798) (xy 160.24404 -274.049744)
			(xy 159.9058 -274.049744) (xy 159.901632 -274.100052) (xy 159.889228 -274.14903) (xy 159.868932 -274.195299)
			(xy 159.841297 -274.237595) (xy 159.807077 -274.274767) (xy 159.767205 -274.305798) (xy 159.722769 -274.329843)
			(xy 159.674982 -274.346247) (xy 159.625146 -274.35456) (xy 159.599884 -274.355052) (xy 159.585701 -274.354877)
			(xy 159.557461 -274.352204) (xy 159.543496 -274.349718) (xy 159.543242 -274.349718) (xy 159.531012 -274.348233)
			(xy 159.507523 -274.355538) (xy 159.498284 -274.363688) (xy 159.429958 -274.432268) (xy 159.422592 -274.45589)
			(xy 159.424878 -274.468336) (xy 159.427366 -274.482364) (xy 159.430036 -274.510732) (xy 159.430212 -274.524978)
			(xy 159.429746 -274.549801) (xy 159.421717 -274.598794) (xy 159.405868 -274.645842) (xy 159.382616 -274.689707)
			(xy 159.352574 -274.729231) (xy 159.316533 -274.763375) (xy 159.275443 -274.791238) (xy 159.230387 -274.812086)
			(xy 159.182551 -274.825371) (xy 159.133196 -274.83074) (xy 159.083622 -274.828055) (xy 159.035136 -274.817384)
			(xy 158.989016 -274.79901) (xy 158.946475 -274.773416) (xy 158.908636 -274.741277) (xy 158.876494 -274.70344)
			(xy 158.850898 -274.660901) (xy 158.832521 -274.614781) (xy 158.821848 -274.566296) (xy 158.819159 -274.516722)
			(xy 158.824526 -274.467367) (xy 158.837807 -274.41953) (xy 158.858653 -274.374472) (xy 158.886513 -274.333381)
			(xy 158.920655 -274.297338) (xy 158.960178 -274.267293) (xy 159.004041 -274.244039) (xy 159.051089 -274.228187)
			(xy 159.100081 -274.220156) (xy 159.124904 -274.21967) (xy 159.139087 -274.219846) (xy 159.167327 -274.222519)
			(xy 159.181292 -274.225004) (xy 159.181546 -274.225004) (xy 159.193776 -274.226476) (xy 159.217263 -274.219179)
			(xy 159.226504 -274.211034) (xy 159.29483 -274.142454) (xy 159.302196 -274.118832) (xy 159.29991 -274.106386)
			(xy 159.297425 -274.092357) (xy 159.294753 -274.06399) (xy 159.294576 -274.049744) (xy 159.294759 -274.035561)
			(xy 159.297427 -274.007321) (xy 159.29991 -273.993356) (xy 159.302196 -273.98091) (xy 159.29483 -273.957288)
			(xy 159.21736 -273.879818) (xy 159.193738 -273.872452) (xy 159.181292 -273.874738) (xy 159.167326 -273.877211)
			(xy 159.139086 -273.879885) (xy 159.124904 -273.880072) (xy 159.099643 -273.879652) (xy 159.04981 -273.871336)
			(xy 159.002026 -273.854933) (xy 158.957593 -273.830887) (xy 158.917724 -273.799856) (xy 158.883506 -273.762687)
			(xy 158.855873 -273.720392) (xy 158.835579 -273.674125) (xy 158.823176 -273.625149) (xy 158.819004 -273.5748)
			(xy 158.480251 -273.5748) (xy 158.479757 -273.599371) (xy 158.471862 -273.647948) (xy 158.456278 -273.694629)
			(xy 158.433407 -273.738206) (xy 158.403842 -273.77755) (xy 158.368349 -273.811642) (xy 158.327846 -273.839598)
			(xy 158.283384 -273.860696) (xy 158.236113 -273.874388) (xy 158.187258 -273.88032) (xy 158.138083 -273.878339)
			(xy 158.089864 -273.868495) (xy 158.043848 -273.851043) (xy 158.001227 -273.826436) (xy 157.963106 -273.795311)
			(xy 157.930471 -273.758474) (xy 157.904168 -273.716878) (xy 157.884877 -273.671602) (xy 157.8731 -273.623818)
			(xy 157.86914 -273.574764) (xy 157.530292 -273.574764) (xy 157.529797 -273.599371) (xy 157.521902 -273.647948)
			(xy 157.506318 -273.694629) (xy 157.483447 -273.738206) (xy 157.453882 -273.77755) (xy 157.418389 -273.811642)
			(xy 157.377886 -273.839598) (xy 157.333424 -273.860696) (xy 157.286153 -273.874388) (xy 157.237298 -273.88032)
			(xy 157.188123 -273.878339) (xy 157.139904 -273.868495) (xy 157.093888 -273.851043) (xy 157.051267 -273.826436)
			(xy 157.013146 -273.795311) (xy 156.980511 -273.758474) (xy 156.954208 -273.716878) (xy 156.934917 -273.671602)
			(xy 156.92314 -273.623818) (xy 156.91918 -273.574764) (xy 156.580332 -273.574764) (xy 156.579837 -273.599371)
			(xy 156.571942 -273.647948) (xy 156.556358 -273.694629) (xy 156.533487 -273.738206) (xy 156.503922 -273.77755)
			(xy 156.468429 -273.811642) (xy 156.427926 -273.839598) (xy 156.383464 -273.860696) (xy 156.336193 -273.874388)
			(xy 156.287338 -273.88032) (xy 156.238163 -273.878339) (xy 156.189944 -273.868495) (xy 156.143928 -273.851043)
			(xy 156.101307 -273.826436) (xy 156.063186 -273.795311) (xy 156.030551 -273.758474) (xy 156.004248 -273.716878)
			(xy 155.984957 -273.671602) (xy 155.97318 -273.623818) (xy 155.96922 -273.574764) (xy 155.630372 -273.574764)
			(xy 155.629877 -273.599371) (xy 155.621982 -273.647948) (xy 155.606398 -273.694629) (xy 155.583527 -273.738206)
			(xy 155.553962 -273.77755) (xy 155.518469 -273.811642) (xy 155.477966 -273.839598) (xy 155.433504 -273.860696)
			(xy 155.386233 -273.874388) (xy 155.337378 -273.88032) (xy 155.288203 -273.878339) (xy 155.239984 -273.868495)
			(xy 155.193968 -273.851043) (xy 155.151347 -273.826436) (xy 155.113226 -273.795311) (xy 155.080591 -273.758474)
			(xy 155.054288 -273.716878) (xy 155.034997 -273.671602) (xy 155.02322 -273.623818) (xy 155.01926 -273.574764)
			(xy 154.680158 -273.574764) (xy 154.679663 -273.599371) (xy 154.671768 -273.647948) (xy 154.656184 -273.694629)
			(xy 154.633313 -273.738206) (xy 154.603748 -273.77755) (xy 154.568255 -273.811642) (xy 154.527752 -273.839598)
			(xy 154.48329 -273.860696) (xy 154.436019 -273.874388) (xy 154.387164 -273.88032) (xy 154.337989 -273.878339)
			(xy 154.28977 -273.868495) (xy 154.243754 -273.851043) (xy 154.201133 -273.826436) (xy 154.163012 -273.795311)
			(xy 154.130377 -273.758474) (xy 154.104074 -273.716878) (xy 154.084783 -273.671602) (xy 154.073006 -273.623818)
			(xy 154.069046 -273.574764) (xy 153.730198 -273.574764) (xy 153.729703 -273.599371) (xy 153.721808 -273.647948)
			(xy 153.706224 -273.694629) (xy 153.683353 -273.738206) (xy 153.653788 -273.77755) (xy 153.618295 -273.811642)
			(xy 153.577792 -273.839598) (xy 153.53333 -273.860696) (xy 153.486059 -273.874388) (xy 153.437204 -273.88032)
			(xy 153.388029 -273.878339) (xy 153.33981 -273.868495) (xy 153.293794 -273.851043) (xy 153.251173 -273.826436)
			(xy 153.213052 -273.795311) (xy 153.180417 -273.758474) (xy 153.154114 -273.716878) (xy 153.134823 -273.671602)
			(xy 153.123046 -273.623818) (xy 153.119086 -273.574764) (xy 149.705824 -273.574764) (xy 149.660147 -273.642802)
			(xy 149.544769 -273.800344) (xy 149.423048 -273.953039) (xy 149.295187 -274.100631) (xy 149.161402 -274.242875)
			(xy 149.021914 -274.379531) (xy 148.876958 -274.510372) (xy 148.859688 -274.524724) (xy 153.119086 -274.524724)
			(xy 153.123046 -274.47567) (xy 153.134823 -274.427886) (xy 153.154114 -274.38261) (xy 153.180417 -274.341014)
			(xy 153.213052 -274.304177) (xy 153.251173 -274.273052) (xy 153.293794 -274.248445) (xy 153.33981 -274.230993)
			(xy 153.388029 -274.221149) (xy 153.437204 -274.219168) (xy 153.486059 -274.2251) (xy 153.53333 -274.238792)
			(xy 153.577792 -274.25989) (xy 153.618295 -274.287846) (xy 153.653788 -274.321938) (xy 153.683353 -274.361282)
			(xy 153.706224 -274.404859) (xy 153.721808 -274.45154) (xy 153.729703 -274.500117) (xy 153.730198 -274.524724)
			(xy 153.730193 -274.524978) (xy 154.0693 -274.524978) (xy 154.07326 -274.475924) (xy 154.085037 -274.42814)
			(xy 154.104328 -274.382864) (xy 154.130631 -274.341268) (xy 154.163266 -274.304431) (xy 154.201387 -274.273306)
			(xy 154.244008 -274.248699) (xy 154.290024 -274.231247) (xy 154.338243 -274.221403) (xy 154.387418 -274.219422)
			(xy 154.436273 -274.225354) (xy 154.483544 -274.239046) (xy 154.528006 -274.260144) (xy 154.568509 -274.2881)
			(xy 154.604002 -274.322192) (xy 154.633567 -274.361536) (xy 154.656438 -274.405113) (xy 154.672022 -274.451794)
			(xy 154.679917 -274.500371) (xy 154.680412 -274.524978) (xy 155.01926 -274.524978) (xy 155.02322 -274.475924)
			(xy 155.034997 -274.42814) (xy 155.054288 -274.382864) (xy 155.080591 -274.341268) (xy 155.113226 -274.304431)
			(xy 155.151347 -274.273306) (xy 155.193968 -274.248699) (xy 155.239984 -274.231247) (xy 155.288203 -274.221403)
			(xy 155.337378 -274.219422) (xy 155.386233 -274.225354) (xy 155.433504 -274.239046) (xy 155.477966 -274.260144)
			(xy 155.518469 -274.2881) (xy 155.553962 -274.322192) (xy 155.583527 -274.361536) (xy 155.606398 -274.405113)
			(xy 155.621982 -274.451794) (xy 155.629877 -274.500371) (xy 155.630372 -274.524978) (xy 155.96922 -274.524978)
			(xy 155.97318 -274.475924) (xy 155.984957 -274.42814) (xy 156.004248 -274.382864) (xy 156.030551 -274.341268)
			(xy 156.063186 -274.304431) (xy 156.101307 -274.273306) (xy 156.143928 -274.248699) (xy 156.189944 -274.231247)
			(xy 156.238163 -274.221403) (xy 156.287338 -274.219422) (xy 156.336193 -274.225354) (xy 156.383464 -274.239046)
			(xy 156.427926 -274.260144) (xy 156.468429 -274.2881) (xy 156.503922 -274.322192) (xy 156.533487 -274.361536)
			(xy 156.556358 -274.405113) (xy 156.571942 -274.451794) (xy 156.579837 -274.500371) (xy 156.580332 -274.524978)
			(xy 156.91918 -274.524978) (xy 156.92314 -274.475924) (xy 156.934917 -274.42814) (xy 156.954208 -274.382864)
			(xy 156.980511 -274.341268) (xy 157.013146 -274.304431) (xy 157.051267 -274.273306) (xy 157.093888 -274.248699)
			(xy 157.139904 -274.231247) (xy 157.188123 -274.221403) (xy 157.237298 -274.219422) (xy 157.286153 -274.225354)
			(xy 157.333424 -274.239046) (xy 157.377886 -274.260144) (xy 157.418389 -274.2881) (xy 157.453882 -274.322192)
			(xy 157.483447 -274.361536) (xy 157.506318 -274.405113) (xy 157.521902 -274.451794) (xy 157.529797 -274.500371)
			(xy 157.530292 -274.524978) (xy 157.86914 -274.524978) (xy 157.8731 -274.475924) (xy 157.884877 -274.42814)
			(xy 157.904168 -274.382864) (xy 157.930471 -274.341268) (xy 157.963106 -274.304431) (xy 158.001227 -274.273306)
			(xy 158.043848 -274.248699) (xy 158.089864 -274.231247) (xy 158.138083 -274.221403) (xy 158.187258 -274.219422)
			(xy 158.236113 -274.225354) (xy 158.283384 -274.239046) (xy 158.327846 -274.260144) (xy 158.368349 -274.2881)
			(xy 158.403842 -274.322192) (xy 158.433407 -274.361536) (xy 158.456278 -274.405113) (xy 158.471862 -274.451794)
			(xy 158.479757 -274.500371) (xy 158.480252 -274.524978) (xy 158.479757 -274.549585) (xy 158.471862 -274.598162)
			(xy 158.456278 -274.644843) (xy 158.433407 -274.68842) (xy 158.403842 -274.727764) (xy 158.368349 -274.761856)
			(xy 158.327846 -274.789812) (xy 158.283384 -274.81091) (xy 158.236113 -274.824602) (xy 158.187258 -274.830534)
			(xy 158.138083 -274.828553) (xy 158.089864 -274.818709) (xy 158.043848 -274.801257) (xy 158.001227 -274.77665)
			(xy 157.963106 -274.745525) (xy 157.930471 -274.708688) (xy 157.904168 -274.667092) (xy 157.884877 -274.621816)
			(xy 157.8731 -274.574032) (xy 157.86914 -274.524978) (xy 157.530292 -274.524978) (xy 157.529797 -274.549585)
			(xy 157.521902 -274.598162) (xy 157.506318 -274.644843) (xy 157.483447 -274.68842) (xy 157.453882 -274.727764)
			(xy 157.418389 -274.761856) (xy 157.377886 -274.789812) (xy 157.333424 -274.81091) (xy 157.286153 -274.824602)
			(xy 157.237298 -274.830534) (xy 157.188123 -274.828553) (xy 157.139904 -274.818709) (xy 157.093888 -274.801257)
			(xy 157.051267 -274.77665) (xy 157.013146 -274.745525) (xy 156.980511 -274.708688) (xy 156.954208 -274.667092)
			(xy 156.934917 -274.621816) (xy 156.92314 -274.574032) (xy 156.91918 -274.524978) (xy 156.580332 -274.524978)
			(xy 156.579837 -274.549585) (xy 156.571942 -274.598162) (xy 156.556358 -274.644843) (xy 156.533487 -274.68842)
			(xy 156.503922 -274.727764) (xy 156.468429 -274.761856) (xy 156.427926 -274.789812) (xy 156.383464 -274.81091)
			(xy 156.336193 -274.824602) (xy 156.287338 -274.830534) (xy 156.238163 -274.828553) (xy 156.189944 -274.818709)
			(xy 156.143928 -274.801257) (xy 156.101307 -274.77665) (xy 156.063186 -274.745525) (xy 156.030551 -274.708688)
			(xy 156.004248 -274.667092) (xy 155.984957 -274.621816) (xy 155.97318 -274.574032) (xy 155.96922 -274.524978)
			(xy 155.630372 -274.524978) (xy 155.629877 -274.549585) (xy 155.621982 -274.598162) (xy 155.606398 -274.644843)
			(xy 155.583527 -274.68842) (xy 155.553962 -274.727764) (xy 155.518469 -274.761856) (xy 155.477966 -274.789812)
			(xy 155.433504 -274.81091) (xy 155.386233 -274.824602) (xy 155.337378 -274.830534) (xy 155.288203 -274.828553)
			(xy 155.239984 -274.818709) (xy 155.193968 -274.801257) (xy 155.151347 -274.77665) (xy 155.113226 -274.745525)
			(xy 155.080591 -274.708688) (xy 155.054288 -274.667092) (xy 155.034997 -274.621816) (xy 155.02322 -274.574032)
			(xy 155.01926 -274.524978) (xy 154.680412 -274.524978) (xy 154.679917 -274.549585) (xy 154.672022 -274.598162)
			(xy 154.656438 -274.644843) (xy 154.633567 -274.68842) (xy 154.604002 -274.727764) (xy 154.568509 -274.761856)
			(xy 154.528006 -274.789812) (xy 154.483544 -274.81091) (xy 154.436273 -274.824602) (xy 154.387418 -274.830534)
			(xy 154.338243 -274.828553) (xy 154.290024 -274.818709) (xy 154.244008 -274.801257) (xy 154.201387 -274.77665)
			(xy 154.163266 -274.745525) (xy 154.130631 -274.708688) (xy 154.104328 -274.667092) (xy 154.085037 -274.621816)
			(xy 154.07326 -274.574032) (xy 154.0693 -274.524978) (xy 153.730193 -274.524978) (xy 153.729703 -274.549331)
			(xy 153.721808 -274.597908) (xy 153.706224 -274.644589) (xy 153.683353 -274.688166) (xy 153.653788 -274.72751)
			(xy 153.618295 -274.761602) (xy 153.577792 -274.789558) (xy 153.53333 -274.810656) (xy 153.486059 -274.824348)
			(xy 153.437204 -274.83028) (xy 153.388029 -274.828299) (xy 153.33981 -274.818455) (xy 153.293794 -274.801003)
			(xy 153.251173 -274.776396) (xy 153.213052 -274.745271) (xy 153.180417 -274.708434) (xy 153.154114 -274.666838)
			(xy 153.134823 -274.621562) (xy 153.123046 -274.573778) (xy 153.119086 -274.524724) (xy 148.859688 -274.524724)
			(xy 148.726775 -274.635179) (xy 148.571617 -274.753743) (xy 148.411742 -274.865867) (xy 148.247418 -274.971363)
			(xy 148.198597 -274.999958) (xy 160.24404 -274.999958) (xy 160.248 -274.950904) (xy 160.259777 -274.90312)
			(xy 160.279068 -274.857844) (xy 160.305371 -274.816248) (xy 160.338006 -274.779411) (xy 160.376127 -274.748286)
			(xy 160.418748 -274.723679) (xy 160.464764 -274.706227) (xy 160.512983 -274.696383) (xy 160.562158 -274.694402)
			(xy 160.611013 -274.700334) (xy 160.658284 -274.714026) (xy 160.702746 -274.735124) (xy 160.743249 -274.76308)
			(xy 160.778742 -274.797172) (xy 160.808307 -274.836516) (xy 160.831178 -274.880093) (xy 160.846762 -274.926774)
			(xy 160.854657 -274.975351) (xy 160.855152 -274.999958) (xy 161.194254 -274.999958) (xy 161.198214 -274.950904)
			(xy 161.209991 -274.90312) (xy 161.229282 -274.857844) (xy 161.255585 -274.816248) (xy 161.28822 -274.779411)
			(xy 161.326341 -274.748286) (xy 161.368962 -274.723679) (xy 161.414978 -274.706227) (xy 161.463197 -274.696383)
			(xy 161.512372 -274.694402) (xy 161.561227 -274.700334) (xy 161.608498 -274.714026) (xy 161.65296 -274.735124)
			(xy 161.693463 -274.76308) (xy 161.728956 -274.797172) (xy 161.758521 -274.836516) (xy 161.781392 -274.880093)
			(xy 161.796976 -274.926774) (xy 161.804871 -274.975351) (xy 161.805366 -274.999958) (xy 162.144214 -274.999958)
			(xy 162.148174 -274.950904) (xy 162.159951 -274.90312) (xy 162.179242 -274.857844) (xy 162.205545 -274.816248)
			(xy 162.23818 -274.779411) (xy 162.276301 -274.748286) (xy 162.318922 -274.723679) (xy 162.364938 -274.706227)
			(xy 162.413157 -274.696383) (xy 162.462332 -274.694402) (xy 162.511187 -274.700334) (xy 162.558458 -274.714026)
			(xy 162.60292 -274.735124) (xy 162.643423 -274.76308) (xy 162.678916 -274.797172) (xy 162.708481 -274.836516)
			(xy 162.731352 -274.880093) (xy 162.746936 -274.926774) (xy 162.754831 -274.975351) (xy 162.755326 -274.999958)
			(xy 163.094174 -274.999958) (xy 163.098134 -274.950904) (xy 163.109911 -274.90312) (xy 163.129202 -274.857844)
			(xy 163.155505 -274.816248) (xy 163.18814 -274.779411) (xy 163.226261 -274.748286) (xy 163.268882 -274.723679)
			(xy 163.314898 -274.706227) (xy 163.363117 -274.696383) (xy 163.412292 -274.694402) (xy 163.461147 -274.700334)
			(xy 163.508418 -274.714026) (xy 163.55288 -274.735124) (xy 163.593383 -274.76308) (xy 163.628876 -274.797172)
			(xy 163.658441 -274.836516) (xy 163.681312 -274.880093) (xy 163.696896 -274.926774) (xy 163.704791 -274.975351)
			(xy 163.705286 -274.999958) (xy 164.044134 -274.999958) (xy 164.048094 -274.950904) (xy 164.059871 -274.90312)
			(xy 164.079162 -274.857844) (xy 164.105465 -274.816248) (xy 164.1381 -274.779411) (xy 164.176221 -274.748286)
			(xy 164.218842 -274.723679) (xy 164.264858 -274.706227) (xy 164.313077 -274.696383) (xy 164.362252 -274.694402)
			(xy 164.411107 -274.700334) (xy 164.458378 -274.714026) (xy 164.50284 -274.735124) (xy 164.543343 -274.76308)
			(xy 164.578836 -274.797172) (xy 164.608401 -274.836516) (xy 164.631272 -274.880093) (xy 164.646856 -274.926774)
			(xy 164.654751 -274.975351) (xy 164.655246 -274.999958) (xy 164.994094 -274.999958) (xy 164.998054 -274.950904)
			(xy 165.009831 -274.90312) (xy 165.029122 -274.857844) (xy 165.055425 -274.816248) (xy 165.08806 -274.779411)
			(xy 165.126181 -274.748286) (xy 165.168802 -274.723679) (xy 165.214818 -274.706227) (xy 165.263037 -274.696383)
			(xy 165.312212 -274.694402) (xy 165.361067 -274.700334) (xy 165.408338 -274.714026) (xy 165.4528 -274.735124)
			(xy 165.493303 -274.76308) (xy 165.528796 -274.797172) (xy 165.558361 -274.836516) (xy 165.581232 -274.880093)
			(xy 165.596816 -274.926774) (xy 165.604711 -274.975351) (xy 165.605206 -274.999958) (xy 165.944054 -274.999958)
			(xy 165.948014 -274.950904) (xy 165.959791 -274.90312) (xy 165.979082 -274.857844) (xy 166.005385 -274.816248)
			(xy 166.03802 -274.779411) (xy 166.076141 -274.748286) (xy 166.118762 -274.723679) (xy 166.164778 -274.706227)
			(xy 166.212997 -274.696383) (xy 166.262172 -274.694402) (xy 166.311027 -274.700334) (xy 166.358298 -274.714026)
			(xy 166.40276 -274.735124) (xy 166.443263 -274.76308) (xy 166.478756 -274.797172) (xy 166.508321 -274.836516)
			(xy 166.531192 -274.880093) (xy 166.546776 -274.926774) (xy 166.554671 -274.975351) (xy 166.555166 -274.999958)
			(xy 166.894268 -274.999958) (xy 166.898228 -274.950904) (xy 166.910005 -274.90312) (xy 166.929296 -274.857844)
			(xy 166.955599 -274.816248) (xy 166.988234 -274.779411) (xy 167.026355 -274.748286) (xy 167.068976 -274.723679)
			(xy 167.114992 -274.706227) (xy 167.163211 -274.696383) (xy 167.212386 -274.694402) (xy 167.261241 -274.700334)
			(xy 167.308512 -274.714026) (xy 167.352974 -274.735124) (xy 167.393477 -274.76308) (xy 167.42897 -274.797172)
			(xy 167.458535 -274.836516) (xy 167.481406 -274.880093) (xy 167.49699 -274.926774) (xy 167.504885 -274.975351)
			(xy 167.50538 -274.999958) (xy 167.844228 -274.999958) (xy 167.848188 -274.950904) (xy 167.859965 -274.90312)
			(xy 167.879256 -274.857844) (xy 167.905559 -274.816248) (xy 167.938194 -274.779411) (xy 167.976315 -274.748286)
			(xy 168.018936 -274.723679) (xy 168.064952 -274.706227) (xy 168.113171 -274.696383) (xy 168.162346 -274.694402)
			(xy 168.211201 -274.700334) (xy 168.258472 -274.714026) (xy 168.302934 -274.735124) (xy 168.343437 -274.76308)
			(xy 168.37893 -274.797172) (xy 168.408495 -274.836516) (xy 168.431366 -274.880093) (xy 168.44695 -274.926774)
			(xy 168.454845 -274.975351) (xy 168.45534 -274.999958) (xy 168.794188 -274.999958) (xy 168.798148 -274.950904)
			(xy 168.809925 -274.90312) (xy 168.829216 -274.857844) (xy 168.855519 -274.816248) (xy 168.888154 -274.779411)
			(xy 168.926275 -274.748286) (xy 168.968896 -274.723679) (xy 169.014912 -274.706227) (xy 169.063131 -274.696383)
			(xy 169.112306 -274.694402) (xy 169.161161 -274.700334) (xy 169.208432 -274.714026) (xy 169.252894 -274.735124)
			(xy 169.293397 -274.76308) (xy 169.32889 -274.797172) (xy 169.358455 -274.836516) (xy 169.381326 -274.880093)
			(xy 169.39691 -274.926774) (xy 169.404805 -274.975351) (xy 169.4053 -274.999958) (xy 169.744148 -274.999958)
			(xy 169.748108 -274.950904) (xy 169.759885 -274.90312) (xy 169.779176 -274.857844) (xy 169.805479 -274.816248)
			(xy 169.838114 -274.779411) (xy 169.876235 -274.748286) (xy 169.918856 -274.723679) (xy 169.964872 -274.706227)
			(xy 170.013091 -274.696383) (xy 170.062266 -274.694402) (xy 170.111121 -274.700334) (xy 170.158392 -274.714026)
			(xy 170.202854 -274.735124) (xy 170.243357 -274.76308) (xy 170.27885 -274.797172) (xy 170.308415 -274.836516)
			(xy 170.331286 -274.880093) (xy 170.34687 -274.926774) (xy 170.354765 -274.975351) (xy 170.35526 -274.999958)
			(xy 170.694108 -274.999958) (xy 170.698068 -274.950904) (xy 170.709845 -274.90312) (xy 170.729136 -274.857844)
			(xy 170.755439 -274.816248) (xy 170.788074 -274.779411) (xy 170.826195 -274.748286) (xy 170.868816 -274.723679)
			(xy 170.914832 -274.706227) (xy 170.963051 -274.696383) (xy 171.012226 -274.694402) (xy 171.061081 -274.700334)
			(xy 171.108352 -274.714026) (xy 171.152814 -274.735124) (xy 171.193317 -274.76308) (xy 171.22881 -274.797172)
			(xy 171.258375 -274.836516) (xy 171.281246 -274.880093) (xy 171.29683 -274.926774) (xy 171.304725 -274.975351)
			(xy 171.30522 -274.999958) (xy 171.644068 -274.999958) (xy 171.648028 -274.950904) (xy 171.659805 -274.90312)
			(xy 171.679096 -274.857844) (xy 171.705399 -274.816248) (xy 171.738034 -274.779411) (xy 171.776155 -274.748286)
			(xy 171.818776 -274.723679) (xy 171.864792 -274.706227) (xy 171.913011 -274.696383) (xy 171.962186 -274.694402)
			(xy 172.011041 -274.700334) (xy 172.058312 -274.714026) (xy 172.102774 -274.735124) (xy 172.143277 -274.76308)
			(xy 172.17877 -274.797172) (xy 172.208335 -274.836516) (xy 172.231206 -274.880093) (xy 172.24679 -274.926774)
			(xy 172.254685 -274.975351) (xy 172.25518 -274.999958) (xy 172.594282 -274.999958) (xy 172.598242 -274.950904)
			(xy 172.610019 -274.90312) (xy 172.62931 -274.857844) (xy 172.655613 -274.816248) (xy 172.688248 -274.779411)
			(xy 172.726369 -274.748286) (xy 172.76899 -274.723679) (xy 172.815006 -274.706227) (xy 172.863225 -274.696383)
			(xy 172.9124 -274.694402) (xy 172.961255 -274.700334) (xy 173.008526 -274.714026) (xy 173.052988 -274.735124)
			(xy 173.093491 -274.76308) (xy 173.128984 -274.797172) (xy 173.158549 -274.836516) (xy 173.18142 -274.880093)
			(xy 173.197004 -274.926774) (xy 173.204899 -274.975351) (xy 173.205394 -274.999958) (xy 173.204899 -275.024565)
			(xy 173.197004 -275.073142) (xy 173.18142 -275.119823) (xy 173.158549 -275.1634) (xy 173.128984 -275.202744)
			(xy 173.093491 -275.236836) (xy 173.052988 -275.264792) (xy 173.008526 -275.28589) (xy 172.961255 -275.299582)
			(xy 172.9124 -275.305514) (xy 172.863225 -275.303533) (xy 172.815006 -275.293689) (xy 172.76899 -275.276237)
			(xy 172.726369 -275.25163) (xy 172.688248 -275.220505) (xy 172.655613 -275.183668) (xy 172.62931 -275.142072)
			(xy 172.610019 -275.096796) (xy 172.598242 -275.049012) (xy 172.594282 -274.999958) (xy 172.25518 -274.999958)
			(xy 172.254685 -275.024565) (xy 172.24679 -275.073142) (xy 172.231206 -275.119823) (xy 172.208335 -275.1634)
			(xy 172.17877 -275.202744) (xy 172.143277 -275.236836) (xy 172.102774 -275.264792) (xy 172.058312 -275.28589)
			(xy 172.011041 -275.299582) (xy 171.962186 -275.305514) (xy 171.913011 -275.303533) (xy 171.864792 -275.293689)
			(xy 171.818776 -275.276237) (xy 171.776155 -275.25163) (xy 171.738034 -275.220505) (xy 171.705399 -275.183668)
			(xy 171.679096 -275.142072) (xy 171.659805 -275.096796) (xy 171.648028 -275.049012) (xy 171.644068 -274.999958)
			(xy 171.30522 -274.999958) (xy 171.304725 -275.024565) (xy 171.29683 -275.073142) (xy 171.281246 -275.119823)
			(xy 171.258375 -275.1634) (xy 171.22881 -275.202744) (xy 171.193317 -275.236836) (xy 171.152814 -275.264792)
			(xy 171.108352 -275.28589) (xy 171.061081 -275.299582) (xy 171.012226 -275.305514) (xy 170.963051 -275.303533)
			(xy 170.914832 -275.293689) (xy 170.868816 -275.276237) (xy 170.826195 -275.25163) (xy 170.788074 -275.220505)
			(xy 170.755439 -275.183668) (xy 170.729136 -275.142072) (xy 170.709845 -275.096796) (xy 170.698068 -275.049012)
			(xy 170.694108 -274.999958) (xy 170.35526 -274.999958) (xy 170.354765 -275.024565) (xy 170.34687 -275.073142)
			(xy 170.331286 -275.119823) (xy 170.308415 -275.1634) (xy 170.27885 -275.202744) (xy 170.243357 -275.236836)
			(xy 170.202854 -275.264792) (xy 170.158392 -275.28589) (xy 170.111121 -275.299582) (xy 170.062266 -275.305514)
			(xy 170.013091 -275.303533) (xy 169.964872 -275.293689) (xy 169.918856 -275.276237) (xy 169.876235 -275.25163)
			(xy 169.838114 -275.220505) (xy 169.805479 -275.183668) (xy 169.779176 -275.142072) (xy 169.759885 -275.096796)
			(xy 169.748108 -275.049012) (xy 169.744148 -274.999958) (xy 169.4053 -274.999958) (xy 169.404805 -275.024565)
			(xy 169.39691 -275.073142) (xy 169.381326 -275.119823) (xy 169.358455 -275.1634) (xy 169.32889 -275.202744)
			(xy 169.293397 -275.236836) (xy 169.252894 -275.264792) (xy 169.208432 -275.28589) (xy 169.161161 -275.299582)
			(xy 169.112306 -275.305514) (xy 169.063131 -275.303533) (xy 169.014912 -275.293689) (xy 168.968896 -275.276237)
			(xy 168.926275 -275.25163) (xy 168.888154 -275.220505) (xy 168.855519 -275.183668) (xy 168.829216 -275.142072)
			(xy 168.809925 -275.096796) (xy 168.798148 -275.049012) (xy 168.794188 -274.999958) (xy 168.45534 -274.999958)
			(xy 168.454845 -275.024565) (xy 168.44695 -275.073142) (xy 168.431366 -275.119823) (xy 168.408495 -275.1634)
			(xy 168.37893 -275.202744) (xy 168.343437 -275.236836) (xy 168.302934 -275.264792) (xy 168.258472 -275.28589)
			(xy 168.211201 -275.299582) (xy 168.162346 -275.305514) (xy 168.113171 -275.303533) (xy 168.064952 -275.293689)
			(xy 168.018936 -275.276237) (xy 167.976315 -275.25163) (xy 167.938194 -275.220505) (xy 167.905559 -275.183668)
			(xy 167.879256 -275.142072) (xy 167.859965 -275.096796) (xy 167.848188 -275.049012) (xy 167.844228 -274.999958)
			(xy 167.50538 -274.999958) (xy 167.504885 -275.024565) (xy 167.49699 -275.073142) (xy 167.481406 -275.119823)
			(xy 167.458535 -275.1634) (xy 167.42897 -275.202744) (xy 167.393477 -275.236836) (xy 167.352974 -275.264792)
			(xy 167.308512 -275.28589) (xy 167.261241 -275.299582) (xy 167.212386 -275.305514) (xy 167.163211 -275.303533)
			(xy 167.114992 -275.293689) (xy 167.068976 -275.276237) (xy 167.026355 -275.25163) (xy 166.988234 -275.220505)
			(xy 166.955599 -275.183668) (xy 166.929296 -275.142072) (xy 166.910005 -275.096796) (xy 166.898228 -275.049012)
			(xy 166.894268 -274.999958) (xy 166.555166 -274.999958) (xy 166.554671 -275.024565) (xy 166.546776 -275.073142)
			(xy 166.531192 -275.119823) (xy 166.508321 -275.1634) (xy 166.478756 -275.202744) (xy 166.443263 -275.236836)
			(xy 166.40276 -275.264792) (xy 166.358298 -275.28589) (xy 166.311027 -275.299582) (xy 166.262172 -275.305514)
			(xy 166.212997 -275.303533) (xy 166.164778 -275.293689) (xy 166.118762 -275.276237) (xy 166.076141 -275.25163)
			(xy 166.03802 -275.220505) (xy 166.005385 -275.183668) (xy 165.979082 -275.142072) (xy 165.959791 -275.096796)
			(xy 165.948014 -275.049012) (xy 165.944054 -274.999958) (xy 165.605206 -274.999958) (xy 165.604711 -275.024565)
			(xy 165.596816 -275.073142) (xy 165.581232 -275.119823) (xy 165.558361 -275.1634) (xy 165.528796 -275.202744)
			(xy 165.493303 -275.236836) (xy 165.4528 -275.264792) (xy 165.408338 -275.28589) (xy 165.361067 -275.299582)
			(xy 165.312212 -275.305514) (xy 165.263037 -275.303533) (xy 165.214818 -275.293689) (xy 165.168802 -275.276237)
			(xy 165.126181 -275.25163) (xy 165.08806 -275.220505) (xy 165.055425 -275.183668) (xy 165.029122 -275.142072)
			(xy 165.009831 -275.096796) (xy 164.998054 -275.049012) (xy 164.994094 -274.999958) (xy 164.655246 -274.999958)
			(xy 164.654751 -275.024565) (xy 164.646856 -275.073142) (xy 164.631272 -275.119823) (xy 164.608401 -275.1634)
			(xy 164.578836 -275.202744) (xy 164.543343 -275.236836) (xy 164.50284 -275.264792) (xy 164.458378 -275.28589)
			(xy 164.411107 -275.299582) (xy 164.362252 -275.305514) (xy 164.313077 -275.303533) (xy 164.264858 -275.293689)
			(xy 164.218842 -275.276237) (xy 164.176221 -275.25163) (xy 164.1381 -275.220505) (xy 164.105465 -275.183668)
			(xy 164.079162 -275.142072) (xy 164.059871 -275.096796) (xy 164.048094 -275.049012) (xy 164.044134 -274.999958)
			(xy 163.705286 -274.999958) (xy 163.704791 -275.024565) (xy 163.696896 -275.073142) (xy 163.681312 -275.119823)
			(xy 163.658441 -275.1634) (xy 163.628876 -275.202744) (xy 163.593383 -275.236836) (xy 163.55288 -275.264792)
			(xy 163.508418 -275.28589) (xy 163.461147 -275.299582) (xy 163.412292 -275.305514) (xy 163.363117 -275.303533)
			(xy 163.314898 -275.293689) (xy 163.268882 -275.276237) (xy 163.226261 -275.25163) (xy 163.18814 -275.220505)
			(xy 163.155505 -275.183668) (xy 163.129202 -275.142072) (xy 163.109911 -275.096796) (xy 163.098134 -275.049012)
			(xy 163.094174 -274.999958) (xy 162.755326 -274.999958) (xy 162.754831 -275.024565) (xy 162.746936 -275.073142)
			(xy 162.731352 -275.119823) (xy 162.708481 -275.1634) (xy 162.678916 -275.202744) (xy 162.643423 -275.236836)
			(xy 162.60292 -275.264792) (xy 162.558458 -275.28589) (xy 162.511187 -275.299582) (xy 162.462332 -275.305514)
			(xy 162.413157 -275.303533) (xy 162.364938 -275.293689) (xy 162.318922 -275.276237) (xy 162.276301 -275.25163)
			(xy 162.23818 -275.220505) (xy 162.205545 -275.183668) (xy 162.179242 -275.142072) (xy 162.159951 -275.096796)
			(xy 162.148174 -275.049012) (xy 162.144214 -274.999958) (xy 161.805366 -274.999958) (xy 161.804871 -275.024565)
			(xy 161.796976 -275.073142) (xy 161.781392 -275.119823) (xy 161.758521 -275.1634) (xy 161.728956 -275.202744)
			(xy 161.693463 -275.236836) (xy 161.65296 -275.264792) (xy 161.608498 -275.28589) (xy 161.561227 -275.299582)
			(xy 161.512372 -275.305514) (xy 161.463197 -275.303533) (xy 161.414978 -275.293689) (xy 161.368962 -275.276237)
			(xy 161.326341 -275.25163) (xy 161.28822 -275.220505) (xy 161.255585 -275.183668) (xy 161.229282 -275.142072)
			(xy 161.209991 -275.096796) (xy 161.198214 -275.049012) (xy 161.194254 -274.999958) (xy 160.855152 -274.999958)
			(xy 160.854657 -275.024565) (xy 160.846762 -275.073142) (xy 160.831178 -275.119823) (xy 160.808307 -275.1634)
			(xy 160.778742 -275.202744) (xy 160.743249 -275.236836) (xy 160.702746 -275.264792) (xy 160.658284 -275.28589)
			(xy 160.611013 -275.299582) (xy 160.562158 -275.305514) (xy 160.512983 -275.303533) (xy 160.464764 -275.293689)
			(xy 160.418748 -275.276237) (xy 160.376127 -275.25163) (xy 160.338006 -275.220505) (xy 160.305371 -275.183668)
			(xy 160.279068 -275.142072) (xy 160.259777 -275.096796) (xy 160.248 -275.049012) (xy 160.24404 -274.999958)
			(xy 148.198597 -274.999958) (xy 148.07892 -275.070055) (xy 147.906529 -275.161777) (xy 147.730533 -275.246377)
			(xy 147.551226 -275.323713) (xy 147.368908 -275.393655) (xy 147.183885 -275.456088) (xy 147.119437 -275.474938)
			(xy 152.169126 -275.474938) (xy 152.173086 -275.425884) (xy 152.184863 -275.3781) (xy 152.204154 -275.332824)
			(xy 152.230457 -275.291228) (xy 152.263092 -275.254391) (xy 152.301213 -275.223266) (xy 152.343834 -275.198659)
			(xy 152.38985 -275.181207) (xy 152.438069 -275.171363) (xy 152.487244 -275.169382) (xy 152.536099 -275.175314)
			(xy 152.58337 -275.189006) (xy 152.627832 -275.210104) (xy 152.668335 -275.23806) (xy 152.703828 -275.272152)
			(xy 152.733393 -275.311496) (xy 152.756264 -275.355073) (xy 152.771848 -275.401754) (xy 152.779743 -275.450331)
			(xy 152.780238 -275.474938) (xy 153.119086 -275.474938) (xy 153.123046 -275.425884) (xy 153.134823 -275.3781)
			(xy 153.154114 -275.332824) (xy 153.180417 -275.291228) (xy 153.213052 -275.254391) (xy 153.251173 -275.223266)
			(xy 153.293794 -275.198659) (xy 153.33981 -275.181207) (xy 153.388029 -275.171363) (xy 153.437204 -275.169382)
			(xy 153.486059 -275.175314) (xy 153.53333 -275.189006) (xy 153.577792 -275.210104) (xy 153.618295 -275.23806)
			(xy 153.653788 -275.272152) (xy 153.683353 -275.311496) (xy 153.706224 -275.355073) (xy 153.721808 -275.401754)
			(xy 153.729703 -275.450331) (xy 153.730198 -275.474938) (xy 154.0693 -275.474938) (xy 154.07326 -275.425884)
			(xy 154.085037 -275.3781) (xy 154.104328 -275.332824) (xy 154.130631 -275.291228) (xy 154.163266 -275.254391)
			(xy 154.201387 -275.223266) (xy 154.244008 -275.198659) (xy 154.290024 -275.181207) (xy 154.338243 -275.171363)
			(xy 154.387418 -275.169382) (xy 154.436273 -275.175314) (xy 154.483544 -275.189006) (xy 154.528006 -275.210104)
			(xy 154.568509 -275.23806) (xy 154.604002 -275.272152) (xy 154.633567 -275.311496) (xy 154.656438 -275.355073)
			(xy 154.672022 -275.401754) (xy 154.679917 -275.450331) (xy 154.680412 -275.474938) (xy 155.01926 -275.474938)
			(xy 155.02322 -275.425884) (xy 155.034997 -275.3781) (xy 155.054288 -275.332824) (xy 155.080591 -275.291228)
			(xy 155.113226 -275.254391) (xy 155.151347 -275.223266) (xy 155.193968 -275.198659) (xy 155.239984 -275.181207)
			(xy 155.288203 -275.171363) (xy 155.337378 -275.169382) (xy 155.386233 -275.175314) (xy 155.433504 -275.189006)
			(xy 155.477966 -275.210104) (xy 155.518469 -275.23806) (xy 155.553962 -275.272152) (xy 155.583527 -275.311496)
			(xy 155.606398 -275.355073) (xy 155.621982 -275.401754) (xy 155.629877 -275.450331) (xy 155.630372 -275.474938)
			(xy 155.96922 -275.474938) (xy 155.97318 -275.425884) (xy 155.984957 -275.3781) (xy 156.004248 -275.332824)
			(xy 156.030551 -275.291228) (xy 156.063186 -275.254391) (xy 156.101307 -275.223266) (xy 156.143928 -275.198659)
			(xy 156.189944 -275.181207) (xy 156.238163 -275.171363) (xy 156.287338 -275.169382) (xy 156.336193 -275.175314)
			(xy 156.383464 -275.189006) (xy 156.427926 -275.210104) (xy 156.468429 -275.23806) (xy 156.503922 -275.272152)
			(xy 156.533487 -275.311496) (xy 156.556358 -275.355073) (xy 156.571942 -275.401754) (xy 156.579837 -275.450331)
			(xy 156.580332 -275.474938) (xy 156.91918 -275.474938) (xy 156.92314 -275.425884) (xy 156.934917 -275.3781)
			(xy 156.954208 -275.332824) (xy 156.980511 -275.291228) (xy 157.013146 -275.254391) (xy 157.051267 -275.223266)
			(xy 157.093888 -275.198659) (xy 157.139904 -275.181207) (xy 157.188123 -275.171363) (xy 157.237298 -275.169382)
			(xy 157.286153 -275.175314) (xy 157.333424 -275.189006) (xy 157.377886 -275.210104) (xy 157.418389 -275.23806)
			(xy 157.453882 -275.272152) (xy 157.483447 -275.311496) (xy 157.506318 -275.355073) (xy 157.521902 -275.401754)
			(xy 157.529797 -275.450331) (xy 157.530292 -275.474938) (xy 157.86914 -275.474938) (xy 157.8731 -275.425884)
			(xy 157.884877 -275.3781) (xy 157.904168 -275.332824) (xy 157.930471 -275.291228) (xy 157.963106 -275.254391)
			(xy 158.001227 -275.223266) (xy 158.043848 -275.198659) (xy 158.089864 -275.181207) (xy 158.138083 -275.171363)
			(xy 158.187258 -275.169382) (xy 158.236113 -275.175314) (xy 158.283384 -275.189006) (xy 158.327846 -275.210104)
			(xy 158.368349 -275.23806) (xy 158.403842 -275.272152) (xy 158.433407 -275.311496) (xy 158.456278 -275.355073)
			(xy 158.471862 -275.401754) (xy 158.479757 -275.450331) (xy 158.480252 -275.474938) (xy 158.8191 -275.474938)
			(xy 158.82306 -275.425884) (xy 158.834837 -275.3781) (xy 158.854128 -275.332824) (xy 158.880431 -275.291228)
			(xy 158.913066 -275.254391) (xy 158.951187 -275.223266) (xy 158.993808 -275.198659) (xy 159.039824 -275.181207)
			(xy 159.088043 -275.171363) (xy 159.137218 -275.169382) (xy 159.186073 -275.175314) (xy 159.233344 -275.189006)
			(xy 159.277806 -275.210104) (xy 159.318309 -275.23806) (xy 159.353802 -275.272152) (xy 159.383367 -275.311496)
			(xy 159.406238 -275.355073) (xy 159.421822 -275.401754) (xy 159.429717 -275.450331) (xy 159.430212 -275.474938)
			(xy 159.429717 -275.499545) (xy 159.421822 -275.548122) (xy 159.406238 -275.594803) (xy 159.383367 -275.63838)
			(xy 159.353802 -275.677724) (xy 159.318309 -275.711816) (xy 159.277806 -275.739772) (xy 159.233344 -275.76087)
			(xy 159.186073 -275.774562) (xy 159.137218 -275.780494) (xy 159.088043 -275.778513) (xy 159.039824 -275.768669)
			(xy 158.993808 -275.751217) (xy 158.951187 -275.72661) (xy 158.913066 -275.695485) (xy 158.880431 -275.658648)
			(xy 158.854128 -275.617052) (xy 158.834837 -275.571776) (xy 158.82306 -275.523992) (xy 158.8191 -275.474938)
			(xy 158.480252 -275.474938) (xy 158.479757 -275.499545) (xy 158.471862 -275.548122) (xy 158.456278 -275.594803)
			(xy 158.433407 -275.63838) (xy 158.403842 -275.677724) (xy 158.368349 -275.711816) (xy 158.327846 -275.739772)
			(xy 158.283384 -275.76087) (xy 158.236113 -275.774562) (xy 158.187258 -275.780494) (xy 158.138083 -275.778513)
			(xy 158.089864 -275.768669) (xy 158.043848 -275.751217) (xy 158.001227 -275.72661) (xy 157.963106 -275.695485)
			(xy 157.930471 -275.658648) (xy 157.904168 -275.617052) (xy 157.884877 -275.571776) (xy 157.8731 -275.523992)
			(xy 157.86914 -275.474938) (xy 157.530292 -275.474938) (xy 157.529797 -275.499545) (xy 157.521902 -275.548122)
			(xy 157.506318 -275.594803) (xy 157.483447 -275.63838) (xy 157.453882 -275.677724) (xy 157.418389 -275.711816)
			(xy 157.377886 -275.739772) (xy 157.333424 -275.76087) (xy 157.286153 -275.774562) (xy 157.237298 -275.780494)
			(xy 157.188123 -275.778513) (xy 157.139904 -275.768669) (xy 157.093888 -275.751217) (xy 157.051267 -275.72661)
			(xy 157.013146 -275.695485) (xy 156.980511 -275.658648) (xy 156.954208 -275.617052) (xy 156.934917 -275.571776)
			(xy 156.92314 -275.523992) (xy 156.91918 -275.474938) (xy 156.580332 -275.474938) (xy 156.579837 -275.499545)
			(xy 156.571942 -275.548122) (xy 156.556358 -275.594803) (xy 156.533487 -275.63838) (xy 156.503922 -275.677724)
			(xy 156.468429 -275.711816) (xy 156.427926 -275.739772) (xy 156.383464 -275.76087) (xy 156.336193 -275.774562)
			(xy 156.287338 -275.780494) (xy 156.238163 -275.778513) (xy 156.189944 -275.768669) (xy 156.143928 -275.751217)
			(xy 156.101307 -275.72661) (xy 156.063186 -275.695485) (xy 156.030551 -275.658648) (xy 156.004248 -275.617052)
			(xy 155.984957 -275.571776) (xy 155.97318 -275.523992) (xy 155.96922 -275.474938) (xy 155.630372 -275.474938)
			(xy 155.629877 -275.499545) (xy 155.621982 -275.548122) (xy 155.606398 -275.594803) (xy 155.583527 -275.63838)
			(xy 155.553962 -275.677724) (xy 155.518469 -275.711816) (xy 155.477966 -275.739772) (xy 155.433504 -275.76087)
			(xy 155.386233 -275.774562) (xy 155.337378 -275.780494) (xy 155.288203 -275.778513) (xy 155.239984 -275.768669)
			(xy 155.193968 -275.751217) (xy 155.151347 -275.72661) (xy 155.113226 -275.695485) (xy 155.080591 -275.658648)
			(xy 155.054288 -275.617052) (xy 155.034997 -275.571776) (xy 155.02322 -275.523992) (xy 155.01926 -275.474938)
			(xy 154.680412 -275.474938) (xy 154.679917 -275.499545) (xy 154.672022 -275.548122) (xy 154.656438 -275.594803)
			(xy 154.633567 -275.63838) (xy 154.604002 -275.677724) (xy 154.568509 -275.711816) (xy 154.528006 -275.739772)
			(xy 154.483544 -275.76087) (xy 154.436273 -275.774562) (xy 154.387418 -275.780494) (xy 154.338243 -275.778513)
			(xy 154.290024 -275.768669) (xy 154.244008 -275.751217) (xy 154.201387 -275.72661) (xy 154.163266 -275.695485)
			(xy 154.130631 -275.658648) (xy 154.104328 -275.617052) (xy 154.085037 -275.571776) (xy 154.07326 -275.523992)
			(xy 154.0693 -275.474938) (xy 153.730198 -275.474938) (xy 153.729703 -275.499545) (xy 153.721808 -275.548122)
			(xy 153.706224 -275.594803) (xy 153.683353 -275.63838) (xy 153.653788 -275.677724) (xy 153.618295 -275.711816)
			(xy 153.577792 -275.739772) (xy 153.53333 -275.76087) (xy 153.486059 -275.774562) (xy 153.437204 -275.780494)
			(xy 153.388029 -275.778513) (xy 153.33981 -275.768669) (xy 153.293794 -275.751217) (xy 153.251173 -275.72661)
			(xy 153.213052 -275.695485) (xy 153.180417 -275.658648) (xy 153.154114 -275.617052) (xy 153.134823 -275.571776)
			(xy 153.123046 -275.523992) (xy 153.119086 -275.474938) (xy 152.780238 -275.474938) (xy 152.779743 -275.499545)
			(xy 152.771848 -275.548122) (xy 152.756264 -275.594803) (xy 152.733393 -275.63838) (xy 152.703828 -275.677724)
			(xy 152.668335 -275.711816) (xy 152.627832 -275.739772) (xy 152.58337 -275.76087) (xy 152.536099 -275.774562)
			(xy 152.487244 -275.780494) (xy 152.438069 -275.778513) (xy 152.38985 -275.768669) (xy 152.343834 -275.751217)
			(xy 152.301213 -275.72661) (xy 152.263092 -275.695485) (xy 152.230457 -275.658648) (xy 152.204154 -275.617052)
			(xy 152.184863 -275.571776) (xy 152.173086 -275.523992) (xy 152.169126 -275.474938) (xy 147.119437 -275.474938)
			(xy 146.996463 -275.510906) (xy 146.806959 -275.558019) (xy 146.615686 -275.597346) (xy 146.422967 -275.628824)
			(xy 146.326098 -275.641054) (xy 146.22932 -275.65233) (xy 146.035082 -275.667947) (xy 145.84037 -275.675627)
			(xy 145.645506 -275.67536) (xy 145.450816 -275.667144) (xy 145.256622 -275.650994) (xy 145.063249 -275.626936)
			(xy 144.871018 -275.595011) (xy 144.680249 -275.555272) (xy 144.49126 -275.507784) (xy 144.304366 -275.452627)
			(xy 144.119876 -275.389893) (xy 143.938099 -275.319687) (xy 143.759337 -275.242124) (xy 143.583887 -275.157334)
			(xy 143.412042 -275.065458) (xy 143.244087 -274.96665) (xy 143.080302 -274.861073) (xy 142.92096 -274.748903)
			(xy 142.766326 -274.630327) (xy 142.616657 -274.505543) (xy 142.472203 -274.374757) (xy 142.333203 -274.238189)
			(xy 142.199889 -274.096064) (xy 142.072484 -273.94862) (xy 141.951199 -273.796102) (xy 141.836235 -273.638763)
			(xy 141.727785 -273.476867) (xy 141.626029 -273.310681) (xy 141.531135 -273.140484) (xy 141.443263 -272.966557)
			(xy 141.362559 -272.789191) (xy 141.289156 -272.608681) (xy 141.223177 -272.425327) (xy 141.164731 -272.239434)
			(xy 141.113917 -272.051313) (xy 141.070818 -271.861275) (xy 141.035507 -271.669637) (xy 141.021308 -271.573244)
			(xy 141.021308 -271.572736) (xy 141.019631 -271.563826) (xy 141.010904 -271.547949) (xy 141.00429 -271.541748)
			(xy 140.997686 -271.535906) (xy 140.980668 -271.529556) (xy 138.611356 -271.529556) (xy 138.605346 -271.529722)
			(xy 138.593662 -271.532543) (xy 138.588242 -271.535144) (xy 138.584766 -271.536982) (xy 138.578385 -271.541573)
			(xy 138.575542 -271.544288) (xy 137.42924 -272.69059) (xy 137.421754 -272.698796) (xy 137.414111 -272.719622)
			(xy 137.414508 -272.730722) (xy 137.415524 -272.737072) (xy 137.432288 -272.815558) (xy 137.433304 -272.820638)
			(xy 137.43432 -272.82394) (xy 137.436076 -272.829624) (xy 137.441854 -272.840019) (xy 137.44575 -272.844514)
			(xy 137.44956 -272.848578) (xy 137.458958 -272.854928) (xy 137.4648 -272.857214) (xy 137.540494 -272.886892)
			(xy 137.689243 -272.952575) (xy 137.83466 -273.025338) (xy 137.976408 -273.105012) (xy 138.114159 -273.191413)
			(xy 138.247595 -273.284341) (xy 138.376405 -273.38358) (xy 138.500292 -273.488901) (xy 138.618969 -273.60006)
			(xy 138.732161 -273.716799) (xy 138.839606 -273.838849) (xy 138.941056 -273.965926) (xy 139.036274 -274.097736)
			(xy 139.125041 -274.233974) (xy 139.207152 -274.374325) (xy 139.282416 -274.518464) (xy 139.350658 -274.666056)
			(xy 139.411721 -274.816761) (xy 139.465464 -274.970228) (xy 139.511761 -275.126103) (xy 139.550507 -275.284025)
			(xy 139.58161 -275.443628) (xy 139.605 -275.604542) (xy 139.620621 -275.766396) (xy 139.628438 -275.928813)
			(xy 139.628553 -275.949918) (xy 160.24404 -275.949918) (xy 160.248 -275.900864) (xy 160.259777 -275.85308)
			(xy 160.279068 -275.807804) (xy 160.305371 -275.766208) (xy 160.338006 -275.729371) (xy 160.376127 -275.698246)
			(xy 160.418748 -275.673639) (xy 160.464764 -275.656187) (xy 160.512983 -275.646343) (xy 160.562158 -275.644362)
			(xy 160.611013 -275.650294) (xy 160.658284 -275.663986) (xy 160.702746 -275.685084) (xy 160.743249 -275.71304)
			(xy 160.778742 -275.747132) (xy 160.808307 -275.786476) (xy 160.831178 -275.830053) (xy 160.846762 -275.876734)
			(xy 160.854657 -275.925311) (xy 160.855152 -275.949918) (xy 161.194254 -275.949918) (xy 161.198214 -275.900864)
			(xy 161.209991 -275.85308) (xy 161.229282 -275.807804) (xy 161.255585 -275.766208) (xy 161.28822 -275.729371)
			(xy 161.326341 -275.698246) (xy 161.368962 -275.673639) (xy 161.414978 -275.656187) (xy 161.463197 -275.646343)
			(xy 161.512372 -275.644362) (xy 161.561227 -275.650294) (xy 161.608498 -275.663986) (xy 161.65296 -275.685084)
			(xy 161.693463 -275.71304) (xy 161.728956 -275.747132) (xy 161.758521 -275.786476) (xy 161.781392 -275.830053)
			(xy 161.796976 -275.876734) (xy 161.804871 -275.925311) (xy 161.805366 -275.949918) (xy 162.144214 -275.949918)
			(xy 162.148174 -275.900864) (xy 162.159951 -275.85308) (xy 162.179242 -275.807804) (xy 162.205545 -275.766208)
			(xy 162.23818 -275.729371) (xy 162.276301 -275.698246) (xy 162.318922 -275.673639) (xy 162.364938 -275.656187)
			(xy 162.413157 -275.646343) (xy 162.462332 -275.644362) (xy 162.511187 -275.650294) (xy 162.558458 -275.663986)
			(xy 162.60292 -275.685084) (xy 162.643423 -275.71304) (xy 162.678916 -275.747132) (xy 162.708481 -275.786476)
			(xy 162.731352 -275.830053) (xy 162.746936 -275.876734) (xy 162.754831 -275.925311) (xy 162.755326 -275.949918)
			(xy 163.094174 -275.949918) (xy 163.098134 -275.900864) (xy 163.109911 -275.85308) (xy 163.129202 -275.807804)
			(xy 163.155505 -275.766208) (xy 163.18814 -275.729371) (xy 163.226261 -275.698246) (xy 163.268882 -275.673639)
			(xy 163.314898 -275.656187) (xy 163.363117 -275.646343) (xy 163.412292 -275.644362) (xy 163.461147 -275.650294)
			(xy 163.508418 -275.663986) (xy 163.55288 -275.685084) (xy 163.593383 -275.71304) (xy 163.628876 -275.747132)
			(xy 163.658441 -275.786476) (xy 163.681312 -275.830053) (xy 163.696896 -275.876734) (xy 163.704791 -275.925311)
			(xy 163.705286 -275.949918) (xy 164.044134 -275.949918) (xy 164.048094 -275.900864) (xy 164.059871 -275.85308)
			(xy 164.079162 -275.807804) (xy 164.105465 -275.766208) (xy 164.1381 -275.729371) (xy 164.176221 -275.698246)
			(xy 164.218842 -275.673639) (xy 164.264858 -275.656187) (xy 164.313077 -275.646343) (xy 164.362252 -275.644362)
			(xy 164.411107 -275.650294) (xy 164.458378 -275.663986) (xy 164.50284 -275.685084) (xy 164.543343 -275.71304)
			(xy 164.578836 -275.747132) (xy 164.608401 -275.786476) (xy 164.631272 -275.830053) (xy 164.646856 -275.876734)
			(xy 164.654751 -275.925311) (xy 164.655246 -275.949918) (xy 164.994094 -275.949918) (xy 164.998054 -275.900864)
			(xy 165.009831 -275.85308) (xy 165.029122 -275.807804) (xy 165.055425 -275.766208) (xy 165.08806 -275.729371)
			(xy 165.126181 -275.698246) (xy 165.168802 -275.673639) (xy 165.214818 -275.656187) (xy 165.263037 -275.646343)
			(xy 165.312212 -275.644362) (xy 165.361067 -275.650294) (xy 165.408338 -275.663986) (xy 165.4528 -275.685084)
			(xy 165.493303 -275.71304) (xy 165.528796 -275.747132) (xy 165.558361 -275.786476) (xy 165.581232 -275.830053)
			(xy 165.596816 -275.876734) (xy 165.604711 -275.925311) (xy 165.605206 -275.949918) (xy 165.944054 -275.949918)
			(xy 165.948014 -275.900864) (xy 165.959791 -275.85308) (xy 165.979082 -275.807804) (xy 166.005385 -275.766208)
			(xy 166.03802 -275.729371) (xy 166.076141 -275.698246) (xy 166.118762 -275.673639) (xy 166.164778 -275.656187)
			(xy 166.212997 -275.646343) (xy 166.262172 -275.644362) (xy 166.311027 -275.650294) (xy 166.358298 -275.663986)
			(xy 166.40276 -275.685084) (xy 166.443263 -275.71304) (xy 166.478756 -275.747132) (xy 166.508321 -275.786476)
			(xy 166.531192 -275.830053) (xy 166.546776 -275.876734) (xy 166.554671 -275.925311) (xy 166.555166 -275.949918)
			(xy 166.894268 -275.949918) (xy 166.898228 -275.900864) (xy 166.910005 -275.85308) (xy 166.929296 -275.807804)
			(xy 166.955599 -275.766208) (xy 166.988234 -275.729371) (xy 167.026355 -275.698246) (xy 167.068976 -275.673639)
			(xy 167.114992 -275.656187) (xy 167.163211 -275.646343) (xy 167.212386 -275.644362) (xy 167.261241 -275.650294)
			(xy 167.308512 -275.663986) (xy 167.352974 -275.685084) (xy 167.393477 -275.71304) (xy 167.42897 -275.747132)
			(xy 167.458535 -275.786476) (xy 167.481406 -275.830053) (xy 167.49699 -275.876734) (xy 167.504885 -275.925311)
			(xy 167.50538 -275.949918) (xy 167.844228 -275.949918) (xy 167.848188 -275.900864) (xy 167.859965 -275.85308)
			(xy 167.879256 -275.807804) (xy 167.905559 -275.766208) (xy 167.938194 -275.729371) (xy 167.976315 -275.698246)
			(xy 168.018936 -275.673639) (xy 168.064952 -275.656187) (xy 168.113171 -275.646343) (xy 168.162346 -275.644362)
			(xy 168.211201 -275.650294) (xy 168.258472 -275.663986) (xy 168.302934 -275.685084) (xy 168.343437 -275.71304)
			(xy 168.37893 -275.747132) (xy 168.408495 -275.786476) (xy 168.431366 -275.830053) (xy 168.44695 -275.876734)
			(xy 168.454845 -275.925311) (xy 168.45534 -275.949918) (xy 168.794188 -275.949918) (xy 168.798148 -275.900864)
			(xy 168.809925 -275.85308) (xy 168.829216 -275.807804) (xy 168.855519 -275.766208) (xy 168.888154 -275.729371)
			(xy 168.926275 -275.698246) (xy 168.968896 -275.673639) (xy 169.014912 -275.656187) (xy 169.063131 -275.646343)
			(xy 169.112306 -275.644362) (xy 169.161161 -275.650294) (xy 169.208432 -275.663986) (xy 169.252894 -275.685084)
			(xy 169.293397 -275.71304) (xy 169.32889 -275.747132) (xy 169.358455 -275.786476) (xy 169.381326 -275.830053)
			(xy 169.39691 -275.876734) (xy 169.404805 -275.925311) (xy 169.4053 -275.949918) (xy 169.744148 -275.949918)
			(xy 169.748108 -275.900864) (xy 169.759885 -275.85308) (xy 169.779176 -275.807804) (xy 169.805479 -275.766208)
			(xy 169.838114 -275.729371) (xy 169.876235 -275.698246) (xy 169.918856 -275.673639) (xy 169.964872 -275.656187)
			(xy 170.013091 -275.646343) (xy 170.062266 -275.644362) (xy 170.111121 -275.650294) (xy 170.158392 -275.663986)
			(xy 170.202854 -275.685084) (xy 170.243357 -275.71304) (xy 170.27885 -275.747132) (xy 170.308415 -275.786476)
			(xy 170.331286 -275.830053) (xy 170.34687 -275.876734) (xy 170.354765 -275.925311) (xy 170.35526 -275.949918)
			(xy 170.694108 -275.949918) (xy 170.698068 -275.900864) (xy 170.709845 -275.85308) (xy 170.729136 -275.807804)
			(xy 170.755439 -275.766208) (xy 170.788074 -275.729371) (xy 170.826195 -275.698246) (xy 170.868816 -275.673639)
			(xy 170.914832 -275.656187) (xy 170.963051 -275.646343) (xy 171.012226 -275.644362) (xy 171.061081 -275.650294)
			(xy 171.108352 -275.663986) (xy 171.152814 -275.685084) (xy 171.193317 -275.71304) (xy 171.22881 -275.747132)
			(xy 171.258375 -275.786476) (xy 171.281246 -275.830053) (xy 171.29683 -275.876734) (xy 171.304725 -275.925311)
			(xy 171.30522 -275.949918) (xy 171.644068 -275.949918) (xy 171.648028 -275.900864) (xy 171.659805 -275.85308)
			(xy 171.679096 -275.807804) (xy 171.705399 -275.766208) (xy 171.738034 -275.729371) (xy 171.776155 -275.698246)
			(xy 171.818776 -275.673639) (xy 171.864792 -275.656187) (xy 171.913011 -275.646343) (xy 171.962186 -275.644362)
			(xy 172.011041 -275.650294) (xy 172.058312 -275.663986) (xy 172.102774 -275.685084) (xy 172.143277 -275.71304)
			(xy 172.17877 -275.747132) (xy 172.208335 -275.786476) (xy 172.231206 -275.830053) (xy 172.24679 -275.876734)
			(xy 172.254685 -275.925311) (xy 172.25518 -275.949918) (xy 172.594282 -275.949918) (xy 172.598242 -275.900864)
			(xy 172.610019 -275.85308) (xy 172.62931 -275.807804) (xy 172.655613 -275.766208) (xy 172.688248 -275.729371)
			(xy 172.726369 -275.698246) (xy 172.76899 -275.673639) (xy 172.815006 -275.656187) (xy 172.863225 -275.646343)
			(xy 172.9124 -275.644362) (xy 172.961255 -275.650294) (xy 173.008526 -275.663986) (xy 173.052988 -275.685084)
			(xy 173.093491 -275.71304) (xy 173.128984 -275.747132) (xy 173.158549 -275.786476) (xy 173.18142 -275.830053)
			(xy 173.197004 -275.876734) (xy 173.204899 -275.925311) (xy 173.205394 -275.949918) (xy 173.204899 -275.974525)
			(xy 173.197004 -276.023102) (xy 173.18142 -276.069783) (xy 173.158549 -276.11336) (xy 173.128984 -276.152704)
			(xy 173.093491 -276.186796) (xy 173.052988 -276.214752) (xy 173.008526 -276.23585) (xy 172.961255 -276.249542)
			(xy 172.9124 -276.255474) (xy 172.863225 -276.253493) (xy 172.815006 -276.243649) (xy 172.76899 -276.226197)
			(xy 172.726369 -276.20159) (xy 172.688248 -276.170465) (xy 172.655613 -276.133628) (xy 172.62931 -276.092032)
			(xy 172.610019 -276.046756) (xy 172.598242 -275.998972) (xy 172.594282 -275.949918) (xy 172.25518 -275.949918)
			(xy 172.254685 -275.974525) (xy 172.24679 -276.023102) (xy 172.231206 -276.069783) (xy 172.208335 -276.11336)
			(xy 172.17877 -276.152704) (xy 172.143277 -276.186796) (xy 172.102774 -276.214752) (xy 172.058312 -276.23585)
			(xy 172.011041 -276.249542) (xy 171.962186 -276.255474) (xy 171.913011 -276.253493) (xy 171.864792 -276.243649)
			(xy 171.818776 -276.226197) (xy 171.776155 -276.20159) (xy 171.738034 -276.170465) (xy 171.705399 -276.133628)
			(xy 171.679096 -276.092032) (xy 171.659805 -276.046756) (xy 171.648028 -275.998972) (xy 171.644068 -275.949918)
			(xy 171.30522 -275.949918) (xy 171.304725 -275.974525) (xy 171.29683 -276.023102) (xy 171.281246 -276.069783)
			(xy 171.258375 -276.11336) (xy 171.22881 -276.152704) (xy 171.193317 -276.186796) (xy 171.152814 -276.214752)
			(xy 171.108352 -276.23585) (xy 171.061081 -276.249542) (xy 171.012226 -276.255474) (xy 170.963051 -276.253493)
			(xy 170.914832 -276.243649) (xy 170.868816 -276.226197) (xy 170.826195 -276.20159) (xy 170.788074 -276.170465)
			(xy 170.755439 -276.133628) (xy 170.729136 -276.092032) (xy 170.709845 -276.046756) (xy 170.698068 -275.998972)
			(xy 170.694108 -275.949918) (xy 170.35526 -275.949918) (xy 170.354765 -275.974525) (xy 170.34687 -276.023102)
			(xy 170.331286 -276.069783) (xy 170.308415 -276.11336) (xy 170.27885 -276.152704) (xy 170.243357 -276.186796)
			(xy 170.202854 -276.214752) (xy 170.158392 -276.23585) (xy 170.111121 -276.249542) (xy 170.062266 -276.255474)
			(xy 170.013091 -276.253493) (xy 169.964872 -276.243649) (xy 169.918856 -276.226197) (xy 169.876235 -276.20159)
			(xy 169.838114 -276.170465) (xy 169.805479 -276.133628) (xy 169.779176 -276.092032) (xy 169.759885 -276.046756)
			(xy 169.748108 -275.998972) (xy 169.744148 -275.949918) (xy 169.4053 -275.949918) (xy 169.404805 -275.974525)
			(xy 169.39691 -276.023102) (xy 169.381326 -276.069783) (xy 169.358455 -276.11336) (xy 169.32889 -276.152704)
			(xy 169.293397 -276.186796) (xy 169.252894 -276.214752) (xy 169.208432 -276.23585) (xy 169.161161 -276.249542)
			(xy 169.112306 -276.255474) (xy 169.063131 -276.253493) (xy 169.014912 -276.243649) (xy 168.968896 -276.226197)
			(xy 168.926275 -276.20159) (xy 168.888154 -276.170465) (xy 168.855519 -276.133628) (xy 168.829216 -276.092032)
			(xy 168.809925 -276.046756) (xy 168.798148 -275.998972) (xy 168.794188 -275.949918) (xy 168.45534 -275.949918)
			(xy 168.454845 -275.974525) (xy 168.44695 -276.023102) (xy 168.431366 -276.069783) (xy 168.408495 -276.11336)
			(xy 168.37893 -276.152704) (xy 168.343437 -276.186796) (xy 168.302934 -276.214752) (xy 168.258472 -276.23585)
			(xy 168.211201 -276.249542) (xy 168.162346 -276.255474) (xy 168.113171 -276.253493) (xy 168.064952 -276.243649)
			(xy 168.018936 -276.226197) (xy 167.976315 -276.20159) (xy 167.938194 -276.170465) (xy 167.905559 -276.133628)
			(xy 167.879256 -276.092032) (xy 167.859965 -276.046756) (xy 167.848188 -275.998972) (xy 167.844228 -275.949918)
			(xy 167.50538 -275.949918) (xy 167.504885 -275.974525) (xy 167.49699 -276.023102) (xy 167.481406 -276.069783)
			(xy 167.458535 -276.11336) (xy 167.42897 -276.152704) (xy 167.393477 -276.186796) (xy 167.352974 -276.214752)
			(xy 167.308512 -276.23585) (xy 167.261241 -276.249542) (xy 167.212386 -276.255474) (xy 167.163211 -276.253493)
			(xy 167.114992 -276.243649) (xy 167.068976 -276.226197) (xy 167.026355 -276.20159) (xy 166.988234 -276.170465)
			(xy 166.955599 -276.133628) (xy 166.929296 -276.092032) (xy 166.910005 -276.046756) (xy 166.898228 -275.998972)
			(xy 166.894268 -275.949918) (xy 166.555166 -275.949918) (xy 166.554671 -275.974525) (xy 166.546776 -276.023102)
			(xy 166.531192 -276.069783) (xy 166.508321 -276.11336) (xy 166.478756 -276.152704) (xy 166.443263 -276.186796)
			(xy 166.40276 -276.214752) (xy 166.358298 -276.23585) (xy 166.311027 -276.249542) (xy 166.262172 -276.255474)
			(xy 166.212997 -276.253493) (xy 166.164778 -276.243649) (xy 166.118762 -276.226197) (xy 166.076141 -276.20159)
			(xy 166.03802 -276.170465) (xy 166.005385 -276.133628) (xy 165.979082 -276.092032) (xy 165.959791 -276.046756)
			(xy 165.948014 -275.998972) (xy 165.944054 -275.949918) (xy 165.605206 -275.949918) (xy 165.604711 -275.974525)
			(xy 165.596816 -276.023102) (xy 165.581232 -276.069783) (xy 165.558361 -276.11336) (xy 165.528796 -276.152704)
			(xy 165.493303 -276.186796) (xy 165.4528 -276.214752) (xy 165.408338 -276.23585) (xy 165.361067 -276.249542)
			(xy 165.312212 -276.255474) (xy 165.263037 -276.253493) (xy 165.214818 -276.243649) (xy 165.168802 -276.226197)
			(xy 165.126181 -276.20159) (xy 165.08806 -276.170465) (xy 165.055425 -276.133628) (xy 165.029122 -276.092032)
			(xy 165.009831 -276.046756) (xy 164.998054 -275.998972) (xy 164.994094 -275.949918) (xy 164.655246 -275.949918)
			(xy 164.654751 -275.974525) (xy 164.646856 -276.023102) (xy 164.631272 -276.069783) (xy 164.608401 -276.11336)
			(xy 164.578836 -276.152704) (xy 164.543343 -276.186796) (xy 164.50284 -276.214752) (xy 164.458378 -276.23585)
			(xy 164.411107 -276.249542) (xy 164.362252 -276.255474) (xy 164.313077 -276.253493) (xy 164.264858 -276.243649)
			(xy 164.218842 -276.226197) (xy 164.176221 -276.20159) (xy 164.1381 -276.170465) (xy 164.105465 -276.133628)
			(xy 164.079162 -276.092032) (xy 164.059871 -276.046756) (xy 164.048094 -275.998972) (xy 164.044134 -275.949918)
			(xy 163.705286 -275.949918) (xy 163.704791 -275.974525) (xy 163.696896 -276.023102) (xy 163.681312 -276.069783)
			(xy 163.658441 -276.11336) (xy 163.628876 -276.152704) (xy 163.593383 -276.186796) (xy 163.55288 -276.214752)
			(xy 163.508418 -276.23585) (xy 163.461147 -276.249542) (xy 163.412292 -276.255474) (xy 163.363117 -276.253493)
			(xy 163.314898 -276.243649) (xy 163.268882 -276.226197) (xy 163.226261 -276.20159) (xy 163.18814 -276.170465)
			(xy 163.155505 -276.133628) (xy 163.129202 -276.092032) (xy 163.109911 -276.046756) (xy 163.098134 -275.998972)
			(xy 163.094174 -275.949918) (xy 162.755326 -275.949918) (xy 162.754831 -275.974525) (xy 162.746936 -276.023102)
			(xy 162.731352 -276.069783) (xy 162.708481 -276.11336) (xy 162.678916 -276.152704) (xy 162.643423 -276.186796)
			(xy 162.60292 -276.214752) (xy 162.558458 -276.23585) (xy 162.511187 -276.249542) (xy 162.462332 -276.255474)
			(xy 162.413157 -276.253493) (xy 162.364938 -276.243649) (xy 162.318922 -276.226197) (xy 162.276301 -276.20159)
			(xy 162.23818 -276.170465) (xy 162.205545 -276.133628) (xy 162.179242 -276.092032) (xy 162.159951 -276.046756)
			(xy 162.148174 -275.998972) (xy 162.144214 -275.949918) (xy 161.805366 -275.949918) (xy 161.804871 -275.974525)
			(xy 161.796976 -276.023102) (xy 161.781392 -276.069783) (xy 161.758521 -276.11336) (xy 161.728956 -276.152704)
			(xy 161.693463 -276.186796) (xy 161.65296 -276.214752) (xy 161.608498 -276.23585) (xy 161.561227 -276.249542)
			(xy 161.512372 -276.255474) (xy 161.463197 -276.253493) (xy 161.414978 -276.243649) (xy 161.368962 -276.226197)
			(xy 161.326341 -276.20159) (xy 161.28822 -276.170465) (xy 161.255585 -276.133628) (xy 161.229282 -276.092032)
			(xy 161.209991 -276.046756) (xy 161.198214 -275.998972) (xy 161.194254 -275.949918) (xy 160.855152 -275.949918)
			(xy 160.854657 -275.974525) (xy 160.846762 -276.023102) (xy 160.831178 -276.069783) (xy 160.808307 -276.11336)
			(xy 160.778742 -276.152704) (xy 160.743249 -276.186796) (xy 160.702746 -276.214752) (xy 160.658284 -276.23585)
			(xy 160.611013 -276.249542) (xy 160.562158 -276.255474) (xy 160.512983 -276.253493) (xy 160.464764 -276.243649)
			(xy 160.418748 -276.226197) (xy 160.376127 -276.20159) (xy 160.338006 -276.170465) (xy 160.305371 -276.133628)
			(xy 160.279068 -276.092032) (xy 160.259777 -276.046756) (xy 160.248 -275.998972) (xy 160.24404 -275.949918)
			(xy 139.628553 -275.949918) (xy 139.62888 -276.010116) (xy 139.628379 -276.093046) (xy 139.62024 -276.258706)
			(xy 139.603982 -276.423767) (xy 139.603814 -276.424898) (xy 152.169126 -276.424898) (xy 152.173086 -276.375844)
			(xy 152.184863 -276.32806) (xy 152.204154 -276.282784) (xy 152.230457 -276.241188) (xy 152.263092 -276.204351)
			(xy 152.301213 -276.173226) (xy 152.343834 -276.148619) (xy 152.38985 -276.131167) (xy 152.438069 -276.121323)
			(xy 152.487244 -276.119342) (xy 152.536099 -276.125274) (xy 152.58337 -276.138966) (xy 152.627832 -276.160064)
			(xy 152.668335 -276.18802) (xy 152.703828 -276.222112) (xy 152.733393 -276.261456) (xy 152.756264 -276.305033)
			(xy 152.771848 -276.351714) (xy 152.779743 -276.400291) (xy 152.780238 -276.424898) (xy 153.119086 -276.424898)
			(xy 153.123046 -276.375844) (xy 153.134823 -276.32806) (xy 153.154114 -276.282784) (xy 153.180417 -276.241188)
			(xy 153.213052 -276.204351) (xy 153.251173 -276.173226) (xy 153.293794 -276.148619) (xy 153.33981 -276.131167)
			(xy 153.388029 -276.121323) (xy 153.437204 -276.119342) (xy 153.486059 -276.125274) (xy 153.53333 -276.138966)
			(xy 153.577792 -276.160064) (xy 153.618295 -276.18802) (xy 153.653788 -276.222112) (xy 153.683353 -276.261456)
			(xy 153.706224 -276.305033) (xy 153.721808 -276.351714) (xy 153.729703 -276.400291) (xy 153.730198 -276.424898)
			(xy 154.0693 -276.424898) (xy 154.07326 -276.375844) (xy 154.085037 -276.32806) (xy 154.104328 -276.282784)
			(xy 154.130631 -276.241188) (xy 154.163266 -276.204351) (xy 154.201387 -276.173226) (xy 154.244008 -276.148619)
			(xy 154.290024 -276.131167) (xy 154.338243 -276.121323) (xy 154.387418 -276.119342) (xy 154.436273 -276.125274)
			(xy 154.483544 -276.138966) (xy 154.528006 -276.160064) (xy 154.568509 -276.18802) (xy 154.604002 -276.222112)
			(xy 154.633567 -276.261456) (xy 154.656438 -276.305033) (xy 154.672022 -276.351714) (xy 154.679917 -276.400291)
			(xy 154.680412 -276.424898) (xy 155.01926 -276.424898) (xy 155.02322 -276.375844) (xy 155.034997 -276.32806)
			(xy 155.054288 -276.282784) (xy 155.080591 -276.241188) (xy 155.113226 -276.204351) (xy 155.151347 -276.173226)
			(xy 155.193968 -276.148619) (xy 155.239984 -276.131167) (xy 155.288203 -276.121323) (xy 155.337378 -276.119342)
			(xy 155.386233 -276.125274) (xy 155.433504 -276.138966) (xy 155.477966 -276.160064) (xy 155.518469 -276.18802)
			(xy 155.553962 -276.222112) (xy 155.583527 -276.261456) (xy 155.606398 -276.305033) (xy 155.621982 -276.351714)
			(xy 155.629877 -276.400291) (xy 155.630372 -276.424898) (xy 155.96922 -276.424898) (xy 155.97318 -276.375844)
			(xy 155.984957 -276.32806) (xy 156.004248 -276.282784) (xy 156.030551 -276.241188) (xy 156.063186 -276.204351)
			(xy 156.101307 -276.173226) (xy 156.143928 -276.148619) (xy 156.189944 -276.131167) (xy 156.238163 -276.121323)
			(xy 156.287338 -276.119342) (xy 156.336193 -276.125274) (xy 156.383464 -276.138966) (xy 156.427926 -276.160064)
			(xy 156.468429 -276.18802) (xy 156.503922 -276.222112) (xy 156.533487 -276.261456) (xy 156.556358 -276.305033)
			(xy 156.571942 -276.351714) (xy 156.579837 -276.400291) (xy 156.580332 -276.424898) (xy 156.91918 -276.424898)
			(xy 156.92314 -276.375844) (xy 156.934917 -276.32806) (xy 156.954208 -276.282784) (xy 156.980511 -276.241188)
			(xy 157.013146 -276.204351) (xy 157.051267 -276.173226) (xy 157.093888 -276.148619) (xy 157.139904 -276.131167)
			(xy 157.188123 -276.121323) (xy 157.237298 -276.119342) (xy 157.286153 -276.125274) (xy 157.333424 -276.138966)
			(xy 157.377886 -276.160064) (xy 157.418389 -276.18802) (xy 157.453882 -276.222112) (xy 157.483447 -276.261456)
			(xy 157.506318 -276.305033) (xy 157.521902 -276.351714) (xy 157.529797 -276.400291) (xy 157.530292 -276.424898)
			(xy 157.86914 -276.424898) (xy 157.8731 -276.375844) (xy 157.884877 -276.32806) (xy 157.904168 -276.282784)
			(xy 157.930471 -276.241188) (xy 157.963106 -276.204351) (xy 158.001227 -276.173226) (xy 158.043848 -276.148619)
			(xy 158.089864 -276.131167) (xy 158.138083 -276.121323) (xy 158.187258 -276.119342) (xy 158.236113 -276.125274)
			(xy 158.283384 -276.138966) (xy 158.327846 -276.160064) (xy 158.368349 -276.18802) (xy 158.403842 -276.222112)
			(xy 158.433407 -276.261456) (xy 158.456278 -276.305033) (xy 158.471862 -276.351714) (xy 158.479757 -276.400291)
			(xy 158.480252 -276.424898) (xy 158.479757 -276.449505) (xy 158.471862 -276.498082) (xy 158.456278 -276.544763)
			(xy 158.433407 -276.58834) (xy 158.403842 -276.627684) (xy 158.368349 -276.661776) (xy 158.327846 -276.689732)
			(xy 158.283384 -276.71083) (xy 158.236113 -276.724522) (xy 158.187258 -276.730454) (xy 158.138083 -276.728473)
			(xy 158.089864 -276.718629) (xy 158.043848 -276.701177) (xy 158.001227 -276.67657) (xy 157.963106 -276.645445)
			(xy 157.930471 -276.608608) (xy 157.904168 -276.567012) (xy 157.884877 -276.521736) (xy 157.8731 -276.473952)
			(xy 157.86914 -276.424898) (xy 157.530292 -276.424898) (xy 157.529797 -276.449505) (xy 157.521902 -276.498082)
			(xy 157.506318 -276.544763) (xy 157.483447 -276.58834) (xy 157.453882 -276.627684) (xy 157.418389 -276.661776)
			(xy 157.377886 -276.689732) (xy 157.333424 -276.71083) (xy 157.286153 -276.724522) (xy 157.237298 -276.730454)
			(xy 157.188123 -276.728473) (xy 157.139904 -276.718629) (xy 157.093888 -276.701177) (xy 157.051267 -276.67657)
			(xy 157.013146 -276.645445) (xy 156.980511 -276.608608) (xy 156.954208 -276.567012) (xy 156.934917 -276.521736)
			(xy 156.92314 -276.473952) (xy 156.91918 -276.424898) (xy 156.580332 -276.424898) (xy 156.579837 -276.449505)
			(xy 156.571942 -276.498082) (xy 156.556358 -276.544763) (xy 156.533487 -276.58834) (xy 156.503922 -276.627684)
			(xy 156.468429 -276.661776) (xy 156.427926 -276.689732) (xy 156.383464 -276.71083) (xy 156.336193 -276.724522)
			(xy 156.287338 -276.730454) (xy 156.238163 -276.728473) (xy 156.189944 -276.718629) (xy 156.143928 -276.701177)
			(xy 156.101307 -276.67657) (xy 156.063186 -276.645445) (xy 156.030551 -276.608608) (xy 156.004248 -276.567012)
			(xy 155.984957 -276.521736) (xy 155.97318 -276.473952) (xy 155.96922 -276.424898) (xy 155.630372 -276.424898)
			(xy 155.629877 -276.449505) (xy 155.621982 -276.498082) (xy 155.606398 -276.544763) (xy 155.583527 -276.58834)
			(xy 155.553962 -276.627684) (xy 155.518469 -276.661776) (xy 155.477966 -276.689732) (xy 155.433504 -276.71083)
			(xy 155.386233 -276.724522) (xy 155.337378 -276.730454) (xy 155.288203 -276.728473) (xy 155.239984 -276.718629)
			(xy 155.193968 -276.701177) (xy 155.151347 -276.67657) (xy 155.113226 -276.645445) (xy 155.080591 -276.608608)
			(xy 155.054288 -276.567012) (xy 155.034997 -276.521736) (xy 155.02322 -276.473952) (xy 155.01926 -276.424898)
			(xy 154.680412 -276.424898) (xy 154.679917 -276.449505) (xy 154.672022 -276.498082) (xy 154.656438 -276.544763)
			(xy 154.633567 -276.58834) (xy 154.604002 -276.627684) (xy 154.568509 -276.661776) (xy 154.528006 -276.689732)
			(xy 154.483544 -276.71083) (xy 154.436273 -276.724522) (xy 154.387418 -276.730454) (xy 154.338243 -276.728473)
			(xy 154.290024 -276.718629) (xy 154.244008 -276.701177) (xy 154.201387 -276.67657) (xy 154.163266 -276.645445)
			(xy 154.130631 -276.608608) (xy 154.104328 -276.567012) (xy 154.085037 -276.521736) (xy 154.07326 -276.473952)
			(xy 154.0693 -276.424898) (xy 153.730198 -276.424898) (xy 153.729703 -276.449505) (xy 153.721808 -276.498082)
			(xy 153.706224 -276.544763) (xy 153.683353 -276.58834) (xy 153.653788 -276.627684) (xy 153.618295 -276.661776)
			(xy 153.577792 -276.689732) (xy 153.53333 -276.71083) (xy 153.486059 -276.724522) (xy 153.437204 -276.730454)
			(xy 153.388029 -276.728473) (xy 153.33981 -276.718629) (xy 153.293794 -276.701177) (xy 153.251173 -276.67657)
			(xy 153.213052 -276.645445) (xy 153.180417 -276.608608) (xy 153.154114 -276.567012) (xy 153.134823 -276.521736)
			(xy 153.123046 -276.473952) (xy 153.119086 -276.424898) (xy 152.780238 -276.424898) (xy 152.779743 -276.449505)
			(xy 152.771848 -276.498082) (xy 152.756264 -276.544763) (xy 152.733393 -276.58834) (xy 152.703828 -276.627684)
			(xy 152.668335 -276.661776) (xy 152.627832 -276.689732) (xy 152.58337 -276.71083) (xy 152.536099 -276.724522)
			(xy 152.487244 -276.730454) (xy 152.438069 -276.728473) (xy 152.38985 -276.718629) (xy 152.343834 -276.701177)
			(xy 152.301213 -276.67657) (xy 152.263092 -276.645445) (xy 152.230457 -276.608608) (xy 152.204154 -276.567012)
			(xy 152.184863 -276.521736) (xy 152.173086 -276.473952) (xy 152.169126 -276.424898) (xy 139.603814 -276.424898)
			(xy 139.579644 -276.587831) (xy 139.547286 -276.750504) (xy 139.506984 -276.911392) (xy 139.458837 -277.07011)
			(xy 139.40296 -277.226274) (xy 139.341413 -277.374858) (xy 152.169126 -277.374858) (xy 152.173086 -277.325804)
			(xy 152.184863 -277.27802) (xy 152.204154 -277.232744) (xy 152.230457 -277.191148) (xy 152.263092 -277.154311)
			(xy 152.301213 -277.123186) (xy 152.343834 -277.098579) (xy 152.38985 -277.081127) (xy 152.438069 -277.071283)
			(xy 152.487244 -277.069302) (xy 152.536099 -277.075234) (xy 152.58337 -277.088926) (xy 152.627832 -277.110024)
			(xy 152.668335 -277.13798) (xy 152.703828 -277.172072) (xy 152.733393 -277.211416) (xy 152.756264 -277.254993)
			(xy 152.771848 -277.301674) (xy 152.779743 -277.350251) (xy 152.780238 -277.374858) (xy 153.119086 -277.374858)
			(xy 153.123046 -277.325804) (xy 153.134823 -277.27802) (xy 153.154114 -277.232744) (xy 153.180417 -277.191148)
			(xy 153.213052 -277.154311) (xy 153.251173 -277.123186) (xy 153.293794 -277.098579) (xy 153.33981 -277.081127)
			(xy 153.388029 -277.071283) (xy 153.437204 -277.069302) (xy 153.486059 -277.075234) (xy 153.53333 -277.088926)
			(xy 153.577792 -277.110024) (xy 153.618295 -277.13798) (xy 153.653788 -277.172072) (xy 153.683353 -277.211416)
			(xy 153.706224 -277.254993) (xy 153.721808 -277.301674) (xy 153.729703 -277.350251) (xy 153.730198 -277.374858)
			(xy 154.0693 -277.374858) (xy 154.07326 -277.325804) (xy 154.085037 -277.27802) (xy 154.104328 -277.232744)
			(xy 154.130631 -277.191148) (xy 154.163266 -277.154311) (xy 154.201387 -277.123186) (xy 154.244008 -277.098579)
			(xy 154.290024 -277.081127) (xy 154.338243 -277.071283) (xy 154.387418 -277.069302) (xy 154.436273 -277.075234)
			(xy 154.483544 -277.088926) (xy 154.528006 -277.110024) (xy 154.568509 -277.13798) (xy 154.604002 -277.172072)
			(xy 154.633567 -277.211416) (xy 154.656438 -277.254993) (xy 154.672022 -277.301674) (xy 154.679917 -277.350251)
			(xy 154.680412 -277.374858) (xy 155.01926 -277.374858) (xy 155.02322 -277.325804) (xy 155.034997 -277.27802)
			(xy 155.054288 -277.232744) (xy 155.080591 -277.191148) (xy 155.113226 -277.154311) (xy 155.151347 -277.123186)
			(xy 155.193968 -277.098579) (xy 155.239984 -277.081127) (xy 155.288203 -277.071283) (xy 155.337378 -277.069302)
			(xy 155.386233 -277.075234) (xy 155.433504 -277.088926) (xy 155.477966 -277.110024) (xy 155.518469 -277.13798)
			(xy 155.553962 -277.172072) (xy 155.583527 -277.211416) (xy 155.606398 -277.254993) (xy 155.621982 -277.301674)
			(xy 155.629877 -277.350251) (xy 155.630372 -277.374858) (xy 155.96922 -277.374858) (xy 155.97318 -277.325804)
			(xy 155.984957 -277.27802) (xy 156.004248 -277.232744) (xy 156.030551 -277.191148) (xy 156.063186 -277.154311)
			(xy 156.101307 -277.123186) (xy 156.143928 -277.098579) (xy 156.189944 -277.081127) (xy 156.238163 -277.071283)
			(xy 156.287338 -277.069302) (xy 156.336193 -277.075234) (xy 156.383464 -277.088926) (xy 156.427926 -277.110024)
			(xy 156.468429 -277.13798) (xy 156.503922 -277.172072) (xy 156.533487 -277.211416) (xy 156.556358 -277.254993)
			(xy 156.571942 -277.301674) (xy 156.579837 -277.350251) (xy 156.580332 -277.374858) (xy 156.91918 -277.374858)
			(xy 156.92314 -277.325804) (xy 156.934917 -277.27802) (xy 156.954208 -277.232744) (xy 156.980511 -277.191148)
			(xy 157.013146 -277.154311) (xy 157.051267 -277.123186) (xy 157.093888 -277.098579) (xy 157.139904 -277.081127)
			(xy 157.188123 -277.071283) (xy 157.237298 -277.069302) (xy 157.286153 -277.075234) (xy 157.333424 -277.088926)
			(xy 157.377886 -277.110024) (xy 157.418389 -277.13798) (xy 157.453882 -277.172072) (xy 157.483447 -277.211416)
			(xy 157.506318 -277.254993) (xy 157.521902 -277.301674) (xy 157.529797 -277.350251) (xy 157.530292 -277.374858)
			(xy 157.86914 -277.374858) (xy 157.8731 -277.325804) (xy 157.884877 -277.27802) (xy 157.904168 -277.232744)
			(xy 157.930471 -277.191148) (xy 157.963106 -277.154311) (xy 158.001227 -277.123186) (xy 158.043848 -277.098579)
			(xy 158.089864 -277.081127) (xy 158.138083 -277.071283) (xy 158.187258 -277.069302) (xy 158.236113 -277.075234)
			(xy 158.283384 -277.088926) (xy 158.327846 -277.110024) (xy 158.368349 -277.13798) (xy 158.403842 -277.172072)
			(xy 158.433407 -277.211416) (xy 158.456278 -277.254993) (xy 158.471862 -277.301674) (xy 158.479757 -277.350251)
			(xy 158.480252 -277.374858) (xy 158.480251 -277.3749) (xy 158.818998 -277.3749) (xy 158.82317 -277.32455)
			(xy 158.835573 -277.275573) (xy 158.855868 -277.229306) (xy 158.883501 -277.18701) (xy 158.91772 -277.149839)
			(xy 158.95759 -277.118808) (xy 159.002023 -277.094762) (xy 159.049809 -277.078358) (xy 159.099643 -277.070042)
			(xy 159.124904 -277.06955) (xy 159.139087 -277.069727) (xy 159.167327 -277.072399) (xy 159.181292 -277.074884)
			(xy 159.193738 -277.07717) (xy 159.21736 -277.069804) (xy 159.29483 -276.992334) (xy 159.302196 -276.968712)
			(xy 159.29991 -276.956266) (xy 159.297433 -276.9423) (xy 159.294762 -276.914061) (xy 159.294576 -276.899878)
			(xy 159.29475 -276.885695) (xy 159.297424 -276.857455) (xy 159.29991 -276.84349) (xy 159.302196 -276.831044)
			(xy 159.29483 -276.807422) (xy 159.21736 -276.729952) (xy 159.193738 -276.722586) (xy 159.181292 -276.724872)
			(xy 159.167326 -276.727345) (xy 159.139086 -276.730019) (xy 159.124904 -276.730206) (xy 159.100083 -276.729726)
			(xy 159.051094 -276.721696) (xy 159.00405 -276.705846) (xy 158.96019 -276.682593) (xy 158.92067 -276.652551)
			(xy 158.88653 -276.616512) (xy 158.858671 -276.575423) (xy 158.837826 -276.530369) (xy 158.824545 -276.482537)
			(xy 158.819177 -276.433185) (xy 158.821864 -276.383616) (xy 158.832535 -276.335134) (xy 158.85091 -276.289017)
			(xy 158.876502 -276.24648) (xy 158.90864 -276.208644) (xy 158.946475 -276.176506) (xy 158.989011 -276.150912)
			(xy 159.035128 -276.132537) (xy 159.08361 -276.121865) (xy 159.133179 -276.119177) (xy 159.182531 -276.124544)
			(xy 159.230364 -276.137824) (xy 159.275418 -276.158668) (xy 159.316507 -276.186527) (xy 159.352547 -276.220665)
			(xy 159.38259 -276.260185) (xy 159.405843 -276.304045) (xy 159.421694 -276.351088) (xy 159.429726 -276.400077)
			(xy 159.430212 -276.424898) (xy 159.430035 -276.439081) (xy 159.427363 -276.467321) (xy 159.424878 -276.481286)
			(xy 159.422592 -276.493732) (xy 159.429958 -276.517354) (xy 159.507428 -276.594824) (xy 159.53105 -276.60219)
			(xy 159.543496 -276.599904) (xy 159.557463 -276.597432) (xy 159.585702 -276.594757) (xy 159.599884 -276.59457)
			(xy 159.625141 -276.595105) (xy 159.674966 -276.603417) (xy 159.722743 -276.619817) (xy 159.767169 -276.643857)
			(xy 159.807032 -276.674882) (xy 159.841245 -276.712045) (xy 159.868874 -276.754333) (xy 159.889166 -276.800591)
			(xy 159.901566 -276.849559) (xy 159.905736 -276.899878) (xy 160.24404 -276.899878) (xy 160.248 -276.850824)
			(xy 160.259777 -276.80304) (xy 160.279068 -276.757764) (xy 160.305371 -276.716168) (xy 160.338006 -276.679331)
			(xy 160.376127 -276.648206) (xy 160.418748 -276.623599) (xy 160.464764 -276.606147) (xy 160.512983 -276.596303)
			(xy 160.562158 -276.594322) (xy 160.611013 -276.600254) (xy 160.658284 -276.613946) (xy 160.702746 -276.635044)
			(xy 160.743249 -276.663) (xy 160.778742 -276.697092) (xy 160.808307 -276.736436) (xy 160.831178 -276.780013)
			(xy 160.846762 -276.826694) (xy 160.854657 -276.875271) (xy 160.855152 -276.899878) (xy 161.194254 -276.899878)
			(xy 161.198214 -276.850824) (xy 161.209991 -276.80304) (xy 161.229282 -276.757764) (xy 161.255585 -276.716168)
			(xy 161.28822 -276.679331) (xy 161.326341 -276.648206) (xy 161.368962 -276.623599) (xy 161.414978 -276.606147)
			(xy 161.463197 -276.596303) (xy 161.512372 -276.594322) (xy 161.561227 -276.600254) (xy 161.608498 -276.613946)
			(xy 161.65296 -276.635044) (xy 161.693463 -276.663) (xy 161.728956 -276.697092) (xy 161.758521 -276.736436)
			(xy 161.781392 -276.780013) (xy 161.796976 -276.826694) (xy 161.804871 -276.875271) (xy 161.805366 -276.899878)
			(xy 162.144214 -276.899878) (xy 162.148174 -276.850824) (xy 162.159951 -276.80304) (xy 162.179242 -276.757764)
			(xy 162.205545 -276.716168) (xy 162.23818 -276.679331) (xy 162.276301 -276.648206) (xy 162.318922 -276.623599)
			(xy 162.364938 -276.606147) (xy 162.413157 -276.596303) (xy 162.462332 -276.594322) (xy 162.511187 -276.600254)
			(xy 162.558458 -276.613946) (xy 162.60292 -276.635044) (xy 162.643423 -276.663) (xy 162.678916 -276.697092)
			(xy 162.708481 -276.736436) (xy 162.731352 -276.780013) (xy 162.746936 -276.826694) (xy 162.754831 -276.875271)
			(xy 162.755326 -276.899878) (xy 163.094174 -276.899878) (xy 163.098134 -276.850824) (xy 163.109911 -276.80304)
			(xy 163.129202 -276.757764) (xy 163.155505 -276.716168) (xy 163.18814 -276.679331) (xy 163.226261 -276.648206)
			(xy 163.268882 -276.623599) (xy 163.314898 -276.606147) (xy 163.363117 -276.596303) (xy 163.412292 -276.594322)
			(xy 163.461147 -276.600254) (xy 163.508418 -276.613946) (xy 163.55288 -276.635044) (xy 163.593383 -276.663)
			(xy 163.628876 -276.697092) (xy 163.658441 -276.736436) (xy 163.681312 -276.780013) (xy 163.696896 -276.826694)
			(xy 163.704791 -276.875271) (xy 163.705286 -276.899878) (xy 164.044134 -276.899878) (xy 164.048094 -276.850824)
			(xy 164.059871 -276.80304) (xy 164.079162 -276.757764) (xy 164.105465 -276.716168) (xy 164.1381 -276.679331)
			(xy 164.176221 -276.648206) (xy 164.218842 -276.623599) (xy 164.264858 -276.606147) (xy 164.313077 -276.596303)
			(xy 164.362252 -276.594322) (xy 164.411107 -276.600254) (xy 164.458378 -276.613946) (xy 164.50284 -276.635044)
			(xy 164.543343 -276.663) (xy 164.578836 -276.697092) (xy 164.608401 -276.736436) (xy 164.631272 -276.780013)
			(xy 164.646856 -276.826694) (xy 164.654751 -276.875271) (xy 164.655246 -276.899878) (xy 164.994094 -276.899878)
			(xy 164.998054 -276.850824) (xy 165.009831 -276.80304) (xy 165.029122 -276.757764) (xy 165.055425 -276.716168)
			(xy 165.08806 -276.679331) (xy 165.126181 -276.648206) (xy 165.168802 -276.623599) (xy 165.214818 -276.606147)
			(xy 165.263037 -276.596303) (xy 165.312212 -276.594322) (xy 165.361067 -276.600254) (xy 165.408338 -276.613946)
			(xy 165.4528 -276.635044) (xy 165.493303 -276.663) (xy 165.528796 -276.697092) (xy 165.558361 -276.736436)
			(xy 165.581232 -276.780013) (xy 165.596816 -276.826694) (xy 165.604711 -276.875271) (xy 165.605206 -276.899878)
			(xy 165.944054 -276.899878) (xy 165.948014 -276.850824) (xy 165.959791 -276.80304) (xy 165.979082 -276.757764)
			(xy 166.005385 -276.716168) (xy 166.03802 -276.679331) (xy 166.076141 -276.648206) (xy 166.118762 -276.623599)
			(xy 166.164778 -276.606147) (xy 166.212997 -276.596303) (xy 166.262172 -276.594322) (xy 166.311027 -276.600254)
			(xy 166.358298 -276.613946) (xy 166.40276 -276.635044) (xy 166.443263 -276.663) (xy 166.478756 -276.697092)
			(xy 166.508321 -276.736436) (xy 166.531192 -276.780013) (xy 166.546776 -276.826694) (xy 166.554671 -276.875271)
			(xy 166.555166 -276.899878) (xy 166.894268 -276.899878) (xy 166.898228 -276.850824) (xy 166.910005 -276.80304)
			(xy 166.929296 -276.757764) (xy 166.955599 -276.716168) (xy 166.988234 -276.679331) (xy 167.026355 -276.648206)
			(xy 167.068976 -276.623599) (xy 167.114992 -276.606147) (xy 167.163211 -276.596303) (xy 167.212386 -276.594322)
			(xy 167.261241 -276.600254) (xy 167.308512 -276.613946) (xy 167.352974 -276.635044) (xy 167.393477 -276.663)
			(xy 167.42897 -276.697092) (xy 167.458535 -276.736436) (xy 167.481406 -276.780013) (xy 167.49699 -276.826694)
			(xy 167.504885 -276.875271) (xy 167.50538 -276.899878) (xy 167.844228 -276.899878) (xy 167.848188 -276.850824)
			(xy 167.859965 -276.80304) (xy 167.879256 -276.757764) (xy 167.905559 -276.716168) (xy 167.938194 -276.679331)
			(xy 167.976315 -276.648206) (xy 168.018936 -276.623599) (xy 168.064952 -276.606147) (xy 168.113171 -276.596303)
			(xy 168.162346 -276.594322) (xy 168.211201 -276.600254) (xy 168.258472 -276.613946) (xy 168.302934 -276.635044)
			(xy 168.343437 -276.663) (xy 168.37893 -276.697092) (xy 168.408495 -276.736436) (xy 168.431366 -276.780013)
			(xy 168.44695 -276.826694) (xy 168.454845 -276.875271) (xy 168.45534 -276.899878) (xy 168.794188 -276.899878)
			(xy 168.798148 -276.850824) (xy 168.809925 -276.80304) (xy 168.829216 -276.757764) (xy 168.855519 -276.716168)
			(xy 168.888154 -276.679331) (xy 168.926275 -276.648206) (xy 168.968896 -276.623599) (xy 169.014912 -276.606147)
			(xy 169.063131 -276.596303) (xy 169.112306 -276.594322) (xy 169.161161 -276.600254) (xy 169.208432 -276.613946)
			(xy 169.252894 -276.635044) (xy 169.293397 -276.663) (xy 169.32889 -276.697092) (xy 169.358455 -276.736436)
			(xy 169.381326 -276.780013) (xy 169.39691 -276.826694) (xy 169.404805 -276.875271) (xy 169.4053 -276.899878)
			(xy 169.744148 -276.899878) (xy 169.748108 -276.850824) (xy 169.759885 -276.80304) (xy 169.779176 -276.757764)
			(xy 169.805479 -276.716168) (xy 169.838114 -276.679331) (xy 169.876235 -276.648206) (xy 169.918856 -276.623599)
			(xy 169.964872 -276.606147) (xy 170.013091 -276.596303) (xy 170.062266 -276.594322) (xy 170.111121 -276.600254)
			(xy 170.158392 -276.613946) (xy 170.202854 -276.635044) (xy 170.243357 -276.663) (xy 170.27885 -276.697092)
			(xy 170.308415 -276.736436) (xy 170.331286 -276.780013) (xy 170.34687 -276.826694) (xy 170.354765 -276.875271)
			(xy 170.35526 -276.899878) (xy 170.694108 -276.899878) (xy 170.698068 -276.850824) (xy 170.709845 -276.80304)
			(xy 170.729136 -276.757764) (xy 170.755439 -276.716168) (xy 170.788074 -276.679331) (xy 170.826195 -276.648206)
			(xy 170.868816 -276.623599) (xy 170.914832 -276.606147) (xy 170.963051 -276.596303) (xy 171.012226 -276.594322)
			(xy 171.061081 -276.600254) (xy 171.108352 -276.613946) (xy 171.152814 -276.635044) (xy 171.193317 -276.663)
			(xy 171.22881 -276.697092) (xy 171.258375 -276.736436) (xy 171.281246 -276.780013) (xy 171.29683 -276.826694)
			(xy 171.304725 -276.875271) (xy 171.30522 -276.899878) (xy 171.644068 -276.899878) (xy 171.648028 -276.850824)
			(xy 171.659805 -276.80304) (xy 171.679096 -276.757764) (xy 171.705399 -276.716168) (xy 171.738034 -276.679331)
			(xy 171.776155 -276.648206) (xy 171.818776 -276.623599) (xy 171.864792 -276.606147) (xy 171.913011 -276.596303)
			(xy 171.962186 -276.594322) (xy 172.011041 -276.600254) (xy 172.058312 -276.613946) (xy 172.102774 -276.635044)
			(xy 172.143277 -276.663) (xy 172.17877 -276.697092) (xy 172.208335 -276.736436) (xy 172.231206 -276.780013)
			(xy 172.24679 -276.826694) (xy 172.254685 -276.875271) (xy 172.25518 -276.899878) (xy 172.594282 -276.899878)
			(xy 172.598242 -276.850824) (xy 172.610019 -276.80304) (xy 172.62931 -276.757764) (xy 172.655613 -276.716168)
			(xy 172.688248 -276.679331) (xy 172.726369 -276.648206) (xy 172.76899 -276.623599) (xy 172.815006 -276.606147)
			(xy 172.863225 -276.596303) (xy 172.9124 -276.594322) (xy 172.961255 -276.600254) (xy 173.008526 -276.613946)
			(xy 173.052988 -276.635044) (xy 173.093491 -276.663) (xy 173.128984 -276.697092) (xy 173.158549 -276.736436)
			(xy 173.18142 -276.780013) (xy 173.197004 -276.826694) (xy 173.204899 -276.875271) (xy 173.205394 -276.899878)
			(xy 173.204899 -276.924485) (xy 173.197004 -276.973062) (xy 173.18142 -277.019743) (xy 173.158549 -277.06332)
			(xy 173.128984 -277.102664) (xy 173.093491 -277.136756) (xy 173.052988 -277.164712) (xy 173.008526 -277.18581)
			(xy 172.961255 -277.199502) (xy 172.9124 -277.205434) (xy 172.863225 -277.203453) (xy 172.815006 -277.193609)
			(xy 172.76899 -277.176157) (xy 172.726369 -277.15155) (xy 172.688248 -277.120425) (xy 172.655613 -277.083588)
			(xy 172.62931 -277.041992) (xy 172.610019 -276.996716) (xy 172.598242 -276.948932) (xy 172.594282 -276.899878)
			(xy 172.25518 -276.899878) (xy 172.254685 -276.924485) (xy 172.24679 -276.973062) (xy 172.231206 -277.019743)
			(xy 172.208335 -277.06332) (xy 172.17877 -277.102664) (xy 172.143277 -277.136756) (xy 172.102774 -277.164712)
			(xy 172.058312 -277.18581) (xy 172.011041 -277.199502) (xy 171.962186 -277.205434) (xy 171.913011 -277.203453)
			(xy 171.864792 -277.193609) (xy 171.818776 -277.176157) (xy 171.776155 -277.15155) (xy 171.738034 -277.120425)
			(xy 171.705399 -277.083588) (xy 171.679096 -277.041992) (xy 171.659805 -276.996716) (xy 171.648028 -276.948932)
			(xy 171.644068 -276.899878) (xy 171.30522 -276.899878) (xy 171.304725 -276.924485) (xy 171.29683 -276.973062)
			(xy 171.281246 -277.019743) (xy 171.258375 -277.06332) (xy 171.22881 -277.102664) (xy 171.193317 -277.136756)
			(xy 171.152814 -277.164712) (xy 171.108352 -277.18581) (xy 171.061081 -277.199502) (xy 171.012226 -277.205434)
			(xy 170.963051 -277.203453) (xy 170.914832 -277.193609) (xy 170.868816 -277.176157) (xy 170.826195 -277.15155)
			(xy 170.788074 -277.120425) (xy 170.755439 -277.083588) (xy 170.729136 -277.041992) (xy 170.709845 -276.996716)
			(xy 170.698068 -276.948932) (xy 170.694108 -276.899878) (xy 170.35526 -276.899878) (xy 170.354765 -276.924485)
			(xy 170.34687 -276.973062) (xy 170.331286 -277.019743) (xy 170.308415 -277.06332) (xy 170.27885 -277.102664)
			(xy 170.243357 -277.136756) (xy 170.202854 -277.164712) (xy 170.158392 -277.18581) (xy 170.111121 -277.199502)
			(xy 170.062266 -277.205434) (xy 170.013091 -277.203453) (xy 169.964872 -277.193609) (xy 169.918856 -277.176157)
			(xy 169.876235 -277.15155) (xy 169.838114 -277.120425) (xy 169.805479 -277.083588) (xy 169.779176 -277.041992)
			(xy 169.759885 -276.996716) (xy 169.748108 -276.948932) (xy 169.744148 -276.899878) (xy 169.4053 -276.899878)
			(xy 169.404805 -276.924485) (xy 169.39691 -276.973062) (xy 169.381326 -277.019743) (xy 169.358455 -277.06332)
			(xy 169.32889 -277.102664) (xy 169.293397 -277.136756) (xy 169.252894 -277.164712) (xy 169.208432 -277.18581)
			(xy 169.161161 -277.199502) (xy 169.112306 -277.205434) (xy 169.063131 -277.203453) (xy 169.014912 -277.193609)
			(xy 168.968896 -277.176157) (xy 168.926275 -277.15155) (xy 168.888154 -277.120425) (xy 168.855519 -277.083588)
			(xy 168.829216 -277.041992) (xy 168.809925 -276.996716) (xy 168.798148 -276.948932) (xy 168.794188 -276.899878)
			(xy 168.45534 -276.899878) (xy 168.454845 -276.924485) (xy 168.44695 -276.973062) (xy 168.431366 -277.019743)
			(xy 168.408495 -277.06332) (xy 168.37893 -277.102664) (xy 168.343437 -277.136756) (xy 168.302934 -277.164712)
			(xy 168.258472 -277.18581) (xy 168.211201 -277.199502) (xy 168.162346 -277.205434) (xy 168.113171 -277.203453)
			(xy 168.064952 -277.193609) (xy 168.018936 -277.176157) (xy 167.976315 -277.15155) (xy 167.938194 -277.120425)
			(xy 167.905559 -277.083588) (xy 167.879256 -277.041992) (xy 167.859965 -276.996716) (xy 167.848188 -276.948932)
			(xy 167.844228 -276.899878) (xy 167.50538 -276.899878) (xy 167.504885 -276.924485) (xy 167.49699 -276.973062)
			(xy 167.481406 -277.019743) (xy 167.458535 -277.06332) (xy 167.42897 -277.102664) (xy 167.393477 -277.136756)
			(xy 167.352974 -277.164712) (xy 167.308512 -277.18581) (xy 167.261241 -277.199502) (xy 167.212386 -277.205434)
			(xy 167.163211 -277.203453) (xy 167.114992 -277.193609) (xy 167.068976 -277.176157) (xy 167.026355 -277.15155)
			(xy 166.988234 -277.120425) (xy 166.955599 -277.083588) (xy 166.929296 -277.041992) (xy 166.910005 -276.996716)
			(xy 166.898228 -276.948932) (xy 166.894268 -276.899878) (xy 166.555166 -276.899878) (xy 166.554671 -276.924485)
			(xy 166.546776 -276.973062) (xy 166.531192 -277.019743) (xy 166.508321 -277.06332) (xy 166.478756 -277.102664)
			(xy 166.443263 -277.136756) (xy 166.40276 -277.164712) (xy 166.358298 -277.18581) (xy 166.311027 -277.199502)
			(xy 166.262172 -277.205434) (xy 166.212997 -277.203453) (xy 166.164778 -277.193609) (xy 166.118762 -277.176157)
			(xy 166.076141 -277.15155) (xy 166.03802 -277.120425) (xy 166.005385 -277.083588) (xy 165.979082 -277.041992)
			(xy 165.959791 -276.996716) (xy 165.948014 -276.948932) (xy 165.944054 -276.899878) (xy 165.605206 -276.899878)
			(xy 165.604711 -276.924485) (xy 165.596816 -276.973062) (xy 165.581232 -277.019743) (xy 165.558361 -277.06332)
			(xy 165.528796 -277.102664) (xy 165.493303 -277.136756) (xy 165.4528 -277.164712) (xy 165.408338 -277.18581)
			(xy 165.361067 -277.199502) (xy 165.312212 -277.205434) (xy 165.263037 -277.203453) (xy 165.214818 -277.193609)
			(xy 165.168802 -277.176157) (xy 165.126181 -277.15155) (xy 165.08806 -277.120425) (xy 165.055425 -277.083588)
			(xy 165.029122 -277.041992) (xy 165.009831 -276.996716) (xy 164.998054 -276.948932) (xy 164.994094 -276.899878)
			(xy 164.655246 -276.899878) (xy 164.654751 -276.924485) (xy 164.646856 -276.973062) (xy 164.631272 -277.019743)
			(xy 164.608401 -277.06332) (xy 164.578836 -277.102664) (xy 164.543343 -277.136756) (xy 164.50284 -277.164712)
			(xy 164.458378 -277.18581) (xy 164.411107 -277.199502) (xy 164.362252 -277.205434) (xy 164.313077 -277.203453)
			(xy 164.264858 -277.193609) (xy 164.218842 -277.176157) (xy 164.176221 -277.15155) (xy 164.1381 -277.120425)
			(xy 164.105465 -277.083588) (xy 164.079162 -277.041992) (xy 164.059871 -276.996716) (xy 164.048094 -276.948932)
			(xy 164.044134 -276.899878) (xy 163.705286 -276.899878) (xy 163.704791 -276.924485) (xy 163.696896 -276.973062)
			(xy 163.681312 -277.019743) (xy 163.658441 -277.06332) (xy 163.628876 -277.102664) (xy 163.593383 -277.136756)
			(xy 163.55288 -277.164712) (xy 163.508418 -277.18581) (xy 163.461147 -277.199502) (xy 163.412292 -277.205434)
			(xy 163.363117 -277.203453) (xy 163.314898 -277.193609) (xy 163.268882 -277.176157) (xy 163.226261 -277.15155)
			(xy 163.18814 -277.120425) (xy 163.155505 -277.083588) (xy 163.129202 -277.041992) (xy 163.109911 -276.996716)
			(xy 163.098134 -276.948932) (xy 163.094174 -276.899878) (xy 162.755326 -276.899878) (xy 162.754831 -276.924485)
			(xy 162.746936 -276.973062) (xy 162.731352 -277.019743) (xy 162.708481 -277.06332) (xy 162.678916 -277.102664)
			(xy 162.643423 -277.136756) (xy 162.60292 -277.164712) (xy 162.558458 -277.18581) (xy 162.511187 -277.199502)
			(xy 162.462332 -277.205434) (xy 162.413157 -277.203453) (xy 162.364938 -277.193609) (xy 162.318922 -277.176157)
			(xy 162.276301 -277.15155) (xy 162.23818 -277.120425) (xy 162.205545 -277.083588) (xy 162.179242 -277.041992)
			(xy 162.159951 -276.996716) (xy 162.148174 -276.948932) (xy 162.144214 -276.899878) (xy 161.805366 -276.899878)
			(xy 161.804871 -276.924485) (xy 161.796976 -276.973062) (xy 161.781392 -277.019743) (xy 161.758521 -277.06332)
			(xy 161.728956 -277.102664) (xy 161.693463 -277.136756) (xy 161.65296 -277.164712) (xy 161.608498 -277.18581)
			(xy 161.561227 -277.199502) (xy 161.512372 -277.205434) (xy 161.463197 -277.203453) (xy 161.414978 -277.193609)
			(xy 161.368962 -277.176157) (xy 161.326341 -277.15155) (xy 161.28822 -277.120425) (xy 161.255585 -277.083588)
			(xy 161.229282 -277.041992) (xy 161.209991 -276.996716) (xy 161.198214 -276.948932) (xy 161.194254 -276.899878)
			(xy 160.855152 -276.899878) (xy 160.854657 -276.924485) (xy 160.846762 -276.973062) (xy 160.831178 -277.019743)
			(xy 160.808307 -277.06332) (xy 160.778742 -277.102664) (xy 160.743249 -277.136756) (xy 160.702746 -277.164712)
			(xy 160.658284 -277.18581) (xy 160.611013 -277.199502) (xy 160.562158 -277.205434) (xy 160.512983 -277.203453)
			(xy 160.464764 -277.193609) (xy 160.418748 -277.176157) (xy 160.376127 -277.15155) (xy 160.338006 -277.120425)
			(xy 160.305371 -277.083588) (xy 160.279068 -277.041992) (xy 160.259777 -276.996716) (xy 160.248 -276.948932)
			(xy 160.24404 -276.899878) (xy 159.905736 -276.899878) (xy 159.905738 -276.8999) (xy 159.901566 -276.950241)
			(xy 159.889166 -276.999209) (xy 159.868874 -277.045467) (xy 159.841245 -277.087755) (xy 159.807032 -277.124918)
			(xy 159.767169 -277.155943) (xy 159.722743 -277.179983) (xy 159.674966 -277.196383) (xy 159.625141 -277.204695)
			(xy 159.599884 -277.205186) (xy 159.585701 -277.205012) (xy 159.557461 -277.202338) (xy 159.543496 -277.199852)
			(xy 159.53105 -277.197566) (xy 159.507428 -277.204932) (xy 159.429958 -277.282402) (xy 159.422592 -277.306024)
			(xy 159.424878 -277.31847) (xy 159.42736 -277.332435) (xy 159.430028 -277.360675) (xy 159.430212 -277.374858)
			(xy 159.430029 -277.389041) (xy 159.427361 -277.417281) (xy 159.424878 -277.431246) (xy 159.422592 -277.443692)
			(xy 159.429958 -277.467314) (xy 159.507428 -277.544784) (xy 159.53105 -277.55215) (xy 159.543496 -277.549864)
			(xy 159.557463 -277.547393) (xy 159.585702 -277.544717) (xy 159.599884 -277.54453) (xy 159.625146 -277.544946)
			(xy 159.67498 -277.553259) (xy 159.722767 -277.569662) (xy 159.767202 -277.593707) (xy 159.807073 -277.624738)
			(xy 159.841292 -277.661908) (xy 159.868927 -277.704204) (xy 159.889223 -277.750472) (xy 159.901626 -277.799449)
			(xy 159.905798 -277.8498) (xy 159.905795 -277.849838) (xy 160.24404 -277.849838) (xy 160.248 -277.800784)
			(xy 160.259777 -277.753) (xy 160.279068 -277.707724) (xy 160.305371 -277.666128) (xy 160.338006 -277.629291)
			(xy 160.376127 -277.598166) (xy 160.418748 -277.573559) (xy 160.464764 -277.556107) (xy 160.512983 -277.546263)
			(xy 160.562158 -277.544282) (xy 160.611013 -277.550214) (xy 160.658284 -277.563906) (xy 160.702746 -277.585004)
			(xy 160.743249 -277.61296) (xy 160.778742 -277.647052) (xy 160.808307 -277.686396) (xy 160.831178 -277.729973)
			(xy 160.846762 -277.776654) (xy 160.854657 -277.825231) (xy 160.855152 -277.849838) (xy 161.194254 -277.849838)
			(xy 161.198214 -277.800784) (xy 161.209991 -277.753) (xy 161.229282 -277.707724) (xy 161.255585 -277.666128)
			(xy 161.28822 -277.629291) (xy 161.326341 -277.598166) (xy 161.368962 -277.573559) (xy 161.414978 -277.556107)
			(xy 161.463197 -277.546263) (xy 161.512372 -277.544282) (xy 161.561227 -277.550214) (xy 161.608498 -277.563906)
			(xy 161.65296 -277.585004) (xy 161.693463 -277.61296) (xy 161.728956 -277.647052) (xy 161.758521 -277.686396)
			(xy 161.781392 -277.729973) (xy 161.796976 -277.776654) (xy 161.804871 -277.825231) (xy 161.805366 -277.849838)
			(xy 162.144214 -277.849838) (xy 162.148174 -277.800784) (xy 162.159951 -277.753) (xy 162.179242 -277.707724)
			(xy 162.205545 -277.666128) (xy 162.23818 -277.629291) (xy 162.276301 -277.598166) (xy 162.318922 -277.573559)
			(xy 162.364938 -277.556107) (xy 162.413157 -277.546263) (xy 162.462332 -277.544282) (xy 162.511187 -277.550214)
			(xy 162.558458 -277.563906) (xy 162.60292 -277.585004) (xy 162.643423 -277.61296) (xy 162.678916 -277.647052)
			(xy 162.708481 -277.686396) (xy 162.731352 -277.729973) (xy 162.746936 -277.776654) (xy 162.754831 -277.825231)
			(xy 162.755326 -277.849838) (xy 163.094174 -277.849838) (xy 163.098134 -277.800784) (xy 163.109911 -277.753)
			(xy 163.129202 -277.707724) (xy 163.155505 -277.666128) (xy 163.18814 -277.629291) (xy 163.226261 -277.598166)
			(xy 163.268882 -277.573559) (xy 163.314898 -277.556107) (xy 163.363117 -277.546263) (xy 163.412292 -277.544282)
			(xy 163.461147 -277.550214) (xy 163.508418 -277.563906) (xy 163.55288 -277.585004) (xy 163.593383 -277.61296)
			(xy 163.628876 -277.647052) (xy 163.658441 -277.686396) (xy 163.681312 -277.729973) (xy 163.696896 -277.776654)
			(xy 163.704791 -277.825231) (xy 163.705286 -277.849838) (xy 164.044134 -277.849838) (xy 164.048094 -277.800784)
			(xy 164.059871 -277.753) (xy 164.079162 -277.707724) (xy 164.105465 -277.666128) (xy 164.1381 -277.629291)
			(xy 164.176221 -277.598166) (xy 164.218842 -277.573559) (xy 164.264858 -277.556107) (xy 164.313077 -277.546263)
			(xy 164.362252 -277.544282) (xy 164.411107 -277.550214) (xy 164.458378 -277.563906) (xy 164.50284 -277.585004)
			(xy 164.543343 -277.61296) (xy 164.578836 -277.647052) (xy 164.608401 -277.686396) (xy 164.631272 -277.729973)
			(xy 164.646856 -277.776654) (xy 164.654751 -277.825231) (xy 164.655246 -277.849838) (xy 164.994094 -277.849838)
			(xy 164.998054 -277.800784) (xy 165.009831 -277.753) (xy 165.029122 -277.707724) (xy 165.055425 -277.666128)
			(xy 165.08806 -277.629291) (xy 165.126181 -277.598166) (xy 165.168802 -277.573559) (xy 165.214818 -277.556107)
			(xy 165.263037 -277.546263) (xy 165.312212 -277.544282) (xy 165.361067 -277.550214) (xy 165.408338 -277.563906)
			(xy 165.4528 -277.585004) (xy 165.493303 -277.61296) (xy 165.528796 -277.647052) (xy 165.558361 -277.686396)
			(xy 165.581232 -277.729973) (xy 165.596816 -277.776654) (xy 165.604711 -277.825231) (xy 165.605206 -277.849838)
			(xy 165.944054 -277.849838) (xy 165.948014 -277.800784) (xy 165.959791 -277.753) (xy 165.979082 -277.707724)
			(xy 166.005385 -277.666128) (xy 166.03802 -277.629291) (xy 166.076141 -277.598166) (xy 166.118762 -277.573559)
			(xy 166.164778 -277.556107) (xy 166.212997 -277.546263) (xy 166.262172 -277.544282) (xy 166.311027 -277.550214)
			(xy 166.358298 -277.563906) (xy 166.40276 -277.585004) (xy 166.443263 -277.61296) (xy 166.478756 -277.647052)
			(xy 166.508321 -277.686396) (xy 166.531192 -277.729973) (xy 166.546776 -277.776654) (xy 166.554671 -277.825231)
			(xy 166.555166 -277.849838) (xy 166.894268 -277.849838) (xy 166.898228 -277.800784) (xy 166.910005 -277.753)
			(xy 166.929296 -277.707724) (xy 166.955599 -277.666128) (xy 166.988234 -277.629291) (xy 167.026355 -277.598166)
			(xy 167.068976 -277.573559) (xy 167.114992 -277.556107) (xy 167.163211 -277.546263) (xy 167.212386 -277.544282)
			(xy 167.261241 -277.550214) (xy 167.308512 -277.563906) (xy 167.352974 -277.585004) (xy 167.393477 -277.61296)
			(xy 167.42897 -277.647052) (xy 167.458535 -277.686396) (xy 167.481406 -277.729973) (xy 167.49699 -277.776654)
			(xy 167.504885 -277.825231) (xy 167.50538 -277.849838) (xy 167.844228 -277.849838) (xy 167.848188 -277.800784)
			(xy 167.859965 -277.753) (xy 167.879256 -277.707724) (xy 167.905559 -277.666128) (xy 167.938194 -277.629291)
			(xy 167.976315 -277.598166) (xy 168.018936 -277.573559) (xy 168.064952 -277.556107) (xy 168.113171 -277.546263)
			(xy 168.162346 -277.544282) (xy 168.211201 -277.550214) (xy 168.258472 -277.563906) (xy 168.302934 -277.585004)
			(xy 168.343437 -277.61296) (xy 168.37893 -277.647052) (xy 168.408495 -277.686396) (xy 168.431366 -277.729973)
			(xy 168.44695 -277.776654) (xy 168.454845 -277.825231) (xy 168.45534 -277.849838) (xy 168.794188 -277.849838)
			(xy 168.798148 -277.800784) (xy 168.809925 -277.753) (xy 168.829216 -277.707724) (xy 168.855519 -277.666128)
			(xy 168.888154 -277.629291) (xy 168.926275 -277.598166) (xy 168.968896 -277.573559) (xy 169.014912 -277.556107)
			(xy 169.063131 -277.546263) (xy 169.112306 -277.544282) (xy 169.161161 -277.550214) (xy 169.208432 -277.563906)
			(xy 169.252894 -277.585004) (xy 169.293397 -277.61296) (xy 169.32889 -277.647052) (xy 169.358455 -277.686396)
			(xy 169.381326 -277.729973) (xy 169.39691 -277.776654) (xy 169.404805 -277.825231) (xy 169.4053 -277.849838)
			(xy 169.744148 -277.849838) (xy 169.748108 -277.800784) (xy 169.759885 -277.753) (xy 169.779176 -277.707724)
			(xy 169.805479 -277.666128) (xy 169.838114 -277.629291) (xy 169.876235 -277.598166) (xy 169.918856 -277.573559)
			(xy 169.964872 -277.556107) (xy 170.013091 -277.546263) (xy 170.062266 -277.544282) (xy 170.111121 -277.550214)
			(xy 170.158392 -277.563906) (xy 170.202854 -277.585004) (xy 170.243357 -277.61296) (xy 170.27885 -277.647052)
			(xy 170.308415 -277.686396) (xy 170.331286 -277.729973) (xy 170.34687 -277.776654) (xy 170.354765 -277.825231)
			(xy 170.35526 -277.849838) (xy 170.694108 -277.849838) (xy 170.698068 -277.800784) (xy 170.709845 -277.753)
			(xy 170.729136 -277.707724) (xy 170.755439 -277.666128) (xy 170.788074 -277.629291) (xy 170.826195 -277.598166)
			(xy 170.868816 -277.573559) (xy 170.914832 -277.556107) (xy 170.963051 -277.546263) (xy 171.012226 -277.544282)
			(xy 171.061081 -277.550214) (xy 171.108352 -277.563906) (xy 171.152814 -277.585004) (xy 171.193317 -277.61296)
			(xy 171.22881 -277.647052) (xy 171.258375 -277.686396) (xy 171.281246 -277.729973) (xy 171.29683 -277.776654)
			(xy 171.304725 -277.825231) (xy 171.30522 -277.849838) (xy 171.644068 -277.849838) (xy 171.648028 -277.800784)
			(xy 171.659805 -277.753) (xy 171.679096 -277.707724) (xy 171.705399 -277.666128) (xy 171.738034 -277.629291)
			(xy 171.776155 -277.598166) (xy 171.818776 -277.573559) (xy 171.864792 -277.556107) (xy 171.913011 -277.546263)
			(xy 171.962186 -277.544282) (xy 172.011041 -277.550214) (xy 172.058312 -277.563906) (xy 172.102774 -277.585004)
			(xy 172.143277 -277.61296) (xy 172.17877 -277.647052) (xy 172.208335 -277.686396) (xy 172.231206 -277.729973)
			(xy 172.24679 -277.776654) (xy 172.254685 -277.825231) (xy 172.25518 -277.849838) (xy 172.594282 -277.849838)
			(xy 172.598242 -277.800784) (xy 172.610019 -277.753) (xy 172.62931 -277.707724) (xy 172.655613 -277.666128)
			(xy 172.688248 -277.629291) (xy 172.726369 -277.598166) (xy 172.76899 -277.573559) (xy 172.815006 -277.556107)
			(xy 172.863225 -277.546263) (xy 172.9124 -277.544282) (xy 172.961255 -277.550214) (xy 173.008526 -277.563906)
			(xy 173.052988 -277.585004) (xy 173.093491 -277.61296) (xy 173.128984 -277.647052) (xy 173.158549 -277.686396)
			(xy 173.18142 -277.729973) (xy 173.197004 -277.776654) (xy 173.204899 -277.825231) (xy 173.205394 -277.849838)
			(xy 173.544242 -277.849838) (xy 173.548202 -277.800784) (xy 173.559979 -277.753) (xy 173.57927 -277.707724)
			(xy 173.605573 -277.666128) (xy 173.638208 -277.629291) (xy 173.676329 -277.598166) (xy 173.71895 -277.573559)
			(xy 173.764966 -277.556107) (xy 173.813185 -277.546263) (xy 173.86236 -277.544282) (xy 173.911215 -277.550214)
			(xy 173.958486 -277.563906) (xy 174.002948 -277.585004) (xy 174.043451 -277.61296) (xy 174.078944 -277.647052)
			(xy 174.108509 -277.686396) (xy 174.13138 -277.729973) (xy 174.146964 -277.776654) (xy 174.154859 -277.825231)
			(xy 174.155354 -277.849838) (xy 174.494202 -277.849838) (xy 174.498162 -277.800784) (xy 174.509939 -277.753)
			(xy 174.52923 -277.707724) (xy 174.555533 -277.666128) (xy 174.588168 -277.629291) (xy 174.626289 -277.598166)
			(xy 174.66891 -277.573559) (xy 174.714926 -277.556107) (xy 174.763145 -277.546263) (xy 174.81232 -277.544282)
			(xy 174.861175 -277.550214) (xy 174.908446 -277.563906) (xy 174.952908 -277.585004) (xy 174.993411 -277.61296)
			(xy 175.028904 -277.647052) (xy 175.058469 -277.686396) (xy 175.08134 -277.729973) (xy 175.096924 -277.776654)
			(xy 175.104819 -277.825231) (xy 175.105314 -277.849838) (xy 175.104819 -277.874445) (xy 175.096924 -277.923022)
			(xy 175.08134 -277.969703) (xy 175.058469 -278.01328) (xy 175.028904 -278.052624) (xy 174.993411 -278.086716)
			(xy 174.952908 -278.114672) (xy 174.908446 -278.13577) (xy 174.861175 -278.149462) (xy 174.81232 -278.155394)
			(xy 174.763145 -278.153413) (xy 174.714926 -278.143569) (xy 174.66891 -278.126117) (xy 174.626289 -278.10151)
			(xy 174.588168 -278.070385) (xy 174.555533 -278.033548) (xy 174.52923 -277.991952) (xy 174.509939 -277.946676)
			(xy 174.498162 -277.898892) (xy 174.494202 -277.849838) (xy 174.155354 -277.849838) (xy 174.154859 -277.874445)
			(xy 174.146964 -277.923022) (xy 174.13138 -277.969703) (xy 174.108509 -278.01328) (xy 174.078944 -278.052624)
			(xy 174.043451 -278.086716) (xy 174.002948 -278.114672) (xy 173.958486 -278.13577) (xy 173.911215 -278.149462)
			(xy 173.86236 -278.155394) (xy 173.813185 -278.153413) (xy 173.764966 -278.143569) (xy 173.71895 -278.126117)
			(xy 173.676329 -278.10151) (xy 173.638208 -278.070385) (xy 173.605573 -278.033548) (xy 173.57927 -277.991952)
			(xy 173.559979 -277.946676) (xy 173.548202 -277.898892) (xy 173.544242 -277.849838) (xy 173.205394 -277.849838)
			(xy 173.204899 -277.874445) (xy 173.197004 -277.923022) (xy 173.18142 -277.969703) (xy 173.158549 -278.01328)
			(xy 173.128984 -278.052624) (xy 173.093491 -278.086716) (xy 173.052988 -278.114672) (xy 173.008526 -278.13577)
			(xy 172.961255 -278.149462) (xy 172.9124 -278.155394) (xy 172.863225 -278.153413) (xy 172.815006 -278.143569)
			(xy 172.76899 -278.126117) (xy 172.726369 -278.10151) (xy 172.688248 -278.070385) (xy 172.655613 -278.033548)
			(xy 172.62931 -277.991952) (xy 172.610019 -277.946676) (xy 172.598242 -277.898892) (xy 172.594282 -277.849838)
			(xy 172.25518 -277.849838) (xy 172.254685 -277.874445) (xy 172.24679 -277.923022) (xy 172.231206 -277.969703)
			(xy 172.208335 -278.01328) (xy 172.17877 -278.052624) (xy 172.143277 -278.086716) (xy 172.102774 -278.114672)
			(xy 172.058312 -278.13577) (xy 172.011041 -278.149462) (xy 171.962186 -278.155394) (xy 171.913011 -278.153413)
			(xy 171.864792 -278.143569) (xy 171.818776 -278.126117) (xy 171.776155 -278.10151) (xy 171.738034 -278.070385)
			(xy 171.705399 -278.033548) (xy 171.679096 -277.991952) (xy 171.659805 -277.946676) (xy 171.648028 -277.898892)
			(xy 171.644068 -277.849838) (xy 171.30522 -277.849838) (xy 171.304725 -277.874445) (xy 171.29683 -277.923022)
			(xy 171.281246 -277.969703) (xy 171.258375 -278.01328) (xy 171.22881 -278.052624) (xy 171.193317 -278.086716)
			(xy 171.152814 -278.114672) (xy 171.108352 -278.13577) (xy 171.061081 -278.149462) (xy 171.012226 -278.155394)
			(xy 170.963051 -278.153413) (xy 170.914832 -278.143569) (xy 170.868816 -278.126117) (xy 170.826195 -278.10151)
			(xy 170.788074 -278.070385) (xy 170.755439 -278.033548) (xy 170.729136 -277.991952) (xy 170.709845 -277.946676)
			(xy 170.698068 -277.898892) (xy 170.694108 -277.849838) (xy 170.35526 -277.849838) (xy 170.354765 -277.874445)
			(xy 170.34687 -277.923022) (xy 170.331286 -277.969703) (xy 170.308415 -278.01328) (xy 170.27885 -278.052624)
			(xy 170.243357 -278.086716) (xy 170.202854 -278.114672) (xy 170.158392 -278.13577) (xy 170.111121 -278.149462)
			(xy 170.062266 -278.155394) (xy 170.013091 -278.153413) (xy 169.964872 -278.143569) (xy 169.918856 -278.126117)
			(xy 169.876235 -278.10151) (xy 169.838114 -278.070385) (xy 169.805479 -278.033548) (xy 169.779176 -277.991952)
			(xy 169.759885 -277.946676) (xy 169.748108 -277.898892) (xy 169.744148 -277.849838) (xy 169.4053 -277.849838)
			(xy 169.404805 -277.874445) (xy 169.39691 -277.923022) (xy 169.381326 -277.969703) (xy 169.358455 -278.01328)
			(xy 169.32889 -278.052624) (xy 169.293397 -278.086716) (xy 169.252894 -278.114672) (xy 169.208432 -278.13577)
			(xy 169.161161 -278.149462) (xy 169.112306 -278.155394) (xy 169.063131 -278.153413) (xy 169.014912 -278.143569)
			(xy 168.968896 -278.126117) (xy 168.926275 -278.10151) (xy 168.888154 -278.070385) (xy 168.855519 -278.033548)
			(xy 168.829216 -277.991952) (xy 168.809925 -277.946676) (xy 168.798148 -277.898892) (xy 168.794188 -277.849838)
			(xy 168.45534 -277.849838) (xy 168.454845 -277.874445) (xy 168.44695 -277.923022) (xy 168.431366 -277.969703)
			(xy 168.408495 -278.01328) (xy 168.37893 -278.052624) (xy 168.343437 -278.086716) (xy 168.302934 -278.114672)
			(xy 168.258472 -278.13577) (xy 168.211201 -278.149462) (xy 168.162346 -278.155394) (xy 168.113171 -278.153413)
			(xy 168.064952 -278.143569) (xy 168.018936 -278.126117) (xy 167.976315 -278.10151) (xy 167.938194 -278.070385)
			(xy 167.905559 -278.033548) (xy 167.879256 -277.991952) (xy 167.859965 -277.946676) (xy 167.848188 -277.898892)
			(xy 167.844228 -277.849838) (xy 167.50538 -277.849838) (xy 167.504885 -277.874445) (xy 167.49699 -277.923022)
			(xy 167.481406 -277.969703) (xy 167.458535 -278.01328) (xy 167.42897 -278.052624) (xy 167.393477 -278.086716)
			(xy 167.352974 -278.114672) (xy 167.308512 -278.13577) (xy 167.261241 -278.149462) (xy 167.212386 -278.155394)
			(xy 167.163211 -278.153413) (xy 167.114992 -278.143569) (xy 167.068976 -278.126117) (xy 167.026355 -278.10151)
			(xy 166.988234 -278.070385) (xy 166.955599 -278.033548) (xy 166.929296 -277.991952) (xy 166.910005 -277.946676)
			(xy 166.898228 -277.898892) (xy 166.894268 -277.849838) (xy 166.555166 -277.849838) (xy 166.554671 -277.874445)
			(xy 166.546776 -277.923022) (xy 166.531192 -277.969703) (xy 166.508321 -278.01328) (xy 166.478756 -278.052624)
			(xy 166.443263 -278.086716) (xy 166.40276 -278.114672) (xy 166.358298 -278.13577) (xy 166.311027 -278.149462)
			(xy 166.262172 -278.155394) (xy 166.212997 -278.153413) (xy 166.164778 -278.143569) (xy 166.118762 -278.126117)
			(xy 166.076141 -278.10151) (xy 166.03802 -278.070385) (xy 166.005385 -278.033548) (xy 165.979082 -277.991952)
			(xy 165.959791 -277.946676) (xy 165.948014 -277.898892) (xy 165.944054 -277.849838) (xy 165.605206 -277.849838)
			(xy 165.604711 -277.874445) (xy 165.596816 -277.923022) (xy 165.581232 -277.969703) (xy 165.558361 -278.01328)
			(xy 165.528796 -278.052624) (xy 165.493303 -278.086716) (xy 165.4528 -278.114672) (xy 165.408338 -278.13577)
			(xy 165.361067 -278.149462) (xy 165.312212 -278.155394) (xy 165.263037 -278.153413) (xy 165.214818 -278.143569)
			(xy 165.168802 -278.126117) (xy 165.126181 -278.10151) (xy 165.08806 -278.070385) (xy 165.055425 -278.033548)
			(xy 165.029122 -277.991952) (xy 165.009831 -277.946676) (xy 164.998054 -277.898892) (xy 164.994094 -277.849838)
			(xy 164.655246 -277.849838) (xy 164.654751 -277.874445) (xy 164.646856 -277.923022) (xy 164.631272 -277.969703)
			(xy 164.608401 -278.01328) (xy 164.578836 -278.052624) (xy 164.543343 -278.086716) (xy 164.50284 -278.114672)
			(xy 164.458378 -278.13577) (xy 164.411107 -278.149462) (xy 164.362252 -278.155394) (xy 164.313077 -278.153413)
			(xy 164.264858 -278.143569) (xy 164.218842 -278.126117) (xy 164.176221 -278.10151) (xy 164.1381 -278.070385)
			(xy 164.105465 -278.033548) (xy 164.079162 -277.991952) (xy 164.059871 -277.946676) (xy 164.048094 -277.898892)
			(xy 164.044134 -277.849838) (xy 163.705286 -277.849838) (xy 163.704791 -277.874445) (xy 163.696896 -277.923022)
			(xy 163.681312 -277.969703) (xy 163.658441 -278.01328) (xy 163.628876 -278.052624) (xy 163.593383 -278.086716)
			(xy 163.55288 -278.114672) (xy 163.508418 -278.13577) (xy 163.461147 -278.149462) (xy 163.412292 -278.155394)
			(xy 163.363117 -278.153413) (xy 163.314898 -278.143569) (xy 163.268882 -278.126117) (xy 163.226261 -278.10151)
			(xy 163.18814 -278.070385) (xy 163.155505 -278.033548) (xy 163.129202 -277.991952) (xy 163.109911 -277.946676)
			(xy 163.098134 -277.898892) (xy 163.094174 -277.849838) (xy 162.755326 -277.849838) (xy 162.754831 -277.874445)
			(xy 162.746936 -277.923022) (xy 162.731352 -277.969703) (xy 162.708481 -278.01328) (xy 162.678916 -278.052624)
			(xy 162.643423 -278.086716) (xy 162.60292 -278.114672) (xy 162.558458 -278.13577) (xy 162.511187 -278.149462)
			(xy 162.462332 -278.155394) (xy 162.413157 -278.153413) (xy 162.364938 -278.143569) (xy 162.318922 -278.126117)
			(xy 162.276301 -278.10151) (xy 162.23818 -278.070385) (xy 162.205545 -278.033548) (xy 162.179242 -277.991952)
			(xy 162.159951 -277.946676) (xy 162.148174 -277.898892) (xy 162.144214 -277.849838) (xy 161.805366 -277.849838)
			(xy 161.804871 -277.874445) (xy 161.796976 -277.923022) (xy 161.781392 -277.969703) (xy 161.758521 -278.01328)
			(xy 161.728956 -278.052624) (xy 161.693463 -278.086716) (xy 161.65296 -278.114672) (xy 161.608498 -278.13577)
			(xy 161.561227 -278.149462) (xy 161.512372 -278.155394) (xy 161.463197 -278.153413) (xy 161.414978 -278.143569)
			(xy 161.368962 -278.126117) (xy 161.326341 -278.10151) (xy 161.28822 -278.070385) (xy 161.255585 -278.033548)
			(xy 161.229282 -277.991952) (xy 161.209991 -277.946676) (xy 161.198214 -277.898892) (xy 161.194254 -277.849838)
			(xy 160.855152 -277.849838) (xy 160.854657 -277.874445) (xy 160.846762 -277.923022) (xy 160.831178 -277.969703)
			(xy 160.808307 -278.01328) (xy 160.778742 -278.052624) (xy 160.743249 -278.086716) (xy 160.702746 -278.114672)
			(xy 160.658284 -278.13577) (xy 160.611013 -278.149462) (xy 160.562158 -278.155394) (xy 160.512983 -278.153413)
			(xy 160.464764 -278.143569) (xy 160.418748 -278.126117) (xy 160.376127 -278.10151) (xy 160.338006 -278.070385)
			(xy 160.305371 -278.033548) (xy 160.279068 -277.991952) (xy 160.259777 -277.946676) (xy 160.248 -277.898892)
			(xy 160.24404 -277.849838) (xy 159.905795 -277.849838) (xy 159.901626 -277.900151) (xy 159.889223 -277.949128)
			(xy 159.868927 -277.995396) (xy 159.841292 -278.037692) (xy 159.807073 -278.074862) (xy 159.767202 -278.105893)
			(xy 159.722767 -278.129938) (xy 159.67498 -278.146341) (xy 159.625146 -278.154654) (xy 159.599884 -278.155146)
			(xy 159.585701 -278.154971) (xy 159.557461 -278.152298) (xy 159.543496 -278.149812) (xy 159.53105 -278.147526)
			(xy 159.507428 -278.154892) (xy 159.429958 -278.232362) (xy 159.422592 -278.255984) (xy 159.424878 -278.26843)
			(xy 159.427354 -278.282396) (xy 159.430026 -278.310635) (xy 159.430212 -278.324818) (xy 159.430038 -278.339001)
			(xy 159.427364 -278.367241) (xy 159.424878 -278.381206) (xy 159.422592 -278.393652) (xy 159.429958 -278.417274)
			(xy 159.507428 -278.494744) (xy 159.53105 -278.50211) (xy 159.543496 -278.499824) (xy 159.557463 -278.497352)
			(xy 159.585702 -278.494677) (xy 159.599884 -278.49449) (xy 159.623877 -278.494953) (xy 159.671271 -278.502457)
			(xy 159.716909 -278.517283) (xy 159.759665 -278.539067) (xy 159.798486 -278.56727) (xy 159.832418 -278.6012)
			(xy 159.860624 -278.64002) (xy 159.88241 -278.682775) (xy 159.897239 -278.728411) (xy 159.904746 -278.775805)
			(xy 159.905192 -278.799798) (xy 159.905015 -278.813981) (xy 159.902343 -278.842221) (xy 159.899858 -278.856186)
			(xy 159.897572 -278.868632) (xy 159.904938 -278.892254) (xy 159.982408 -278.969724) (xy 160.00603 -278.97709)
			(xy 160.018476 -278.974804) (xy 160.032441 -278.972321) (xy 160.060681 -278.969654) (xy 160.074864 -278.96947)
			(xy 160.089047 -278.969652) (xy 160.117287 -278.972321) (xy 160.131252 -278.974804) (xy 160.143698 -278.97709)
			(xy 160.16732 -278.969724) (xy 160.24479 -278.892254) (xy 160.252156 -278.868632) (xy 160.24987 -278.856186)
			(xy 160.247395 -278.84222) (xy 160.244722 -278.81398) (xy 160.244536 -278.799798) (xy 160.24498 -278.774978)
			(xy 160.253011 -278.725992) (xy 160.268861 -278.678951) (xy 160.292112 -278.635093) (xy 160.322152 -278.595575)
			(xy 160.35819 -278.561437) (xy 160.399275 -278.533579) (xy 160.444327 -278.512734) (xy 160.492157 -278.499452)
			(xy 160.541505 -278.494084) (xy 160.591072 -278.496769) (xy 160.639552 -278.507437) (xy 160.685667 -278.525808)
			(xy 160.728203 -278.551398) (xy 160.766039 -278.583531) (xy 160.798178 -278.621363) (xy 160.823773 -278.663895)
			(xy 160.84215 -278.710008) (xy 160.852826 -278.758486) (xy 160.85507 -278.799798) (xy 161.194254 -278.799798)
			(xy 161.198214 -278.750744) (xy 161.209991 -278.70296) (xy 161.229282 -278.657684) (xy 161.255585 -278.616088)
			(xy 161.28822 -278.579251) (xy 161.326341 -278.548126) (xy 161.368962 -278.523519) (xy 161.414978 -278.506067)
			(xy 161.463197 -278.496223) (xy 161.512372 -278.494242) (xy 161.561227 -278.500174) (xy 161.608498 -278.513866)
			(xy 161.65296 -278.534964) (xy 161.693463 -278.56292) (xy 161.728956 -278.597012) (xy 161.758521 -278.636356)
			(xy 161.781392 -278.679933) (xy 161.796976 -278.726614) (xy 161.804871 -278.775191) (xy 161.805366 -278.799798)
			(xy 162.144214 -278.799798) (xy 162.148174 -278.750744) (xy 162.159951 -278.70296) (xy 162.179242 -278.657684)
			(xy 162.205545 -278.616088) (xy 162.23818 -278.579251) (xy 162.276301 -278.548126) (xy 162.318922 -278.523519)
			(xy 162.364938 -278.506067) (xy 162.413157 -278.496223) (xy 162.462332 -278.494242) (xy 162.511187 -278.500174)
			(xy 162.558458 -278.513866) (xy 162.60292 -278.534964) (xy 162.643423 -278.56292) (xy 162.678916 -278.597012)
			(xy 162.708481 -278.636356) (xy 162.731352 -278.679933) (xy 162.746936 -278.726614) (xy 162.754831 -278.775191)
			(xy 162.755326 -278.799798) (xy 163.094174 -278.799798) (xy 163.098134 -278.750744) (xy 163.109911 -278.70296)
			(xy 163.129202 -278.657684) (xy 163.155505 -278.616088) (xy 163.18814 -278.579251) (xy 163.226261 -278.548126)
			(xy 163.268882 -278.523519) (xy 163.314898 -278.506067) (xy 163.363117 -278.496223) (xy 163.412292 -278.494242)
			(xy 163.461147 -278.500174) (xy 163.508418 -278.513866) (xy 163.55288 -278.534964) (xy 163.593383 -278.56292)
			(xy 163.628876 -278.597012) (xy 163.658441 -278.636356) (xy 163.681312 -278.679933) (xy 163.696896 -278.726614)
			(xy 163.704791 -278.775191) (xy 163.705286 -278.799798) (xy 164.044134 -278.799798) (xy 164.048094 -278.750744)
			(xy 164.059871 -278.70296) (xy 164.079162 -278.657684) (xy 164.105465 -278.616088) (xy 164.1381 -278.579251)
			(xy 164.176221 -278.548126) (xy 164.218842 -278.523519) (xy 164.264858 -278.506067) (xy 164.313077 -278.496223)
			(xy 164.362252 -278.494242) (xy 164.411107 -278.500174) (xy 164.458378 -278.513866) (xy 164.50284 -278.534964)
			(xy 164.543343 -278.56292) (xy 164.578836 -278.597012) (xy 164.608401 -278.636356) (xy 164.631272 -278.679933)
			(xy 164.646856 -278.726614) (xy 164.654751 -278.775191) (xy 164.655246 -278.799798) (xy 164.994094 -278.799798)
			(xy 164.998054 -278.750744) (xy 165.009831 -278.70296) (xy 165.029122 -278.657684) (xy 165.055425 -278.616088)
			(xy 165.08806 -278.579251) (xy 165.126181 -278.548126) (xy 165.168802 -278.523519) (xy 165.214818 -278.506067)
			(xy 165.263037 -278.496223) (xy 165.312212 -278.494242) (xy 165.361067 -278.500174) (xy 165.408338 -278.513866)
			(xy 165.4528 -278.534964) (xy 165.493303 -278.56292) (xy 165.528796 -278.597012) (xy 165.558361 -278.636356)
			(xy 165.581232 -278.679933) (xy 165.596816 -278.726614) (xy 165.604711 -278.775191) (xy 165.605206 -278.799798)
			(xy 165.944054 -278.799798) (xy 165.948014 -278.750744) (xy 165.959791 -278.70296) (xy 165.979082 -278.657684)
			(xy 166.005385 -278.616088) (xy 166.03802 -278.579251) (xy 166.076141 -278.548126) (xy 166.118762 -278.523519)
			(xy 166.164778 -278.506067) (xy 166.212997 -278.496223) (xy 166.262172 -278.494242) (xy 166.311027 -278.500174)
			(xy 166.358298 -278.513866) (xy 166.40276 -278.534964) (xy 166.443263 -278.56292) (xy 166.478756 -278.597012)
			(xy 166.508321 -278.636356) (xy 166.531192 -278.679933) (xy 166.546776 -278.726614) (xy 166.554671 -278.775191)
			(xy 166.555166 -278.799798) (xy 166.894268 -278.799798) (xy 166.898228 -278.750744) (xy 166.910005 -278.70296)
			(xy 166.929296 -278.657684) (xy 166.955599 -278.616088) (xy 166.988234 -278.579251) (xy 167.026355 -278.548126)
			(xy 167.068976 -278.523519) (xy 167.114992 -278.506067) (xy 167.163211 -278.496223) (xy 167.212386 -278.494242)
			(xy 167.261241 -278.500174) (xy 167.308512 -278.513866) (xy 167.352974 -278.534964) (xy 167.393477 -278.56292)
			(xy 167.42897 -278.597012) (xy 167.458535 -278.636356) (xy 167.481406 -278.679933) (xy 167.49699 -278.726614)
			(xy 167.504885 -278.775191) (xy 167.50538 -278.799798) (xy 167.844228 -278.799798) (xy 167.848188 -278.750744)
			(xy 167.859965 -278.70296) (xy 167.879256 -278.657684) (xy 167.905559 -278.616088) (xy 167.938194 -278.579251)
			(xy 167.976315 -278.548126) (xy 168.018936 -278.523519) (xy 168.064952 -278.506067) (xy 168.113171 -278.496223)
			(xy 168.162346 -278.494242) (xy 168.211201 -278.500174) (xy 168.258472 -278.513866) (xy 168.302934 -278.534964)
			(xy 168.343437 -278.56292) (xy 168.37893 -278.597012) (xy 168.408495 -278.636356) (xy 168.431366 -278.679933)
			(xy 168.44695 -278.726614) (xy 168.454845 -278.775191) (xy 168.45534 -278.799798) (xy 168.794188 -278.799798)
			(xy 168.798148 -278.750744) (xy 168.809925 -278.70296) (xy 168.829216 -278.657684) (xy 168.855519 -278.616088)
			(xy 168.888154 -278.579251) (xy 168.926275 -278.548126) (xy 168.968896 -278.523519) (xy 169.014912 -278.506067)
			(xy 169.063131 -278.496223) (xy 169.112306 -278.494242) (xy 169.161161 -278.500174) (xy 169.208432 -278.513866)
			(xy 169.252894 -278.534964) (xy 169.293397 -278.56292) (xy 169.32889 -278.597012) (xy 169.358455 -278.636356)
			(xy 169.381326 -278.679933) (xy 169.39691 -278.726614) (xy 169.404805 -278.775191) (xy 169.4053 -278.799798)
			(xy 169.744148 -278.799798) (xy 169.748108 -278.750744) (xy 169.759885 -278.70296) (xy 169.779176 -278.657684)
			(xy 169.805479 -278.616088) (xy 169.838114 -278.579251) (xy 169.876235 -278.548126) (xy 169.918856 -278.523519)
			(xy 169.964872 -278.506067) (xy 170.013091 -278.496223) (xy 170.062266 -278.494242) (xy 170.111121 -278.500174)
			(xy 170.158392 -278.513866) (xy 170.202854 -278.534964) (xy 170.243357 -278.56292) (xy 170.27885 -278.597012)
			(xy 170.308415 -278.636356) (xy 170.331286 -278.679933) (xy 170.34687 -278.726614) (xy 170.354765 -278.775191)
			(xy 170.35526 -278.799798) (xy 170.694108 -278.799798) (xy 170.698068 -278.750744) (xy 170.709845 -278.70296)
			(xy 170.729136 -278.657684) (xy 170.755439 -278.616088) (xy 170.788074 -278.579251) (xy 170.826195 -278.548126)
			(xy 170.868816 -278.523519) (xy 170.914832 -278.506067) (xy 170.963051 -278.496223) (xy 171.012226 -278.494242)
			(xy 171.061081 -278.500174) (xy 171.108352 -278.513866) (xy 171.152814 -278.534964) (xy 171.193317 -278.56292)
			(xy 171.22881 -278.597012) (xy 171.258375 -278.636356) (xy 171.281246 -278.679933) (xy 171.29683 -278.726614)
			(xy 171.304725 -278.775191) (xy 171.30522 -278.799798) (xy 171.644068 -278.799798) (xy 171.648028 -278.750744)
			(xy 171.659805 -278.70296) (xy 171.679096 -278.657684) (xy 171.705399 -278.616088) (xy 171.738034 -278.579251)
			(xy 171.776155 -278.548126) (xy 171.818776 -278.523519) (xy 171.864792 -278.506067) (xy 171.913011 -278.496223)
			(xy 171.962186 -278.494242) (xy 172.011041 -278.500174) (xy 172.058312 -278.513866) (xy 172.102774 -278.534964)
			(xy 172.143277 -278.56292) (xy 172.17877 -278.597012) (xy 172.208335 -278.636356) (xy 172.231206 -278.679933)
			(xy 172.24679 -278.726614) (xy 172.254685 -278.775191) (xy 172.25518 -278.799798) (xy 172.594282 -278.799798)
			(xy 172.598242 -278.750744) (xy 172.610019 -278.70296) (xy 172.62931 -278.657684) (xy 172.655613 -278.616088)
			(xy 172.688248 -278.579251) (xy 172.726369 -278.548126) (xy 172.76899 -278.523519) (xy 172.815006 -278.506067)
			(xy 172.863225 -278.496223) (xy 172.9124 -278.494242) (xy 172.961255 -278.500174) (xy 173.008526 -278.513866)
			(xy 173.052988 -278.534964) (xy 173.093491 -278.56292) (xy 173.128984 -278.597012) (xy 173.158549 -278.636356)
			(xy 173.18142 -278.679933) (xy 173.197004 -278.726614) (xy 173.204899 -278.775191) (xy 173.205394 -278.799798)
			(xy 173.544242 -278.799798) (xy 173.548202 -278.750744) (xy 173.559979 -278.70296) (xy 173.57927 -278.657684)
			(xy 173.605573 -278.616088) (xy 173.638208 -278.579251) (xy 173.676329 -278.548126) (xy 173.71895 -278.523519)
			(xy 173.764966 -278.506067) (xy 173.813185 -278.496223) (xy 173.86236 -278.494242) (xy 173.911215 -278.500174)
			(xy 173.958486 -278.513866) (xy 174.002948 -278.534964) (xy 174.043451 -278.56292) (xy 174.078944 -278.597012)
			(xy 174.108509 -278.636356) (xy 174.13138 -278.679933) (xy 174.146964 -278.726614) (xy 174.154859 -278.775191)
			(xy 174.155354 -278.799798) (xy 174.494202 -278.799798) (xy 174.498162 -278.750744) (xy 174.509939 -278.70296)
			(xy 174.52923 -278.657684) (xy 174.555533 -278.616088) (xy 174.588168 -278.579251) (xy 174.626289 -278.548126)
			(xy 174.66891 -278.523519) (xy 174.714926 -278.506067) (xy 174.763145 -278.496223) (xy 174.81232 -278.494242)
			(xy 174.861175 -278.500174) (xy 174.908446 -278.513866) (xy 174.952908 -278.534964) (xy 174.993411 -278.56292)
			(xy 175.028904 -278.597012) (xy 175.058469 -278.636356) (xy 175.08134 -278.679933) (xy 175.096924 -278.726614)
			(xy 175.104819 -278.775191) (xy 175.105314 -278.799798) (xy 175.104819 -278.824405) (xy 175.096924 -278.872982)
			(xy 175.08134 -278.919663) (xy 175.058469 -278.96324) (xy 175.028904 -279.002584) (xy 174.993411 -279.036676)
			(xy 174.952908 -279.064632) (xy 174.908446 -279.08573) (xy 174.861175 -279.099422) (xy 174.81232 -279.105354)
			(xy 174.763145 -279.103373) (xy 174.714926 -279.093529) (xy 174.66891 -279.076077) (xy 174.626289 -279.05147)
			(xy 174.588168 -279.020345) (xy 174.555533 -278.983508) (xy 174.52923 -278.941912) (xy 174.509939 -278.896636)
			(xy 174.498162 -278.848852) (xy 174.494202 -278.799798) (xy 174.155354 -278.799798) (xy 174.154859 -278.824405)
			(xy 174.146964 -278.872982) (xy 174.13138 -278.919663) (xy 174.108509 -278.96324) (xy 174.078944 -279.002584)
			(xy 174.043451 -279.036676) (xy 174.002948 -279.064632) (xy 173.958486 -279.08573) (xy 173.911215 -279.099422)
			(xy 173.86236 -279.105354) (xy 173.813185 -279.103373) (xy 173.764966 -279.093529) (xy 173.71895 -279.076077)
			(xy 173.676329 -279.05147) (xy 173.638208 -279.020345) (xy 173.605573 -278.983508) (xy 173.57927 -278.941912)
			(xy 173.559979 -278.896636) (xy 173.548202 -278.848852) (xy 173.544242 -278.799798) (xy 173.205394 -278.799798)
			(xy 173.204899 -278.824405) (xy 173.197004 -278.872982) (xy 173.18142 -278.919663) (xy 173.158549 -278.96324)
			(xy 173.128984 -279.002584) (xy 173.093491 -279.036676) (xy 173.052988 -279.064632) (xy 173.008526 -279.08573)
			(xy 172.961255 -279.099422) (xy 172.9124 -279.105354) (xy 172.863225 -279.103373) (xy 172.815006 -279.093529)
			(xy 172.76899 -279.076077) (xy 172.726369 -279.05147) (xy 172.688248 -279.020345) (xy 172.655613 -278.983508)
			(xy 172.62931 -278.941912) (xy 172.610019 -278.896636) (xy 172.598242 -278.848852) (xy 172.594282 -278.799798)
			(xy 172.25518 -278.799798) (xy 172.254685 -278.824405) (xy 172.24679 -278.872982) (xy 172.231206 -278.919663)
			(xy 172.208335 -278.96324) (xy 172.17877 -279.002584) (xy 172.143277 -279.036676) (xy 172.102774 -279.064632)
			(xy 172.058312 -279.08573) (xy 172.011041 -279.099422) (xy 171.962186 -279.105354) (xy 171.913011 -279.103373)
			(xy 171.864792 -279.093529) (xy 171.818776 -279.076077) (xy 171.776155 -279.05147) (xy 171.738034 -279.020345)
			(xy 171.705399 -278.983508) (xy 171.679096 -278.941912) (xy 171.659805 -278.896636) (xy 171.648028 -278.848852)
			(xy 171.644068 -278.799798) (xy 171.30522 -278.799798) (xy 171.304725 -278.824405) (xy 171.29683 -278.872982)
			(xy 171.281246 -278.919663) (xy 171.258375 -278.96324) (xy 171.22881 -279.002584) (xy 171.193317 -279.036676)
			(xy 171.152814 -279.064632) (xy 171.108352 -279.08573) (xy 171.061081 -279.099422) (xy 171.012226 -279.105354)
			(xy 170.963051 -279.103373) (xy 170.914832 -279.093529) (xy 170.868816 -279.076077) (xy 170.826195 -279.05147)
			(xy 170.788074 -279.020345) (xy 170.755439 -278.983508) (xy 170.729136 -278.941912) (xy 170.709845 -278.896636)
			(xy 170.698068 -278.848852) (xy 170.694108 -278.799798) (xy 170.35526 -278.799798) (xy 170.354765 -278.824405)
			(xy 170.34687 -278.872982) (xy 170.331286 -278.919663) (xy 170.308415 -278.96324) (xy 170.27885 -279.002584)
			(xy 170.243357 -279.036676) (xy 170.202854 -279.064632) (xy 170.158392 -279.08573) (xy 170.111121 -279.099422)
			(xy 170.062266 -279.105354) (xy 170.013091 -279.103373) (xy 169.964872 -279.093529) (xy 169.918856 -279.076077)
			(xy 169.876235 -279.05147) (xy 169.838114 -279.020345) (xy 169.805479 -278.983508) (xy 169.779176 -278.941912)
			(xy 169.759885 -278.896636) (xy 169.748108 -278.848852) (xy 169.744148 -278.799798) (xy 169.4053 -278.799798)
			(xy 169.404805 -278.824405) (xy 169.39691 -278.872982) (xy 169.381326 -278.919663) (xy 169.358455 -278.96324)
			(xy 169.32889 -279.002584) (xy 169.293397 -279.036676) (xy 169.252894 -279.064632) (xy 169.208432 -279.08573)
			(xy 169.161161 -279.099422) (xy 169.112306 -279.105354) (xy 169.063131 -279.103373) (xy 169.014912 -279.093529)
			(xy 168.968896 -279.076077) (xy 168.926275 -279.05147) (xy 168.888154 -279.020345) (xy 168.855519 -278.983508)
			(xy 168.829216 -278.941912) (xy 168.809925 -278.896636) (xy 168.798148 -278.848852) (xy 168.794188 -278.799798)
			(xy 168.45534 -278.799798) (xy 168.454845 -278.824405) (xy 168.44695 -278.872982) (xy 168.431366 -278.919663)
			(xy 168.408495 -278.96324) (xy 168.37893 -279.002584) (xy 168.343437 -279.036676) (xy 168.302934 -279.064632)
			(xy 168.258472 -279.08573) (xy 168.211201 -279.099422) (xy 168.162346 -279.105354) (xy 168.113171 -279.103373)
			(xy 168.064952 -279.093529) (xy 168.018936 -279.076077) (xy 167.976315 -279.05147) (xy 167.938194 -279.020345)
			(xy 167.905559 -278.983508) (xy 167.879256 -278.941912) (xy 167.859965 -278.896636) (xy 167.848188 -278.848852)
			(xy 167.844228 -278.799798) (xy 167.50538 -278.799798) (xy 167.504885 -278.824405) (xy 167.49699 -278.872982)
			(xy 167.481406 -278.919663) (xy 167.458535 -278.96324) (xy 167.42897 -279.002584) (xy 167.393477 -279.036676)
			(xy 167.352974 -279.064632) (xy 167.308512 -279.08573) (xy 167.261241 -279.099422) (xy 167.212386 -279.105354)
			(xy 167.163211 -279.103373) (xy 167.114992 -279.093529) (xy 167.068976 -279.076077) (xy 167.026355 -279.05147)
			(xy 166.988234 -279.020345) (xy 166.955599 -278.983508) (xy 166.929296 -278.941912) (xy 166.910005 -278.896636)
			(xy 166.898228 -278.848852) (xy 166.894268 -278.799798) (xy 166.555166 -278.799798) (xy 166.554671 -278.824405)
			(xy 166.546776 -278.872982) (xy 166.531192 -278.919663) (xy 166.508321 -278.96324) (xy 166.478756 -279.002584)
			(xy 166.443263 -279.036676) (xy 166.40276 -279.064632) (xy 166.358298 -279.08573) (xy 166.311027 -279.099422)
			(xy 166.262172 -279.105354) (xy 166.212997 -279.103373) (xy 166.164778 -279.093529) (xy 166.118762 -279.076077)
			(xy 166.076141 -279.05147) (xy 166.03802 -279.020345) (xy 166.005385 -278.983508) (xy 165.979082 -278.941912)
			(xy 165.959791 -278.896636) (xy 165.948014 -278.848852) (xy 165.944054 -278.799798) (xy 165.605206 -278.799798)
			(xy 165.604711 -278.824405) (xy 165.596816 -278.872982) (xy 165.581232 -278.919663) (xy 165.558361 -278.96324)
			(xy 165.528796 -279.002584) (xy 165.493303 -279.036676) (xy 165.4528 -279.064632) (xy 165.408338 -279.08573)
			(xy 165.361067 -279.099422) (xy 165.312212 -279.105354) (xy 165.263037 -279.103373) (xy 165.214818 -279.093529)
			(xy 165.168802 -279.076077) (xy 165.126181 -279.05147) (xy 165.08806 -279.020345) (xy 165.055425 -278.983508)
			(xy 165.029122 -278.941912) (xy 165.009831 -278.896636) (xy 164.998054 -278.848852) (xy 164.994094 -278.799798)
			(xy 164.655246 -278.799798) (xy 164.654751 -278.824405) (xy 164.646856 -278.872982) (xy 164.631272 -278.919663)
			(xy 164.608401 -278.96324) (xy 164.578836 -279.002584) (xy 164.543343 -279.036676) (xy 164.50284 -279.064632)
			(xy 164.458378 -279.08573) (xy 164.411107 -279.099422) (xy 164.362252 -279.105354) (xy 164.313077 -279.103373)
			(xy 164.264858 -279.093529) (xy 164.218842 -279.076077) (xy 164.176221 -279.05147) (xy 164.1381 -279.020345)
			(xy 164.105465 -278.983508) (xy 164.079162 -278.941912) (xy 164.059871 -278.896636) (xy 164.048094 -278.848852)
			(xy 164.044134 -278.799798) (xy 163.705286 -278.799798) (xy 163.704791 -278.824405) (xy 163.696896 -278.872982)
			(xy 163.681312 -278.919663) (xy 163.658441 -278.96324) (xy 163.628876 -279.002584) (xy 163.593383 -279.036676)
			(xy 163.55288 -279.064632) (xy 163.508418 -279.08573) (xy 163.461147 -279.099422) (xy 163.412292 -279.105354)
			(xy 163.363117 -279.103373) (xy 163.314898 -279.093529) (xy 163.268882 -279.076077) (xy 163.226261 -279.05147)
			(xy 163.18814 -279.020345) (xy 163.155505 -278.983508) (xy 163.129202 -278.941912) (xy 163.109911 -278.896636)
			(xy 163.098134 -278.848852) (xy 163.094174 -278.799798) (xy 162.755326 -278.799798) (xy 162.754831 -278.824405)
			(xy 162.746936 -278.872982) (xy 162.731352 -278.919663) (xy 162.708481 -278.96324) (xy 162.678916 -279.002584)
			(xy 162.643423 -279.036676) (xy 162.60292 -279.064632) (xy 162.558458 -279.08573) (xy 162.511187 -279.099422)
			(xy 162.462332 -279.105354) (xy 162.413157 -279.103373) (xy 162.364938 -279.093529) (xy 162.318922 -279.076077)
			(xy 162.276301 -279.05147) (xy 162.23818 -279.020345) (xy 162.205545 -278.983508) (xy 162.179242 -278.941912)
			(xy 162.159951 -278.896636) (xy 162.148174 -278.848852) (xy 162.144214 -278.799798) (xy 161.805366 -278.799798)
			(xy 161.804871 -278.824405) (xy 161.796976 -278.872982) (xy 161.781392 -278.919663) (xy 161.758521 -278.96324)
			(xy 161.728956 -279.002584) (xy 161.693463 -279.036676) (xy 161.65296 -279.064632) (xy 161.608498 -279.08573)
			(xy 161.561227 -279.099422) (xy 161.512372 -279.105354) (xy 161.463197 -279.103373) (xy 161.414978 -279.093529)
			(xy 161.368962 -279.076077) (xy 161.326341 -279.05147) (xy 161.28822 -279.020345) (xy 161.255585 -278.983508)
			(xy 161.229282 -278.941912) (xy 161.209991 -278.896636) (xy 161.198214 -278.848852) (xy 161.194254 -278.799798)
			(xy 160.85507 -278.799798) (xy 160.855518 -278.808053) (xy 160.850155 -278.857402) (xy 160.83688 -278.905234)
			(xy 160.816042 -278.950288) (xy 160.788189 -278.991377) (xy 160.754056 -279.02742) (xy 160.714542 -279.057465)
			(xy 160.670688 -279.080723) (xy 160.623649 -279.096579) (xy 160.574664 -279.104617) (xy 160.549844 -279.105106)
			(xy 160.535661 -279.104923) (xy 160.507421 -279.102255) (xy 160.493456 -279.099772) (xy 160.48101 -279.097486)
			(xy 160.457388 -279.104852) (xy 160.379918 -279.182322) (xy 160.372552 -279.205944) (xy 160.374838 -279.21839)
			(xy 160.377309 -279.232357) (xy 160.379984 -279.260596) (xy 160.380172 -279.274778) (xy 160.379993 -279.288961)
			(xy 160.377323 -279.317201) (xy 160.374838 -279.331166) (xy 160.372552 -279.343612) (xy 160.379918 -279.367234)
			(xy 160.457388 -279.444704) (xy 160.48101 -279.45207) (xy 160.493456 -279.449784) (xy 160.507421 -279.447304)
			(xy 160.535661 -279.444634) (xy 160.549844 -279.44445) (xy 160.575093 -279.445059) (xy 160.624903 -279.453377)
			(xy 160.672664 -279.46978) (xy 160.717074 -279.493819) (xy 160.756922 -279.524839) (xy 160.791122 -279.561995)
			(xy 160.81874 -279.604273) (xy 160.839024 -279.650519) (xy 160.851419 -279.699473) (xy 160.855564 -279.749504)
			(xy 161.194254 -279.749504) (xy 161.198214 -279.70045) (xy 161.209991 -279.652666) (xy 161.229282 -279.60739)
			(xy 161.255585 -279.565794) (xy 161.28822 -279.528957) (xy 161.326341 -279.497832) (xy 161.368962 -279.473225)
			(xy 161.414978 -279.455773) (xy 161.463197 -279.445929) (xy 161.512372 -279.443948) (xy 161.561227 -279.44988)
			(xy 161.608498 -279.463572) (xy 161.65296 -279.48467) (xy 161.693463 -279.512626) (xy 161.728956 -279.546718)
			(xy 161.758521 -279.586062) (xy 161.781392 -279.629639) (xy 161.796976 -279.67632) (xy 161.804871 -279.724897)
			(xy 161.805366 -279.749504) (xy 161.805361 -279.749758) (xy 162.144214 -279.749758) (xy 162.148174 -279.700704)
			(xy 162.159951 -279.65292) (xy 162.179242 -279.607644) (xy 162.205545 -279.566048) (xy 162.23818 -279.529211)
			(xy 162.276301 -279.498086) (xy 162.318922 -279.473479) (xy 162.364938 -279.456027) (xy 162.413157 -279.446183)
			(xy 162.462332 -279.444202) (xy 162.511187 -279.450134) (xy 162.558458 -279.463826) (xy 162.60292 -279.484924)
			(xy 162.643423 -279.51288) (xy 162.678916 -279.546972) (xy 162.708481 -279.586316) (xy 162.731352 -279.629893)
			(xy 162.746936 -279.676574) (xy 162.754831 -279.725151) (xy 162.755321 -279.749504) (xy 163.094174 -279.749504)
			(xy 163.098134 -279.70045) (xy 163.109911 -279.652666) (xy 163.129202 -279.60739) (xy 163.155505 -279.565794)
			(xy 163.18814 -279.528957) (xy 163.226261 -279.497832) (xy 163.268882 -279.473225) (xy 163.314898 -279.455773)
			(xy 163.363117 -279.445929) (xy 163.412292 -279.443948) (xy 163.461147 -279.44988) (xy 163.508418 -279.463572)
			(xy 163.55288 -279.48467) (xy 163.593383 -279.512626) (xy 163.628876 -279.546718) (xy 163.658441 -279.586062)
			(xy 163.681312 -279.629639) (xy 163.696896 -279.67632) (xy 163.704791 -279.724897) (xy 163.705286 -279.749504)
			(xy 163.705281 -279.749758) (xy 164.044134 -279.749758) (xy 164.048094 -279.700704) (xy 164.059871 -279.65292)
			(xy 164.079162 -279.607644) (xy 164.105465 -279.566048) (xy 164.1381 -279.529211) (xy 164.176221 -279.498086)
			(xy 164.218842 -279.473479) (xy 164.264858 -279.456027) (xy 164.313077 -279.446183) (xy 164.362252 -279.444202)
			(xy 164.411107 -279.450134) (xy 164.458378 -279.463826) (xy 164.50284 -279.484924) (xy 164.543343 -279.51288)
			(xy 164.578836 -279.546972) (xy 164.608401 -279.586316) (xy 164.631272 -279.629893) (xy 164.646856 -279.676574)
			(xy 164.654751 -279.725151) (xy 164.655241 -279.749504) (xy 164.994094 -279.749504) (xy 164.998054 -279.70045)
			(xy 165.009831 -279.652666) (xy 165.029122 -279.60739) (xy 165.055425 -279.565794) (xy 165.08806 -279.528957)
			(xy 165.126181 -279.497832) (xy 165.168802 -279.473225) (xy 165.214818 -279.455773) (xy 165.263037 -279.445929)
			(xy 165.312212 -279.443948) (xy 165.361067 -279.44988) (xy 165.408338 -279.463572) (xy 165.4528 -279.48467)
			(xy 165.493303 -279.512626) (xy 165.528796 -279.546718) (xy 165.558361 -279.586062) (xy 165.581232 -279.629639)
			(xy 165.596816 -279.67632) (xy 165.604711 -279.724897) (xy 165.605206 -279.749504) (xy 165.605201 -279.749758)
			(xy 165.944054 -279.749758) (xy 165.948014 -279.700704) (xy 165.959791 -279.65292) (xy 165.979082 -279.607644)
			(xy 166.005385 -279.566048) (xy 166.03802 -279.529211) (xy 166.076141 -279.498086) (xy 166.118762 -279.473479)
			(xy 166.164778 -279.456027) (xy 166.212997 -279.446183) (xy 166.262172 -279.444202) (xy 166.311027 -279.450134)
			(xy 166.358298 -279.463826) (xy 166.40276 -279.484924) (xy 166.443263 -279.51288) (xy 166.478756 -279.546972)
			(xy 166.508321 -279.586316) (xy 166.531192 -279.629893) (xy 166.546776 -279.676574) (xy 166.554671 -279.725151)
			(xy 166.555161 -279.749504) (xy 166.894268 -279.749504) (xy 166.898228 -279.70045) (xy 166.910005 -279.652666)
			(xy 166.929296 -279.60739) (xy 166.955599 -279.565794) (xy 166.988234 -279.528957) (xy 167.026355 -279.497832)
			(xy 167.068976 -279.473225) (xy 167.114992 -279.455773) (xy 167.163211 -279.445929) (xy 167.212386 -279.443948)
			(xy 167.261241 -279.44988) (xy 167.308512 -279.463572) (xy 167.352974 -279.48467) (xy 167.393477 -279.512626)
			(xy 167.42897 -279.546718) (xy 167.458535 -279.586062) (xy 167.481406 -279.629639) (xy 167.49699 -279.67632)
			(xy 167.504885 -279.724897) (xy 167.50538 -279.749504) (xy 167.505375 -279.749758) (xy 167.844228 -279.749758)
			(xy 167.848188 -279.700704) (xy 167.859965 -279.65292) (xy 167.879256 -279.607644) (xy 167.905559 -279.566048)
			(xy 167.938194 -279.529211) (xy 167.976315 -279.498086) (xy 168.018936 -279.473479) (xy 168.064952 -279.456027)
			(xy 168.113171 -279.446183) (xy 168.162346 -279.444202) (xy 168.211201 -279.450134) (xy 168.258472 -279.463826)
			(xy 168.302934 -279.484924) (xy 168.343437 -279.51288) (xy 168.37893 -279.546972) (xy 168.408495 -279.586316)
			(xy 168.431366 -279.629893) (xy 168.44695 -279.676574) (xy 168.454845 -279.725151) (xy 168.455335 -279.749504)
			(xy 168.794188 -279.749504) (xy 168.798148 -279.70045) (xy 168.809925 -279.652666) (xy 168.829216 -279.60739)
			(xy 168.855519 -279.565794) (xy 168.888154 -279.528957) (xy 168.926275 -279.497832) (xy 168.968896 -279.473225)
			(xy 169.014912 -279.455773) (xy 169.063131 -279.445929) (xy 169.112306 -279.443948) (xy 169.161161 -279.44988)
			(xy 169.208432 -279.463572) (xy 169.252894 -279.48467) (xy 169.293397 -279.512626) (xy 169.32889 -279.546718)
			(xy 169.358455 -279.586062) (xy 169.381326 -279.629639) (xy 169.39691 -279.67632) (xy 169.404805 -279.724897)
			(xy 169.4053 -279.749504) (xy 169.405295 -279.749758) (xy 169.744148 -279.749758) (xy 169.748108 -279.700704)
			(xy 169.759885 -279.65292) (xy 169.779176 -279.607644) (xy 169.805479 -279.566048) (xy 169.838114 -279.529211)
			(xy 169.876235 -279.498086) (xy 169.918856 -279.473479) (xy 169.964872 -279.456027) (xy 170.013091 -279.446183)
			(xy 170.062266 -279.444202) (xy 170.111121 -279.450134) (xy 170.158392 -279.463826) (xy 170.202854 -279.484924)
			(xy 170.243357 -279.51288) (xy 170.27885 -279.546972) (xy 170.308415 -279.586316) (xy 170.331286 -279.629893)
			(xy 170.34687 -279.676574) (xy 170.354765 -279.725151) (xy 170.355255 -279.749504) (xy 170.694108 -279.749504)
			(xy 170.698068 -279.70045) (xy 170.709845 -279.652666) (xy 170.729136 -279.60739) (xy 170.755439 -279.565794)
			(xy 170.788074 -279.528957) (xy 170.826195 -279.497832) (xy 170.868816 -279.473225) (xy 170.914832 -279.455773)
			(xy 170.963051 -279.445929) (xy 171.012226 -279.443948) (xy 171.061081 -279.44988) (xy 171.108352 -279.463572)
			(xy 171.152814 -279.48467) (xy 171.193317 -279.512626) (xy 171.22881 -279.546718) (xy 171.258375 -279.586062)
			(xy 171.281246 -279.629639) (xy 171.29683 -279.67632) (xy 171.304725 -279.724897) (xy 171.30522 -279.749504)
			(xy 171.305215 -279.749758) (xy 171.644068 -279.749758) (xy 171.648028 -279.700704) (xy 171.659805 -279.65292)
			(xy 171.679096 -279.607644) (xy 171.705399 -279.566048) (xy 171.738034 -279.529211) (xy 171.776155 -279.498086)
			(xy 171.818776 -279.473479) (xy 171.864792 -279.456027) (xy 171.913011 -279.446183) (xy 171.962186 -279.444202)
			(xy 172.011041 -279.450134) (xy 172.058312 -279.463826) (xy 172.102774 -279.484924) (xy 172.143277 -279.51288)
			(xy 172.17877 -279.546972) (xy 172.208335 -279.586316) (xy 172.231206 -279.629893) (xy 172.24679 -279.676574)
			(xy 172.254685 -279.725151) (xy 172.255175 -279.749504) (xy 172.594028 -279.749504) (xy 172.597988 -279.70045)
			(xy 172.609765 -279.652666) (xy 172.629056 -279.60739) (xy 172.655359 -279.565794) (xy 172.687994 -279.528957)
			(xy 172.726115 -279.497832) (xy 172.768736 -279.473225) (xy 172.814752 -279.455773) (xy 172.862971 -279.445929)
			(xy 172.912146 -279.443948) (xy 172.961001 -279.44988) (xy 173.008272 -279.463572) (xy 173.052734 -279.48467)
			(xy 173.093237 -279.512626) (xy 173.12873 -279.546718) (xy 173.158295 -279.586062) (xy 173.181166 -279.629639)
			(xy 173.19675 -279.67632) (xy 173.204645 -279.724897) (xy 173.20514 -279.749504) (xy 173.205135 -279.749758)
			(xy 173.544242 -279.749758) (xy 173.548202 -279.700704) (xy 173.559979 -279.65292) (xy 173.57927 -279.607644)
			(xy 173.605573 -279.566048) (xy 173.638208 -279.529211) (xy 173.676329 -279.498086) (xy 173.71895 -279.473479)
			(xy 173.764966 -279.456027) (xy 173.813185 -279.446183) (xy 173.86236 -279.444202) (xy 173.911215 -279.450134)
			(xy 173.958486 -279.463826) (xy 174.002948 -279.484924) (xy 174.043451 -279.51288) (xy 174.078944 -279.546972)
			(xy 174.108509 -279.586316) (xy 174.13138 -279.629893) (xy 174.146964 -279.676574) (xy 174.154859 -279.725151)
			(xy 174.155349 -279.749504) (xy 174.494202 -279.749504) (xy 174.498162 -279.70045) (xy 174.509939 -279.652666)
			(xy 174.52923 -279.60739) (xy 174.555533 -279.565794) (xy 174.588168 -279.528957) (xy 174.626289 -279.497832)
			(xy 174.66891 -279.473225) (xy 174.714926 -279.455773) (xy 174.763145 -279.445929) (xy 174.81232 -279.443948)
			(xy 174.861175 -279.44988) (xy 174.908446 -279.463572) (xy 174.952908 -279.48467) (xy 174.993411 -279.512626)
			(xy 175.028904 -279.546718) (xy 175.058469 -279.586062) (xy 175.08134 -279.629639) (xy 175.096924 -279.67632)
			(xy 175.104819 -279.724897) (xy 175.105314 -279.749504) (xy 175.105309 -279.749758) (xy 175.444162 -279.749758)
			(xy 175.448122 -279.700704) (xy 175.459899 -279.65292) (xy 175.47919 -279.607644) (xy 175.505493 -279.566048)
			(xy 175.538128 -279.529211) (xy 175.576249 -279.498086) (xy 175.61887 -279.473479) (xy 175.664886 -279.456027)
			(xy 175.713105 -279.446183) (xy 175.76228 -279.444202) (xy 175.811135 -279.450134) (xy 175.858406 -279.463826)
			(xy 175.902868 -279.484924) (xy 175.943371 -279.51288) (xy 175.978864 -279.546972) (xy 176.008429 -279.586316)
			(xy 176.0313 -279.629893) (xy 176.046884 -279.676574) (xy 176.054779 -279.725151) (xy 176.055269 -279.749504)
			(xy 176.394122 -279.749504) (xy 176.398082 -279.70045) (xy 176.409859 -279.652666) (xy 176.42915 -279.60739)
			(xy 176.455453 -279.565794) (xy 176.488088 -279.528957) (xy 176.526209 -279.497832) (xy 176.56883 -279.473225)
			(xy 176.614846 -279.455773) (xy 176.663065 -279.445929) (xy 176.71224 -279.443948) (xy 176.761095 -279.44988)
			(xy 176.808366 -279.463572) (xy 176.852828 -279.48467) (xy 176.893331 -279.512626) (xy 176.928824 -279.546718)
			(xy 176.958389 -279.586062) (xy 176.98126 -279.629639) (xy 176.996844 -279.67632) (xy 177.004739 -279.724897)
			(xy 177.005234 -279.749504) (xy 177.005229 -279.749758) (xy 177.344082 -279.749758) (xy 177.348042 -279.700704)
			(xy 177.359819 -279.65292) (xy 177.37911 -279.607644) (xy 177.405413 -279.566048) (xy 177.438048 -279.529211)
			(xy 177.476169 -279.498086) (xy 177.51879 -279.473479) (xy 177.564806 -279.456027) (xy 177.613025 -279.446183)
			(xy 177.6622 -279.444202) (xy 177.711055 -279.450134) (xy 177.758326 -279.463826) (xy 177.802788 -279.484924)
			(xy 177.843291 -279.51288) (xy 177.878784 -279.546972) (xy 177.908349 -279.586316) (xy 177.93122 -279.629893)
			(xy 177.946804 -279.676574) (xy 177.954699 -279.725151) (xy 177.955189 -279.749504) (xy 178.294042 -279.749504)
			(xy 178.298002 -279.70045) (xy 178.309779 -279.652666) (xy 178.32907 -279.60739) (xy 178.355373 -279.565794)
			(xy 178.388008 -279.528957) (xy 178.426129 -279.497832) (xy 178.46875 -279.473225) (xy 178.514766 -279.455773)
			(xy 178.562985 -279.445929) (xy 178.61216 -279.443948) (xy 178.661015 -279.44988) (xy 178.708286 -279.463572)
			(xy 178.752748 -279.48467) (xy 178.793251 -279.512626) (xy 178.828744 -279.546718) (xy 178.858309 -279.586062)
			(xy 178.88118 -279.629639) (xy 178.896764 -279.67632) (xy 178.904659 -279.724897) (xy 178.905154 -279.749504)
			(xy 178.905149 -279.749758) (xy 179.244256 -279.749758) (xy 179.248216 -279.700704) (xy 179.259993 -279.65292)
			(xy 179.279284 -279.607644) (xy 179.305587 -279.566048) (xy 179.338222 -279.529211) (xy 179.376343 -279.498086)
			(xy 179.418964 -279.473479) (xy 179.46498 -279.456027) (xy 179.513199 -279.446183) (xy 179.562374 -279.444202)
			(xy 179.611229 -279.450134) (xy 179.6585 -279.463826) (xy 179.702962 -279.484924) (xy 179.743465 -279.51288)
			(xy 179.778958 -279.546972) (xy 179.808523 -279.586316) (xy 179.831394 -279.629893) (xy 179.846978 -279.676574)
			(xy 179.854873 -279.725151) (xy 179.855363 -279.749504) (xy 180.194216 -279.749504) (xy 180.198176 -279.70045)
			(xy 180.209953 -279.652666) (xy 180.229244 -279.60739) (xy 180.255547 -279.565794) (xy 180.288182 -279.528957)
			(xy 180.326303 -279.497832) (xy 180.368924 -279.473225) (xy 180.41494 -279.455773) (xy 180.463159 -279.445929)
			(xy 180.512334 -279.443948) (xy 180.561189 -279.44988) (xy 180.60846 -279.463572) (xy 180.652922 -279.48467)
			(xy 180.693425 -279.512626) (xy 180.728918 -279.546718) (xy 180.758483 -279.586062) (xy 180.781354 -279.629639)
			(xy 180.796938 -279.67632) (xy 180.804833 -279.724897) (xy 180.805328 -279.749504) (xy 180.805323 -279.749758)
			(xy 181.144176 -279.749758) (xy 181.148136 -279.700704) (xy 181.159913 -279.65292) (xy 181.179204 -279.607644)
			(xy 181.205507 -279.566048) (xy 181.238142 -279.529211) (xy 181.276263 -279.498086) (xy 181.318884 -279.473479)
			(xy 181.3649 -279.456027) (xy 181.413119 -279.446183) (xy 181.462294 -279.444202) (xy 181.511149 -279.450134)
			(xy 181.55842 -279.463826) (xy 181.602882 -279.484924) (xy 181.643385 -279.51288) (xy 181.678878 -279.546972)
			(xy 181.708443 -279.586316) (xy 181.731314 -279.629893) (xy 181.746898 -279.676574) (xy 181.754793 -279.725151)
			(xy 181.755283 -279.749504) (xy 182.094136 -279.749504) (xy 182.098096 -279.70045) (xy 182.109873 -279.652666)
			(xy 182.129164 -279.60739) (xy 182.155467 -279.565794) (xy 182.188102 -279.528957) (xy 182.226223 -279.497832)
			(xy 182.268844 -279.473225) (xy 182.31486 -279.455773) (xy 182.363079 -279.445929) (xy 182.412254 -279.443948)
			(xy 182.461109 -279.44988) (xy 182.50838 -279.463572) (xy 182.552842 -279.48467) (xy 182.593345 -279.512626)
			(xy 182.628838 -279.546718) (xy 182.658403 -279.586062) (xy 182.681274 -279.629639) (xy 182.696858 -279.67632)
			(xy 182.704753 -279.724897) (xy 182.705248 -279.749504) (xy 182.705243 -279.749758) (xy 183.044096 -279.749758)
			(xy 183.048056 -279.700704) (xy 183.059833 -279.65292) (xy 183.079124 -279.607644) (xy 183.105427 -279.566048)
			(xy 183.138062 -279.529211) (xy 183.176183 -279.498086) (xy 183.218804 -279.473479) (xy 183.26482 -279.456027)
			(xy 183.313039 -279.446183) (xy 183.362214 -279.444202) (xy 183.411069 -279.450134) (xy 183.45834 -279.463826)
			(xy 183.502802 -279.484924) (xy 183.543305 -279.51288) (xy 183.578798 -279.546972) (xy 183.608363 -279.586316)
			(xy 183.631234 -279.629893) (xy 183.646818 -279.676574) (xy 183.654713 -279.725151) (xy 183.655203 -279.749504)
			(xy 183.994056 -279.749504) (xy 183.998016 -279.70045) (xy 184.009793 -279.652666) (xy 184.029084 -279.60739)
			(xy 184.055387 -279.565794) (xy 184.088022 -279.528957) (xy 184.126143 -279.497832) (xy 184.168764 -279.473225)
			(xy 184.21478 -279.455773) (xy 184.262999 -279.445929) (xy 184.312174 -279.443948) (xy 184.361029 -279.44988)
			(xy 184.4083 -279.463572) (xy 184.452762 -279.48467) (xy 184.493265 -279.512626) (xy 184.528758 -279.546718)
			(xy 184.558323 -279.586062) (xy 184.581194 -279.629639) (xy 184.596778 -279.67632) (xy 184.604673 -279.724897)
			(xy 184.605168 -279.749504) (xy 184.604673 -279.774111) (xy 184.596778 -279.822688) (xy 184.581194 -279.869369)
			(xy 184.558323 -279.912946) (xy 184.528758 -279.95229) (xy 184.493265 -279.986382) (xy 184.452762 -280.014338)
			(xy 184.4083 -280.035436) (xy 184.361029 -280.049128) (xy 184.312174 -280.05506) (xy 184.262999 -280.053079)
			(xy 184.21478 -280.043235) (xy 184.168764 -280.025783) (xy 184.126143 -280.001176) (xy 184.088022 -279.970051)
			(xy 184.055387 -279.933214) (xy 184.029084 -279.891618) (xy 184.009793 -279.846342) (xy 183.998016 -279.798558)
			(xy 183.994056 -279.749504) (xy 183.655203 -279.749504) (xy 183.655208 -279.749758) (xy 183.654713 -279.774365)
			(xy 183.646818 -279.822942) (xy 183.631234 -279.869623) (xy 183.608363 -279.9132) (xy 183.578798 -279.952544)
			(xy 183.543305 -279.986636) (xy 183.502802 -280.014592) (xy 183.45834 -280.03569) (xy 183.411069 -280.049382)
			(xy 183.362214 -280.055314) (xy 183.313039 -280.053333) (xy 183.26482 -280.043489) (xy 183.218804 -280.026037)
			(xy 183.176183 -280.00143) (xy 183.138062 -279.970305) (xy 183.105427 -279.933468) (xy 183.079124 -279.891872)
			(xy 183.059833 -279.846596) (xy 183.048056 -279.798812) (xy 183.044096 -279.749758) (xy 182.705243 -279.749758)
			(xy 182.704753 -279.774111) (xy 182.696858 -279.822688) (xy 182.681274 -279.869369) (xy 182.658403 -279.912946)
			(xy 182.628838 -279.95229) (xy 182.593345 -279.986382) (xy 182.552842 -280.014338) (xy 182.50838 -280.035436)
			(xy 182.461109 -280.049128) (xy 182.412254 -280.05506) (xy 182.363079 -280.053079) (xy 182.31486 -280.043235)
			(xy 182.268844 -280.025783) (xy 182.226223 -280.001176) (xy 182.188102 -279.970051) (xy 182.155467 -279.933214)
			(xy 182.129164 -279.891618) (xy 182.109873 -279.846342) (xy 182.098096 -279.798558) (xy 182.094136 -279.749504)
			(xy 181.755283 -279.749504) (xy 181.755288 -279.749758) (xy 181.754793 -279.774365) (xy 181.746898 -279.822942)
			(xy 181.731314 -279.869623) (xy 181.708443 -279.9132) (xy 181.678878 -279.952544) (xy 181.643385 -279.986636)
			(xy 181.602882 -280.014592) (xy 181.55842 -280.03569) (xy 181.511149 -280.049382) (xy 181.462294 -280.055314)
			(xy 181.413119 -280.053333) (xy 181.3649 -280.043489) (xy 181.318884 -280.026037) (xy 181.276263 -280.00143)
			(xy 181.238142 -279.970305) (xy 181.205507 -279.933468) (xy 181.179204 -279.891872) (xy 181.159913 -279.846596)
			(xy 181.148136 -279.798812) (xy 181.144176 -279.749758) (xy 180.805323 -279.749758) (xy 180.804833 -279.774111)
			(xy 180.796938 -279.822688) (xy 180.781354 -279.869369) (xy 180.758483 -279.912946) (xy 180.728918 -279.95229)
			(xy 180.693425 -279.986382) (xy 180.652922 -280.014338) (xy 180.60846 -280.035436) (xy 180.561189 -280.049128)
			(xy 180.512334 -280.05506) (xy 180.463159 -280.053079) (xy 180.41494 -280.043235) (xy 180.368924 -280.025783)
			(xy 180.326303 -280.001176) (xy 180.288182 -279.970051) (xy 180.255547 -279.933214) (xy 180.229244 -279.891618)
			(xy 180.209953 -279.846342) (xy 180.198176 -279.798558) (xy 180.194216 -279.749504) (xy 179.855363 -279.749504)
			(xy 179.855368 -279.749758) (xy 179.854873 -279.774365) (xy 179.846978 -279.822942) (xy 179.831394 -279.869623)
			(xy 179.808523 -279.9132) (xy 179.778958 -279.952544) (xy 179.743465 -279.986636) (xy 179.702962 -280.014592)
			(xy 179.6585 -280.03569) (xy 179.611229 -280.049382) (xy 179.562374 -280.055314) (xy 179.513199 -280.053333)
			(xy 179.46498 -280.043489) (xy 179.418964 -280.026037) (xy 179.376343 -280.00143) (xy 179.338222 -279.970305)
			(xy 179.305587 -279.933468) (xy 179.279284 -279.891872) (xy 179.259993 -279.846596) (xy 179.248216 -279.798812)
			(xy 179.244256 -279.749758) (xy 178.905149 -279.749758) (xy 178.904659 -279.774111) (xy 178.896764 -279.822688)
			(xy 178.88118 -279.869369) (xy 178.858309 -279.912946) (xy 178.828744 -279.95229) (xy 178.793251 -279.986382)
			(xy 178.752748 -280.014338) (xy 178.708286 -280.035436) (xy 178.661015 -280.049128) (xy 178.61216 -280.05506)
			(xy 178.562985 -280.053079) (xy 178.514766 -280.043235) (xy 178.46875 -280.025783) (xy 178.426129 -280.001176)
			(xy 178.388008 -279.970051) (xy 178.355373 -279.933214) (xy 178.32907 -279.891618) (xy 178.309779 -279.846342)
			(xy 178.298002 -279.798558) (xy 178.294042 -279.749504) (xy 177.955189 -279.749504) (xy 177.955194 -279.749758)
			(xy 177.954699 -279.774365) (xy 177.946804 -279.822942) (xy 177.93122 -279.869623) (xy 177.908349 -279.9132)
			(xy 177.878784 -279.952544) (xy 177.843291 -279.986636) (xy 177.802788 -280.014592) (xy 177.758326 -280.03569)
			(xy 177.711055 -280.049382) (xy 177.6622 -280.055314) (xy 177.613025 -280.053333) (xy 177.564806 -280.043489)
			(xy 177.51879 -280.026037) (xy 177.476169 -280.00143) (xy 177.438048 -279.970305) (xy 177.405413 -279.933468)
			(xy 177.37911 -279.891872) (xy 177.359819 -279.846596) (xy 177.348042 -279.798812) (xy 177.344082 -279.749758)
			(xy 177.005229 -279.749758) (xy 177.004739 -279.774111) (xy 176.996844 -279.822688) (xy 176.98126 -279.869369)
			(xy 176.958389 -279.912946) (xy 176.928824 -279.95229) (xy 176.893331 -279.986382) (xy 176.852828 -280.014338)
			(xy 176.808366 -280.035436) (xy 176.761095 -280.049128) (xy 176.71224 -280.05506) (xy 176.663065 -280.053079)
			(xy 176.614846 -280.043235) (xy 176.56883 -280.025783) (xy 176.526209 -280.001176) (xy 176.488088 -279.970051)
			(xy 176.455453 -279.933214) (xy 176.42915 -279.891618) (xy 176.409859 -279.846342) (xy 176.398082 -279.798558)
			(xy 176.394122 -279.749504) (xy 176.055269 -279.749504) (xy 176.055274 -279.749758) (xy 176.054779 -279.774365)
			(xy 176.046884 -279.822942) (xy 176.0313 -279.869623) (xy 176.008429 -279.9132) (xy 175.978864 -279.952544)
			(xy 175.943371 -279.986636) (xy 175.902868 -280.014592) (xy 175.858406 -280.03569) (xy 175.811135 -280.049382)
			(xy 175.76228 -280.055314) (xy 175.713105 -280.053333) (xy 175.664886 -280.043489) (xy 175.61887 -280.026037)
			(xy 175.576249 -280.00143) (xy 175.538128 -279.970305) (xy 175.505493 -279.933468) (xy 175.47919 -279.891872)
			(xy 175.459899 -279.846596) (xy 175.448122 -279.798812) (xy 175.444162 -279.749758) (xy 175.105309 -279.749758)
			(xy 175.104819 -279.774111) (xy 175.096924 -279.822688) (xy 175.08134 -279.869369) (xy 175.058469 -279.912946)
			(xy 175.028904 -279.95229) (xy 174.993411 -279.986382) (xy 174.952908 -280.014338) (xy 174.908446 -280.035436)
			(xy 174.861175 -280.049128) (xy 174.81232 -280.05506) (xy 174.763145 -280.053079) (xy 174.714926 -280.043235)
			(xy 174.66891 -280.025783) (xy 174.626289 -280.001176) (xy 174.588168 -279.970051) (xy 174.555533 -279.933214)
			(xy 174.52923 -279.891618) (xy 174.509939 -279.846342) (xy 174.498162 -279.798558) (xy 174.494202 -279.749504)
			(xy 174.155349 -279.749504) (xy 174.155354 -279.749758) (xy 174.154859 -279.774365) (xy 174.146964 -279.822942)
			(xy 174.13138 -279.869623) (xy 174.108509 -279.9132) (xy 174.078944 -279.952544) (xy 174.043451 -279.986636)
			(xy 174.002948 -280.014592) (xy 173.958486 -280.03569) (xy 173.911215 -280.049382) (xy 173.86236 -280.055314)
			(xy 173.813185 -280.053333) (xy 173.764966 -280.043489) (xy 173.71895 -280.026037) (xy 173.676329 -280.00143)
			(xy 173.638208 -279.970305) (xy 173.605573 -279.933468) (xy 173.57927 -279.891872) (xy 173.559979 -279.846596)
			(xy 173.548202 -279.798812) (xy 173.544242 -279.749758) (xy 173.205135 -279.749758) (xy 173.204645 -279.774111)
			(xy 173.19675 -279.822688) (xy 173.181166 -279.869369) (xy 173.158295 -279.912946) (xy 173.12873 -279.95229)
			(xy 173.093237 -279.986382) (xy 173.052734 -280.014338) (xy 173.008272 -280.035436) (xy 172.961001 -280.049128)
			(xy 172.912146 -280.05506) (xy 172.862971 -280.053079) (xy 172.814752 -280.043235) (xy 172.768736 -280.025783)
			(xy 172.726115 -280.001176) (xy 172.687994 -279.970051) (xy 172.655359 -279.933214) (xy 172.629056 -279.891618)
			(xy 172.609765 -279.846342) (xy 172.597988 -279.798558) (xy 172.594028 -279.749504) (xy 172.255175 -279.749504)
			(xy 172.25518 -279.749758) (xy 172.254685 -279.774365) (xy 172.24679 -279.822942) (xy 172.231206 -279.869623)
			(xy 172.208335 -279.9132) (xy 172.17877 -279.952544) (xy 172.143277 -279.986636) (xy 172.102774 -280.014592)
			(xy 172.058312 -280.03569) (xy 172.011041 -280.049382) (xy 171.962186 -280.055314) (xy 171.913011 -280.053333)
			(xy 171.864792 -280.043489) (xy 171.818776 -280.026037) (xy 171.776155 -280.00143) (xy 171.738034 -279.970305)
			(xy 171.705399 -279.933468) (xy 171.679096 -279.891872) (xy 171.659805 -279.846596) (xy 171.648028 -279.798812)
			(xy 171.644068 -279.749758) (xy 171.305215 -279.749758) (xy 171.304725 -279.774111) (xy 171.29683 -279.822688)
			(xy 171.281246 -279.869369) (xy 171.258375 -279.912946) (xy 171.22881 -279.95229) (xy 171.193317 -279.986382)
			(xy 171.152814 -280.014338) (xy 171.108352 -280.035436) (xy 171.061081 -280.049128) (xy 171.012226 -280.05506)
			(xy 170.963051 -280.053079) (xy 170.914832 -280.043235) (xy 170.868816 -280.025783) (xy 170.826195 -280.001176)
			(xy 170.788074 -279.970051) (xy 170.755439 -279.933214) (xy 170.729136 -279.891618) (xy 170.709845 -279.846342)
			(xy 170.698068 -279.798558) (xy 170.694108 -279.749504) (xy 170.355255 -279.749504) (xy 170.35526 -279.749758)
			(xy 170.354765 -279.774365) (xy 170.34687 -279.822942) (xy 170.331286 -279.869623) (xy 170.308415 -279.9132)
			(xy 170.27885 -279.952544) (xy 170.243357 -279.986636) (xy 170.202854 -280.014592) (xy 170.158392 -280.03569)
			(xy 170.111121 -280.049382) (xy 170.062266 -280.055314) (xy 170.013091 -280.053333) (xy 169.964872 -280.043489)
			(xy 169.918856 -280.026037) (xy 169.876235 -280.00143) (xy 169.838114 -279.970305) (xy 169.805479 -279.933468)
			(xy 169.779176 -279.891872) (xy 169.759885 -279.846596) (xy 169.748108 -279.798812) (xy 169.744148 -279.749758)
			(xy 169.405295 -279.749758) (xy 169.404805 -279.774111) (xy 169.39691 -279.822688) (xy 169.381326 -279.869369)
			(xy 169.358455 -279.912946) (xy 169.32889 -279.95229) (xy 169.293397 -279.986382) (xy 169.252894 -280.014338)
			(xy 169.208432 -280.035436) (xy 169.161161 -280.049128) (xy 169.112306 -280.05506) (xy 169.063131 -280.053079)
			(xy 169.014912 -280.043235) (xy 168.968896 -280.025783) (xy 168.926275 -280.001176) (xy 168.888154 -279.970051)
			(xy 168.855519 -279.933214) (xy 168.829216 -279.891618) (xy 168.809925 -279.846342) (xy 168.798148 -279.798558)
			(xy 168.794188 -279.749504) (xy 168.455335 -279.749504) (xy 168.45534 -279.749758) (xy 168.454845 -279.774365)
			(xy 168.44695 -279.822942) (xy 168.431366 -279.869623) (xy 168.408495 -279.9132) (xy 168.37893 -279.952544)
			(xy 168.343437 -279.986636) (xy 168.302934 -280.014592) (xy 168.258472 -280.03569) (xy 168.211201 -280.049382)
			(xy 168.162346 -280.055314) (xy 168.113171 -280.053333) (xy 168.064952 -280.043489) (xy 168.018936 -280.026037)
			(xy 167.976315 -280.00143) (xy 167.938194 -279.970305) (xy 167.905559 -279.933468) (xy 167.879256 -279.891872)
			(xy 167.859965 -279.846596) (xy 167.848188 -279.798812) (xy 167.844228 -279.749758) (xy 167.505375 -279.749758)
			(xy 167.504885 -279.774111) (xy 167.49699 -279.822688) (xy 167.481406 -279.869369) (xy 167.458535 -279.912946)
			(xy 167.42897 -279.95229) (xy 167.393477 -279.986382) (xy 167.352974 -280.014338) (xy 167.308512 -280.035436)
			(xy 167.261241 -280.049128) (xy 167.212386 -280.05506) (xy 167.163211 -280.053079) (xy 167.114992 -280.043235)
			(xy 167.068976 -280.025783) (xy 167.026355 -280.001176) (xy 166.988234 -279.970051) (xy 166.955599 -279.933214)
			(xy 166.929296 -279.891618) (xy 166.910005 -279.846342) (xy 166.898228 -279.798558) (xy 166.894268 -279.749504)
			(xy 166.555161 -279.749504) (xy 166.555166 -279.749758) (xy 166.554671 -279.774365) (xy 166.546776 -279.822942)
			(xy 166.531192 -279.869623) (xy 166.508321 -279.9132) (xy 166.478756 -279.952544) (xy 166.443263 -279.986636)
			(xy 166.40276 -280.014592) (xy 166.358298 -280.03569) (xy 166.311027 -280.049382) (xy 166.262172 -280.055314)
			(xy 166.212997 -280.053333) (xy 166.164778 -280.043489) (xy 166.118762 -280.026037) (xy 166.076141 -280.00143)
			(xy 166.03802 -279.970305) (xy 166.005385 -279.933468) (xy 165.979082 -279.891872) (xy 165.959791 -279.846596)
			(xy 165.948014 -279.798812) (xy 165.944054 -279.749758) (xy 165.605201 -279.749758) (xy 165.604711 -279.774111)
			(xy 165.596816 -279.822688) (xy 165.581232 -279.869369) (xy 165.558361 -279.912946) (xy 165.528796 -279.95229)
			(xy 165.493303 -279.986382) (xy 165.4528 -280.014338) (xy 165.408338 -280.035436) (xy 165.361067 -280.049128)
			(xy 165.312212 -280.05506) (xy 165.263037 -280.053079) (xy 165.214818 -280.043235) (xy 165.168802 -280.025783)
			(xy 165.126181 -280.001176) (xy 165.08806 -279.970051) (xy 165.055425 -279.933214) (xy 165.029122 -279.891618)
			(xy 165.009831 -279.846342) (xy 164.998054 -279.798558) (xy 164.994094 -279.749504) (xy 164.655241 -279.749504)
			(xy 164.655246 -279.749758) (xy 164.654751 -279.774365) (xy 164.646856 -279.822942) (xy 164.631272 -279.869623)
			(xy 164.608401 -279.9132) (xy 164.578836 -279.952544) (xy 164.543343 -279.986636) (xy 164.50284 -280.014592)
			(xy 164.458378 -280.03569) (xy 164.411107 -280.049382) (xy 164.362252 -280.055314) (xy 164.313077 -280.053333)
			(xy 164.264858 -280.043489) (xy 164.218842 -280.026037) (xy 164.176221 -280.00143) (xy 164.1381 -279.970305)
			(xy 164.105465 -279.933468) (xy 164.079162 -279.891872) (xy 164.059871 -279.846596) (xy 164.048094 -279.798812)
			(xy 164.044134 -279.749758) (xy 163.705281 -279.749758) (xy 163.704791 -279.774111) (xy 163.696896 -279.822688)
			(xy 163.681312 -279.869369) (xy 163.658441 -279.912946) (xy 163.628876 -279.95229) (xy 163.593383 -279.986382)
			(xy 163.55288 -280.014338) (xy 163.508418 -280.035436) (xy 163.461147 -280.049128) (xy 163.412292 -280.05506)
			(xy 163.363117 -280.053079) (xy 163.314898 -280.043235) (xy 163.268882 -280.025783) (xy 163.226261 -280.001176)
			(xy 163.18814 -279.970051) (xy 163.155505 -279.933214) (xy 163.129202 -279.891618) (xy 163.109911 -279.846342)
			(xy 163.098134 -279.798558) (xy 163.094174 -279.749504) (xy 162.755321 -279.749504) (xy 162.755326 -279.749758)
			(xy 162.754831 -279.774365) (xy 162.746936 -279.822942) (xy 162.731352 -279.869623) (xy 162.708481 -279.9132)
			(xy 162.678916 -279.952544) (xy 162.643423 -279.986636) (xy 162.60292 -280.014592) (xy 162.558458 -280.03569)
			(xy 162.511187 -280.049382) (xy 162.462332 -280.055314) (xy 162.413157 -280.053333) (xy 162.364938 -280.043489)
			(xy 162.318922 -280.026037) (xy 162.276301 -280.00143) (xy 162.23818 -279.970305) (xy 162.205545 -279.933468)
			(xy 162.179242 -279.891872) (xy 162.159951 -279.846596) (xy 162.148174 -279.798812) (xy 162.144214 -279.749758)
			(xy 161.805361 -279.749758) (xy 161.804871 -279.774111) (xy 161.796976 -279.822688) (xy 161.781392 -279.869369)
			(xy 161.758521 -279.912946) (xy 161.728956 -279.95229) (xy 161.693463 -279.986382) (xy 161.65296 -280.014338)
			(xy 161.608498 -280.035436) (xy 161.561227 -280.049128) (xy 161.512372 -280.05506) (xy 161.463197 -280.053079)
			(xy 161.414978 -280.043235) (xy 161.368962 -280.025783) (xy 161.326341 -280.001176) (xy 161.28822 -279.970051)
			(xy 161.255585 -279.933214) (xy 161.229282 -279.891618) (xy 161.209991 -279.846342) (xy 161.198214 -279.798558)
			(xy 161.194254 -279.749504) (xy 160.855564 -279.749504) (xy 160.855589 -279.7498) (xy 160.851419 -279.800127)
			(xy 160.839024 -279.849081) (xy 160.81874 -279.895327) (xy 160.791122 -279.937605) (xy 160.756922 -279.974761)
			(xy 160.717074 -280.005781) (xy 160.672664 -280.02982) (xy 160.624903 -280.046223) (xy 160.575093 -280.054541)
			(xy 160.549844 -280.055066) (xy 160.535661 -280.054884) (xy 160.507421 -280.052216) (xy 160.493456 -280.049732)
			(xy 160.48101 -280.047446) (xy 160.457388 -280.054812) (xy 160.379918 -280.132282) (xy 160.372552 -280.155904)
			(xy 160.374838 -280.16835) (xy 160.377317 -280.182316) (xy 160.379987 -280.210555) (xy 160.380172 -280.224738)
			(xy 160.380001 -280.238921) (xy 160.377325 -280.267161) (xy 160.374838 -280.281126) (xy 160.372552 -280.293572)
			(xy 160.379918 -280.317194) (xy 160.457388 -280.394664) (xy 160.48101 -280.40203) (xy 160.493456 -280.399744)
			(xy 160.507421 -280.397264) (xy 160.535661 -280.394595) (xy 160.549844 -280.39441) (xy 160.57466 -280.394925)
			(xy 160.623638 -280.402962) (xy 160.67067 -280.418815) (xy 160.714518 -280.442069) (xy 160.754026 -280.47211)
			(xy 160.788155 -280.508147) (xy 160.816004 -280.54923) (xy 160.836839 -280.594277) (xy 160.850113 -280.642101)
			(xy 160.855476 -280.691443) (xy 160.855027 -280.699718) (xy 161.194254 -280.699718) (xy 161.198214 -280.650664)
			(xy 161.209991 -280.60288) (xy 161.229282 -280.557604) (xy 161.255585 -280.516008) (xy 161.28822 -280.479171)
			(xy 161.326341 -280.448046) (xy 161.368962 -280.423439) (xy 161.414978 -280.405987) (xy 161.463197 -280.396143)
			(xy 161.512372 -280.394162) (xy 161.561227 -280.400094) (xy 161.608498 -280.413786) (xy 161.65296 -280.434884)
			(xy 161.693463 -280.46284) (xy 161.728956 -280.496932) (xy 161.758521 -280.536276) (xy 161.781392 -280.579853)
			(xy 161.796976 -280.626534) (xy 161.804871 -280.675111) (xy 161.805366 -280.699718) (xy 162.144214 -280.699718)
			(xy 162.148174 -280.650664) (xy 162.159951 -280.60288) (xy 162.179242 -280.557604) (xy 162.205545 -280.516008)
			(xy 162.23818 -280.479171) (xy 162.276301 -280.448046) (xy 162.318922 -280.423439) (xy 162.364938 -280.405987)
			(xy 162.413157 -280.396143) (xy 162.462332 -280.394162) (xy 162.511187 -280.400094) (xy 162.558458 -280.413786)
			(xy 162.60292 -280.434884) (xy 162.643423 -280.46284) (xy 162.678916 -280.496932) (xy 162.708481 -280.536276)
			(xy 162.731352 -280.579853) (xy 162.746936 -280.626534) (xy 162.754831 -280.675111) (xy 162.755326 -280.699718)
			(xy 163.094174 -280.699718) (xy 163.098134 -280.650664) (xy 163.109911 -280.60288) (xy 163.129202 -280.557604)
			(xy 163.155505 -280.516008) (xy 163.18814 -280.479171) (xy 163.226261 -280.448046) (xy 163.268882 -280.423439)
			(xy 163.314898 -280.405987) (xy 163.363117 -280.396143) (xy 163.412292 -280.394162) (xy 163.461147 -280.400094)
			(xy 163.508418 -280.413786) (xy 163.55288 -280.434884) (xy 163.593383 -280.46284) (xy 163.628876 -280.496932)
			(xy 163.658441 -280.536276) (xy 163.681312 -280.579853) (xy 163.696896 -280.626534) (xy 163.704791 -280.675111)
			(xy 163.705286 -280.699718) (xy 164.044134 -280.699718) (xy 164.048094 -280.650664) (xy 164.059871 -280.60288)
			(xy 164.079162 -280.557604) (xy 164.105465 -280.516008) (xy 164.1381 -280.479171) (xy 164.176221 -280.448046)
			(xy 164.218842 -280.423439) (xy 164.264858 -280.405987) (xy 164.313077 -280.396143) (xy 164.362252 -280.394162)
			(xy 164.411107 -280.400094) (xy 164.458378 -280.413786) (xy 164.50284 -280.434884) (xy 164.543343 -280.46284)
			(xy 164.578836 -280.496932) (xy 164.608401 -280.536276) (xy 164.631272 -280.579853) (xy 164.646856 -280.626534)
			(xy 164.654751 -280.675111) (xy 164.655246 -280.699718) (xy 164.994094 -280.699718) (xy 164.998054 -280.650664)
			(xy 165.009831 -280.60288) (xy 165.029122 -280.557604) (xy 165.055425 -280.516008) (xy 165.08806 -280.479171)
			(xy 165.126181 -280.448046) (xy 165.168802 -280.423439) (xy 165.214818 -280.405987) (xy 165.263037 -280.396143)
			(xy 165.312212 -280.394162) (xy 165.361067 -280.400094) (xy 165.408338 -280.413786) (xy 165.4528 -280.434884)
			(xy 165.493303 -280.46284) (xy 165.528796 -280.496932) (xy 165.558361 -280.536276) (xy 165.581232 -280.579853)
			(xy 165.596816 -280.626534) (xy 165.604711 -280.675111) (xy 165.605206 -280.699718) (xy 165.944054 -280.699718)
			(xy 165.948014 -280.650664) (xy 165.959791 -280.60288) (xy 165.979082 -280.557604) (xy 166.005385 -280.516008)
			(xy 166.03802 -280.479171) (xy 166.076141 -280.448046) (xy 166.118762 -280.423439) (xy 166.164778 -280.405987)
			(xy 166.212997 -280.396143) (xy 166.262172 -280.394162) (xy 166.311027 -280.400094) (xy 166.358298 -280.413786)
			(xy 166.40276 -280.434884) (xy 166.443263 -280.46284) (xy 166.478756 -280.496932) (xy 166.508321 -280.536276)
			(xy 166.531192 -280.579853) (xy 166.546776 -280.626534) (xy 166.554671 -280.675111) (xy 166.555166 -280.699718)
			(xy 166.894268 -280.699718) (xy 166.898228 -280.650664) (xy 166.910005 -280.60288) (xy 166.929296 -280.557604)
			(xy 166.955599 -280.516008) (xy 166.988234 -280.479171) (xy 167.026355 -280.448046) (xy 167.068976 -280.423439)
			(xy 167.114992 -280.405987) (xy 167.163211 -280.396143) (xy 167.212386 -280.394162) (xy 167.261241 -280.400094)
			(xy 167.308512 -280.413786) (xy 167.352974 -280.434884) (xy 167.393477 -280.46284) (xy 167.42897 -280.496932)
			(xy 167.458535 -280.536276) (xy 167.481406 -280.579853) (xy 167.49699 -280.626534) (xy 167.504885 -280.675111)
			(xy 167.50538 -280.699718) (xy 167.844228 -280.699718) (xy 167.848188 -280.650664) (xy 167.859965 -280.60288)
			(xy 167.879256 -280.557604) (xy 167.905559 -280.516008) (xy 167.938194 -280.479171) (xy 167.976315 -280.448046)
			(xy 168.018936 -280.423439) (xy 168.064952 -280.405987) (xy 168.113171 -280.396143) (xy 168.162346 -280.394162)
			(xy 168.211201 -280.400094) (xy 168.258472 -280.413786) (xy 168.302934 -280.434884) (xy 168.343437 -280.46284)
			(xy 168.37893 -280.496932) (xy 168.408495 -280.536276) (xy 168.431366 -280.579853) (xy 168.44695 -280.626534)
			(xy 168.454845 -280.675111) (xy 168.45534 -280.699718) (xy 168.794188 -280.699718) (xy 168.798148 -280.650664)
			(xy 168.809925 -280.60288) (xy 168.829216 -280.557604) (xy 168.855519 -280.516008) (xy 168.888154 -280.479171)
			(xy 168.926275 -280.448046) (xy 168.968896 -280.423439) (xy 169.014912 -280.405987) (xy 169.063131 -280.396143)
			(xy 169.112306 -280.394162) (xy 169.161161 -280.400094) (xy 169.208432 -280.413786) (xy 169.252894 -280.434884)
			(xy 169.293397 -280.46284) (xy 169.32889 -280.496932) (xy 169.358455 -280.536276) (xy 169.381326 -280.579853)
			(xy 169.39691 -280.626534) (xy 169.404805 -280.675111) (xy 169.4053 -280.699718) (xy 169.744148 -280.699718)
			(xy 169.748108 -280.650664) (xy 169.759885 -280.60288) (xy 169.779176 -280.557604) (xy 169.805479 -280.516008)
			(xy 169.838114 -280.479171) (xy 169.876235 -280.448046) (xy 169.918856 -280.423439) (xy 169.964872 -280.405987)
			(xy 170.013091 -280.396143) (xy 170.062266 -280.394162) (xy 170.111121 -280.400094) (xy 170.158392 -280.413786)
			(xy 170.202854 -280.434884) (xy 170.243357 -280.46284) (xy 170.27885 -280.496932) (xy 170.308415 -280.536276)
			(xy 170.331286 -280.579853) (xy 170.34687 -280.626534) (xy 170.354765 -280.675111) (xy 170.35526 -280.699718)
			(xy 170.694108 -280.699718) (xy 170.698068 -280.650664) (xy 170.709845 -280.60288) (xy 170.729136 -280.557604)
			(xy 170.755439 -280.516008) (xy 170.788074 -280.479171) (xy 170.826195 -280.448046) (xy 170.868816 -280.423439)
			(xy 170.914832 -280.405987) (xy 170.963051 -280.396143) (xy 171.012226 -280.394162) (xy 171.061081 -280.400094)
			(xy 171.108352 -280.413786) (xy 171.152814 -280.434884) (xy 171.193317 -280.46284) (xy 171.22881 -280.496932)
			(xy 171.258375 -280.536276) (xy 171.281246 -280.579853) (xy 171.29683 -280.626534) (xy 171.304725 -280.675111)
			(xy 171.30522 -280.699718) (xy 171.644068 -280.699718) (xy 171.648028 -280.650664) (xy 171.659805 -280.60288)
			(xy 171.679096 -280.557604) (xy 171.705399 -280.516008) (xy 171.738034 -280.479171) (xy 171.776155 -280.448046)
			(xy 171.818776 -280.423439) (xy 171.864792 -280.405987) (xy 171.913011 -280.396143) (xy 171.962186 -280.394162)
			(xy 172.011041 -280.400094) (xy 172.058312 -280.413786) (xy 172.102774 -280.434884) (xy 172.143277 -280.46284)
			(xy 172.17877 -280.496932) (xy 172.208335 -280.536276) (xy 172.231206 -280.579853) (xy 172.24679 -280.626534)
			(xy 172.254685 -280.675111) (xy 172.25518 -280.699718) (xy 172.594028 -280.699718) (xy 172.597988 -280.650664)
			(xy 172.609765 -280.60288) (xy 172.629056 -280.557604) (xy 172.655359 -280.516008) (xy 172.687994 -280.479171)
			(xy 172.726115 -280.448046) (xy 172.768736 -280.423439) (xy 172.814752 -280.405987) (xy 172.862971 -280.396143)
			(xy 172.912146 -280.394162) (xy 172.961001 -280.400094) (xy 173.008272 -280.413786) (xy 173.052734 -280.434884)
			(xy 173.093237 -280.46284) (xy 173.12873 -280.496932) (xy 173.158295 -280.536276) (xy 173.181166 -280.579853)
			(xy 173.19675 -280.626534) (xy 173.204645 -280.675111) (xy 173.20514 -280.699718) (xy 173.544242 -280.699718)
			(xy 173.548202 -280.650664) (xy 173.559979 -280.60288) (xy 173.57927 -280.557604) (xy 173.605573 -280.516008)
			(xy 173.638208 -280.479171) (xy 173.676329 -280.448046) (xy 173.71895 -280.423439) (xy 173.764966 -280.405987)
			(xy 173.813185 -280.396143) (xy 173.86236 -280.394162) (xy 173.911215 -280.400094) (xy 173.958486 -280.413786)
			(xy 174.002948 -280.434884) (xy 174.043451 -280.46284) (xy 174.078944 -280.496932) (xy 174.108509 -280.536276)
			(xy 174.13138 -280.579853) (xy 174.146964 -280.626534) (xy 174.154859 -280.675111) (xy 174.155354 -280.699718)
			(xy 174.494202 -280.699718) (xy 174.498162 -280.650664) (xy 174.509939 -280.60288) (xy 174.52923 -280.557604)
			(xy 174.555533 -280.516008) (xy 174.588168 -280.479171) (xy 174.626289 -280.448046) (xy 174.66891 -280.423439)
			(xy 174.714926 -280.405987) (xy 174.763145 -280.396143) (xy 174.81232 -280.394162) (xy 174.861175 -280.400094)
			(xy 174.908446 -280.413786) (xy 174.952908 -280.434884) (xy 174.993411 -280.46284) (xy 175.028904 -280.496932)
			(xy 175.058469 -280.536276) (xy 175.08134 -280.579853) (xy 175.096924 -280.626534) (xy 175.104819 -280.675111)
			(xy 175.105314 -280.699718) (xy 175.444162 -280.699718) (xy 175.448122 -280.650664) (xy 175.459899 -280.60288)
			(xy 175.47919 -280.557604) (xy 175.505493 -280.516008) (xy 175.538128 -280.479171) (xy 175.576249 -280.448046)
			(xy 175.61887 -280.423439) (xy 175.664886 -280.405987) (xy 175.713105 -280.396143) (xy 175.76228 -280.394162)
			(xy 175.811135 -280.400094) (xy 175.858406 -280.413786) (xy 175.902868 -280.434884) (xy 175.943371 -280.46284)
			(xy 175.978864 -280.496932) (xy 176.008429 -280.536276) (xy 176.0313 -280.579853) (xy 176.046884 -280.626534)
			(xy 176.054779 -280.675111) (xy 176.055274 -280.699718) (xy 176.394122 -280.699718) (xy 176.398082 -280.650664)
			(xy 176.409859 -280.60288) (xy 176.42915 -280.557604) (xy 176.455453 -280.516008) (xy 176.488088 -280.479171)
			(xy 176.526209 -280.448046) (xy 176.56883 -280.423439) (xy 176.614846 -280.405987) (xy 176.663065 -280.396143)
			(xy 176.71224 -280.394162) (xy 176.761095 -280.400094) (xy 176.808366 -280.413786) (xy 176.852828 -280.434884)
			(xy 176.893331 -280.46284) (xy 176.928824 -280.496932) (xy 176.958389 -280.536276) (xy 176.98126 -280.579853)
			(xy 176.996844 -280.626534) (xy 177.004739 -280.675111) (xy 177.005234 -280.699718) (xy 177.344082 -280.699718)
			(xy 177.348042 -280.650664) (xy 177.359819 -280.60288) (xy 177.37911 -280.557604) (xy 177.405413 -280.516008)
			(xy 177.438048 -280.479171) (xy 177.476169 -280.448046) (xy 177.51879 -280.423439) (xy 177.564806 -280.405987)
			(xy 177.613025 -280.396143) (xy 177.6622 -280.394162) (xy 177.711055 -280.400094) (xy 177.758326 -280.413786)
			(xy 177.802788 -280.434884) (xy 177.843291 -280.46284) (xy 177.878784 -280.496932) (xy 177.908349 -280.536276)
			(xy 177.93122 -280.579853) (xy 177.946804 -280.626534) (xy 177.954699 -280.675111) (xy 177.955194 -280.699718)
			(xy 178.294042 -280.699718) (xy 178.298002 -280.650664) (xy 178.309779 -280.60288) (xy 178.32907 -280.557604)
			(xy 178.355373 -280.516008) (xy 178.388008 -280.479171) (xy 178.426129 -280.448046) (xy 178.46875 -280.423439)
			(xy 178.514766 -280.405987) (xy 178.562985 -280.396143) (xy 178.61216 -280.394162) (xy 178.661015 -280.400094)
			(xy 178.708286 -280.413786) (xy 178.752748 -280.434884) (xy 178.793251 -280.46284) (xy 178.828744 -280.496932)
			(xy 178.858309 -280.536276) (xy 178.88118 -280.579853) (xy 178.896764 -280.626534) (xy 178.904659 -280.675111)
			(xy 178.905154 -280.699718) (xy 179.244256 -280.699718) (xy 179.248216 -280.650664) (xy 179.259993 -280.60288)
			(xy 179.279284 -280.557604) (xy 179.305587 -280.516008) (xy 179.338222 -280.479171) (xy 179.376343 -280.448046)
			(xy 179.418964 -280.423439) (xy 179.46498 -280.405987) (xy 179.513199 -280.396143) (xy 179.562374 -280.394162)
			(xy 179.611229 -280.400094) (xy 179.6585 -280.413786) (xy 179.702962 -280.434884) (xy 179.743465 -280.46284)
			(xy 179.778958 -280.496932) (xy 179.808523 -280.536276) (xy 179.831394 -280.579853) (xy 179.846978 -280.626534)
			(xy 179.854873 -280.675111) (xy 179.855368 -280.699718) (xy 180.194216 -280.699718) (xy 180.198176 -280.650664)
			(xy 180.209953 -280.60288) (xy 180.229244 -280.557604) (xy 180.255547 -280.516008) (xy 180.288182 -280.479171)
			(xy 180.326303 -280.448046) (xy 180.368924 -280.423439) (xy 180.41494 -280.405987) (xy 180.463159 -280.396143)
			(xy 180.512334 -280.394162) (xy 180.561189 -280.400094) (xy 180.60846 -280.413786) (xy 180.652922 -280.434884)
			(xy 180.693425 -280.46284) (xy 180.728918 -280.496932) (xy 180.758483 -280.536276) (xy 180.781354 -280.579853)
			(xy 180.796938 -280.626534) (xy 180.804833 -280.675111) (xy 180.805328 -280.699718) (xy 181.144176 -280.699718)
			(xy 181.148136 -280.650664) (xy 181.159913 -280.60288) (xy 181.179204 -280.557604) (xy 181.205507 -280.516008)
			(xy 181.238142 -280.479171) (xy 181.276263 -280.448046) (xy 181.318884 -280.423439) (xy 181.3649 -280.405987)
			(xy 181.413119 -280.396143) (xy 181.462294 -280.394162) (xy 181.511149 -280.400094) (xy 181.55842 -280.413786)
			(xy 181.602882 -280.434884) (xy 181.643385 -280.46284) (xy 181.678878 -280.496932) (xy 181.708443 -280.536276)
			(xy 181.731314 -280.579853) (xy 181.746898 -280.626534) (xy 181.754793 -280.675111) (xy 181.755288 -280.699718)
			(xy 182.094136 -280.699718) (xy 182.098096 -280.650664) (xy 182.109873 -280.60288) (xy 182.129164 -280.557604)
			(xy 182.155467 -280.516008) (xy 182.188102 -280.479171) (xy 182.226223 -280.448046) (xy 182.268844 -280.423439)
			(xy 182.31486 -280.405987) (xy 182.363079 -280.396143) (xy 182.412254 -280.394162) (xy 182.461109 -280.400094)
			(xy 182.50838 -280.413786) (xy 182.552842 -280.434884) (xy 182.593345 -280.46284) (xy 182.628838 -280.496932)
			(xy 182.658403 -280.536276) (xy 182.681274 -280.579853) (xy 182.696858 -280.626534) (xy 182.704753 -280.675111)
			(xy 182.705248 -280.699718) (xy 183.044096 -280.699718) (xy 183.048056 -280.650664) (xy 183.059833 -280.60288)
			(xy 183.079124 -280.557604) (xy 183.105427 -280.516008) (xy 183.138062 -280.479171) (xy 183.176183 -280.448046)
			(xy 183.218804 -280.423439) (xy 183.26482 -280.405987) (xy 183.313039 -280.396143) (xy 183.362214 -280.394162)
			(xy 183.411069 -280.400094) (xy 183.45834 -280.413786) (xy 183.502802 -280.434884) (xy 183.543305 -280.46284)
			(xy 183.578798 -280.496932) (xy 183.608363 -280.536276) (xy 183.631234 -280.579853) (xy 183.646818 -280.626534)
			(xy 183.654713 -280.675111) (xy 183.655208 -280.699718) (xy 183.994056 -280.699718) (xy 183.998016 -280.650664)
			(xy 184.009793 -280.60288) (xy 184.029084 -280.557604) (xy 184.055387 -280.516008) (xy 184.088022 -280.479171)
			(xy 184.126143 -280.448046) (xy 184.168764 -280.423439) (xy 184.21478 -280.405987) (xy 184.262999 -280.396143)
			(xy 184.312174 -280.394162) (xy 184.361029 -280.400094) (xy 184.4083 -280.413786) (xy 184.452762 -280.434884)
			(xy 184.493265 -280.46284) (xy 184.528758 -280.496932) (xy 184.558323 -280.536276) (xy 184.581194 -280.579853)
			(xy 184.596778 -280.626534) (xy 184.604673 -280.675111) (xy 184.605168 -280.699718) (xy 184.604673 -280.724325)
			(xy 184.596778 -280.772902) (xy 184.581194 -280.819583) (xy 184.558323 -280.86316) (xy 184.528758 -280.902504)
			(xy 184.493265 -280.936596) (xy 184.452762 -280.964552) (xy 184.4083 -280.98565) (xy 184.361029 -280.999342)
			(xy 184.312174 -281.005274) (xy 184.262999 -281.003293) (xy 184.21478 -280.993449) (xy 184.168764 -280.975997)
			(xy 184.126143 -280.95139) (xy 184.088022 -280.920265) (xy 184.055387 -280.883428) (xy 184.029084 -280.841832)
			(xy 184.009793 -280.796556) (xy 183.998016 -280.748772) (xy 183.994056 -280.699718) (xy 183.655208 -280.699718)
			(xy 183.654713 -280.724325) (xy 183.646818 -280.772902) (xy 183.631234 -280.819583) (xy 183.608363 -280.86316)
			(xy 183.578798 -280.902504) (xy 183.543305 -280.936596) (xy 183.502802 -280.964552) (xy 183.45834 -280.98565)
			(xy 183.411069 -280.999342) (xy 183.362214 -281.005274) (xy 183.313039 -281.003293) (xy 183.26482 -280.993449)
			(xy 183.218804 -280.975997) (xy 183.176183 -280.95139) (xy 183.138062 -280.920265) (xy 183.105427 -280.883428)
			(xy 183.079124 -280.841832) (xy 183.059833 -280.796556) (xy 183.048056 -280.748772) (xy 183.044096 -280.699718)
			(xy 182.705248 -280.699718) (xy 182.704753 -280.724325) (xy 182.696858 -280.772902) (xy 182.681274 -280.819583)
			(xy 182.658403 -280.86316) (xy 182.628838 -280.902504) (xy 182.593345 -280.936596) (xy 182.552842 -280.964552)
			(xy 182.50838 -280.98565) (xy 182.461109 -280.999342) (xy 182.412254 -281.005274) (xy 182.363079 -281.003293)
			(xy 182.31486 -280.993449) (xy 182.268844 -280.975997) (xy 182.226223 -280.95139) (xy 182.188102 -280.920265)
			(xy 182.155467 -280.883428) (xy 182.129164 -280.841832) (xy 182.109873 -280.796556) (xy 182.098096 -280.748772)
			(xy 182.094136 -280.699718) (xy 181.755288 -280.699718) (xy 181.754793 -280.724325) (xy 181.746898 -280.772902)
			(xy 181.731314 -280.819583) (xy 181.708443 -280.86316) (xy 181.678878 -280.902504) (xy 181.643385 -280.936596)
			(xy 181.602882 -280.964552) (xy 181.55842 -280.98565) (xy 181.511149 -280.999342) (xy 181.462294 -281.005274)
			(xy 181.413119 -281.003293) (xy 181.3649 -280.993449) (xy 181.318884 -280.975997) (xy 181.276263 -280.95139)
			(xy 181.238142 -280.920265) (xy 181.205507 -280.883428) (xy 181.179204 -280.841832) (xy 181.159913 -280.796556)
			(xy 181.148136 -280.748772) (xy 181.144176 -280.699718) (xy 180.805328 -280.699718) (xy 180.804833 -280.724325)
			(xy 180.796938 -280.772902) (xy 180.781354 -280.819583) (xy 180.758483 -280.86316) (xy 180.728918 -280.902504)
			(xy 180.693425 -280.936596) (xy 180.652922 -280.964552) (xy 180.60846 -280.98565) (xy 180.561189 -280.999342)
			(xy 180.512334 -281.005274) (xy 180.463159 -281.003293) (xy 180.41494 -280.993449) (xy 180.368924 -280.975997)
			(xy 180.326303 -280.95139) (xy 180.288182 -280.920265) (xy 180.255547 -280.883428) (xy 180.229244 -280.841832)
			(xy 180.209953 -280.796556) (xy 180.198176 -280.748772) (xy 180.194216 -280.699718) (xy 179.855368 -280.699718)
			(xy 179.854873 -280.724325) (xy 179.846978 -280.772902) (xy 179.831394 -280.819583) (xy 179.808523 -280.86316)
			(xy 179.778958 -280.902504) (xy 179.743465 -280.936596) (xy 179.702962 -280.964552) (xy 179.6585 -280.98565)
			(xy 179.611229 -280.999342) (xy 179.562374 -281.005274) (xy 179.513199 -281.003293) (xy 179.46498 -280.993449)
			(xy 179.418964 -280.975997) (xy 179.376343 -280.95139) (xy 179.338222 -280.920265) (xy 179.305587 -280.883428)
			(xy 179.279284 -280.841832) (xy 179.259993 -280.796556) (xy 179.248216 -280.748772) (xy 179.244256 -280.699718)
			(xy 178.905154 -280.699718) (xy 178.904659 -280.724325) (xy 178.896764 -280.772902) (xy 178.88118 -280.819583)
			(xy 178.858309 -280.86316) (xy 178.828744 -280.902504) (xy 178.793251 -280.936596) (xy 178.752748 -280.964552)
			(xy 178.708286 -280.98565) (xy 178.661015 -280.999342) (xy 178.61216 -281.005274) (xy 178.562985 -281.003293)
			(xy 178.514766 -280.993449) (xy 178.46875 -280.975997) (xy 178.426129 -280.95139) (xy 178.388008 -280.920265)
			(xy 178.355373 -280.883428) (xy 178.32907 -280.841832) (xy 178.309779 -280.796556) (xy 178.298002 -280.748772)
			(xy 178.294042 -280.699718) (xy 177.955194 -280.699718) (xy 177.954699 -280.724325) (xy 177.946804 -280.772902)
			(xy 177.93122 -280.819583) (xy 177.908349 -280.86316) (xy 177.878784 -280.902504) (xy 177.843291 -280.936596)
			(xy 177.802788 -280.964552) (xy 177.758326 -280.98565) (xy 177.711055 -280.999342) (xy 177.6622 -281.005274)
			(xy 177.613025 -281.003293) (xy 177.564806 -280.993449) (xy 177.51879 -280.975997) (xy 177.476169 -280.95139)
			(xy 177.438048 -280.920265) (xy 177.405413 -280.883428) (xy 177.37911 -280.841832) (xy 177.359819 -280.796556)
			(xy 177.348042 -280.748772) (xy 177.344082 -280.699718) (xy 177.005234 -280.699718) (xy 177.004739 -280.724325)
			(xy 176.996844 -280.772902) (xy 176.98126 -280.819583) (xy 176.958389 -280.86316) (xy 176.928824 -280.902504)
			(xy 176.893331 -280.936596) (xy 176.852828 -280.964552) (xy 176.808366 -280.98565) (xy 176.761095 -280.999342)
			(xy 176.71224 -281.005274) (xy 176.663065 -281.003293) (xy 176.614846 -280.993449) (xy 176.56883 -280.975997)
			(xy 176.526209 -280.95139) (xy 176.488088 -280.920265) (xy 176.455453 -280.883428) (xy 176.42915 -280.841832)
			(xy 176.409859 -280.796556) (xy 176.398082 -280.748772) (xy 176.394122 -280.699718) (xy 176.055274 -280.699718)
			(xy 176.054779 -280.724325) (xy 176.046884 -280.772902) (xy 176.0313 -280.819583) (xy 176.008429 -280.86316)
			(xy 175.978864 -280.902504) (xy 175.943371 -280.936596) (xy 175.902868 -280.964552) (xy 175.858406 -280.98565)
			(xy 175.811135 -280.999342) (xy 175.76228 -281.005274) (xy 175.713105 -281.003293) (xy 175.664886 -280.993449)
			(xy 175.61887 -280.975997) (xy 175.576249 -280.95139) (xy 175.538128 -280.920265) (xy 175.505493 -280.883428)
			(xy 175.47919 -280.841832) (xy 175.459899 -280.796556) (xy 175.448122 -280.748772) (xy 175.444162 -280.699718)
			(xy 175.105314 -280.699718) (xy 175.104819 -280.724325) (xy 175.096924 -280.772902) (xy 175.08134 -280.819583)
			(xy 175.058469 -280.86316) (xy 175.028904 -280.902504) (xy 174.993411 -280.936596) (xy 174.952908 -280.964552)
			(xy 174.908446 -280.98565) (xy 174.861175 -280.999342) (xy 174.81232 -281.005274) (xy 174.763145 -281.003293)
			(xy 174.714926 -280.993449) (xy 174.66891 -280.975997) (xy 174.626289 -280.95139) (xy 174.588168 -280.920265)
			(xy 174.555533 -280.883428) (xy 174.52923 -280.841832) (xy 174.509939 -280.796556) (xy 174.498162 -280.748772)
			(xy 174.494202 -280.699718) (xy 174.155354 -280.699718) (xy 174.154859 -280.724325) (xy 174.146964 -280.772902)
			(xy 174.13138 -280.819583) (xy 174.108509 -280.86316) (xy 174.078944 -280.902504) (xy 174.043451 -280.936596)
			(xy 174.002948 -280.964552) (xy 173.958486 -280.98565) (xy 173.911215 -280.999342) (xy 173.86236 -281.005274)
			(xy 173.813185 -281.003293) (xy 173.764966 -280.993449) (xy 173.71895 -280.975997) (xy 173.676329 -280.95139)
			(xy 173.638208 -280.920265) (xy 173.605573 -280.883428) (xy 173.57927 -280.841832) (xy 173.559979 -280.796556)
			(xy 173.548202 -280.748772) (xy 173.544242 -280.699718) (xy 173.20514 -280.699718) (xy 173.204645 -280.724325)
			(xy 173.19675 -280.772902) (xy 173.181166 -280.819583) (xy 173.158295 -280.86316) (xy 173.12873 -280.902504)
			(xy 173.093237 -280.936596) (xy 173.052734 -280.964552) (xy 173.008272 -280.98565) (xy 172.961001 -280.999342)
			(xy 172.912146 -281.005274) (xy 172.862971 -281.003293) (xy 172.814752 -280.993449) (xy 172.768736 -280.975997)
			(xy 172.726115 -280.95139) (xy 172.687994 -280.920265) (xy 172.655359 -280.883428) (xy 172.629056 -280.841832)
			(xy 172.609765 -280.796556) (xy 172.597988 -280.748772) (xy 172.594028 -280.699718) (xy 172.25518 -280.699718)
			(xy 172.254685 -280.724325) (xy 172.24679 -280.772902) (xy 172.231206 -280.819583) (xy 172.208335 -280.86316)
			(xy 172.17877 -280.902504) (xy 172.143277 -280.936596) (xy 172.102774 -280.964552) (xy 172.058312 -280.98565)
			(xy 172.011041 -280.999342) (xy 171.962186 -281.005274) (xy 171.913011 -281.003293) (xy 171.864792 -280.993449)
			(xy 171.818776 -280.975997) (xy 171.776155 -280.95139) (xy 171.738034 -280.920265) (xy 171.705399 -280.883428)
			(xy 171.679096 -280.841832) (xy 171.659805 -280.796556) (xy 171.648028 -280.748772) (xy 171.644068 -280.699718)
			(xy 171.30522 -280.699718) (xy 171.304725 -280.724325) (xy 171.29683 -280.772902) (xy 171.281246 -280.819583)
			(xy 171.258375 -280.86316) (xy 171.22881 -280.902504) (xy 171.193317 -280.936596) (xy 171.152814 -280.964552)
			(xy 171.108352 -280.98565) (xy 171.061081 -280.999342) (xy 171.012226 -281.005274) (xy 170.963051 -281.003293)
			(xy 170.914832 -280.993449) (xy 170.868816 -280.975997) (xy 170.826195 -280.95139) (xy 170.788074 -280.920265)
			(xy 170.755439 -280.883428) (xy 170.729136 -280.841832) (xy 170.709845 -280.796556) (xy 170.698068 -280.748772)
			(xy 170.694108 -280.699718) (xy 170.35526 -280.699718) (xy 170.354765 -280.724325) (xy 170.34687 -280.772902)
			(xy 170.331286 -280.819583) (xy 170.308415 -280.86316) (xy 170.27885 -280.902504) (xy 170.243357 -280.936596)
			(xy 170.202854 -280.964552) (xy 170.158392 -280.98565) (xy 170.111121 -280.999342) (xy 170.062266 -281.005274)
			(xy 170.013091 -281.003293) (xy 169.964872 -280.993449) (xy 169.918856 -280.975997) (xy 169.876235 -280.95139)
			(xy 169.838114 -280.920265) (xy 169.805479 -280.883428) (xy 169.779176 -280.841832) (xy 169.759885 -280.796556)
			(xy 169.748108 -280.748772) (xy 169.744148 -280.699718) (xy 169.4053 -280.699718) (xy 169.404805 -280.724325)
			(xy 169.39691 -280.772902) (xy 169.381326 -280.819583) (xy 169.358455 -280.86316) (xy 169.32889 -280.902504)
			(xy 169.293397 -280.936596) (xy 169.252894 -280.964552) (xy 169.208432 -280.98565) (xy 169.161161 -280.999342)
			(xy 169.112306 -281.005274) (xy 169.063131 -281.003293) (xy 169.014912 -280.993449) (xy 168.968896 -280.975997)
			(xy 168.926275 -280.95139) (xy 168.888154 -280.920265) (xy 168.855519 -280.883428) (xy 168.829216 -280.841832)
			(xy 168.809925 -280.796556) (xy 168.798148 -280.748772) (xy 168.794188 -280.699718) (xy 168.45534 -280.699718)
			(xy 168.454845 -280.724325) (xy 168.44695 -280.772902) (xy 168.431366 -280.819583) (xy 168.408495 -280.86316)
			(xy 168.37893 -280.902504) (xy 168.343437 -280.936596) (xy 168.302934 -280.964552) (xy 168.258472 -280.98565)
			(xy 168.211201 -280.999342) (xy 168.162346 -281.005274) (xy 168.113171 -281.003293) (xy 168.064952 -280.993449)
			(xy 168.018936 -280.975997) (xy 167.976315 -280.95139) (xy 167.938194 -280.920265) (xy 167.905559 -280.883428)
			(xy 167.879256 -280.841832) (xy 167.859965 -280.796556) (xy 167.848188 -280.748772) (xy 167.844228 -280.699718)
			(xy 167.50538 -280.699718) (xy 167.504885 -280.724325) (xy 167.49699 -280.772902) (xy 167.481406 -280.819583)
			(xy 167.458535 -280.86316) (xy 167.42897 -280.902504) (xy 167.393477 -280.936596) (xy 167.352974 -280.964552)
			(xy 167.308512 -280.98565) (xy 167.261241 -280.999342) (xy 167.212386 -281.005274) (xy 167.163211 -281.003293)
			(xy 167.114992 -280.993449) (xy 167.068976 -280.975997) (xy 167.026355 -280.95139) (xy 166.988234 -280.920265)
			(xy 166.955599 -280.883428) (xy 166.929296 -280.841832) (xy 166.910005 -280.796556) (xy 166.898228 -280.748772)
			(xy 166.894268 -280.699718) (xy 166.555166 -280.699718) (xy 166.554671 -280.724325) (xy 166.546776 -280.772902)
			(xy 166.531192 -280.819583) (xy 166.508321 -280.86316) (xy 166.478756 -280.902504) (xy 166.443263 -280.936596)
			(xy 166.40276 -280.964552) (xy 166.358298 -280.98565) (xy 166.311027 -280.999342) (xy 166.262172 -281.005274)
			(xy 166.212997 -281.003293) (xy 166.164778 -280.993449) (xy 166.118762 -280.975997) (xy 166.076141 -280.95139)
			(xy 166.03802 -280.920265) (xy 166.005385 -280.883428) (xy 165.979082 -280.841832) (xy 165.959791 -280.796556)
			(xy 165.948014 -280.748772) (xy 165.944054 -280.699718) (xy 165.605206 -280.699718) (xy 165.604711 -280.724325)
			(xy 165.596816 -280.772902) (xy 165.581232 -280.819583) (xy 165.558361 -280.86316) (xy 165.528796 -280.902504)
			(xy 165.493303 -280.936596) (xy 165.4528 -280.964552) (xy 165.408338 -280.98565) (xy 165.361067 -280.999342)
			(xy 165.312212 -281.005274) (xy 165.263037 -281.003293) (xy 165.214818 -280.993449) (xy 165.168802 -280.975997)
			(xy 165.126181 -280.95139) (xy 165.08806 -280.920265) (xy 165.055425 -280.883428) (xy 165.029122 -280.841832)
			(xy 165.009831 -280.796556) (xy 164.998054 -280.748772) (xy 164.994094 -280.699718) (xy 164.655246 -280.699718)
			(xy 164.654751 -280.724325) (xy 164.646856 -280.772902) (xy 164.631272 -280.819583) (xy 164.608401 -280.86316)
			(xy 164.578836 -280.902504) (xy 164.543343 -280.936596) (xy 164.50284 -280.964552) (xy 164.458378 -280.98565)
			(xy 164.411107 -280.999342) (xy 164.362252 -281.005274) (xy 164.313077 -281.003293) (xy 164.264858 -280.993449)
			(xy 164.218842 -280.975997) (xy 164.176221 -280.95139) (xy 164.1381 -280.920265) (xy 164.105465 -280.883428)
			(xy 164.079162 -280.841832) (xy 164.059871 -280.796556) (xy 164.048094 -280.748772) (xy 164.044134 -280.699718)
			(xy 163.705286 -280.699718) (xy 163.704791 -280.724325) (xy 163.696896 -280.772902) (xy 163.681312 -280.819583)
			(xy 163.658441 -280.86316) (xy 163.628876 -280.902504) (xy 163.593383 -280.936596) (xy 163.55288 -280.964552)
			(xy 163.508418 -280.98565) (xy 163.461147 -280.999342) (xy 163.412292 -281.005274) (xy 163.363117 -281.003293)
			(xy 163.314898 -280.993449) (xy 163.268882 -280.975997) (xy 163.226261 -280.95139) (xy 163.18814 -280.920265)
			(xy 163.155505 -280.883428) (xy 163.129202 -280.841832) (xy 163.109911 -280.796556) (xy 163.098134 -280.748772)
			(xy 163.094174 -280.699718) (xy 162.755326 -280.699718) (xy 162.754831 -280.724325) (xy 162.746936 -280.772902)
			(xy 162.731352 -280.819583) (xy 162.708481 -280.86316) (xy 162.678916 -280.902504) (xy 162.643423 -280.936596)
			(xy 162.60292 -280.964552) (xy 162.558458 -280.98565) (xy 162.511187 -280.999342) (xy 162.462332 -281.005274)
			(xy 162.413157 -281.003293) (xy 162.364938 -280.993449) (xy 162.318922 -280.975997) (xy 162.276301 -280.95139)
			(xy 162.23818 -280.920265) (xy 162.205545 -280.883428) (xy 162.179242 -280.841832) (xy 162.159951 -280.796556)
			(xy 162.148174 -280.748772) (xy 162.144214 -280.699718) (xy 161.805366 -280.699718) (xy 161.804871 -280.724325)
			(xy 161.796976 -280.772902) (xy 161.781392 -280.819583) (xy 161.758521 -280.86316) (xy 161.728956 -280.902504)
			(xy 161.693463 -280.936596) (xy 161.65296 -280.964552) (xy 161.608498 -280.98565) (xy 161.561227 -280.999342)
			(xy 161.512372 -281.005274) (xy 161.463197 -281.003293) (xy 161.414978 -280.993449) (xy 161.368962 -280.975997)
			(xy 161.326341 -280.95139) (xy 161.28822 -280.920265) (xy 161.255585 -280.883428) (xy 161.229282 -280.841832)
			(xy 161.209991 -280.796556) (xy 161.198214 -280.748772) (xy 161.194254 -280.699718) (xy 160.855027 -280.699718)
			(xy 160.852785 -280.741003) (xy 160.842112 -280.789474) (xy 160.823738 -280.83558) (xy 160.798148 -280.878107)
			(xy 160.766015 -280.915933) (xy 160.728186 -280.948063) (xy 160.685657 -280.97365) (xy 160.639549 -280.99202)
			(xy 160.591077 -281.002688) (xy 160.541517 -281.005375) (xy 160.492176 -281.000008) (xy 160.444352 -280.98673)
			(xy 160.399307 -280.965891) (xy 160.358226 -280.938038) (xy 160.322193 -280.903907) (xy 160.292155 -280.864396)
			(xy 160.268905 -280.820546) (xy 160.253055 -280.773512) (xy 160.245023 -280.724534) (xy 160.244536 -280.699718)
			(xy 160.244714 -280.685535) (xy 160.247385 -280.657295) (xy 160.24987 -280.64333) (xy 160.252156 -280.630884)
			(xy 160.24479 -280.607262) (xy 160.16732 -280.529792) (xy 160.143698 -280.522426) (xy 160.131252 -280.524712)
			(xy 160.117287 -280.527191) (xy 160.089047 -280.529861) (xy 160.074864 -280.530046) (xy 160.049614 -280.529446)
			(xy 159.999803 -280.521128) (xy 159.95204 -280.504726) (xy 159.907628 -280.480687) (xy 159.867778 -280.449666)
			(xy 159.833577 -280.41251) (xy 159.805958 -280.370231) (xy 159.785673 -280.323984) (xy 159.773277 -280.275028)
			(xy 159.769107 -280.2247) (xy 159.773277 -280.174372) (xy 159.785673 -280.125416) (xy 159.805958 -280.079169)
			(xy 159.833577 -280.03689) (xy 159.867778 -279.999734) (xy 159.907628 -279.968713) (xy 159.95204 -279.944674)
			(xy 159.999803 -279.928272) (xy 160.049614 -279.919954) (xy 160.074864 -279.91943) (xy 160.089047 -279.919611)
			(xy 160.117287 -279.92228) (xy 160.131252 -279.924764) (xy 160.143698 -279.92705) (xy 160.16732 -279.919684)
			(xy 160.24479 -279.842214) (xy 160.252156 -279.818592) (xy 160.24987 -279.806146) (xy 160.24739 -279.792181)
			(xy 160.244721 -279.763941) (xy 160.244536 -279.749758) (xy 160.244706 -279.735575) (xy 160.247382 -279.707335)
			(xy 160.24987 -279.69337) (xy 160.252156 -279.680924) (xy 160.24479 -279.657302) (xy 160.16732 -279.579832)
			(xy 160.143698 -279.572466) (xy 160.131252 -279.574752) (xy 160.117286 -279.577231) (xy 160.089047 -279.579901)
			(xy 160.074864 -279.580086) (xy 160.050871 -279.57967) (xy 160.003476 -279.572158) (xy 159.957839 -279.557325)
			(xy 159.915085 -279.535535) (xy 159.876266 -279.507325) (xy 159.842337 -279.47339) (xy 159.814135 -279.434565)
			(xy 159.792353 -279.391807) (xy 159.777528 -279.346168) (xy 159.770025 -279.298771) (xy 159.769556 -279.274778)
			(xy 159.76973 -279.260595) (xy 159.772404 -279.232355) (xy 159.77489 -279.21839) (xy 159.777176 -279.205944)
			(xy 159.76981 -279.182322) (xy 159.69234 -279.104852) (xy 159.668718 -279.097486) (xy 159.656272 -279.099772)
			(xy 159.642306 -279.102248) (xy 159.614067 -279.10492) (xy 159.599884 -279.105106) (xy 159.585701 -279.104932)
			(xy 159.557461 -279.102258) (xy 159.543496 -279.099772) (xy 159.53105 -279.097486) (xy 159.507428 -279.104852)
			(xy 159.429958 -279.182322) (xy 159.422592 -279.205944) (xy 159.424878 -279.21839) (xy 159.427349 -279.232357)
			(xy 159.430024 -279.260596) (xy 159.430212 -279.274778) (xy 159.429746 -279.299601) (xy 159.421717 -279.348594)
			(xy 159.405868 -279.395642) (xy 159.382616 -279.439507) (xy 159.352574 -279.479031) (xy 159.316533 -279.513175)
			(xy 159.275443 -279.541038) (xy 159.230387 -279.561886) (xy 159.182551 -279.575171) (xy 159.133196 -279.58054)
			(xy 159.083622 -279.577855) (xy 159.035136 -279.567184) (xy 158.989016 -279.54881) (xy 158.946475 -279.523216)
			(xy 158.908636 -279.491077) (xy 158.876494 -279.45324) (xy 158.850898 -279.410701) (xy 158.832521 -279.364581)
			(xy 158.821848 -279.316096) (xy 158.819159 -279.266522) (xy 158.824526 -279.217167) (xy 158.837807 -279.16933)
			(xy 158.858653 -279.124272) (xy 158.886513 -279.083181) (xy 158.920655 -279.047138) (xy 158.960178 -279.017093)
			(xy 159.004041 -278.993839) (xy 159.051089 -278.977987) (xy 159.100081 -278.969956) (xy 159.124904 -278.96947)
			(xy 159.139087 -278.969646) (xy 159.167327 -278.972319) (xy 159.181292 -278.974804) (xy 159.193738 -278.97709)
			(xy 159.21736 -278.969724) (xy 159.29483 -278.892254) (xy 159.302196 -278.868632) (xy 159.29991 -278.856186)
			(xy 159.297436 -278.84222) (xy 159.294762 -278.81398) (xy 159.294576 -278.799798) (xy 159.294753 -278.785615)
			(xy 159.297425 -278.757375) (xy 159.29991 -278.74341) (xy 159.302196 -278.730964) (xy 159.29483 -278.707342)
			(xy 159.21736 -278.629872) (xy 159.193738 -278.622506) (xy 159.181292 -278.624792) (xy 159.167326 -278.627266)
			(xy 159.139086 -278.629939) (xy 159.124904 -278.630126) (xy 159.099648 -278.629598) (xy 159.049823 -278.621284)
			(xy 159.002047 -278.604883) (xy 158.957622 -278.580842) (xy 158.91776 -278.549817) (xy 158.883549 -278.512653)
			(xy 158.855921 -278.470366) (xy 158.83563 -278.424108) (xy 158.823229 -278.37514) (xy 158.819058 -278.3248)
			(xy 158.823229 -278.27446) (xy 158.83563 -278.225492) (xy 158.855921 -278.179234) (xy 158.883549 -278.136947)
			(xy 158.91776 -278.099783) (xy 158.957622 -278.068758) (xy 159.002047 -278.044717) (xy 159.049823 -278.028316)
			(xy 159.099648 -278.020002) (xy 159.124904 -278.01951) (xy 159.139087 -278.019686) (xy 159.167327 -278.022358)
			(xy 159.181292 -278.024844) (xy 159.193738 -278.02713) (xy 159.21736 -278.019764) (xy 159.29483 -277.942294)
			(xy 159.302196 -277.918672) (xy 159.29991 -277.906226) (xy 159.297427 -277.892261) (xy 159.29476 -277.864021)
			(xy 159.294576 -277.849838) (xy 159.294758 -277.835655) (xy 159.297427 -277.807415) (xy 159.29991 -277.79345)
			(xy 159.302196 -277.781004) (xy 159.29483 -277.757382) (xy 159.21736 -277.679912) (xy 159.193738 -277.672546)
			(xy 159.181292 -277.674832) (xy 159.167326 -277.677306) (xy 159.139086 -277.679979) (xy 159.124904 -277.680166)
			(xy 159.099643 -277.679758) (xy 159.049809 -277.671442) (xy 159.002023 -277.655038) (xy 158.95759 -277.630992)
			(xy 158.91772 -277.599961) (xy 158.883501 -277.56279) (xy 158.855868 -277.520494) (xy 158.835573 -277.474227)
			(xy 158.82317 -277.42525) (xy 158.818998 -277.3749) (xy 158.480251 -277.3749) (xy 158.479757 -277.399465)
			(xy 158.471862 -277.448042) (xy 158.456278 -277.494723) (xy 158.433407 -277.5383) (xy 158.403842 -277.577644)
			(xy 158.368349 -277.611736) (xy 158.327846 -277.639692) (xy 158.283384 -277.66079) (xy 158.236113 -277.674482)
			(xy 158.187258 -277.680414) (xy 158.138083 -277.678433) (xy 158.089864 -277.668589) (xy 158.043848 -277.651137)
			(xy 158.001227 -277.62653) (xy 157.963106 -277.595405) (xy 157.930471 -277.558568) (xy 157.904168 -277.516972)
			(xy 157.884877 -277.471696) (xy 157.8731 -277.423912) (xy 157.86914 -277.374858) (xy 157.530292 -277.374858)
			(xy 157.529797 -277.399465) (xy 157.521902 -277.448042) (xy 157.506318 -277.494723) (xy 157.483447 -277.5383)
			(xy 157.453882 -277.577644) (xy 157.418389 -277.611736) (xy 157.377886 -277.639692) (xy 157.333424 -277.66079)
			(xy 157.286153 -277.674482) (xy 157.237298 -277.680414) (xy 157.188123 -277.678433) (xy 157.139904 -277.668589)
			(xy 157.093888 -277.651137) (xy 157.051267 -277.62653) (xy 157.013146 -277.595405) (xy 156.980511 -277.558568)
			(xy 156.954208 -277.516972) (xy 156.934917 -277.471696) (xy 156.92314 -277.423912) (xy 156.91918 -277.374858)
			(xy 156.580332 -277.374858) (xy 156.579837 -277.399465) (xy 156.571942 -277.448042) (xy 156.556358 -277.494723)
			(xy 156.533487 -277.5383) (xy 156.503922 -277.577644) (xy 156.468429 -277.611736) (xy 156.427926 -277.639692)
			(xy 156.383464 -277.66079) (xy 156.336193 -277.674482) (xy 156.287338 -277.680414) (xy 156.238163 -277.678433)
			(xy 156.189944 -277.668589) (xy 156.143928 -277.651137) (xy 156.101307 -277.62653) (xy 156.063186 -277.595405)
			(xy 156.030551 -277.558568) (xy 156.004248 -277.516972) (xy 155.984957 -277.471696) (xy 155.97318 -277.423912)
			(xy 155.96922 -277.374858) (xy 155.630372 -277.374858) (xy 155.629877 -277.399465) (xy 155.621982 -277.448042)
			(xy 155.606398 -277.494723) (xy 155.583527 -277.5383) (xy 155.553962 -277.577644) (xy 155.518469 -277.611736)
			(xy 155.477966 -277.639692) (xy 155.433504 -277.66079) (xy 155.386233 -277.674482) (xy 155.337378 -277.680414)
			(xy 155.288203 -277.678433) (xy 155.239984 -277.668589) (xy 155.193968 -277.651137) (xy 155.151347 -277.62653)
			(xy 155.113226 -277.595405) (xy 155.080591 -277.558568) (xy 155.054288 -277.516972) (xy 155.034997 -277.471696)
			(xy 155.02322 -277.423912) (xy 155.01926 -277.374858) (xy 154.680412 -277.374858) (xy 154.679917 -277.399465)
			(xy 154.672022 -277.448042) (xy 154.656438 -277.494723) (xy 154.633567 -277.5383) (xy 154.604002 -277.577644)
			(xy 154.568509 -277.611736) (xy 154.528006 -277.639692) (xy 154.483544 -277.66079) (xy 154.436273 -277.674482)
			(xy 154.387418 -277.680414) (xy 154.338243 -277.678433) (xy 154.290024 -277.668589) (xy 154.244008 -277.651137)
			(xy 154.201387 -277.62653) (xy 154.163266 -277.595405) (xy 154.130631 -277.558568) (xy 154.104328 -277.516972)
			(xy 154.085037 -277.471696) (xy 154.07326 -277.423912) (xy 154.0693 -277.374858) (xy 153.730198 -277.374858)
			(xy 153.729703 -277.399465) (xy 153.721808 -277.448042) (xy 153.706224 -277.494723) (xy 153.683353 -277.5383)
			(xy 153.653788 -277.577644) (xy 153.618295 -277.611736) (xy 153.577792 -277.639692) (xy 153.53333 -277.66079)
			(xy 153.486059 -277.674482) (xy 153.437204 -277.680414) (xy 153.388029 -277.678433) (xy 153.33981 -277.668589)
			(xy 153.293794 -277.651137) (xy 153.251173 -277.62653) (xy 153.213052 -277.595405) (xy 153.180417 -277.558568)
			(xy 153.154114 -277.516972) (xy 153.134823 -277.471696) (xy 153.123046 -277.423912) (xy 153.119086 -277.374858)
			(xy 152.780238 -277.374858) (xy 152.779743 -277.399465) (xy 152.771848 -277.448042) (xy 152.756264 -277.494723)
			(xy 152.733393 -277.5383) (xy 152.703828 -277.577644) (xy 152.668335 -277.611736) (xy 152.627832 -277.639692)
			(xy 152.58337 -277.66079) (xy 152.536099 -277.674482) (xy 152.487244 -277.680414) (xy 152.438069 -277.678433)
			(xy 152.38985 -277.668589) (xy 152.343834 -277.651137) (xy 152.301213 -277.62653) (xy 152.263092 -277.595405)
			(xy 152.230457 -277.558568) (xy 152.204154 -277.516972) (xy 152.184863 -277.471696) (xy 152.173086 -277.423912)
			(xy 152.169126 -277.374858) (xy 139.341413 -277.374858) (xy 139.339487 -277.379508) (xy 139.268572 -277.529443)
			(xy 139.190386 -277.675717) (xy 139.105116 -277.81798) (xy 139.012968 -277.955886) (xy 138.914165 -278.089105)
			(xy 138.808944 -278.217316) (xy 138.711509 -278.324818) (xy 152.169126 -278.324818) (xy 152.173086 -278.275764)
			(xy 152.184863 -278.22798) (xy 152.204154 -278.182704) (xy 152.230457 -278.141108) (xy 152.263092 -278.104271)
			(xy 152.301213 -278.073146) (xy 152.343834 -278.048539) (xy 152.38985 -278.031087) (xy 152.438069 -278.021243)
			(xy 152.487244 -278.019262) (xy 152.536099 -278.025194) (xy 152.58337 -278.038886) (xy 152.627832 -278.059984)
			(xy 152.668335 -278.08794) (xy 152.703828 -278.122032) (xy 152.733393 -278.161376) (xy 152.756264 -278.204953)
			(xy 152.771848 -278.251634) (xy 152.779743 -278.300211) (xy 152.780238 -278.324818) (xy 153.119086 -278.324818)
			(xy 153.123046 -278.275764) (xy 153.134823 -278.22798) (xy 153.154114 -278.182704) (xy 153.180417 -278.141108)
			(xy 153.213052 -278.104271) (xy 153.251173 -278.073146) (xy 153.293794 -278.048539) (xy 153.33981 -278.031087)
			(xy 153.388029 -278.021243) (xy 153.437204 -278.019262) (xy 153.486059 -278.025194) (xy 153.53333 -278.038886)
			(xy 153.577792 -278.059984) (xy 153.618295 -278.08794) (xy 153.653788 -278.122032) (xy 153.683353 -278.161376)
			(xy 153.706224 -278.204953) (xy 153.721808 -278.251634) (xy 153.729703 -278.300211) (xy 153.730198 -278.324818)
			(xy 154.0693 -278.324818) (xy 154.07326 -278.275764) (xy 154.085037 -278.22798) (xy 154.104328 -278.182704)
			(xy 154.130631 -278.141108) (xy 154.163266 -278.104271) (xy 154.201387 -278.073146) (xy 154.244008 -278.048539)
			(xy 154.290024 -278.031087) (xy 154.338243 -278.021243) (xy 154.387418 -278.019262) (xy 154.436273 -278.025194)
			(xy 154.483544 -278.038886) (xy 154.528006 -278.059984) (xy 154.568509 -278.08794) (xy 154.604002 -278.122032)
			(xy 154.633567 -278.161376) (xy 154.656438 -278.204953) (xy 154.672022 -278.251634) (xy 154.679917 -278.300211)
			(xy 154.680412 -278.324818) (xy 155.01926 -278.324818) (xy 155.02322 -278.275764) (xy 155.034997 -278.22798)
			(xy 155.054288 -278.182704) (xy 155.080591 -278.141108) (xy 155.113226 -278.104271) (xy 155.151347 -278.073146)
			(xy 155.193968 -278.048539) (xy 155.239984 -278.031087) (xy 155.288203 -278.021243) (xy 155.337378 -278.019262)
			(xy 155.386233 -278.025194) (xy 155.433504 -278.038886) (xy 155.477966 -278.059984) (xy 155.518469 -278.08794)
			(xy 155.553962 -278.122032) (xy 155.583527 -278.161376) (xy 155.606398 -278.204953) (xy 155.621982 -278.251634)
			(xy 155.629877 -278.300211) (xy 155.630372 -278.324818) (xy 155.96922 -278.324818) (xy 155.97318 -278.275764)
			(xy 155.984957 -278.22798) (xy 156.004248 -278.182704) (xy 156.030551 -278.141108) (xy 156.063186 -278.104271)
			(xy 156.101307 -278.073146) (xy 156.143928 -278.048539) (xy 156.189944 -278.031087) (xy 156.238163 -278.021243)
			(xy 156.287338 -278.019262) (xy 156.336193 -278.025194) (xy 156.383464 -278.038886) (xy 156.427926 -278.059984)
			(xy 156.468429 -278.08794) (xy 156.503922 -278.122032) (xy 156.533487 -278.161376) (xy 156.556358 -278.204953)
			(xy 156.571942 -278.251634) (xy 156.579837 -278.300211) (xy 156.580332 -278.324818) (xy 156.91918 -278.324818)
			(xy 156.92314 -278.275764) (xy 156.934917 -278.22798) (xy 156.954208 -278.182704) (xy 156.980511 -278.141108)
			(xy 157.013146 -278.104271) (xy 157.051267 -278.073146) (xy 157.093888 -278.048539) (xy 157.139904 -278.031087)
			(xy 157.188123 -278.021243) (xy 157.237298 -278.019262) (xy 157.286153 -278.025194) (xy 157.333424 -278.038886)
			(xy 157.377886 -278.059984) (xy 157.418389 -278.08794) (xy 157.453882 -278.122032) (xy 157.483447 -278.161376)
			(xy 157.506318 -278.204953) (xy 157.521902 -278.251634) (xy 157.529797 -278.300211) (xy 157.530292 -278.324818)
			(xy 157.86914 -278.324818) (xy 157.8731 -278.275764) (xy 157.884877 -278.22798) (xy 157.904168 -278.182704)
			(xy 157.930471 -278.141108) (xy 157.963106 -278.104271) (xy 158.001227 -278.073146) (xy 158.043848 -278.048539)
			(xy 158.089864 -278.031087) (xy 158.138083 -278.021243) (xy 158.187258 -278.019262) (xy 158.236113 -278.025194)
			(xy 158.283384 -278.038886) (xy 158.327846 -278.059984) (xy 158.368349 -278.08794) (xy 158.403842 -278.122032)
			(xy 158.433407 -278.161376) (xy 158.456278 -278.204953) (xy 158.471862 -278.251634) (xy 158.479757 -278.300211)
			(xy 158.480252 -278.324818) (xy 158.479757 -278.349425) (xy 158.471862 -278.398002) (xy 158.456278 -278.444683)
			(xy 158.433407 -278.48826) (xy 158.403842 -278.527604) (xy 158.368349 -278.561696) (xy 158.327846 -278.589652)
			(xy 158.283384 -278.61075) (xy 158.236113 -278.624442) (xy 158.187258 -278.630374) (xy 158.138083 -278.628393)
			(xy 158.089864 -278.618549) (xy 158.043848 -278.601097) (xy 158.001227 -278.57649) (xy 157.963106 -278.545365)
			(xy 157.930471 -278.508528) (xy 157.904168 -278.466932) (xy 157.884877 -278.421656) (xy 157.8731 -278.373872)
			(xy 157.86914 -278.324818) (xy 157.530292 -278.324818) (xy 157.529797 -278.349425) (xy 157.521902 -278.398002)
			(xy 157.506318 -278.444683) (xy 157.483447 -278.48826) (xy 157.453882 -278.527604) (xy 157.418389 -278.561696)
			(xy 157.377886 -278.589652) (xy 157.333424 -278.61075) (xy 157.286153 -278.624442) (xy 157.237298 -278.630374)
			(xy 157.188123 -278.628393) (xy 157.139904 -278.618549) (xy 157.093888 -278.601097) (xy 157.051267 -278.57649)
			(xy 157.013146 -278.545365) (xy 156.980511 -278.508528) (xy 156.954208 -278.466932) (xy 156.934917 -278.421656)
			(xy 156.92314 -278.373872) (xy 156.91918 -278.324818) (xy 156.580332 -278.324818) (xy 156.579837 -278.349425)
			(xy 156.571942 -278.398002) (xy 156.556358 -278.444683) (xy 156.533487 -278.48826) (xy 156.503922 -278.527604)
			(xy 156.468429 -278.561696) (xy 156.427926 -278.589652) (xy 156.383464 -278.61075) (xy 156.336193 -278.624442)
			(xy 156.287338 -278.630374) (xy 156.238163 -278.628393) (xy 156.189944 -278.618549) (xy 156.143928 -278.601097)
			(xy 156.101307 -278.57649) (xy 156.063186 -278.545365) (xy 156.030551 -278.508528) (xy 156.004248 -278.466932)
			(xy 155.984957 -278.421656) (xy 155.97318 -278.373872) (xy 155.96922 -278.324818) (xy 155.630372 -278.324818)
			(xy 155.629877 -278.349425) (xy 155.621982 -278.398002) (xy 155.606398 -278.444683) (xy 155.583527 -278.48826)
			(xy 155.553962 -278.527604) (xy 155.518469 -278.561696) (xy 155.477966 -278.589652) (xy 155.433504 -278.61075)
			(xy 155.386233 -278.624442) (xy 155.337378 -278.630374) (xy 155.288203 -278.628393) (xy 155.239984 -278.618549)
			(xy 155.193968 -278.601097) (xy 155.151347 -278.57649) (xy 155.113226 -278.545365) (xy 155.080591 -278.508528)
			(xy 155.054288 -278.466932) (xy 155.034997 -278.421656) (xy 155.02322 -278.373872) (xy 155.01926 -278.324818)
			(xy 154.680412 -278.324818) (xy 154.679917 -278.349425) (xy 154.672022 -278.398002) (xy 154.656438 -278.444683)
			(xy 154.633567 -278.48826) (xy 154.604002 -278.527604) (xy 154.568509 -278.561696) (xy 154.528006 -278.589652)
			(xy 154.483544 -278.61075) (xy 154.436273 -278.624442) (xy 154.387418 -278.630374) (xy 154.338243 -278.628393)
			(xy 154.290024 -278.618549) (xy 154.244008 -278.601097) (xy 154.201387 -278.57649) (xy 154.163266 -278.545365)
			(xy 154.130631 -278.508528) (xy 154.104328 -278.466932) (xy 154.085037 -278.421656) (xy 154.07326 -278.373872)
			(xy 154.0693 -278.324818) (xy 153.730198 -278.324818) (xy 153.729703 -278.349425) (xy 153.721808 -278.398002)
			(xy 153.706224 -278.444683) (xy 153.683353 -278.48826) (xy 153.653788 -278.527604) (xy 153.618295 -278.561696)
			(xy 153.577792 -278.589652) (xy 153.53333 -278.61075) (xy 153.486059 -278.624442) (xy 153.437204 -278.630374)
			(xy 153.388029 -278.628393) (xy 153.33981 -278.618549) (xy 153.293794 -278.601097) (xy 153.251173 -278.57649)
			(xy 153.213052 -278.545365) (xy 153.180417 -278.508528) (xy 153.154114 -278.466932) (xy 153.134823 -278.421656)
			(xy 153.123046 -278.373872) (xy 153.119086 -278.324818) (xy 152.780238 -278.324818) (xy 152.779743 -278.349425)
			(xy 152.771848 -278.398002) (xy 152.756264 -278.444683) (xy 152.733393 -278.48826) (xy 152.703828 -278.527604)
			(xy 152.668335 -278.561696) (xy 152.627832 -278.589652) (xy 152.58337 -278.61075) (xy 152.536099 -278.624442)
			(xy 152.487244 -278.630374) (xy 152.438069 -278.628393) (xy 152.38985 -278.618549) (xy 152.343834 -278.601097)
			(xy 152.301213 -278.57649) (xy 152.263092 -278.545365) (xy 152.230457 -278.508528) (xy 152.204154 -278.466932)
			(xy 152.184863 -278.421656) (xy 152.173086 -278.373872) (xy 152.169126 -278.324818) (xy 138.711509 -278.324818)
			(xy 138.697559 -278.340209) (xy 138.580277 -278.457489) (xy 138.457383 -278.568873) (xy 138.329171 -278.674092)
			(xy 138.19595 -278.772894) (xy 138.058042 -278.865039) (xy 137.915779 -278.950307) (xy 137.769503 -279.028492)
			(xy 137.619568 -279.099405) (xy 137.466333 -279.162876) (xy 137.310168 -279.218751) (xy 137.15145 -279.266896)
			(xy 137.119982 -279.274778) (xy 152.169126 -279.274778) (xy 152.173086 -279.225724) (xy 152.184863 -279.17794)
			(xy 152.204154 -279.132664) (xy 152.230457 -279.091068) (xy 152.263092 -279.054231) (xy 152.301213 -279.023106)
			(xy 152.343834 -278.998499) (xy 152.38985 -278.981047) (xy 152.438069 -278.971203) (xy 152.487244 -278.969222)
			(xy 152.536099 -278.975154) (xy 152.58337 -278.988846) (xy 152.627832 -279.009944) (xy 152.668335 -279.0379)
			(xy 152.703828 -279.071992) (xy 152.733393 -279.111336) (xy 152.756264 -279.154913) (xy 152.771848 -279.201594)
			(xy 152.779743 -279.250171) (xy 152.780238 -279.274778) (xy 153.119086 -279.274778) (xy 153.123046 -279.225724)
			(xy 153.134823 -279.17794) (xy 153.154114 -279.132664) (xy 153.180417 -279.091068) (xy 153.213052 -279.054231)
			(xy 153.251173 -279.023106) (xy 153.293794 -278.998499) (xy 153.33981 -278.981047) (xy 153.388029 -278.971203)
			(xy 153.437204 -278.969222) (xy 153.486059 -278.975154) (xy 153.53333 -278.988846) (xy 153.577792 -279.009944)
			(xy 153.618295 -279.0379) (xy 153.653788 -279.071992) (xy 153.683353 -279.111336) (xy 153.706224 -279.154913)
			(xy 153.721808 -279.201594) (xy 153.729703 -279.250171) (xy 153.730198 -279.274778) (xy 154.0693 -279.274778)
			(xy 154.07326 -279.225724) (xy 154.085037 -279.17794) (xy 154.104328 -279.132664) (xy 154.130631 -279.091068)
			(xy 154.163266 -279.054231) (xy 154.201387 -279.023106) (xy 154.244008 -278.998499) (xy 154.290024 -278.981047)
			(xy 154.338243 -278.971203) (xy 154.387418 -278.969222) (xy 154.436273 -278.975154) (xy 154.483544 -278.988846)
			(xy 154.528006 -279.009944) (xy 154.568509 -279.0379) (xy 154.604002 -279.071992) (xy 154.633567 -279.111336)
			(xy 154.656438 -279.154913) (xy 154.672022 -279.201594) (xy 154.679917 -279.250171) (xy 154.680412 -279.274778)
			(xy 155.01926 -279.274778) (xy 155.02322 -279.225724) (xy 155.034997 -279.17794) (xy 155.054288 -279.132664)
			(xy 155.080591 -279.091068) (xy 155.113226 -279.054231) (xy 155.151347 -279.023106) (xy 155.193968 -278.998499)
			(xy 155.239984 -278.981047) (xy 155.288203 -278.971203) (xy 155.337378 -278.969222) (xy 155.386233 -278.975154)
			(xy 155.433504 -278.988846) (xy 155.477966 -279.009944) (xy 155.518469 -279.0379) (xy 155.553962 -279.071992)
			(xy 155.583527 -279.111336) (xy 155.606398 -279.154913) (xy 155.621982 -279.201594) (xy 155.629877 -279.250171)
			(xy 155.630372 -279.274778) (xy 155.96922 -279.274778) (xy 155.97318 -279.225724) (xy 155.984957 -279.17794)
			(xy 156.004248 -279.132664) (xy 156.030551 -279.091068) (xy 156.063186 -279.054231) (xy 156.101307 -279.023106)
			(xy 156.143928 -278.998499) (xy 156.189944 -278.981047) (xy 156.238163 -278.971203) (xy 156.287338 -278.969222)
			(xy 156.336193 -278.975154) (xy 156.383464 -278.988846) (xy 156.427926 -279.009944) (xy 156.468429 -279.0379)
			(xy 156.503922 -279.071992) (xy 156.533487 -279.111336) (xy 156.556358 -279.154913) (xy 156.571942 -279.201594)
			(xy 156.579837 -279.250171) (xy 156.580332 -279.274778) (xy 156.91918 -279.274778) (xy 156.92314 -279.225724)
			(xy 156.934917 -279.17794) (xy 156.954208 -279.132664) (xy 156.980511 -279.091068) (xy 157.013146 -279.054231)
			(xy 157.051267 -279.023106) (xy 157.093888 -278.998499) (xy 157.139904 -278.981047) (xy 157.188123 -278.971203)
			(xy 157.237298 -278.969222) (xy 157.286153 -278.975154) (xy 157.333424 -278.988846) (xy 157.377886 -279.009944)
			(xy 157.418389 -279.0379) (xy 157.453882 -279.071992) (xy 157.483447 -279.111336) (xy 157.506318 -279.154913)
			(xy 157.521902 -279.201594) (xy 157.529797 -279.250171) (xy 157.530292 -279.274778) (xy 157.86914 -279.274778)
			(xy 157.8731 -279.225724) (xy 157.884877 -279.17794) (xy 157.904168 -279.132664) (xy 157.930471 -279.091068)
			(xy 157.963106 -279.054231) (xy 158.001227 -279.023106) (xy 158.043848 -278.998499) (xy 158.089864 -278.981047)
			(xy 158.138083 -278.971203) (xy 158.187258 -278.969222) (xy 158.236113 -278.975154) (xy 158.283384 -278.988846)
			(xy 158.327846 -279.009944) (xy 158.368349 -279.0379) (xy 158.403842 -279.071992) (xy 158.433407 -279.111336)
			(xy 158.456278 -279.154913) (xy 158.471862 -279.201594) (xy 158.479757 -279.250171) (xy 158.480252 -279.274778)
			(xy 158.479757 -279.299385) (xy 158.471862 -279.347962) (xy 158.456278 -279.394643) (xy 158.433407 -279.43822)
			(xy 158.403842 -279.477564) (xy 158.368349 -279.511656) (xy 158.327846 -279.539612) (xy 158.283384 -279.56071)
			(xy 158.236113 -279.574402) (xy 158.187258 -279.580334) (xy 158.138083 -279.578353) (xy 158.089864 -279.568509)
			(xy 158.043848 -279.551057) (xy 158.001227 -279.52645) (xy 157.963106 -279.495325) (xy 157.930471 -279.458488)
			(xy 157.904168 -279.416892) (xy 157.884877 -279.371616) (xy 157.8731 -279.323832) (xy 157.86914 -279.274778)
			(xy 157.530292 -279.274778) (xy 157.529797 -279.299385) (xy 157.521902 -279.347962) (xy 157.506318 -279.394643)
			(xy 157.483447 -279.43822) (xy 157.453882 -279.477564) (xy 157.418389 -279.511656) (xy 157.377886 -279.539612)
			(xy 157.333424 -279.56071) (xy 157.286153 -279.574402) (xy 157.237298 -279.580334) (xy 157.188123 -279.578353)
			(xy 157.139904 -279.568509) (xy 157.093888 -279.551057) (xy 157.051267 -279.52645) (xy 157.013146 -279.495325)
			(xy 156.980511 -279.458488) (xy 156.954208 -279.416892) (xy 156.934917 -279.371616) (xy 156.92314 -279.323832)
			(xy 156.91918 -279.274778) (xy 156.580332 -279.274778) (xy 156.579837 -279.299385) (xy 156.571942 -279.347962)
			(xy 156.556358 -279.394643) (xy 156.533487 -279.43822) (xy 156.503922 -279.477564) (xy 156.468429 -279.511656)
			(xy 156.427926 -279.539612) (xy 156.383464 -279.56071) (xy 156.336193 -279.574402) (xy 156.287338 -279.580334)
			(xy 156.238163 -279.578353) (xy 156.189944 -279.568509) (xy 156.143928 -279.551057) (xy 156.101307 -279.52645)
			(xy 156.063186 -279.495325) (xy 156.030551 -279.458488) (xy 156.004248 -279.416892) (xy 155.984957 -279.371616)
			(xy 155.97318 -279.323832) (xy 155.96922 -279.274778) (xy 155.630372 -279.274778) (xy 155.629877 -279.299385)
			(xy 155.621982 -279.347962) (xy 155.606398 -279.394643) (xy 155.583527 -279.43822) (xy 155.553962 -279.477564)
			(xy 155.518469 -279.511656) (xy 155.477966 -279.539612) (xy 155.433504 -279.56071) (xy 155.386233 -279.574402)
			(xy 155.337378 -279.580334) (xy 155.288203 -279.578353) (xy 155.239984 -279.568509) (xy 155.193968 -279.551057)
			(xy 155.151347 -279.52645) (xy 155.113226 -279.495325) (xy 155.080591 -279.458488) (xy 155.054288 -279.416892)
			(xy 155.034997 -279.371616) (xy 155.02322 -279.323832) (xy 155.01926 -279.274778) (xy 154.680412 -279.274778)
			(xy 154.679917 -279.299385) (xy 154.672022 -279.347962) (xy 154.656438 -279.394643) (xy 154.633567 -279.43822)
			(xy 154.604002 -279.477564) (xy 154.568509 -279.511656) (xy 154.528006 -279.539612) (xy 154.483544 -279.56071)
			(xy 154.436273 -279.574402) (xy 154.387418 -279.580334) (xy 154.338243 -279.578353) (xy 154.290024 -279.568509)
			(xy 154.244008 -279.551057) (xy 154.201387 -279.52645) (xy 154.163266 -279.495325) (xy 154.130631 -279.458488)
			(xy 154.104328 -279.416892) (xy 154.085037 -279.371616) (xy 154.07326 -279.323832) (xy 154.0693 -279.274778)
			(xy 153.730198 -279.274778) (xy 153.729703 -279.299385) (xy 153.721808 -279.347962) (xy 153.706224 -279.394643)
			(xy 153.683353 -279.43822) (xy 153.653788 -279.477564) (xy 153.618295 -279.511656) (xy 153.577792 -279.539612)
			(xy 153.53333 -279.56071) (xy 153.486059 -279.574402) (xy 153.437204 -279.580334) (xy 153.388029 -279.578353)
			(xy 153.33981 -279.568509) (xy 153.293794 -279.551057) (xy 153.251173 -279.52645) (xy 153.213052 -279.495325)
			(xy 153.180417 -279.458488) (xy 153.154114 -279.416892) (xy 153.134823 -279.371616) (xy 153.123046 -279.323832)
			(xy 153.119086 -279.274778) (xy 152.780238 -279.274778) (xy 152.779743 -279.299385) (xy 152.771848 -279.347962)
			(xy 152.756264 -279.394643) (xy 152.733393 -279.43822) (xy 152.703828 -279.477564) (xy 152.668335 -279.511656)
			(xy 152.627832 -279.539612) (xy 152.58337 -279.56071) (xy 152.536099 -279.574402) (xy 152.487244 -279.580334)
			(xy 152.438069 -279.578353) (xy 152.38985 -279.568509) (xy 152.343834 -279.551057) (xy 152.301213 -279.52645)
			(xy 152.263092 -279.495325) (xy 152.230457 -279.458488) (xy 152.204154 -279.416892) (xy 152.184863 -279.371616)
			(xy 152.173086 -279.323832) (xy 152.169126 -279.274778) (xy 137.119982 -279.274778) (xy 136.990561 -279.307195)
			(xy 136.827888 -279.339552) (xy 136.663823 -279.363887) (xy 136.498762 -279.380143) (xy 136.333102 -279.38828)
			(xy 136.250172 -279.388824) (xy 136.169834 -279.38834) (xy 136.009341 -279.380688) (xy 135.849392 -279.365418)
			(xy 135.690351 -279.342563) (xy 135.532575 -279.312175) (xy 135.376421 -279.274324) (xy 135.299196 -279.252172)
			(xy 135.298688 -279.252172) (xy 135.287262 -279.2495) (xy 135.26421 -279.253726) (xy 135.254492 -279.2603)
			(xy 135.22198 -279.284684) (xy 135.187944 -279.310084) (xy 135.179429 -279.317715) (xy 135.169533 -279.338292)
			(xy 135.168894 -279.349708) (xy 135.168894 -279.931114) (xy 141.911576 -279.931114) (xy 141.915647 -279.875492)
			(xy 141.927773 -279.821055) (xy 141.947696 -279.768964) (xy 141.974992 -279.720329) (xy 142.009078 -279.676186)
			(xy 142.049227 -279.637477) (xy 142.094585 -279.605026) (xy 142.144185 -279.579525) (xy 142.196969 -279.561518)
			(xy 142.251812 -279.551388) (xy 142.307546 -279.549351) (xy 142.362983 -279.555451) (xy 142.41694 -279.569557)
			(xy 142.468269 -279.591369) (xy 142.515875 -279.620423) (xy 142.558743 -279.656098) (xy 142.59596 -279.697635)
			(xy 142.626733 -279.744148) (xy 142.650405 -279.794645) (xy 142.666473 -279.848052) (xy 142.674593 -279.903228)
			(xy 142.675102 -279.931114) (xy 143.387062 -279.931114) (xy 143.391133 -279.875492) (xy 143.403259 -279.821055)
			(xy 143.423182 -279.768964) (xy 143.450478 -279.720329) (xy 143.484564 -279.676186) (xy 143.524713 -279.637477)
			(xy 143.570071 -279.605026) (xy 143.619671 -279.579525) (xy 143.672455 -279.561518) (xy 143.727298 -279.551388)
			(xy 143.783032 -279.549351) (xy 143.838469 -279.555451) (xy 143.892426 -279.569557) (xy 143.943755 -279.591369)
			(xy 143.991361 -279.620423) (xy 144.034229 -279.656098) (xy 144.071446 -279.697635) (xy 144.102219 -279.744148)
			(xy 144.125891 -279.794645) (xy 144.141959 -279.848052) (xy 144.150079 -279.903228) (xy 144.150588 -279.931114)
			(xy 144.276062 -279.931114) (xy 144.280133 -279.875492) (xy 144.292259 -279.821055) (xy 144.312182 -279.768964)
			(xy 144.339478 -279.720329) (xy 144.373564 -279.676186) (xy 144.413713 -279.637477) (xy 144.459071 -279.605026)
			(xy 144.508671 -279.579525) (xy 144.561455 -279.561518) (xy 144.616298 -279.551388) (xy 144.672032 -279.549351)
			(xy 144.727469 -279.555451) (xy 144.781426 -279.569557) (xy 144.832755 -279.591369) (xy 144.880361 -279.620423)
			(xy 144.923229 -279.656098) (xy 144.960446 -279.697635) (xy 144.991219 -279.744148) (xy 145.014891 -279.794645)
			(xy 145.030959 -279.848052) (xy 145.039079 -279.903228) (xy 145.039588 -279.931114) (xy 145.039079 -279.959)
			(xy 145.030959 -280.014176) (xy 145.014891 -280.067583) (xy 144.991219 -280.11808) (xy 144.960446 -280.164593)
			(xy 144.923229 -280.20613) (xy 144.880361 -280.241805) (xy 144.832755 -280.270859) (xy 144.781426 -280.292671)
			(xy 144.727469 -280.306777) (xy 144.672032 -280.312877) (xy 144.616298 -280.31084) (xy 144.561455 -280.30071)
			(xy 144.508671 -280.282703) (xy 144.459071 -280.257202) (xy 144.413713 -280.224751) (xy 144.373564 -280.186042)
			(xy 144.339478 -280.141899) (xy 144.312182 -280.093264) (xy 144.292259 -280.041173) (xy 144.280133 -279.986736)
			(xy 144.276062 -279.931114) (xy 144.150588 -279.931114) (xy 144.150079 -279.959) (xy 144.141959 -280.014176)
			(xy 144.125891 -280.067583) (xy 144.102219 -280.11808) (xy 144.071446 -280.164593) (xy 144.034229 -280.20613)
			(xy 143.991361 -280.241805) (xy 143.943755 -280.270859) (xy 143.892426 -280.292671) (xy 143.838469 -280.306777)
			(xy 143.783032 -280.312877) (xy 143.727298 -280.31084) (xy 143.672455 -280.30071) (xy 143.619671 -280.282703)
			(xy 143.570071 -280.257202) (xy 143.524713 -280.224751) (xy 143.484564 -280.186042) (xy 143.450478 -280.141899)
			(xy 143.423182 -280.093264) (xy 143.403259 -280.041173) (xy 143.391133 -279.986736) (xy 143.387062 -279.931114)
			(xy 142.675102 -279.931114) (xy 142.674593 -279.959) (xy 142.666473 -280.014176) (xy 142.650405 -280.067583)
			(xy 142.626733 -280.11808) (xy 142.59596 -280.164593) (xy 142.558743 -280.20613) (xy 142.515875 -280.241805)
			(xy 142.468269 -280.270859) (xy 142.41694 -280.292671) (xy 142.362983 -280.306777) (xy 142.307546 -280.312877)
			(xy 142.251812 -280.31084) (xy 142.196969 -280.30071) (xy 142.144185 -280.282703) (xy 142.094585 -280.257202)
			(xy 142.049227 -280.224751) (xy 142.009078 -280.186042) (xy 141.974992 -280.141899) (xy 141.947696 -280.093264)
			(xy 141.927773 -280.041173) (xy 141.915647 -279.986736) (xy 141.911576 -279.931114) (xy 135.168894 -279.931114)
			(xy 135.168894 -280.693114) (xy 147.43811 -280.693114) (xy 147.438654 -280.663732) (xy 147.447683 -280.605665)
			(xy 147.465514 -280.549671) (xy 147.491725 -280.497075) (xy 147.525695 -280.449124) (xy 147.56662 -280.406952)
			(xy 147.589748 -280.388822) (xy 147.598672 -280.381342) (xy 147.609132 -280.360568) (xy 147.609814 -280.348944)
			(xy 147.611084 -280.256996) (xy 147.601178 -280.235914) (xy 147.592034 -280.228548) (xy 147.570186 -280.210342)
			(xy 147.531644 -280.168524) (xy 147.499736 -280.121449) (xy 147.475169 -280.070159) (xy 147.458486 -280.015791)
			(xy 147.450058 -279.959549) (xy 147.44954 -279.931114) (xy 147.450026 -279.903863) (xy 147.457782 -279.849915)
			(xy 147.473137 -279.79762) (xy 147.495779 -279.748043) (xy 147.525245 -279.702193) (xy 147.560936 -279.661002)
			(xy 147.602127 -279.625311) (xy 147.647977 -279.595845) (xy 147.697554 -279.573203) (xy 147.749849 -279.557848)
			(xy 147.803797 -279.550092) (xy 147.858299 -279.550092) (xy 147.912247 -279.557848) (xy 147.964542 -279.573203)
			(xy 148.014119 -279.595845) (xy 148.059969 -279.625311) (xy 148.10116 -279.661002) (xy 148.136851 -279.702193)
			(xy 148.166317 -279.748043) (xy 148.188959 -279.79762) (xy 148.204314 -279.849915) (xy 148.21207 -279.903863)
			(xy 148.212556 -279.931114) (xy 148.212006 -279.960496) (xy 148.202975 -280.018561) (xy 148.185143 -280.074554)
			(xy 148.158933 -280.127149) (xy 148.124966 -280.175101) (xy 148.084044 -280.217274) (xy 148.074524 -280.224738)
			(xy 152.169126 -280.224738) (xy 152.173086 -280.175684) (xy 152.184863 -280.1279) (xy 152.204154 -280.082624)
			(xy 152.230457 -280.041028) (xy 152.263092 -280.004191) (xy 152.301213 -279.973066) (xy 152.343834 -279.948459)
			(xy 152.38985 -279.931007) (xy 152.438069 -279.921163) (xy 152.487244 -279.919182) (xy 152.536099 -279.925114)
			(xy 152.58337 -279.938806) (xy 152.627832 -279.959904) (xy 152.668335 -279.98786) (xy 152.703828 -280.021952)
			(xy 152.733393 -280.061296) (xy 152.756264 -280.104873) (xy 152.771848 -280.151554) (xy 152.779743 -280.200131)
			(xy 152.780238 -280.224738) (xy 153.119086 -280.224738) (xy 153.123046 -280.175684) (xy 153.134823 -280.1279)
			(xy 153.154114 -280.082624) (xy 153.180417 -280.041028) (xy 153.213052 -280.004191) (xy 153.251173 -279.973066)
			(xy 153.293794 -279.948459) (xy 153.33981 -279.931007) (xy 153.388029 -279.921163) (xy 153.437204 -279.919182)
			(xy 153.486059 -279.925114) (xy 153.53333 -279.938806) (xy 153.577792 -279.959904) (xy 153.618295 -279.98786)
			(xy 153.653788 -280.021952) (xy 153.683353 -280.061296) (xy 153.706224 -280.104873) (xy 153.721808 -280.151554)
			(xy 153.729703 -280.200131) (xy 153.730198 -280.224738) (xy 154.0693 -280.224738) (xy 154.07326 -280.175684)
			(xy 154.085037 -280.1279) (xy 154.104328 -280.082624) (xy 154.130631 -280.041028) (xy 154.163266 -280.004191)
			(xy 154.201387 -279.973066) (xy 154.244008 -279.948459) (xy 154.290024 -279.931007) (xy 154.338243 -279.921163)
			(xy 154.387418 -279.919182) (xy 154.436273 -279.925114) (xy 154.483544 -279.938806) (xy 154.528006 -279.959904)
			(xy 154.568509 -279.98786) (xy 154.604002 -280.021952) (xy 154.633567 -280.061296) (xy 154.656438 -280.104873)
			(xy 154.672022 -280.151554) (xy 154.679917 -280.200131) (xy 154.680412 -280.224738) (xy 155.01926 -280.224738)
			(xy 155.02322 -280.175684) (xy 155.034997 -280.1279) (xy 155.054288 -280.082624) (xy 155.080591 -280.041028)
			(xy 155.113226 -280.004191) (xy 155.151347 -279.973066) (xy 155.193968 -279.948459) (xy 155.239984 -279.931007)
			(xy 155.288203 -279.921163) (xy 155.337378 -279.919182) (xy 155.386233 -279.925114) (xy 155.433504 -279.938806)
			(xy 155.477966 -279.959904) (xy 155.518469 -279.98786) (xy 155.553962 -280.021952) (xy 155.583527 -280.061296)
			(xy 155.606398 -280.104873) (xy 155.621982 -280.151554) (xy 155.629877 -280.200131) (xy 155.630372 -280.224738)
			(xy 155.96922 -280.224738) (xy 155.97318 -280.175684) (xy 155.984957 -280.1279) (xy 156.004248 -280.082624)
			(xy 156.030551 -280.041028) (xy 156.063186 -280.004191) (xy 156.101307 -279.973066) (xy 156.143928 -279.948459)
			(xy 156.189944 -279.931007) (xy 156.238163 -279.921163) (xy 156.287338 -279.919182) (xy 156.336193 -279.925114)
			(xy 156.383464 -279.938806) (xy 156.427926 -279.959904) (xy 156.468429 -279.98786) (xy 156.503922 -280.021952)
			(xy 156.533487 -280.061296) (xy 156.556358 -280.104873) (xy 156.571942 -280.151554) (xy 156.579837 -280.200131)
			(xy 156.580332 -280.224738) (xy 156.91918 -280.224738) (xy 156.92314 -280.175684) (xy 156.934917 -280.1279)
			(xy 156.954208 -280.082624) (xy 156.980511 -280.041028) (xy 157.013146 -280.004191) (xy 157.051267 -279.973066)
			(xy 157.093888 -279.948459) (xy 157.139904 -279.931007) (xy 157.188123 -279.921163) (xy 157.237298 -279.919182)
			(xy 157.286153 -279.925114) (xy 157.333424 -279.938806) (xy 157.377886 -279.959904) (xy 157.418389 -279.98786)
			(xy 157.453882 -280.021952) (xy 157.483447 -280.061296) (xy 157.506318 -280.104873) (xy 157.521902 -280.151554)
			(xy 157.529797 -280.200131) (xy 157.530292 -280.224738) (xy 157.86914 -280.224738) (xy 157.8731 -280.175684)
			(xy 157.884877 -280.1279) (xy 157.904168 -280.082624) (xy 157.930471 -280.041028) (xy 157.963106 -280.004191)
			(xy 158.001227 -279.973066) (xy 158.043848 -279.948459) (xy 158.089864 -279.931007) (xy 158.138083 -279.921163)
			(xy 158.187258 -279.919182) (xy 158.236113 -279.925114) (xy 158.283384 -279.938806) (xy 158.327846 -279.959904)
			(xy 158.368349 -279.98786) (xy 158.403842 -280.021952) (xy 158.433407 -280.061296) (xy 158.456278 -280.104873)
			(xy 158.471862 -280.151554) (xy 158.479757 -280.200131) (xy 158.480252 -280.224738) (xy 158.8191 -280.224738)
			(xy 158.82306 -280.175684) (xy 158.834837 -280.1279) (xy 158.854128 -280.082624) (xy 158.880431 -280.041028)
			(xy 158.913066 -280.004191) (xy 158.951187 -279.973066) (xy 158.993808 -279.948459) (xy 159.039824 -279.931007)
			(xy 159.088043 -279.921163) (xy 159.137218 -279.919182) (xy 159.186073 -279.925114) (xy 159.233344 -279.938806)
			(xy 159.277806 -279.959904) (xy 159.318309 -279.98786) (xy 159.353802 -280.021952) (xy 159.383367 -280.061296)
			(xy 159.406238 -280.104873) (xy 159.421822 -280.151554) (xy 159.429717 -280.200131) (xy 159.430212 -280.224738)
			(xy 159.429717 -280.249345) (xy 159.421822 -280.297922) (xy 159.406238 -280.344603) (xy 159.383367 -280.38818)
			(xy 159.353802 -280.427524) (xy 159.318309 -280.461616) (xy 159.277806 -280.489572) (xy 159.233344 -280.51067)
			(xy 159.186073 -280.524362) (xy 159.137218 -280.530294) (xy 159.088043 -280.528313) (xy 159.039824 -280.518469)
			(xy 158.993808 -280.501017) (xy 158.951187 -280.47641) (xy 158.913066 -280.445285) (xy 158.880431 -280.408448)
			(xy 158.854128 -280.366852) (xy 158.834837 -280.321576) (xy 158.82306 -280.273792) (xy 158.8191 -280.224738)
			(xy 158.480252 -280.224738) (xy 158.479757 -280.249345) (xy 158.471862 -280.297922) (xy 158.456278 -280.344603)
			(xy 158.433407 -280.38818) (xy 158.403842 -280.427524) (xy 158.368349 -280.461616) (xy 158.327846 -280.489572)
			(xy 158.283384 -280.51067) (xy 158.236113 -280.524362) (xy 158.187258 -280.530294) (xy 158.138083 -280.528313)
			(xy 158.089864 -280.518469) (xy 158.043848 -280.501017) (xy 158.001227 -280.47641) (xy 157.963106 -280.445285)
			(xy 157.930471 -280.408448) (xy 157.904168 -280.366852) (xy 157.884877 -280.321576) (xy 157.8731 -280.273792)
			(xy 157.86914 -280.224738) (xy 157.530292 -280.224738) (xy 157.529797 -280.249345) (xy 157.521902 -280.297922)
			(xy 157.506318 -280.344603) (xy 157.483447 -280.38818) (xy 157.453882 -280.427524) (xy 157.418389 -280.461616)
			(xy 157.377886 -280.489572) (xy 157.333424 -280.51067) (xy 157.286153 -280.524362) (xy 157.237298 -280.530294)
			(xy 157.188123 -280.528313) (xy 157.139904 -280.518469) (xy 157.093888 -280.501017) (xy 157.051267 -280.47641)
			(xy 157.013146 -280.445285) (xy 156.980511 -280.408448) (xy 156.954208 -280.366852) (xy 156.934917 -280.321576)
			(xy 156.92314 -280.273792) (xy 156.91918 -280.224738) (xy 156.580332 -280.224738) (xy 156.579837 -280.249345)
			(xy 156.571942 -280.297922) (xy 156.556358 -280.344603) (xy 156.533487 -280.38818) (xy 156.503922 -280.427524)
			(xy 156.468429 -280.461616) (xy 156.427926 -280.489572) (xy 156.383464 -280.51067) (xy 156.336193 -280.524362)
			(xy 156.287338 -280.530294) (xy 156.238163 -280.528313) (xy 156.189944 -280.518469) (xy 156.143928 -280.501017)
			(xy 156.101307 -280.47641) (xy 156.063186 -280.445285) (xy 156.030551 -280.408448) (xy 156.004248 -280.366852)
			(xy 155.984957 -280.321576) (xy 155.97318 -280.273792) (xy 155.96922 -280.224738) (xy 155.630372 -280.224738)
			(xy 155.629877 -280.249345) (xy 155.621982 -280.297922) (xy 155.606398 -280.344603) (xy 155.583527 -280.38818)
			(xy 155.553962 -280.427524) (xy 155.518469 -280.461616) (xy 155.477966 -280.489572) (xy 155.433504 -280.51067)
			(xy 155.386233 -280.524362) (xy 155.337378 -280.530294) (xy 155.288203 -280.528313) (xy 155.239984 -280.518469)
			(xy 155.193968 -280.501017) (xy 155.151347 -280.47641) (xy 155.113226 -280.445285) (xy 155.080591 -280.408448)
			(xy 155.054288 -280.366852) (xy 155.034997 -280.321576) (xy 155.02322 -280.273792) (xy 155.01926 -280.224738)
			(xy 154.680412 -280.224738) (xy 154.679917 -280.249345) (xy 154.672022 -280.297922) (xy 154.656438 -280.344603)
			(xy 154.633567 -280.38818) (xy 154.604002 -280.427524) (xy 154.568509 -280.461616) (xy 154.528006 -280.489572)
			(xy 154.483544 -280.51067) (xy 154.436273 -280.524362) (xy 154.387418 -280.530294) (xy 154.338243 -280.528313)
			(xy 154.290024 -280.518469) (xy 154.244008 -280.501017) (xy 154.201387 -280.47641) (xy 154.163266 -280.445285)
			(xy 154.130631 -280.408448) (xy 154.104328 -280.366852) (xy 154.085037 -280.321576) (xy 154.07326 -280.273792)
			(xy 154.0693 -280.224738) (xy 153.730198 -280.224738) (xy 153.729703 -280.249345) (xy 153.721808 -280.297922)
			(xy 153.706224 -280.344603) (xy 153.683353 -280.38818) (xy 153.653788 -280.427524) (xy 153.618295 -280.461616)
			(xy 153.577792 -280.489572) (xy 153.53333 -280.51067) (xy 153.486059 -280.524362) (xy 153.437204 -280.530294)
			(xy 153.388029 -280.528313) (xy 153.33981 -280.518469) (xy 153.293794 -280.501017) (xy 153.251173 -280.47641)
			(xy 153.213052 -280.445285) (xy 153.180417 -280.408448) (xy 153.154114 -280.366852) (xy 153.134823 -280.321576)
			(xy 153.123046 -280.273792) (xy 153.119086 -280.224738) (xy 152.780238 -280.224738) (xy 152.779743 -280.249345)
			(xy 152.771848 -280.297922) (xy 152.756264 -280.344603) (xy 152.733393 -280.38818) (xy 152.703828 -280.427524)
			(xy 152.668335 -280.461616) (xy 152.627832 -280.489572) (xy 152.58337 -280.51067) (xy 152.536099 -280.524362)
			(xy 152.487244 -280.530294) (xy 152.438069 -280.528313) (xy 152.38985 -280.518469) (xy 152.343834 -280.501017)
			(xy 152.301213 -280.47641) (xy 152.263092 -280.445285) (xy 152.230457 -280.408448) (xy 152.204154 -280.366852)
			(xy 152.184863 -280.321576) (xy 152.173086 -280.273792) (xy 152.169126 -280.224738) (xy 148.074524 -280.224738)
			(xy 148.060918 -280.235406) (xy 148.051975 -280.242867) (xy 148.041527 -280.263656) (xy 148.040852 -280.275284)
			(xy 148.039582 -280.367232) (xy 148.049488 -280.388314) (xy 148.058632 -280.39568) (xy 148.080459 -280.413909)
			(xy 148.118999 -280.455724) (xy 148.150908 -280.502795) (xy 148.175478 -280.55408) (xy 148.192166 -280.608443)
			(xy 148.200603 -280.664681) (xy 148.201126 -280.693114) (xy 148.8346 -280.693114) (xy 148.838671 -280.637492)
			(xy 148.850797 -280.583055) (xy 148.87072 -280.530964) (xy 148.898016 -280.482329) (xy 148.932102 -280.438186)
			(xy 148.972251 -280.399477) (xy 149.017609 -280.367026) (xy 149.067209 -280.341525) (xy 149.119993 -280.323518)
			(xy 149.174836 -280.313388) (xy 149.23057 -280.311351) (xy 149.286007 -280.317451) (xy 149.339964 -280.331557)
			(xy 149.391293 -280.353369) (xy 149.438899 -280.382423) (xy 149.481767 -280.418098) (xy 149.518984 -280.459635)
			(xy 149.549757 -280.506148) (xy 149.573429 -280.556645) (xy 149.589497 -280.610052) (xy 149.597617 -280.665228)
			(xy 149.598126 -280.693114) (xy 149.72106 -280.693114) (xy 149.725131 -280.637492) (xy 149.737257 -280.583055)
			(xy 149.75718 -280.530964) (xy 149.784476 -280.482329) (xy 149.818562 -280.438186) (xy 149.858711 -280.399477)
			(xy 149.904069 -280.367026) (xy 149.953669 -280.341525) (xy 150.006453 -280.323518) (xy 150.061296 -280.313388)
			(xy 150.11703 -280.311351) (xy 150.172467 -280.317451) (xy 150.226424 -280.331557) (xy 150.277753 -280.353369)
			(xy 150.325359 -280.382423) (xy 150.368227 -280.418098) (xy 150.405444 -280.459635) (xy 150.436217 -280.506148)
			(xy 150.459889 -280.556645) (xy 150.475957 -280.610052) (xy 150.484077 -280.665228) (xy 150.484586 -280.693114)
			(xy 150.484077 -280.721) (xy 150.475957 -280.776176) (xy 150.459889 -280.829583) (xy 150.436217 -280.88008)
			(xy 150.405444 -280.926593) (xy 150.368227 -280.96813) (xy 150.325359 -281.003805) (xy 150.277753 -281.032859)
			(xy 150.226424 -281.054671) (xy 150.172467 -281.068777) (xy 150.11703 -281.074877) (xy 150.061296 -281.07284)
			(xy 150.006453 -281.06271) (xy 149.953669 -281.044703) (xy 149.904069 -281.019202) (xy 149.858711 -280.986751)
			(xy 149.818562 -280.948042) (xy 149.784476 -280.903899) (xy 149.75718 -280.855264) (xy 149.737257 -280.803173)
			(xy 149.725131 -280.748736) (xy 149.72106 -280.693114) (xy 149.598126 -280.693114) (xy 149.597617 -280.721)
			(xy 149.589497 -280.776176) (xy 149.573429 -280.829583) (xy 149.549757 -280.88008) (xy 149.518984 -280.926593)
			(xy 149.481767 -280.96813) (xy 149.438899 -281.003805) (xy 149.391293 -281.032859) (xy 149.339964 -281.054671)
			(xy 149.286007 -281.068777) (xy 149.23057 -281.074877) (xy 149.174836 -281.07284) (xy 149.119993 -281.06271)
			(xy 149.067209 -281.044703) (xy 149.017609 -281.019202) (xy 148.972251 -280.986751) (xy 148.932102 -280.948042)
			(xy 148.898016 -280.903899) (xy 148.87072 -280.855264) (xy 148.850797 -280.803173) (xy 148.838671 -280.748736)
			(xy 148.8346 -280.693114) (xy 148.201126 -280.693114) (xy 148.20064 -280.720365) (xy 148.192884 -280.774313)
			(xy 148.177529 -280.826608) (xy 148.154887 -280.876185) (xy 148.125421 -280.922035) (xy 148.08973 -280.963226)
			(xy 148.048539 -280.998917) (xy 148.002689 -281.028383) (xy 147.953112 -281.051025) (xy 147.900817 -281.06638)
			(xy 147.846869 -281.074136) (xy 147.792367 -281.074136) (xy 147.738419 -281.06638) (xy 147.686124 -281.051025)
			(xy 147.636547 -281.028383) (xy 147.590697 -280.998917) (xy 147.549506 -280.963226) (xy 147.513815 -280.922035)
			(xy 147.484349 -280.876185) (xy 147.461707 -280.826608) (xy 147.446352 -280.774313) (xy 147.438596 -280.720365)
			(xy 147.43811 -280.693114) (xy 135.168894 -280.693114) (xy 135.168894 -281.174952) (xy 152.169126 -281.174952)
			(xy 152.173086 -281.125898) (xy 152.184863 -281.078114) (xy 152.204154 -281.032838) (xy 152.230457 -280.991242)
			(xy 152.263092 -280.954405) (xy 152.301213 -280.92328) (xy 152.343834 -280.898673) (xy 152.38985 -280.881221)
			(xy 152.438069 -280.871377) (xy 152.487244 -280.869396) (xy 152.536099 -280.875328) (xy 152.58337 -280.88902)
			(xy 152.627832 -280.910118) (xy 152.668335 -280.938074) (xy 152.703828 -280.972166) (xy 152.733393 -281.01151)
			(xy 152.756264 -281.055087) (xy 152.771848 -281.101768) (xy 152.779743 -281.150345) (xy 152.780238 -281.174952)
			(xy 153.119086 -281.174952) (xy 153.123046 -281.125898) (xy 153.134823 -281.078114) (xy 153.154114 -281.032838)
			(xy 153.180417 -280.991242) (xy 153.213052 -280.954405) (xy 153.251173 -280.92328) (xy 153.293794 -280.898673)
			(xy 153.33981 -280.881221) (xy 153.388029 -280.871377) (xy 153.437204 -280.869396) (xy 153.486059 -280.875328)
			(xy 153.53333 -280.88902) (xy 153.577792 -280.910118) (xy 153.618295 -280.938074) (xy 153.653788 -280.972166)
			(xy 153.683353 -281.01151) (xy 153.706224 -281.055087) (xy 153.721808 -281.101768) (xy 153.729703 -281.150345)
			(xy 153.730198 -281.174952) (xy 154.0693 -281.174952) (xy 154.07326 -281.125898) (xy 154.085037 -281.078114)
			(xy 154.104328 -281.032838) (xy 154.130631 -280.991242) (xy 154.163266 -280.954405) (xy 154.201387 -280.92328)
			(xy 154.244008 -280.898673) (xy 154.290024 -280.881221) (xy 154.338243 -280.871377) (xy 154.387418 -280.869396)
			(xy 154.436273 -280.875328) (xy 154.483544 -280.88902) (xy 154.528006 -280.910118) (xy 154.568509 -280.938074)
			(xy 154.604002 -280.972166) (xy 154.633567 -281.01151) (xy 154.656438 -281.055087) (xy 154.672022 -281.101768)
			(xy 154.679917 -281.150345) (xy 154.680412 -281.174952) (xy 155.01926 -281.174952) (xy 155.02322 -281.125898)
			(xy 155.034997 -281.078114) (xy 155.054288 -281.032838) (xy 155.080591 -280.991242) (xy 155.113226 -280.954405)
			(xy 155.151347 -280.92328) (xy 155.193968 -280.898673) (xy 155.239984 -280.881221) (xy 155.288203 -280.871377)
			(xy 155.337378 -280.869396) (xy 155.386233 -280.875328) (xy 155.433504 -280.88902) (xy 155.477966 -280.910118)
			(xy 155.518469 -280.938074) (xy 155.553962 -280.972166) (xy 155.583527 -281.01151) (xy 155.606398 -281.055087)
			(xy 155.621982 -281.101768) (xy 155.629877 -281.150345) (xy 155.630372 -281.174952) (xy 155.96922 -281.174952)
			(xy 155.97318 -281.125898) (xy 155.984957 -281.078114) (xy 156.004248 -281.032838) (xy 156.030551 -280.991242)
			(xy 156.063186 -280.954405) (xy 156.101307 -280.92328) (xy 156.143928 -280.898673) (xy 156.189944 -280.881221)
			(xy 156.238163 -280.871377) (xy 156.287338 -280.869396) (xy 156.336193 -280.875328) (xy 156.383464 -280.88902)
			(xy 156.427926 -280.910118) (xy 156.468429 -280.938074) (xy 156.503922 -280.972166) (xy 156.533487 -281.01151)
			(xy 156.556358 -281.055087) (xy 156.571942 -281.101768) (xy 156.579837 -281.150345) (xy 156.580332 -281.174952)
			(xy 156.91918 -281.174952) (xy 156.92314 -281.125898) (xy 156.934917 -281.078114) (xy 156.954208 -281.032838)
			(xy 156.980511 -280.991242) (xy 157.013146 -280.954405) (xy 157.051267 -280.92328) (xy 157.093888 -280.898673)
			(xy 157.139904 -280.881221) (xy 157.188123 -280.871377) (xy 157.237298 -280.869396) (xy 157.286153 -280.875328)
			(xy 157.333424 -280.88902) (xy 157.377886 -280.910118) (xy 157.418389 -280.938074) (xy 157.453882 -280.972166)
			(xy 157.483447 -281.01151) (xy 157.506318 -281.055087) (xy 157.521902 -281.101768) (xy 157.529797 -281.150345)
			(xy 157.530292 -281.174952) (xy 157.86914 -281.174952) (xy 157.8731 -281.125898) (xy 157.884877 -281.078114)
			(xy 157.904168 -281.032838) (xy 157.930471 -280.991242) (xy 157.963106 -280.954405) (xy 158.001227 -280.92328)
			(xy 158.043848 -280.898673) (xy 158.089864 -280.881221) (xy 158.138083 -280.871377) (xy 158.187258 -280.869396)
			(xy 158.236113 -280.875328) (xy 158.283384 -280.88902) (xy 158.327846 -280.910118) (xy 158.368349 -280.938074)
			(xy 158.403842 -280.972166) (xy 158.433407 -281.01151) (xy 158.456278 -281.055087) (xy 158.471862 -281.101768)
			(xy 158.479757 -281.150345) (xy 158.480252 -281.174952) (xy 158.8191 -281.174952) (xy 158.82306 -281.125898)
			(xy 158.834837 -281.078114) (xy 158.854128 -281.032838) (xy 158.880431 -280.991242) (xy 158.913066 -280.954405)
			(xy 158.951187 -280.92328) (xy 158.993808 -280.898673) (xy 159.039824 -280.881221) (xy 159.088043 -280.871377)
			(xy 159.137218 -280.869396) (xy 159.186073 -280.875328) (xy 159.233344 -280.88902) (xy 159.277806 -280.910118)
			(xy 159.318309 -280.938074) (xy 159.353802 -280.972166) (xy 159.383367 -281.01151) (xy 159.406238 -281.055087)
			(xy 159.421822 -281.101768) (xy 159.429717 -281.150345) (xy 159.430212 -281.174952) (xy 159.429717 -281.199559)
			(xy 159.421822 -281.248136) (xy 159.406238 -281.294817) (xy 159.383367 -281.338394) (xy 159.353802 -281.377738)
			(xy 159.318309 -281.41183) (xy 159.277806 -281.439786) (xy 159.233344 -281.460884) (xy 159.186073 -281.474576)
			(xy 159.137218 -281.480508) (xy 159.088043 -281.478527) (xy 159.039824 -281.468683) (xy 158.993808 -281.451231)
			(xy 158.951187 -281.426624) (xy 158.913066 -281.395499) (xy 158.880431 -281.358662) (xy 158.854128 -281.317066)
			(xy 158.834837 -281.27179) (xy 158.82306 -281.224006) (xy 158.8191 -281.174952) (xy 158.480252 -281.174952)
			(xy 158.479757 -281.199559) (xy 158.471862 -281.248136) (xy 158.456278 -281.294817) (xy 158.433407 -281.338394)
			(xy 158.403842 -281.377738) (xy 158.368349 -281.41183) (xy 158.327846 -281.439786) (xy 158.283384 -281.460884)
			(xy 158.236113 -281.474576) (xy 158.187258 -281.480508) (xy 158.138083 -281.478527) (xy 158.089864 -281.468683)
			(xy 158.043848 -281.451231) (xy 158.001227 -281.426624) (xy 157.963106 -281.395499) (xy 157.930471 -281.358662)
			(xy 157.904168 -281.317066) (xy 157.884877 -281.27179) (xy 157.8731 -281.224006) (xy 157.86914 -281.174952)
			(xy 157.530292 -281.174952) (xy 157.529797 -281.199559) (xy 157.521902 -281.248136) (xy 157.506318 -281.294817)
			(xy 157.483447 -281.338394) (xy 157.453882 -281.377738) (xy 157.418389 -281.41183) (xy 157.377886 -281.439786)
			(xy 157.333424 -281.460884) (xy 157.286153 -281.474576) (xy 157.237298 -281.480508) (xy 157.188123 -281.478527)
			(xy 157.139904 -281.468683) (xy 157.093888 -281.451231) (xy 157.051267 -281.426624) (xy 157.013146 -281.395499)
			(xy 156.980511 -281.358662) (xy 156.954208 -281.317066) (xy 156.934917 -281.27179) (xy 156.92314 -281.224006)
			(xy 156.91918 -281.174952) (xy 156.580332 -281.174952) (xy 156.579837 -281.199559) (xy 156.571942 -281.248136)
			(xy 156.556358 -281.294817) (xy 156.533487 -281.338394) (xy 156.503922 -281.377738) (xy 156.468429 -281.41183)
			(xy 156.427926 -281.439786) (xy 156.383464 -281.460884) (xy 156.336193 -281.474576) (xy 156.287338 -281.480508)
			(xy 156.238163 -281.478527) (xy 156.189944 -281.468683) (xy 156.143928 -281.451231) (xy 156.101307 -281.426624)
			(xy 156.063186 -281.395499) (xy 156.030551 -281.358662) (xy 156.004248 -281.317066) (xy 155.984957 -281.27179)
			(xy 155.97318 -281.224006) (xy 155.96922 -281.174952) (xy 155.630372 -281.174952) (xy 155.629877 -281.199559)
			(xy 155.621982 -281.248136) (xy 155.606398 -281.294817) (xy 155.583527 -281.338394) (xy 155.553962 -281.377738)
			(xy 155.518469 -281.41183) (xy 155.477966 -281.439786) (xy 155.433504 -281.460884) (xy 155.386233 -281.474576)
			(xy 155.337378 -281.480508) (xy 155.288203 -281.478527) (xy 155.239984 -281.468683) (xy 155.193968 -281.451231)
			(xy 155.151347 -281.426624) (xy 155.113226 -281.395499) (xy 155.080591 -281.358662) (xy 155.054288 -281.317066)
			(xy 155.034997 -281.27179) (xy 155.02322 -281.224006) (xy 155.01926 -281.174952) (xy 154.680412 -281.174952)
			(xy 154.679917 -281.199559) (xy 154.672022 -281.248136) (xy 154.656438 -281.294817) (xy 154.633567 -281.338394)
			(xy 154.604002 -281.377738) (xy 154.568509 -281.41183) (xy 154.528006 -281.439786) (xy 154.483544 -281.460884)
			(xy 154.436273 -281.474576) (xy 154.387418 -281.480508) (xy 154.338243 -281.478527) (xy 154.290024 -281.468683)
			(xy 154.244008 -281.451231) (xy 154.201387 -281.426624) (xy 154.163266 -281.395499) (xy 154.130631 -281.358662)
			(xy 154.104328 -281.317066) (xy 154.085037 -281.27179) (xy 154.07326 -281.224006) (xy 154.0693 -281.174952)
			(xy 153.730198 -281.174952) (xy 153.729703 -281.199559) (xy 153.721808 -281.248136) (xy 153.706224 -281.294817)
			(xy 153.683353 -281.338394) (xy 153.653788 -281.377738) (xy 153.618295 -281.41183) (xy 153.577792 -281.439786)
			(xy 153.53333 -281.460884) (xy 153.486059 -281.474576) (xy 153.437204 -281.480508) (xy 153.388029 -281.478527)
			(xy 153.33981 -281.468683) (xy 153.293794 -281.451231) (xy 153.251173 -281.426624) (xy 153.213052 -281.395499)
			(xy 153.180417 -281.358662) (xy 153.154114 -281.317066) (xy 153.134823 -281.27179) (xy 153.123046 -281.224006)
			(xy 153.119086 -281.174952) (xy 152.780238 -281.174952) (xy 152.779743 -281.199559) (xy 152.771848 -281.248136)
			(xy 152.756264 -281.294817) (xy 152.733393 -281.338394) (xy 152.703828 -281.377738) (xy 152.668335 -281.41183)
			(xy 152.627832 -281.439786) (xy 152.58337 -281.460884) (xy 152.536099 -281.474576) (xy 152.487244 -281.480508)
			(xy 152.438069 -281.478527) (xy 152.38985 -281.468683) (xy 152.343834 -281.451231) (xy 152.301213 -281.426624)
			(xy 152.263092 -281.395499) (xy 152.230457 -281.358662) (xy 152.204154 -281.317066) (xy 152.184863 -281.27179)
			(xy 152.173086 -281.224006) (xy 152.169126 -281.174952) (xy 135.168894 -281.174952) (xy 135.168894 -281.829256)
			(xy 141.911576 -281.829256) (xy 141.915647 -281.773634) (xy 141.927773 -281.719197) (xy 141.947696 -281.667106)
			(xy 141.974992 -281.618471) (xy 142.009078 -281.574328) (xy 142.049227 -281.535619) (xy 142.094585 -281.503168)
			(xy 142.144185 -281.477667) (xy 142.196969 -281.45966) (xy 142.251812 -281.44953) (xy 142.307546 -281.447493)
			(xy 142.362983 -281.453593) (xy 142.41694 -281.467699) (xy 142.468269 -281.489511) (xy 142.515875 -281.518565)
			(xy 142.558743 -281.55424) (xy 142.59596 -281.595777) (xy 142.626733 -281.64229) (xy 142.650405 -281.692787)
			(xy 142.666473 -281.746194) (xy 142.674593 -281.80137) (xy 142.675102 -281.829256) (xy 143.396714 -281.829256)
			(xy 143.400785 -281.773634) (xy 143.412911 -281.719197) (xy 143.432834 -281.667106) (xy 143.46013 -281.618471)
			(xy 143.494216 -281.574328) (xy 143.534365 -281.535619) (xy 143.579723 -281.503168) (xy 143.629323 -281.477667)
			(xy 143.682107 -281.45966) (xy 143.73695 -281.44953) (xy 143.792684 -281.447493) (xy 143.848121 -281.453593)
			(xy 143.902078 -281.467699) (xy 143.953407 -281.489511) (xy 144.001013 -281.518565) (xy 144.043881 -281.55424)
			(xy 144.081098 -281.595777) (xy 144.111871 -281.64229) (xy 144.135543 -281.692787) (xy 144.151611 -281.746194)
			(xy 144.159731 -281.80137) (xy 144.16024 -281.829256) (xy 144.159731 -281.857142) (xy 144.151611 -281.912318)
			(xy 144.135543 -281.965725) (xy 144.111871 -282.016222) (xy 144.081098 -282.062735) (xy 144.043881 -282.104272)
			(xy 144.019079 -282.124912) (xy 152.169126 -282.124912) (xy 152.173086 -282.075858) (xy 152.184863 -282.028074)
			(xy 152.204154 -281.982798) (xy 152.230457 -281.941202) (xy 152.263092 -281.904365) (xy 152.301213 -281.87324)
			(xy 152.343834 -281.848633) (xy 152.38985 -281.831181) (xy 152.438069 -281.821337) (xy 152.487244 -281.819356)
			(xy 152.536099 -281.825288) (xy 152.58337 -281.83898) (xy 152.627832 -281.860078) (xy 152.668335 -281.888034)
			(xy 152.703828 -281.922126) (xy 152.733393 -281.96147) (xy 152.756264 -282.005047) (xy 152.771848 -282.051728)
			(xy 152.779743 -282.100305) (xy 152.780238 -282.124912) (xy 153.119086 -282.124912) (xy 153.123046 -282.075858)
			(xy 153.134823 -282.028074) (xy 153.154114 -281.982798) (xy 153.180417 -281.941202) (xy 153.213052 -281.904365)
			(xy 153.251173 -281.87324) (xy 153.293794 -281.848633) (xy 153.33981 -281.831181) (xy 153.388029 -281.821337)
			(xy 153.437204 -281.819356) (xy 153.486059 -281.825288) (xy 153.53333 -281.83898) (xy 153.577792 -281.860078)
			(xy 153.618295 -281.888034) (xy 153.653788 -281.922126) (xy 153.683353 -281.96147) (xy 153.706224 -282.005047)
			(xy 153.721808 -282.051728) (xy 153.729703 -282.100305) (xy 153.730198 -282.124912) (xy 154.0693 -282.124912)
			(xy 154.07326 -282.075858) (xy 154.085037 -282.028074) (xy 154.104328 -281.982798) (xy 154.130631 -281.941202)
			(xy 154.163266 -281.904365) (xy 154.201387 -281.87324) (xy 154.244008 -281.848633) (xy 154.290024 -281.831181)
			(xy 154.338243 -281.821337) (xy 154.387418 -281.819356) (xy 154.436273 -281.825288) (xy 154.483544 -281.83898)
			(xy 154.528006 -281.860078) (xy 154.568509 -281.888034) (xy 154.604002 -281.922126) (xy 154.633567 -281.96147)
			(xy 154.656438 -282.005047) (xy 154.672022 -282.051728) (xy 154.679917 -282.100305) (xy 154.680412 -282.124912)
			(xy 155.01926 -282.124912) (xy 155.02322 -282.075858) (xy 155.034997 -282.028074) (xy 155.054288 -281.982798)
			(xy 155.080591 -281.941202) (xy 155.113226 -281.904365) (xy 155.151347 -281.87324) (xy 155.193968 -281.848633)
			(xy 155.239984 -281.831181) (xy 155.288203 -281.821337) (xy 155.337378 -281.819356) (xy 155.386233 -281.825288)
			(xy 155.433504 -281.83898) (xy 155.477966 -281.860078) (xy 155.518469 -281.888034) (xy 155.553962 -281.922126)
			(xy 155.583527 -281.96147) (xy 155.606398 -282.005047) (xy 155.621982 -282.051728) (xy 155.629877 -282.100305)
			(xy 155.630372 -282.124912) (xy 155.96922 -282.124912) (xy 155.97318 -282.075858) (xy 155.984957 -282.028074)
			(xy 156.004248 -281.982798) (xy 156.030551 -281.941202) (xy 156.063186 -281.904365) (xy 156.101307 -281.87324)
			(xy 156.143928 -281.848633) (xy 156.189944 -281.831181) (xy 156.238163 -281.821337) (xy 156.287338 -281.819356)
			(xy 156.336193 -281.825288) (xy 156.383464 -281.83898) (xy 156.427926 -281.860078) (xy 156.468429 -281.888034)
			(xy 156.503922 -281.922126) (xy 156.533487 -281.96147) (xy 156.556358 -282.005047) (xy 156.571942 -282.051728)
			(xy 156.579837 -282.100305) (xy 156.580332 -282.124912) (xy 156.91918 -282.124912) (xy 156.92314 -282.075858)
			(xy 156.934917 -282.028074) (xy 156.954208 -281.982798) (xy 156.980511 -281.941202) (xy 157.013146 -281.904365)
			(xy 157.051267 -281.87324) (xy 157.093888 -281.848633) (xy 157.139904 -281.831181) (xy 157.188123 -281.821337)
			(xy 157.237298 -281.819356) (xy 157.286153 -281.825288) (xy 157.333424 -281.83898) (xy 157.377886 -281.860078)
			(xy 157.418389 -281.888034) (xy 157.453882 -281.922126) (xy 157.483447 -281.96147) (xy 157.506318 -282.005047)
			(xy 157.521902 -282.051728) (xy 157.529797 -282.100305) (xy 157.530292 -282.124912) (xy 157.86914 -282.124912)
			(xy 157.8731 -282.075858) (xy 157.884877 -282.028074) (xy 157.904168 -281.982798) (xy 157.930471 -281.941202)
			(xy 157.963106 -281.904365) (xy 158.001227 -281.87324) (xy 158.043848 -281.848633) (xy 158.089864 -281.831181)
			(xy 158.138083 -281.821337) (xy 158.187258 -281.819356) (xy 158.236113 -281.825288) (xy 158.283384 -281.83898)
			(xy 158.327846 -281.860078) (xy 158.368349 -281.888034) (xy 158.403842 -281.922126) (xy 158.433407 -281.96147)
			(xy 158.456278 -282.005047) (xy 158.471862 -282.051728) (xy 158.479757 -282.100305) (xy 158.480252 -282.124912)
			(xy 158.8191 -282.124912) (xy 158.82306 -282.075858) (xy 158.834837 -282.028074) (xy 158.854128 -281.982798)
			(xy 158.880431 -281.941202) (xy 158.913066 -281.904365) (xy 158.951187 -281.87324) (xy 158.993808 -281.848633)
			(xy 159.039824 -281.831181) (xy 159.088043 -281.821337) (xy 159.137218 -281.819356) (xy 159.186073 -281.825288)
			(xy 159.233344 -281.83898) (xy 159.277806 -281.860078) (xy 159.318309 -281.888034) (xy 159.353802 -281.922126)
			(xy 159.383367 -281.96147) (xy 159.406238 -282.005047) (xy 159.421822 -282.051728) (xy 159.429717 -282.100305)
			(xy 159.430046 -282.116639) (xy 159.769193 -282.116639) (xy 159.774556 -282.067291) (xy 159.787832 -282.019462)
			(xy 159.808671 -281.97441) (xy 159.836524 -281.933322) (xy 159.870657 -281.897282) (xy 159.91017 -281.867239)
			(xy 159.954024 -281.843983) (xy 160.001062 -281.828129) (xy 160.050045 -281.820093) (xy 160.074864 -281.819604)
			(xy 160.089047 -281.819785) (xy 160.117287 -281.822454) (xy 160.131252 -281.824938) (xy 160.143698 -281.827224)
			(xy 160.16732 -281.819858) (xy 160.24479 -281.742388) (xy 160.252156 -281.718766) (xy 160.24987 -281.70632)
			(xy 160.247386 -281.692355) (xy 160.244719 -281.664115) (xy 160.244536 -281.649932) (xy 160.245058 -281.624677)
			(xy 160.253371 -281.574855) (xy 160.269772 -281.527081) (xy 160.293813 -281.482658) (xy 160.324837 -281.442798)
			(xy 160.361999 -281.408588) (xy 160.404285 -281.380962) (xy 160.450541 -281.360672) (xy 160.499506 -281.348272)
			(xy 160.549844 -281.344101) (xy 160.600182 -281.348272) (xy 160.649147 -281.360672) (xy 160.695403 -281.380962)
			(xy 160.737689 -281.408588) (xy 160.774851 -281.442798) (xy 160.805875 -281.482658) (xy 160.829916 -281.527081)
			(xy 160.846317 -281.574855) (xy 160.85463 -281.624677) (xy 160.855152 -281.649932) (xy 160.854979 -281.664115)
			(xy 160.852304 -281.692355) (xy 160.849818 -281.70632) (xy 160.849818 -281.706574) (xy 160.848322 -281.718803)
			(xy 160.855634 -281.742294) (xy 160.863788 -281.751532) (xy 160.932368 -281.819858) (xy 160.95599 -281.827224)
			(xy 160.968436 -281.824938) (xy 160.982464 -281.82245) (xy 161.010832 -281.81978) (xy 161.025078 -281.819604)
			(xy 161.039261 -281.819784) (xy 161.067501 -281.822454) (xy 161.081466 -281.824938) (xy 161.093912 -281.827224)
			(xy 161.117534 -281.819858) (xy 161.195004 -281.742388) (xy 161.20237 -281.718766) (xy 161.200084 -281.70632)
			(xy 161.1976 -281.692355) (xy 161.194933 -281.664115) (xy 161.19475 -281.649932) (xy 161.195272 -281.624677)
			(xy 161.203585 -281.574855) (xy 161.219986 -281.527081) (xy 161.244027 -281.482658) (xy 161.275051 -281.442798)
			(xy 161.312213 -281.408588) (xy 161.354499 -281.380962) (xy 161.400755 -281.360672) (xy 161.44972 -281.348272)
			(xy 161.500058 -281.344101) (xy 161.550396 -281.348272) (xy 161.599361 -281.360672) (xy 161.645617 -281.380962)
			(xy 161.687903 -281.408588) (xy 161.725065 -281.442798) (xy 161.756089 -281.482658) (xy 161.78013 -281.527081)
			(xy 161.796531 -281.574855) (xy 161.804844 -281.624677) (xy 161.805366 -281.649932) (xy 161.805194 -281.664115)
			(xy 161.802519 -281.692355) (xy 161.800032 -281.70632) (xy 161.797746 -281.718766) (xy 161.805112 -281.742388)
			(xy 161.882582 -281.819858) (xy 161.906204 -281.827224) (xy 161.91865 -281.824938) (xy 161.932615 -281.822459)
			(xy 161.960855 -281.819789) (xy 161.975038 -281.819604) (xy 161.989221 -281.819775) (xy 162.017461 -281.822451)
			(xy 162.031426 -281.824938) (xy 162.043872 -281.827224) (xy 162.067494 -281.819858) (xy 162.144964 -281.742388)
			(xy 162.15233 -281.718766) (xy 162.150044 -281.70632) (xy 162.147561 -281.692355) (xy 162.144893 -281.664115)
			(xy 162.14471 -281.649932) (xy 162.145143 -281.625108) (xy 162.15317 -281.576114) (xy 162.169018 -281.529064)
			(xy 162.192269 -281.485198) (xy 162.22231 -281.445671) (xy 162.258351 -281.411525) (xy 162.299441 -281.383659)
			(xy 162.344498 -281.362809) (xy 162.392334 -281.349522) (xy 162.44169 -281.34415) (xy 162.491265 -281.346833)
			(xy 162.539752 -281.357502) (xy 162.585875 -281.375874) (xy 162.628418 -281.401467) (xy 162.66626 -281.433604)
			(xy 162.698404 -281.471441) (xy 162.724003 -281.51398) (xy 162.742383 -281.5601) (xy 162.75306 -281.608586)
			(xy 162.755304 -281.649932) (xy 163.094174 -281.649932) (xy 163.098134 -281.600878) (xy 163.109911 -281.553094)
			(xy 163.129202 -281.507818) (xy 163.155505 -281.466222) (xy 163.18814 -281.429385) (xy 163.226261 -281.39826)
			(xy 163.268882 -281.373653) (xy 163.314898 -281.356201) (xy 163.363117 -281.346357) (xy 163.412292 -281.344376)
			(xy 163.461147 -281.350308) (xy 163.508418 -281.364) (xy 163.55288 -281.385098) (xy 163.593383 -281.413054)
			(xy 163.628876 -281.447146) (xy 163.658441 -281.48649) (xy 163.681312 -281.530067) (xy 163.696896 -281.576748)
			(xy 163.704791 -281.625325) (xy 163.705286 -281.649932) (xy 164.044134 -281.649932) (xy 164.048094 -281.600878)
			(xy 164.059871 -281.553094) (xy 164.079162 -281.507818) (xy 164.105465 -281.466222) (xy 164.1381 -281.429385)
			(xy 164.176221 -281.39826) (xy 164.218842 -281.373653) (xy 164.264858 -281.356201) (xy 164.313077 -281.346357)
			(xy 164.362252 -281.344376) (xy 164.411107 -281.350308) (xy 164.458378 -281.364) (xy 164.50284 -281.385098)
			(xy 164.543343 -281.413054) (xy 164.578836 -281.447146) (xy 164.608401 -281.48649) (xy 164.631272 -281.530067)
			(xy 164.646856 -281.576748) (xy 164.654751 -281.625325) (xy 164.655246 -281.649932) (xy 164.994094 -281.649932)
			(xy 164.998054 -281.600878) (xy 165.009831 -281.553094) (xy 165.029122 -281.507818) (xy 165.055425 -281.466222)
			(xy 165.08806 -281.429385) (xy 165.126181 -281.39826) (xy 165.168802 -281.373653) (xy 165.214818 -281.356201)
			(xy 165.263037 -281.346357) (xy 165.312212 -281.344376) (xy 165.361067 -281.350308) (xy 165.408338 -281.364)
			(xy 165.4528 -281.385098) (xy 165.493303 -281.413054) (xy 165.528796 -281.447146) (xy 165.558361 -281.48649)
			(xy 165.581232 -281.530067) (xy 165.596816 -281.576748) (xy 165.604711 -281.625325) (xy 165.605206 -281.649932)
			(xy 165.944054 -281.649932) (xy 165.948014 -281.600878) (xy 165.959791 -281.553094) (xy 165.979082 -281.507818)
			(xy 166.005385 -281.466222) (xy 166.03802 -281.429385) (xy 166.076141 -281.39826) (xy 166.118762 -281.373653)
			(xy 166.164778 -281.356201) (xy 166.212997 -281.346357) (xy 166.262172 -281.344376) (xy 166.311027 -281.350308)
			(xy 166.358298 -281.364) (xy 166.40276 -281.385098) (xy 166.443263 -281.413054) (xy 166.478756 -281.447146)
			(xy 166.508321 -281.48649) (xy 166.531192 -281.530067) (xy 166.546776 -281.576748) (xy 166.554671 -281.625325)
			(xy 166.555166 -281.649932) (xy 166.894268 -281.649932) (xy 166.898228 -281.600878) (xy 166.910005 -281.553094)
			(xy 166.929296 -281.507818) (xy 166.955599 -281.466222) (xy 166.988234 -281.429385) (xy 167.026355 -281.39826)
			(xy 167.068976 -281.373653) (xy 167.114992 -281.356201) (xy 167.163211 -281.346357) (xy 167.212386 -281.344376)
			(xy 167.261241 -281.350308) (xy 167.308512 -281.364) (xy 167.352974 -281.385098) (xy 167.393477 -281.413054)
			(xy 167.42897 -281.447146) (xy 167.458535 -281.48649) (xy 167.481406 -281.530067) (xy 167.49699 -281.576748)
			(xy 167.504885 -281.625325) (xy 167.50538 -281.649932) (xy 167.844228 -281.649932) (xy 167.848188 -281.600878)
			(xy 167.859965 -281.553094) (xy 167.879256 -281.507818) (xy 167.905559 -281.466222) (xy 167.938194 -281.429385)
			(xy 167.976315 -281.39826) (xy 168.018936 -281.373653) (xy 168.064952 -281.356201) (xy 168.113171 -281.346357)
			(xy 168.162346 -281.344376) (xy 168.211201 -281.350308) (xy 168.258472 -281.364) (xy 168.302934 -281.385098)
			(xy 168.343437 -281.413054) (xy 168.37893 -281.447146) (xy 168.408495 -281.48649) (xy 168.431366 -281.530067)
			(xy 168.44695 -281.576748) (xy 168.454845 -281.625325) (xy 168.45534 -281.649932) (xy 168.794188 -281.649932)
			(xy 168.798148 -281.600878) (xy 168.809925 -281.553094) (xy 168.829216 -281.507818) (xy 168.855519 -281.466222)
			(xy 168.888154 -281.429385) (xy 168.926275 -281.39826) (xy 168.968896 -281.373653) (xy 169.014912 -281.356201)
			(xy 169.063131 -281.346357) (xy 169.112306 -281.344376) (xy 169.161161 -281.350308) (xy 169.208432 -281.364)
			(xy 169.252894 -281.385098) (xy 169.293397 -281.413054) (xy 169.32889 -281.447146) (xy 169.358455 -281.48649)
			(xy 169.381326 -281.530067) (xy 169.39691 -281.576748) (xy 169.404805 -281.625325) (xy 169.4053 -281.649932)
			(xy 169.744148 -281.649932) (xy 169.748108 -281.600878) (xy 169.759885 -281.553094) (xy 169.779176 -281.507818)
			(xy 169.805479 -281.466222) (xy 169.838114 -281.429385) (xy 169.876235 -281.39826) (xy 169.918856 -281.373653)
			(xy 169.964872 -281.356201) (xy 170.013091 -281.346357) (xy 170.062266 -281.344376) (xy 170.111121 -281.350308)
			(xy 170.158392 -281.364) (xy 170.202854 -281.385098) (xy 170.243357 -281.413054) (xy 170.27885 -281.447146)
			(xy 170.308415 -281.48649) (xy 170.331286 -281.530067) (xy 170.34687 -281.576748) (xy 170.354765 -281.625325)
			(xy 170.35526 -281.649932) (xy 170.694108 -281.649932) (xy 170.698068 -281.600878) (xy 170.709845 -281.553094)
			(xy 170.729136 -281.507818) (xy 170.755439 -281.466222) (xy 170.788074 -281.429385) (xy 170.826195 -281.39826)
			(xy 170.868816 -281.373653) (xy 170.914832 -281.356201) (xy 170.963051 -281.346357) (xy 171.012226 -281.344376)
			(xy 171.061081 -281.350308) (xy 171.108352 -281.364) (xy 171.152814 -281.385098) (xy 171.193317 -281.413054)
			(xy 171.22881 -281.447146) (xy 171.258375 -281.48649) (xy 171.281246 -281.530067) (xy 171.29683 -281.576748)
			(xy 171.304725 -281.625325) (xy 171.30522 -281.649932) (xy 171.644068 -281.649932) (xy 171.648028 -281.600878)
			(xy 171.659805 -281.553094) (xy 171.679096 -281.507818) (xy 171.705399 -281.466222) (xy 171.738034 -281.429385)
			(xy 171.776155 -281.39826) (xy 171.818776 -281.373653) (xy 171.864792 -281.356201) (xy 171.913011 -281.346357)
			(xy 171.962186 -281.344376) (xy 172.011041 -281.350308) (xy 172.058312 -281.364) (xy 172.102774 -281.385098)
			(xy 172.143277 -281.413054) (xy 172.17877 -281.447146) (xy 172.208335 -281.48649) (xy 172.231206 -281.530067)
			(xy 172.24679 -281.576748) (xy 172.254685 -281.625325) (xy 172.25518 -281.649932) (xy 172.594282 -281.649932)
			(xy 172.598242 -281.600878) (xy 172.610019 -281.553094) (xy 172.62931 -281.507818) (xy 172.655613 -281.466222)
			(xy 172.688248 -281.429385) (xy 172.726369 -281.39826) (xy 172.76899 -281.373653) (xy 172.815006 -281.356201)
			(xy 172.863225 -281.346357) (xy 172.9124 -281.344376) (xy 172.961255 -281.350308) (xy 173.008526 -281.364)
			(xy 173.052988 -281.385098) (xy 173.093491 -281.413054) (xy 173.128984 -281.447146) (xy 173.158549 -281.48649)
			(xy 173.18142 -281.530067) (xy 173.197004 -281.576748) (xy 173.204899 -281.625325) (xy 173.205394 -281.649932)
			(xy 173.544242 -281.649932) (xy 173.548202 -281.600878) (xy 173.559979 -281.553094) (xy 173.57927 -281.507818)
			(xy 173.605573 -281.466222) (xy 173.638208 -281.429385) (xy 173.676329 -281.39826) (xy 173.71895 -281.373653)
			(xy 173.764966 -281.356201) (xy 173.813185 -281.346357) (xy 173.86236 -281.344376) (xy 173.911215 -281.350308)
			(xy 173.958486 -281.364) (xy 174.002948 -281.385098) (xy 174.043451 -281.413054) (xy 174.078944 -281.447146)
			(xy 174.108509 -281.48649) (xy 174.13138 -281.530067) (xy 174.146964 -281.576748) (xy 174.154859 -281.625325)
			(xy 174.155354 -281.649932) (xy 174.494202 -281.649932) (xy 174.498162 -281.600878) (xy 174.509939 -281.553094)
			(xy 174.52923 -281.507818) (xy 174.555533 -281.466222) (xy 174.588168 -281.429385) (xy 174.626289 -281.39826)
			(xy 174.66891 -281.373653) (xy 174.714926 -281.356201) (xy 174.763145 -281.346357) (xy 174.81232 -281.344376)
			(xy 174.861175 -281.350308) (xy 174.908446 -281.364) (xy 174.952908 -281.385098) (xy 174.993411 -281.413054)
			(xy 175.028904 -281.447146) (xy 175.058469 -281.48649) (xy 175.08134 -281.530067) (xy 175.096924 -281.576748)
			(xy 175.104819 -281.625325) (xy 175.105314 -281.649932) (xy 175.444162 -281.649932) (xy 175.448122 -281.600878)
			(xy 175.459899 -281.553094) (xy 175.47919 -281.507818) (xy 175.505493 -281.466222) (xy 175.538128 -281.429385)
			(xy 175.576249 -281.39826) (xy 175.61887 -281.373653) (xy 175.664886 -281.356201) (xy 175.713105 -281.346357)
			(xy 175.76228 -281.344376) (xy 175.811135 -281.350308) (xy 175.858406 -281.364) (xy 175.902868 -281.385098)
			(xy 175.943371 -281.413054) (xy 175.978864 -281.447146) (xy 176.008429 -281.48649) (xy 176.0313 -281.530067)
			(xy 176.046884 -281.576748) (xy 176.054779 -281.625325) (xy 176.055274 -281.649932) (xy 176.394122 -281.649932)
			(xy 176.398082 -281.600878) (xy 176.409859 -281.553094) (xy 176.42915 -281.507818) (xy 176.455453 -281.466222)
			(xy 176.488088 -281.429385) (xy 176.526209 -281.39826) (xy 176.56883 -281.373653) (xy 176.614846 -281.356201)
			(xy 176.663065 -281.346357) (xy 176.71224 -281.344376) (xy 176.761095 -281.350308) (xy 176.808366 -281.364)
			(xy 176.852828 -281.385098) (xy 176.893331 -281.413054) (xy 176.928824 -281.447146) (xy 176.958389 -281.48649)
			(xy 176.98126 -281.530067) (xy 176.996844 -281.576748) (xy 177.004739 -281.625325) (xy 177.005234 -281.649932)
			(xy 177.344082 -281.649932) (xy 177.348042 -281.600878) (xy 177.359819 -281.553094) (xy 177.37911 -281.507818)
			(xy 177.405413 -281.466222) (xy 177.438048 -281.429385) (xy 177.476169 -281.39826) (xy 177.51879 -281.373653)
			(xy 177.564806 -281.356201) (xy 177.613025 -281.346357) (xy 177.6622 -281.344376) (xy 177.711055 -281.350308)
			(xy 177.758326 -281.364) (xy 177.802788 -281.385098) (xy 177.843291 -281.413054) (xy 177.878784 -281.447146)
			(xy 177.908349 -281.48649) (xy 177.93122 -281.530067) (xy 177.946804 -281.576748) (xy 177.954699 -281.625325)
			(xy 177.955194 -281.649932) (xy 178.294042 -281.649932) (xy 178.298002 -281.600878) (xy 178.309779 -281.553094)
			(xy 178.32907 -281.507818) (xy 178.355373 -281.466222) (xy 178.388008 -281.429385) (xy 178.426129 -281.39826)
			(xy 178.46875 -281.373653) (xy 178.514766 -281.356201) (xy 178.562985 -281.346357) (xy 178.61216 -281.344376)
			(xy 178.661015 -281.350308) (xy 178.708286 -281.364) (xy 178.752748 -281.385098) (xy 178.793251 -281.413054)
			(xy 178.828744 -281.447146) (xy 178.858309 -281.48649) (xy 178.88118 -281.530067) (xy 178.896764 -281.576748)
			(xy 178.904659 -281.625325) (xy 178.905154 -281.649932) (xy 179.244256 -281.649932) (xy 179.248216 -281.600878)
			(xy 179.259993 -281.553094) (xy 179.279284 -281.507818) (xy 179.305587 -281.466222) (xy 179.338222 -281.429385)
			(xy 179.376343 -281.39826) (xy 179.418964 -281.373653) (xy 179.46498 -281.356201) (xy 179.513199 -281.346357)
			(xy 179.562374 -281.344376) (xy 179.611229 -281.350308) (xy 179.6585 -281.364) (xy 179.702962 -281.385098)
			(xy 179.743465 -281.413054) (xy 179.778958 -281.447146) (xy 179.808523 -281.48649) (xy 179.831394 -281.530067)
			(xy 179.846978 -281.576748) (xy 179.854873 -281.625325) (xy 179.855368 -281.649932) (xy 180.194216 -281.649932)
			(xy 180.198176 -281.600878) (xy 180.209953 -281.553094) (xy 180.229244 -281.507818) (xy 180.255547 -281.466222)
			(xy 180.288182 -281.429385) (xy 180.326303 -281.39826) (xy 180.368924 -281.373653) (xy 180.41494 -281.356201)
			(xy 180.463159 -281.346357) (xy 180.512334 -281.344376) (xy 180.561189 -281.350308) (xy 180.60846 -281.364)
			(xy 180.652922 -281.385098) (xy 180.693425 -281.413054) (xy 180.728918 -281.447146) (xy 180.758483 -281.48649)
			(xy 180.781354 -281.530067) (xy 180.796938 -281.576748) (xy 180.804833 -281.625325) (xy 180.805328 -281.649932)
			(xy 181.144176 -281.649932) (xy 181.148136 -281.600878) (xy 181.159913 -281.553094) (xy 181.179204 -281.507818)
			(xy 181.205507 -281.466222) (xy 181.238142 -281.429385) (xy 181.276263 -281.39826) (xy 181.318884 -281.373653)
			(xy 181.3649 -281.356201) (xy 181.413119 -281.346357) (xy 181.462294 -281.344376) (xy 181.511149 -281.350308)
			(xy 181.55842 -281.364) (xy 181.602882 -281.385098) (xy 181.643385 -281.413054) (xy 181.678878 -281.447146)
			(xy 181.708443 -281.48649) (xy 181.731314 -281.530067) (xy 181.746898 -281.576748) (xy 181.754793 -281.625325)
			(xy 181.755288 -281.649932) (xy 182.094136 -281.649932) (xy 182.098096 -281.600878) (xy 182.109873 -281.553094)
			(xy 182.129164 -281.507818) (xy 182.155467 -281.466222) (xy 182.188102 -281.429385) (xy 182.226223 -281.39826)
			(xy 182.268844 -281.373653) (xy 182.31486 -281.356201) (xy 182.363079 -281.346357) (xy 182.412254 -281.344376)
			(xy 182.461109 -281.350308) (xy 182.50838 -281.364) (xy 182.552842 -281.385098) (xy 182.593345 -281.413054)
			(xy 182.628838 -281.447146) (xy 182.658403 -281.48649) (xy 182.681274 -281.530067) (xy 182.696858 -281.576748)
			(xy 182.704753 -281.625325) (xy 182.705248 -281.649932) (xy 183.044096 -281.649932) (xy 183.048056 -281.600878)
			(xy 183.059833 -281.553094) (xy 183.079124 -281.507818) (xy 183.105427 -281.466222) (xy 183.138062 -281.429385)
			(xy 183.176183 -281.39826) (xy 183.218804 -281.373653) (xy 183.26482 -281.356201) (xy 183.313039 -281.346357)
			(xy 183.362214 -281.344376) (xy 183.411069 -281.350308) (xy 183.45834 -281.364) (xy 183.502802 -281.385098)
			(xy 183.543305 -281.413054) (xy 183.578798 -281.447146) (xy 183.608363 -281.48649) (xy 183.631234 -281.530067)
			(xy 183.646818 -281.576748) (xy 183.654713 -281.625325) (xy 183.655208 -281.649932) (xy 183.994056 -281.649932)
			(xy 183.998016 -281.600878) (xy 184.009793 -281.553094) (xy 184.029084 -281.507818) (xy 184.055387 -281.466222)
			(xy 184.088022 -281.429385) (xy 184.126143 -281.39826) (xy 184.168764 -281.373653) (xy 184.21478 -281.356201)
			(xy 184.262999 -281.346357) (xy 184.312174 -281.344376) (xy 184.361029 -281.350308) (xy 184.4083 -281.364)
			(xy 184.452762 -281.385098) (xy 184.493265 -281.413054) (xy 184.528758 -281.447146) (xy 184.558323 -281.48649)
			(xy 184.581194 -281.530067) (xy 184.596778 -281.576748) (xy 184.604673 -281.625325) (xy 184.605168 -281.649932)
			(xy 184.604673 -281.674539) (xy 184.596778 -281.723116) (xy 184.581194 -281.769797) (xy 184.558323 -281.813374)
			(xy 184.528758 -281.852718) (xy 184.493265 -281.88681) (xy 184.452762 -281.914766) (xy 184.4083 -281.935864)
			(xy 184.361029 -281.949556) (xy 184.312174 -281.955488) (xy 184.262999 -281.953507) (xy 184.21478 -281.943663)
			(xy 184.168764 -281.926211) (xy 184.126143 -281.901604) (xy 184.088022 -281.870479) (xy 184.055387 -281.833642)
			(xy 184.029084 -281.792046) (xy 184.009793 -281.74677) (xy 183.998016 -281.698986) (xy 183.994056 -281.649932)
			(xy 183.655208 -281.649932) (xy 183.654713 -281.674539) (xy 183.646818 -281.723116) (xy 183.631234 -281.769797)
			(xy 183.608363 -281.813374) (xy 183.578798 -281.852718) (xy 183.543305 -281.88681) (xy 183.502802 -281.914766)
			(xy 183.45834 -281.935864) (xy 183.411069 -281.949556) (xy 183.362214 -281.955488) (xy 183.313039 -281.953507)
			(xy 183.26482 -281.943663) (xy 183.218804 -281.926211) (xy 183.176183 -281.901604) (xy 183.138062 -281.870479)
			(xy 183.105427 -281.833642) (xy 183.079124 -281.792046) (xy 183.059833 -281.74677) (xy 183.048056 -281.698986)
			(xy 183.044096 -281.649932) (xy 182.705248 -281.649932) (xy 182.704753 -281.674539) (xy 182.696858 -281.723116)
			(xy 182.681274 -281.769797) (xy 182.658403 -281.813374) (xy 182.628838 -281.852718) (xy 182.593345 -281.88681)
			(xy 182.552842 -281.914766) (xy 182.50838 -281.935864) (xy 182.461109 -281.949556) (xy 182.412254 -281.955488)
			(xy 182.363079 -281.953507) (xy 182.31486 -281.943663) (xy 182.268844 -281.926211) (xy 182.226223 -281.901604)
			(xy 182.188102 -281.870479) (xy 182.155467 -281.833642) (xy 182.129164 -281.792046) (xy 182.109873 -281.74677)
			(xy 182.098096 -281.698986) (xy 182.094136 -281.649932) (xy 181.755288 -281.649932) (xy 181.754793 -281.674539)
			(xy 181.746898 -281.723116) (xy 181.731314 -281.769797) (xy 181.708443 -281.813374) (xy 181.678878 -281.852718)
			(xy 181.643385 -281.88681) (xy 181.602882 -281.914766) (xy 181.55842 -281.935864) (xy 181.511149 -281.949556)
			(xy 181.462294 -281.955488) (xy 181.413119 -281.953507) (xy 181.3649 -281.943663) (xy 181.318884 -281.926211)
			(xy 181.276263 -281.901604) (xy 181.238142 -281.870479) (xy 181.205507 -281.833642) (xy 181.179204 -281.792046)
			(xy 181.159913 -281.74677) (xy 181.148136 -281.698986) (xy 181.144176 -281.649932) (xy 180.805328 -281.649932)
			(xy 180.804833 -281.674539) (xy 180.796938 -281.723116) (xy 180.781354 -281.769797) (xy 180.758483 -281.813374)
			(xy 180.728918 -281.852718) (xy 180.693425 -281.88681) (xy 180.652922 -281.914766) (xy 180.60846 -281.935864)
			(xy 180.561189 -281.949556) (xy 180.512334 -281.955488) (xy 180.463159 -281.953507) (xy 180.41494 -281.943663)
			(xy 180.368924 -281.926211) (xy 180.326303 -281.901604) (xy 180.288182 -281.870479) (xy 180.255547 -281.833642)
			(xy 180.229244 -281.792046) (xy 180.209953 -281.74677) (xy 180.198176 -281.698986) (xy 180.194216 -281.649932)
			(xy 179.855368 -281.649932) (xy 179.854873 -281.674539) (xy 179.846978 -281.723116) (xy 179.831394 -281.769797)
			(xy 179.808523 -281.813374) (xy 179.778958 -281.852718) (xy 179.743465 -281.88681) (xy 179.702962 -281.914766)
			(xy 179.6585 -281.935864) (xy 179.611229 -281.949556) (xy 179.562374 -281.955488) (xy 179.513199 -281.953507)
			(xy 179.46498 -281.943663) (xy 179.418964 -281.926211) (xy 179.376343 -281.901604) (xy 179.338222 -281.870479)
			(xy 179.305587 -281.833642) (xy 179.279284 -281.792046) (xy 179.259993 -281.74677) (xy 179.248216 -281.698986)
			(xy 179.244256 -281.649932) (xy 178.905154 -281.649932) (xy 178.904659 -281.674539) (xy 178.896764 -281.723116)
			(xy 178.88118 -281.769797) (xy 178.858309 -281.813374) (xy 178.828744 -281.852718) (xy 178.793251 -281.88681)
			(xy 178.752748 -281.914766) (xy 178.708286 -281.935864) (xy 178.661015 -281.949556) (xy 178.61216 -281.955488)
			(xy 178.562985 -281.953507) (xy 178.514766 -281.943663) (xy 178.46875 -281.926211) (xy 178.426129 -281.901604)
			(xy 178.388008 -281.870479) (xy 178.355373 -281.833642) (xy 178.32907 -281.792046) (xy 178.309779 -281.74677)
			(xy 178.298002 -281.698986) (xy 178.294042 -281.649932) (xy 177.955194 -281.649932) (xy 177.954699 -281.674539)
			(xy 177.946804 -281.723116) (xy 177.93122 -281.769797) (xy 177.908349 -281.813374) (xy 177.878784 -281.852718)
			(xy 177.843291 -281.88681) (xy 177.802788 -281.914766) (xy 177.758326 -281.935864) (xy 177.711055 -281.949556)
			(xy 177.6622 -281.955488) (xy 177.613025 -281.953507) (xy 177.564806 -281.943663) (xy 177.51879 -281.926211)
			(xy 177.476169 -281.901604) (xy 177.438048 -281.870479) (xy 177.405413 -281.833642) (xy 177.37911 -281.792046)
			(xy 177.359819 -281.74677) (xy 177.348042 -281.698986) (xy 177.344082 -281.649932) (xy 177.005234 -281.649932)
			(xy 177.004739 -281.674539) (xy 176.996844 -281.723116) (xy 176.98126 -281.769797) (xy 176.958389 -281.813374)
			(xy 176.928824 -281.852718) (xy 176.893331 -281.88681) (xy 176.852828 -281.914766) (xy 176.808366 -281.935864)
			(xy 176.761095 -281.949556) (xy 176.71224 -281.955488) (xy 176.663065 -281.953507) (xy 176.614846 -281.943663)
			(xy 176.56883 -281.926211) (xy 176.526209 -281.901604) (xy 176.488088 -281.870479) (xy 176.455453 -281.833642)
			(xy 176.42915 -281.792046) (xy 176.409859 -281.74677) (xy 176.398082 -281.698986) (xy 176.394122 -281.649932)
			(xy 176.055274 -281.649932) (xy 176.054779 -281.674539) (xy 176.046884 -281.723116) (xy 176.0313 -281.769797)
			(xy 176.008429 -281.813374) (xy 175.978864 -281.852718) (xy 175.943371 -281.88681) (xy 175.902868 -281.914766)
			(xy 175.858406 -281.935864) (xy 175.811135 -281.949556) (xy 175.76228 -281.955488) (xy 175.713105 -281.953507)
			(xy 175.664886 -281.943663) (xy 175.61887 -281.926211) (xy 175.576249 -281.901604) (xy 175.538128 -281.870479)
			(xy 175.505493 -281.833642) (xy 175.47919 -281.792046) (xy 175.459899 -281.74677) (xy 175.448122 -281.698986)
			(xy 175.444162 -281.649932) (xy 175.105314 -281.649932) (xy 175.104819 -281.674539) (xy 175.096924 -281.723116)
			(xy 175.08134 -281.769797) (xy 175.058469 -281.813374) (xy 175.028904 -281.852718) (xy 174.993411 -281.88681)
			(xy 174.952908 -281.914766) (xy 174.908446 -281.935864) (xy 174.861175 -281.949556) (xy 174.81232 -281.955488)
			(xy 174.763145 -281.953507) (xy 174.714926 -281.943663) (xy 174.66891 -281.926211) (xy 174.626289 -281.901604)
			(xy 174.588168 -281.870479) (xy 174.555533 -281.833642) (xy 174.52923 -281.792046) (xy 174.509939 -281.74677)
			(xy 174.498162 -281.698986) (xy 174.494202 -281.649932) (xy 174.155354 -281.649932) (xy 174.154859 -281.674539)
			(xy 174.146964 -281.723116) (xy 174.13138 -281.769797) (xy 174.108509 -281.813374) (xy 174.078944 -281.852718)
			(xy 174.043451 -281.88681) (xy 174.002948 -281.914766) (xy 173.958486 -281.935864) (xy 173.911215 -281.949556)
			(xy 173.86236 -281.955488) (xy 173.813185 -281.953507) (xy 173.764966 -281.943663) (xy 173.71895 -281.926211)
			(xy 173.676329 -281.901604) (xy 173.638208 -281.870479) (xy 173.605573 -281.833642) (xy 173.57927 -281.792046)
			(xy 173.559979 -281.74677) (xy 173.548202 -281.698986) (xy 173.544242 -281.649932) (xy 173.205394 -281.649932)
			(xy 173.204899 -281.674539) (xy 173.197004 -281.723116) (xy 173.18142 -281.769797) (xy 173.158549 -281.813374)
			(xy 173.128984 -281.852718) (xy 173.093491 -281.88681) (xy 173.052988 -281.914766) (xy 173.008526 -281.935864)
			(xy 172.961255 -281.949556) (xy 172.9124 -281.955488) (xy 172.863225 -281.953507) (xy 172.815006 -281.943663)
			(xy 172.76899 -281.926211) (xy 172.726369 -281.901604) (xy 172.688248 -281.870479) (xy 172.655613 -281.833642)
			(xy 172.62931 -281.792046) (xy 172.610019 -281.74677) (xy 172.598242 -281.698986) (xy 172.594282 -281.649932)
			(xy 172.25518 -281.649932) (xy 172.254685 -281.674539) (xy 172.24679 -281.723116) (xy 172.231206 -281.769797)
			(xy 172.208335 -281.813374) (xy 172.17877 -281.852718) (xy 172.143277 -281.88681) (xy 172.102774 -281.914766)
			(xy 172.058312 -281.935864) (xy 172.011041 -281.949556) (xy 171.962186 -281.955488) (xy 171.913011 -281.953507)
			(xy 171.864792 -281.943663) (xy 171.818776 -281.926211) (xy 171.776155 -281.901604) (xy 171.738034 -281.870479)
			(xy 171.705399 -281.833642) (xy 171.679096 -281.792046) (xy 171.659805 -281.74677) (xy 171.648028 -281.698986)
			(xy 171.644068 -281.649932) (xy 171.30522 -281.649932) (xy 171.304725 -281.674539) (xy 171.29683 -281.723116)
			(xy 171.281246 -281.769797) (xy 171.258375 -281.813374) (xy 171.22881 -281.852718) (xy 171.193317 -281.88681)
			(xy 171.152814 -281.914766) (xy 171.108352 -281.935864) (xy 171.061081 -281.949556) (xy 171.012226 -281.955488)
			(xy 170.963051 -281.953507) (xy 170.914832 -281.943663) (xy 170.868816 -281.926211) (xy 170.826195 -281.901604)
			(xy 170.788074 -281.870479) (xy 170.755439 -281.833642) (xy 170.729136 -281.792046) (xy 170.709845 -281.74677)
			(xy 170.698068 -281.698986) (xy 170.694108 -281.649932) (xy 170.35526 -281.649932) (xy 170.354765 -281.674539)
			(xy 170.34687 -281.723116) (xy 170.331286 -281.769797) (xy 170.308415 -281.813374) (xy 170.27885 -281.852718)
			(xy 170.243357 -281.88681) (xy 170.202854 -281.914766) (xy 170.158392 -281.935864) (xy 170.111121 -281.949556)
			(xy 170.062266 -281.955488) (xy 170.013091 -281.953507) (xy 169.964872 -281.943663) (xy 169.918856 -281.926211)
			(xy 169.876235 -281.901604) (xy 169.838114 -281.870479) (xy 169.805479 -281.833642) (xy 169.779176 -281.792046)
			(xy 169.759885 -281.74677) (xy 169.748108 -281.698986) (xy 169.744148 -281.649932) (xy 169.4053 -281.649932)
			(xy 169.404805 -281.674539) (xy 169.39691 -281.723116) (xy 169.381326 -281.769797) (xy 169.358455 -281.813374)
			(xy 169.32889 -281.852718) (xy 169.293397 -281.88681) (xy 169.252894 -281.914766) (xy 169.208432 -281.935864)
			(xy 169.161161 -281.949556) (xy 169.112306 -281.955488) (xy 169.063131 -281.953507) (xy 169.014912 -281.943663)
			(xy 168.968896 -281.926211) (xy 168.926275 -281.901604) (xy 168.888154 -281.870479) (xy 168.855519 -281.833642)
			(xy 168.829216 -281.792046) (xy 168.809925 -281.74677) (xy 168.798148 -281.698986) (xy 168.794188 -281.649932)
			(xy 168.45534 -281.649932) (xy 168.454845 -281.674539) (xy 168.44695 -281.723116) (xy 168.431366 -281.769797)
			(xy 168.408495 -281.813374) (xy 168.37893 -281.852718) (xy 168.343437 -281.88681) (xy 168.302934 -281.914766)
			(xy 168.258472 -281.935864) (xy 168.211201 -281.949556) (xy 168.162346 -281.955488) (xy 168.113171 -281.953507)
			(xy 168.064952 -281.943663) (xy 168.018936 -281.926211) (xy 167.976315 -281.901604) (xy 167.938194 -281.870479)
			(xy 167.905559 -281.833642) (xy 167.879256 -281.792046) (xy 167.859965 -281.74677) (xy 167.848188 -281.698986)
			(xy 167.844228 -281.649932) (xy 167.50538 -281.649932) (xy 167.504885 -281.674539) (xy 167.49699 -281.723116)
			(xy 167.481406 -281.769797) (xy 167.458535 -281.813374) (xy 167.42897 -281.852718) (xy 167.393477 -281.88681)
			(xy 167.352974 -281.914766) (xy 167.308512 -281.935864) (xy 167.261241 -281.949556) (xy 167.212386 -281.955488)
			(xy 167.163211 -281.953507) (xy 167.114992 -281.943663) (xy 167.068976 -281.926211) (xy 167.026355 -281.901604)
			(xy 166.988234 -281.870479) (xy 166.955599 -281.833642) (xy 166.929296 -281.792046) (xy 166.910005 -281.74677)
			(xy 166.898228 -281.698986) (xy 166.894268 -281.649932) (xy 166.555166 -281.649932) (xy 166.554671 -281.674539)
			(xy 166.546776 -281.723116) (xy 166.531192 -281.769797) (xy 166.508321 -281.813374) (xy 166.478756 -281.852718)
			(xy 166.443263 -281.88681) (xy 166.40276 -281.914766) (xy 166.358298 -281.935864) (xy 166.311027 -281.949556)
			(xy 166.262172 -281.955488) (xy 166.212997 -281.953507) (xy 166.164778 -281.943663) (xy 166.118762 -281.926211)
			(xy 166.076141 -281.901604) (xy 166.03802 -281.870479) (xy 166.005385 -281.833642) (xy 165.979082 -281.792046)
			(xy 165.959791 -281.74677) (xy 165.948014 -281.698986) (xy 165.944054 -281.649932) (xy 165.605206 -281.649932)
			(xy 165.604711 -281.674539) (xy 165.596816 -281.723116) (xy 165.581232 -281.769797) (xy 165.558361 -281.813374)
			(xy 165.528796 -281.852718) (xy 165.493303 -281.88681) (xy 165.4528 -281.914766) (xy 165.408338 -281.935864)
			(xy 165.361067 -281.949556) (xy 165.312212 -281.955488) (xy 165.263037 -281.953507) (xy 165.214818 -281.943663)
			(xy 165.168802 -281.926211) (xy 165.126181 -281.901604) (xy 165.08806 -281.870479) (xy 165.055425 -281.833642)
			(xy 165.029122 -281.792046) (xy 165.009831 -281.74677) (xy 164.998054 -281.698986) (xy 164.994094 -281.649932)
			(xy 164.655246 -281.649932) (xy 164.654751 -281.674539) (xy 164.646856 -281.723116) (xy 164.631272 -281.769797)
			(xy 164.608401 -281.813374) (xy 164.578836 -281.852718) (xy 164.543343 -281.88681) (xy 164.50284 -281.914766)
			(xy 164.458378 -281.935864) (xy 164.411107 -281.949556) (xy 164.362252 -281.955488) (xy 164.313077 -281.953507)
			(xy 164.264858 -281.943663) (xy 164.218842 -281.926211) (xy 164.176221 -281.901604) (xy 164.1381 -281.870479)
			(xy 164.105465 -281.833642) (xy 164.079162 -281.792046) (xy 164.059871 -281.74677) (xy 164.048094 -281.698986)
			(xy 164.044134 -281.649932) (xy 163.705286 -281.649932) (xy 163.704791 -281.674539) (xy 163.696896 -281.723116)
			(xy 163.681312 -281.769797) (xy 163.658441 -281.813374) (xy 163.628876 -281.852718) (xy 163.593383 -281.88681)
			(xy 163.55288 -281.914766) (xy 163.508418 -281.935864) (xy 163.461147 -281.949556) (xy 163.412292 -281.955488)
			(xy 163.363117 -281.953507) (xy 163.314898 -281.943663) (xy 163.268882 -281.926211) (xy 163.226261 -281.901604)
			(xy 163.18814 -281.870479) (xy 163.155505 -281.833642) (xy 163.129202 -281.792046) (xy 163.109911 -281.74677)
			(xy 163.098134 -281.698986) (xy 163.094174 -281.649932) (xy 162.755304 -281.649932) (xy 162.755751 -281.65816)
			(xy 162.750387 -281.707517) (xy 162.737109 -281.755355) (xy 162.716265 -281.800416) (xy 162.688407 -281.84151)
			(xy 162.654267 -281.877556) (xy 162.614745 -281.907604) (xy 162.570882 -281.930862) (xy 162.523835 -281.946718)
			(xy 162.474842 -281.954753) (xy 162.450018 -281.95524) (xy 162.435835 -281.95506) (xy 162.407595 -281.95239)
			(xy 162.39363 -281.949906) (xy 162.381184 -281.94762) (xy 162.357562 -281.954986) (xy 162.280092 -282.032456)
			(xy 162.272726 -282.056078) (xy 162.275012 -282.068524) (xy 162.277488 -282.08249) (xy 162.28016 -282.110729)
			(xy 162.280346 -282.124912) (xy 162.279824 -282.150167) (xy 162.271511 -282.199989) (xy 162.25511 -282.247763)
			(xy 162.231069 -282.292186) (xy 162.200045 -282.332046) (xy 162.162883 -282.366256) (xy 162.120597 -282.393882)
			(xy 162.074341 -282.414172) (xy 162.025376 -282.426572) (xy 161.975038 -282.430743) (xy 161.9247 -282.426572)
			(xy 161.875735 -282.414172) (xy 161.829479 -282.393882) (xy 161.787193 -282.366256) (xy 161.750031 -282.332046)
			(xy 161.719007 -282.292186) (xy 161.694966 -282.247763) (xy 161.678565 -282.199989) (xy 161.670252 -282.150167)
			(xy 161.66973 -282.124912) (xy 161.669908 -282.110729) (xy 161.672579 -282.082489) (xy 161.675064 -282.068524)
			(xy 161.67735 -282.056078) (xy 161.669984 -282.032456) (xy 161.592514 -281.954986) (xy 161.568892 -281.94762)
			(xy 161.556446 -281.949906) (xy 161.542481 -281.952386) (xy 161.514241 -281.955055) (xy 161.500058 -281.95524)
			(xy 161.485875 -281.955069) (xy 161.457635 -281.952393) (xy 161.44367 -281.949906) (xy 161.431224 -281.94762)
			(xy 161.407602 -281.954986) (xy 161.330132 -282.032456) (xy 161.322766 -282.056078) (xy 161.325052 -282.068524)
			(xy 161.327527 -282.08249) (xy 161.3302 -282.11073) (xy 161.330386 -282.124912) (xy 161.329864 -282.150167)
			(xy 161.321551 -282.199989) (xy 161.30515 -282.247763) (xy 161.281109 -282.292186) (xy 161.250085 -282.332046)
			(xy 161.212923 -282.366256) (xy 161.170637 -282.393882) (xy 161.124381 -282.414172) (xy 161.075416 -282.426572)
			(xy 161.025078 -282.430743) (xy 160.97474 -282.426572) (xy 160.925775 -282.414172) (xy 160.879519 -282.393882)
			(xy 160.837233 -282.366256) (xy 160.800071 -282.332046) (xy 160.769047 -282.292186) (xy 160.745006 -282.247763)
			(xy 160.728605 -282.199989) (xy 160.720292 -282.150167) (xy 160.71977 -282.124912) (xy 160.719949 -282.110729)
			(xy 160.722619 -282.082489) (xy 160.725104 -282.068524) (xy 160.725104 -282.06827) (xy 160.726565 -282.056039)
			(xy 160.719276 -282.032553) (xy 160.711134 -282.023312) (xy 160.642554 -281.954986) (xy 160.618932 -281.94762)
			(xy 160.606486 -281.949906) (xy 160.592457 -281.95239) (xy 160.56409 -281.955062) (xy 160.549844 -281.95524)
			(xy 160.535661 -281.955057) (xy 160.507421 -281.952389) (xy 160.493456 -281.949906) (xy 160.48101 -281.94762)
			(xy 160.457388 -281.954986) (xy 160.379918 -282.032456) (xy 160.372552 -282.056078) (xy 160.374838 -282.068524)
			(xy 160.377313 -282.08249) (xy 160.379986 -282.11073) (xy 160.380172 -282.124912) (xy 160.379709 -282.149731)
			(xy 160.371677 -282.198715) (xy 160.355826 -282.245754) (xy 160.332574 -282.28961) (xy 160.302534 -282.329126)
			(xy 160.266496 -282.363261) (xy 160.225411 -282.391117) (xy 160.180361 -282.41196) (xy 160.132532 -282.425239)
			(xy 160.083185 -282.430607) (xy 160.03362 -282.42792) (xy 159.985142 -282.41725) (xy 159.939029 -282.398879)
			(xy 159.896495 -282.373289) (xy 159.858662 -282.341155) (xy 159.826525 -282.303324) (xy 159.800932 -282.260793)
			(xy 159.782557 -282.214681) (xy 159.771883 -282.166204) (xy 159.769193 -282.116639) (xy 159.430046 -282.116639)
			(xy 159.430212 -282.124912) (xy 159.429717 -282.149519) (xy 159.421822 -282.198096) (xy 159.406238 -282.244777)
			(xy 159.383367 -282.288354) (xy 159.353802 -282.327698) (xy 159.318309 -282.36179) (xy 159.277806 -282.389746)
			(xy 159.233344 -282.410844) (xy 159.186073 -282.424536) (xy 159.137218 -282.430468) (xy 159.088043 -282.428487)
			(xy 159.039824 -282.418643) (xy 158.993808 -282.401191) (xy 158.951187 -282.376584) (xy 158.913066 -282.345459)
			(xy 158.880431 -282.308622) (xy 158.854128 -282.267026) (xy 158.834837 -282.22175) (xy 158.82306 -282.173966)
			(xy 158.8191 -282.124912) (xy 158.480252 -282.124912) (xy 158.479757 -282.149519) (xy 158.471862 -282.198096)
			(xy 158.456278 -282.244777) (xy 158.433407 -282.288354) (xy 158.403842 -282.327698) (xy 158.368349 -282.36179)
			(xy 158.327846 -282.389746) (xy 158.283384 -282.410844) (xy 158.236113 -282.424536) (xy 158.187258 -282.430468)
			(xy 158.138083 -282.428487) (xy 158.089864 -282.418643) (xy 158.043848 -282.401191) (xy 158.001227 -282.376584)
			(xy 157.963106 -282.345459) (xy 157.930471 -282.308622) (xy 157.904168 -282.267026) (xy 157.884877 -282.22175)
			(xy 157.8731 -282.173966) (xy 157.86914 -282.124912) (xy 157.530292 -282.124912) (xy 157.529797 -282.149519)
			(xy 157.521902 -282.198096) (xy 157.506318 -282.244777) (xy 157.483447 -282.288354) (xy 157.453882 -282.327698)
			(xy 157.418389 -282.36179) (xy 157.377886 -282.389746) (xy 157.333424 -282.410844) (xy 157.286153 -282.424536)
			(xy 157.237298 -282.430468) (xy 157.188123 -282.428487) (xy 157.139904 -282.418643) (xy 157.093888 -282.401191)
			(xy 157.051267 -282.376584) (xy 157.013146 -282.345459) (xy 156.980511 -282.308622) (xy 156.954208 -282.267026)
			(xy 156.934917 -282.22175) (xy 156.92314 -282.173966) (xy 156.91918 -282.124912) (xy 156.580332 -282.124912)
			(xy 156.579837 -282.149519) (xy 156.571942 -282.198096) (xy 156.556358 -282.244777) (xy 156.533487 -282.288354)
			(xy 156.503922 -282.327698) (xy 156.468429 -282.36179) (xy 156.427926 -282.389746) (xy 156.383464 -282.410844)
			(xy 156.336193 -282.424536) (xy 156.287338 -282.430468) (xy 156.238163 -282.428487) (xy 156.189944 -282.418643)
			(xy 156.143928 -282.401191) (xy 156.101307 -282.376584) (xy 156.063186 -282.345459) (xy 156.030551 -282.308622)
			(xy 156.004248 -282.267026) (xy 155.984957 -282.22175) (xy 155.97318 -282.173966) (xy 155.96922 -282.124912)
			(xy 155.630372 -282.124912) (xy 155.629877 -282.149519) (xy 155.621982 -282.198096) (xy 155.606398 -282.244777)
			(xy 155.583527 -282.288354) (xy 155.553962 -282.327698) (xy 155.518469 -282.36179) (xy 155.477966 -282.389746)
			(xy 155.433504 -282.410844) (xy 155.386233 -282.424536) (xy 155.337378 -282.430468) (xy 155.288203 -282.428487)
			(xy 155.239984 -282.418643) (xy 155.193968 -282.401191) (xy 155.151347 -282.376584) (xy 155.113226 -282.345459)
			(xy 155.080591 -282.308622) (xy 155.054288 -282.267026) (xy 155.034997 -282.22175) (xy 155.02322 -282.173966)
			(xy 155.01926 -282.124912) (xy 154.680412 -282.124912) (xy 154.679917 -282.149519) (xy 154.672022 -282.198096)
			(xy 154.656438 -282.244777) (xy 154.633567 -282.288354) (xy 154.604002 -282.327698) (xy 154.568509 -282.36179)
			(xy 154.528006 -282.389746) (xy 154.483544 -282.410844) (xy 154.436273 -282.424536) (xy 154.387418 -282.430468)
			(xy 154.338243 -282.428487) (xy 154.290024 -282.418643) (xy 154.244008 -282.401191) (xy 154.201387 -282.376584)
			(xy 154.163266 -282.345459) (xy 154.130631 -282.308622) (xy 154.104328 -282.267026) (xy 154.085037 -282.22175)
			(xy 154.07326 -282.173966) (xy 154.0693 -282.124912) (xy 153.730198 -282.124912) (xy 153.729703 -282.149519)
			(xy 153.721808 -282.198096) (xy 153.706224 -282.244777) (xy 153.683353 -282.288354) (xy 153.653788 -282.327698)
			(xy 153.618295 -282.36179) (xy 153.577792 -282.389746) (xy 153.53333 -282.410844) (xy 153.486059 -282.424536)
			(xy 153.437204 -282.430468) (xy 153.388029 -282.428487) (xy 153.33981 -282.418643) (xy 153.293794 -282.401191)
			(xy 153.251173 -282.376584) (xy 153.213052 -282.345459) (xy 153.180417 -282.308622) (xy 153.154114 -282.267026)
			(xy 153.134823 -282.22175) (xy 153.123046 -282.173966) (xy 153.119086 -282.124912) (xy 152.780238 -282.124912)
			(xy 152.779743 -282.149519) (xy 152.771848 -282.198096) (xy 152.756264 -282.244777) (xy 152.733393 -282.288354)
			(xy 152.703828 -282.327698) (xy 152.668335 -282.36179) (xy 152.627832 -282.389746) (xy 152.58337 -282.410844)
			(xy 152.536099 -282.424536) (xy 152.487244 -282.430468) (xy 152.438069 -282.428487) (xy 152.38985 -282.418643)
			(xy 152.343834 -282.401191) (xy 152.301213 -282.376584) (xy 152.263092 -282.345459) (xy 152.230457 -282.308622)
			(xy 152.204154 -282.267026) (xy 152.184863 -282.22175) (xy 152.173086 -282.173966) (xy 152.169126 -282.124912)
			(xy 144.019079 -282.124912) (xy 144.001013 -282.139947) (xy 143.953407 -282.169001) (xy 143.902078 -282.190813)
			(xy 143.848121 -282.204919) (xy 143.792684 -282.211019) (xy 143.73695 -282.208982) (xy 143.682107 -282.198852)
			(xy 143.629323 -282.180845) (xy 143.579723 -282.155344) (xy 143.534365 -282.122893) (xy 143.494216 -282.084184)
			(xy 143.46013 -282.040041) (xy 143.432834 -281.991406) (xy 143.412911 -281.939315) (xy 143.400785 -281.884878)
			(xy 143.396714 -281.829256) (xy 142.675102 -281.829256) (xy 142.674593 -281.857142) (xy 142.666473 -281.912318)
			(xy 142.650405 -281.965725) (xy 142.626733 -282.016222) (xy 142.59596 -282.062735) (xy 142.558743 -282.104272)
			(xy 142.515875 -282.139947) (xy 142.468269 -282.169001) (xy 142.41694 -282.190813) (xy 142.362983 -282.204919)
			(xy 142.307546 -282.211019) (xy 142.251812 -282.208982) (xy 142.196969 -282.198852) (xy 142.144185 -282.180845)
			(xy 142.094585 -282.155344) (xy 142.049227 -282.122893) (xy 142.009078 -282.084184) (xy 141.974992 -282.040041)
			(xy 141.947696 -281.991406) (xy 141.927773 -281.939315) (xy 141.915647 -281.884878) (xy 141.911576 -281.829256)
			(xy 135.168894 -281.829256) (xy 135.168894 -282.135072) (xy 135.168727 -282.14143) (xy 135.165637 -282.153764)
			(xy 135.162798 -282.159456) (xy 135.156956 -282.170124) (xy 135.153908 -282.181046) (xy 135.153908 -282.191206)
			(xy 135.161528 -282.209748) (xy 135.222742 -282.270708) (xy 135.243478 -282.292284) (xy 135.27864 -282.3407)
			(xy 135.305799 -282.394019) (xy 135.324289 -282.450929) (xy 135.333652 -282.510029) (xy 135.334248 -282.539948)
			(xy 135.334248 -283.131514) (xy 141.911576 -283.131514) (xy 141.915647 -283.075892) (xy 141.927773 -283.021455)
			(xy 141.947696 -282.969364) (xy 141.974992 -282.920729) (xy 142.009078 -282.876586) (xy 142.049227 -282.837877)
			(xy 142.094585 -282.805426) (xy 142.144185 -282.779925) (xy 142.196969 -282.761918) (xy 142.251812 -282.751788)
			(xy 142.307546 -282.749751) (xy 142.362983 -282.755851) (xy 142.41694 -282.769957) (xy 142.468269 -282.791769)
			(xy 142.515875 -282.820823) (xy 142.558743 -282.856498) (xy 142.59596 -282.898035) (xy 142.626733 -282.944548)
			(xy 142.650405 -282.995045) (xy 142.666473 -283.048452) (xy 142.674593 -283.103628) (xy 142.675102 -283.131514)
			(xy 143.387062 -283.131514) (xy 143.391133 -283.075892) (xy 143.403259 -283.021455) (xy 143.423182 -282.969364)
			(xy 143.450478 -282.920729) (xy 143.484564 -282.876586) (xy 143.524713 -282.837877) (xy 143.570071 -282.805426)
			(xy 143.619671 -282.779925) (xy 143.672455 -282.761918) (xy 143.727298 -282.751788) (xy 143.783032 -282.749751)
			(xy 143.838469 -282.755851) (xy 143.892426 -282.769957) (xy 143.943755 -282.791769) (xy 143.991361 -282.820823)
			(xy 144.034229 -282.856498) (xy 144.071446 -282.898035) (xy 144.102219 -282.944548) (xy 144.125891 -282.995045)
			(xy 144.141959 -283.048452) (xy 144.150079 -283.103628) (xy 144.150588 -283.131514) (xy 144.276062 -283.131514)
			(xy 144.280133 -283.075892) (xy 144.292259 -283.021455) (xy 144.312182 -282.969364) (xy 144.339478 -282.920729)
			(xy 144.373564 -282.876586) (xy 144.413713 -282.837877) (xy 144.459071 -282.805426) (xy 144.508671 -282.779925)
			(xy 144.561455 -282.761918) (xy 144.616298 -282.751788) (xy 144.672032 -282.749751) (xy 144.727469 -282.755851)
			(xy 144.781426 -282.769957) (xy 144.832755 -282.791769) (xy 144.880361 -282.820823) (xy 144.923229 -282.856498)
			(xy 144.960446 -282.898035) (xy 144.991219 -282.944548) (xy 145.014891 -282.995045) (xy 145.030959 -283.048452)
			(xy 145.039079 -283.103628) (xy 145.039588 -283.131514) (xy 145.039079 -283.1594) (xy 145.030959 -283.214576)
			(xy 145.014891 -283.267983) (xy 144.991219 -283.31848) (xy 144.960446 -283.364993) (xy 144.923229 -283.40653)
			(xy 144.880361 -283.442205) (xy 144.832755 -283.471259) (xy 144.781426 -283.493071) (xy 144.727469 -283.507177)
			(xy 144.672032 -283.513277) (xy 144.616298 -283.51124) (xy 144.561455 -283.50111) (xy 144.508671 -283.483103)
			(xy 144.459071 -283.457602) (xy 144.413713 -283.425151) (xy 144.373564 -283.386442) (xy 144.339478 -283.342299)
			(xy 144.312182 -283.293664) (xy 144.292259 -283.241573) (xy 144.280133 -283.187136) (xy 144.276062 -283.131514)
			(xy 144.150588 -283.131514) (xy 144.150079 -283.1594) (xy 144.141959 -283.214576) (xy 144.125891 -283.267983)
			(xy 144.102219 -283.31848) (xy 144.071446 -283.364993) (xy 144.034229 -283.40653) (xy 143.991361 -283.442205)
			(xy 143.943755 -283.471259) (xy 143.892426 -283.493071) (xy 143.838469 -283.507177) (xy 143.783032 -283.513277)
			(xy 143.727298 -283.51124) (xy 143.672455 -283.50111) (xy 143.619671 -283.483103) (xy 143.570071 -283.457602)
			(xy 143.524713 -283.425151) (xy 143.484564 -283.386442) (xy 143.450478 -283.342299) (xy 143.423182 -283.293664)
			(xy 143.403259 -283.241573) (xy 143.391133 -283.187136) (xy 143.387062 -283.131514) (xy 142.675102 -283.131514)
			(xy 142.674593 -283.1594) (xy 142.666473 -283.214576) (xy 142.650405 -283.267983) (xy 142.626733 -283.31848)
			(xy 142.59596 -283.364993) (xy 142.558743 -283.40653) (xy 142.515875 -283.442205) (xy 142.468269 -283.471259)
			(xy 142.41694 -283.493071) (xy 142.362983 -283.507177) (xy 142.307546 -283.513277) (xy 142.251812 -283.51124)
			(xy 142.196969 -283.50111) (xy 142.144185 -283.483103) (xy 142.094585 -283.457602) (xy 142.049227 -283.425151)
			(xy 142.009078 -283.386442) (xy 141.974992 -283.342299) (xy 141.947696 -283.293664) (xy 141.927773 -283.241573)
			(xy 141.915647 -283.187136) (xy 141.911576 -283.131514) (xy 135.334248 -283.131514) (xy 135.334248 -284.061154)
			(xy 140.967204 -284.061154) (xy 140.971275 -284.005532) (xy 140.983401 -283.951095) (xy 141.003324 -283.899004)
			(xy 141.03062 -283.850369) (xy 141.064706 -283.806226) (xy 141.104855 -283.767517) (xy 141.150213 -283.735066)
			(xy 141.199813 -283.709565) (xy 141.252597 -283.691558) (xy 141.30744 -283.681428) (xy 141.363174 -283.679391)
			(xy 141.418611 -283.685491) (xy 141.472568 -283.699597) (xy 141.523897 -283.721409) (xy 141.571503 -283.750463)
			(xy 141.614371 -283.786138) (xy 141.651588 -283.827675) (xy 141.682361 -283.874188) (xy 141.706033 -283.924685)
			(xy 141.722101 -283.978092) (xy 141.730221 -284.033268) (xy 141.73073 -284.061154) (xy 141.730221 -284.08904)
			(xy 141.722101 -284.144216) (xy 141.706033 -284.197623) (xy 141.682361 -284.24812) (xy 141.651588 -284.294633)
			(xy 141.614371 -284.33617) (xy 141.571503 -284.371845) (xy 141.523897 -284.400899) (xy 141.472568 -284.422711)
			(xy 141.418611 -284.436817) (xy 141.363174 -284.442917) (xy 141.30744 -284.44088) (xy 141.252597 -284.43075)
			(xy 141.199813 -284.412743) (xy 141.150213 -284.387242) (xy 141.104855 -284.354791) (xy 141.064706 -284.316082)
			(xy 141.03062 -284.271939) (xy 141.003324 -284.223304) (xy 140.983401 -284.171213) (xy 140.971275 -284.116776)
			(xy 140.967204 -284.061154) (xy 135.334248 -284.061154) (xy 135.334248 -284.563312) (xy 135.333641 -284.593228)
			(xy 135.324253 -284.65232) (xy 135.305756 -284.709222) (xy 135.278604 -284.762539) (xy 135.243463 -284.810965)
			(xy 135.222742 -284.832552) (xy 135.168894 -284.886146) (xy 135.162055 -284.893547) (xy 135.154339 -284.912145)
			(xy 135.153908 -284.922214) (xy 135.153908 -285.029656) (xy 141.911576 -285.029656) (xy 141.915647 -284.974034)
			(xy 141.927773 -284.919597) (xy 141.947696 -284.867506) (xy 141.974992 -284.818871) (xy 142.009078 -284.774728)
			(xy 142.049227 -284.736019) (xy 142.094585 -284.703568) (xy 142.144185 -284.678067) (xy 142.196969 -284.66006)
			(xy 142.251812 -284.64993) (xy 142.307546 -284.647893) (xy 142.362983 -284.653993) (xy 142.41694 -284.668099)
			(xy 142.468269 -284.689911) (xy 142.515875 -284.718965) (xy 142.558743 -284.75464) (xy 142.59596 -284.796177)
			(xy 142.626733 -284.84269) (xy 142.650405 -284.893187) (xy 142.666473 -284.946594) (xy 142.674593 -285.00177)
			(xy 142.675102 -285.029656) (xy 143.396714 -285.029656) (xy 143.400785 -284.974034) (xy 143.412911 -284.919597)
			(xy 143.432834 -284.867506) (xy 143.46013 -284.818871) (xy 143.494216 -284.774728) (xy 143.534365 -284.736019)
			(xy 143.579723 -284.703568) (xy 143.629323 -284.678067) (xy 143.682107 -284.66006) (xy 143.73695 -284.64993)
			(xy 143.792684 -284.647893) (xy 143.848121 -284.653993) (xy 143.902078 -284.668099) (xy 143.953407 -284.689911)
			(xy 144.001013 -284.718965) (xy 144.043881 -284.75464) (xy 144.081098 -284.796177) (xy 144.111871 -284.84269)
			(xy 144.135543 -284.893187) (xy 144.151611 -284.946594) (xy 144.159731 -285.00177) (xy 144.16024 -285.029656)
			(xy 144.159731 -285.057542) (xy 144.151611 -285.112718) (xy 144.135543 -285.166125) (xy 144.111871 -285.216622)
			(xy 144.081098 -285.263135) (xy 144.043881 -285.304672) (xy 144.001013 -285.340347) (xy 143.953407 -285.369401)
			(xy 143.902078 -285.391213) (xy 143.848121 -285.405319) (xy 143.792684 -285.411419) (xy 143.73695 -285.409382)
			(xy 143.682107 -285.399252) (xy 143.629323 -285.381245) (xy 143.579723 -285.355744) (xy 143.534365 -285.323293)
			(xy 143.494216 -285.284584) (xy 143.46013 -285.240441) (xy 143.432834 -285.191806) (xy 143.412911 -285.139715)
			(xy 143.400785 -285.085278) (xy 143.396714 -285.029656) (xy 142.675102 -285.029656) (xy 142.674593 -285.057542)
			(xy 142.666473 -285.112718) (xy 142.650405 -285.166125) (xy 142.626733 -285.216622) (xy 142.59596 -285.263135)
			(xy 142.558743 -285.304672) (xy 142.515875 -285.340347) (xy 142.468269 -285.369401) (xy 142.41694 -285.391213)
			(xy 142.362983 -285.405319) (xy 142.307546 -285.411419) (xy 142.251812 -285.409382) (xy 142.196969 -285.399252)
			(xy 142.144185 -285.381245) (xy 142.094585 -285.355744) (xy 142.049227 -285.323293) (xy 142.009078 -285.284584)
			(xy 141.974992 -285.240441) (xy 141.947696 -285.191806) (xy 141.927773 -285.139715) (xy 141.915647 -285.085278)
			(xy 141.911576 -285.029656) (xy 135.153908 -285.029656) (xy 135.153908 -286.331914) (xy 141.911576 -286.331914)
			(xy 141.915647 -286.276292) (xy 141.927773 -286.221855) (xy 141.947696 -286.169764) (xy 141.974992 -286.121129)
			(xy 142.009078 -286.076986) (xy 142.049227 -286.038277) (xy 142.094585 -286.005826) (xy 142.144185 -285.980325)
			(xy 142.196969 -285.962318) (xy 142.251812 -285.952188) (xy 142.307546 -285.950151) (xy 142.362983 -285.956251)
			(xy 142.41694 -285.970357) (xy 142.468269 -285.992169) (xy 142.515875 -286.021223) (xy 142.558743 -286.056898)
			(xy 142.59596 -286.098435) (xy 142.626733 -286.144948) (xy 142.650405 -286.195445) (xy 142.666473 -286.248852)
			(xy 142.674593 -286.304028) (xy 142.675102 -286.331914) (xy 143.387062 -286.331914) (xy 143.391133 -286.276292)
			(xy 143.403259 -286.221855) (xy 143.423182 -286.169764) (xy 143.450478 -286.121129) (xy 143.484564 -286.076986)
			(xy 143.524713 -286.038277) (xy 143.570071 -286.005826) (xy 143.619671 -285.980325) (xy 143.672455 -285.962318)
			(xy 143.727298 -285.952188) (xy 143.783032 -285.950151) (xy 143.838469 -285.956251) (xy 143.892426 -285.970357)
			(xy 143.943755 -285.992169) (xy 143.991361 -286.021223) (xy 144.034229 -286.056898) (xy 144.071446 -286.098435)
			(xy 144.102219 -286.144948) (xy 144.125891 -286.195445) (xy 144.141959 -286.248852) (xy 144.150079 -286.304028)
			(xy 144.150588 -286.331914) (xy 144.276062 -286.331914) (xy 144.280133 -286.276292) (xy 144.292259 -286.221855)
			(xy 144.312182 -286.169764) (xy 144.339478 -286.121129) (xy 144.373564 -286.076986) (xy 144.413713 -286.038277)
			(xy 144.459071 -286.005826) (xy 144.508671 -285.980325) (xy 144.561455 -285.962318) (xy 144.616298 -285.952188)
			(xy 144.672032 -285.950151) (xy 144.727469 -285.956251) (xy 144.781426 -285.970357) (xy 144.832755 -285.992169)
			(xy 144.880361 -286.021223) (xy 144.923229 -286.056898) (xy 144.960446 -286.098435) (xy 144.991219 -286.144948)
			(xy 145.014891 -286.195445) (xy 145.030959 -286.248852) (xy 145.039079 -286.304028) (xy 145.039588 -286.331914)
			(xy 145.039079 -286.3598) (xy 145.030959 -286.414976) (xy 145.014891 -286.468383) (xy 144.991219 -286.51888)
			(xy 144.960446 -286.565393) (xy 144.923229 -286.60693) (xy 144.880361 -286.642605) (xy 144.832755 -286.671659)
			(xy 144.781426 -286.693471) (xy 144.727469 -286.707577) (xy 144.672032 -286.713677) (xy 144.616298 -286.71164)
			(xy 144.561455 -286.70151) (xy 144.508671 -286.683503) (xy 144.459071 -286.658002) (xy 144.413713 -286.625551)
			(xy 144.373564 -286.586842) (xy 144.339478 -286.542699) (xy 144.312182 -286.494064) (xy 144.292259 -286.441973)
			(xy 144.280133 -286.387536) (xy 144.276062 -286.331914) (xy 144.150588 -286.331914) (xy 144.150079 -286.3598)
			(xy 144.141959 -286.414976) (xy 144.125891 -286.468383) (xy 144.102219 -286.51888) (xy 144.071446 -286.565393)
			(xy 144.034229 -286.60693) (xy 143.991361 -286.642605) (xy 143.943755 -286.671659) (xy 143.892426 -286.693471)
			(xy 143.838469 -286.707577) (xy 143.783032 -286.713677) (xy 143.727298 -286.71164) (xy 143.672455 -286.70151)
			(xy 143.619671 -286.683503) (xy 143.570071 -286.658002) (xy 143.524713 -286.625551) (xy 143.484564 -286.586842)
			(xy 143.450478 -286.542699) (xy 143.423182 -286.494064) (xy 143.403259 -286.441973) (xy 143.391133 -286.387536)
			(xy 143.387062 -286.331914) (xy 142.675102 -286.331914) (xy 142.674593 -286.3598) (xy 142.666473 -286.414976)
			(xy 142.650405 -286.468383) (xy 142.626733 -286.51888) (xy 142.59596 -286.565393) (xy 142.558743 -286.60693)
			(xy 142.515875 -286.642605) (xy 142.468269 -286.671659) (xy 142.41694 -286.693471) (xy 142.362983 -286.707577)
			(xy 142.307546 -286.713677) (xy 142.251812 -286.71164) (xy 142.196969 -286.70151) (xy 142.144185 -286.683503)
			(xy 142.094585 -286.658002) (xy 142.049227 -286.625551) (xy 142.009078 -286.586842) (xy 141.974992 -286.542699)
			(xy 141.947696 -286.494064) (xy 141.927773 -286.441973) (xy 141.915647 -286.387536) (xy 141.911576 -286.331914)
			(xy 135.153908 -286.331914) (xy 135.153908 -288.230056) (xy 141.911576 -288.230056) (xy 141.915647 -288.174434)
			(xy 141.927773 -288.119997) (xy 141.947696 -288.067906) (xy 141.974992 -288.019271) (xy 142.009078 -287.975128)
			(xy 142.049227 -287.936419) (xy 142.094585 -287.903968) (xy 142.144185 -287.878467) (xy 142.196969 -287.86046)
			(xy 142.251812 -287.85033) (xy 142.307546 -287.848293) (xy 142.362983 -287.854393) (xy 142.41694 -287.868499)
			(xy 142.468269 -287.890311) (xy 142.515875 -287.919365) (xy 142.558743 -287.95504) (xy 142.59596 -287.996577)
			(xy 142.626733 -288.04309) (xy 142.650405 -288.093587) (xy 142.666473 -288.146994) (xy 142.674593 -288.20217)
			(xy 142.675102 -288.230056) (xy 143.396714 -288.230056) (xy 143.400785 -288.174434) (xy 143.412911 -288.119997)
			(xy 143.432834 -288.067906) (xy 143.46013 -288.019271) (xy 143.494216 -287.975128) (xy 143.534365 -287.936419)
			(xy 143.579723 -287.903968) (xy 143.629323 -287.878467) (xy 143.682107 -287.86046) (xy 143.73695 -287.85033)
			(xy 143.792684 -287.848293) (xy 143.848121 -287.854393) (xy 143.902078 -287.868499) (xy 143.953407 -287.890311)
			(xy 144.001013 -287.919365) (xy 144.043881 -287.95504) (xy 144.081098 -287.996577) (xy 144.111871 -288.04309)
			(xy 144.135543 -288.093587) (xy 144.151611 -288.146994) (xy 144.159731 -288.20217) (xy 144.16024 -288.230056)
			(xy 144.159731 -288.257942) (xy 144.151611 -288.313118) (xy 144.135543 -288.366525) (xy 144.111871 -288.417022)
			(xy 144.081098 -288.463535) (xy 144.043881 -288.505072) (xy 144.001013 -288.540747) (xy 143.953407 -288.569801)
			(xy 143.902078 -288.591613) (xy 143.848121 -288.605719) (xy 143.792684 -288.611819) (xy 143.73695 -288.609782)
			(xy 143.682107 -288.599652) (xy 143.629323 -288.581645) (xy 143.579723 -288.556144) (xy 143.534365 -288.523693)
			(xy 143.494216 -288.484984) (xy 143.46013 -288.440841) (xy 143.432834 -288.392206) (xy 143.412911 -288.340115)
			(xy 143.400785 -288.285678) (xy 143.396714 -288.230056) (xy 142.675102 -288.230056) (xy 142.674593 -288.257942)
			(xy 142.666473 -288.313118) (xy 142.650405 -288.366525) (xy 142.626733 -288.417022) (xy 142.59596 -288.463535)
			(xy 142.558743 -288.505072) (xy 142.515875 -288.540747) (xy 142.468269 -288.569801) (xy 142.41694 -288.591613)
			(xy 142.362983 -288.605719) (xy 142.307546 -288.611819) (xy 142.251812 -288.609782) (xy 142.196969 -288.599652)
			(xy 142.144185 -288.581645) (xy 142.094585 -288.556144) (xy 142.049227 -288.523693) (xy 142.009078 -288.484984)
			(xy 141.974992 -288.440841) (xy 141.947696 -288.392206) (xy 141.927773 -288.340115) (xy 141.915647 -288.285678)
			(xy 141.911576 -288.230056) (xy 135.153908 -288.230056) (xy 135.153908 -289.532314) (xy 141.911576 -289.532314)
			(xy 141.915647 -289.476692) (xy 141.927773 -289.422255) (xy 141.947696 -289.370164) (xy 141.974992 -289.321529)
			(xy 142.009078 -289.277386) (xy 142.049227 -289.238677) (xy 142.094585 -289.206226) (xy 142.144185 -289.180725)
			(xy 142.196969 -289.162718) (xy 142.251812 -289.152588) (xy 142.307546 -289.150551) (xy 142.362983 -289.156651)
			(xy 142.41694 -289.170757) (xy 142.468269 -289.192569) (xy 142.515875 -289.221623) (xy 142.558743 -289.257298)
			(xy 142.59596 -289.298835) (xy 142.626733 -289.345348) (xy 142.650405 -289.395845) (xy 142.666473 -289.449252)
			(xy 142.674593 -289.504428) (xy 142.675102 -289.532314) (xy 143.387062 -289.532314) (xy 143.391133 -289.476692)
			(xy 143.403259 -289.422255) (xy 143.423182 -289.370164) (xy 143.450478 -289.321529) (xy 143.484564 -289.277386)
			(xy 143.524713 -289.238677) (xy 143.570071 -289.206226) (xy 143.619671 -289.180725) (xy 143.672455 -289.162718)
			(xy 143.727298 -289.152588) (xy 143.783032 -289.150551) (xy 143.838469 -289.156651) (xy 143.892426 -289.170757)
			(xy 143.943755 -289.192569) (xy 143.991361 -289.221623) (xy 144.034229 -289.257298) (xy 144.071446 -289.298835)
			(xy 144.102219 -289.345348) (xy 144.125891 -289.395845) (xy 144.141959 -289.449252) (xy 144.150079 -289.504428)
			(xy 144.150588 -289.532314) (xy 144.276062 -289.532314) (xy 144.280133 -289.476692) (xy 144.292259 -289.422255)
			(xy 144.312182 -289.370164) (xy 144.339478 -289.321529) (xy 144.373564 -289.277386) (xy 144.413713 -289.238677)
			(xy 144.459071 -289.206226) (xy 144.508671 -289.180725) (xy 144.561455 -289.162718) (xy 144.616298 -289.152588)
			(xy 144.672032 -289.150551) (xy 144.727469 -289.156651) (xy 144.781426 -289.170757) (xy 144.832755 -289.192569)
			(xy 144.880361 -289.221623) (xy 144.923229 -289.257298) (xy 144.960446 -289.298835) (xy 144.991219 -289.345348)
			(xy 145.014891 -289.395845) (xy 145.030959 -289.449252) (xy 145.039079 -289.504428) (xy 145.039588 -289.532314)
			(xy 145.039079 -289.5602) (xy 145.030959 -289.615376) (xy 145.014891 -289.668783) (xy 144.991219 -289.71928)
			(xy 144.960446 -289.765793) (xy 144.923229 -289.80733) (xy 144.880361 -289.843005) (xy 144.832755 -289.872059)
			(xy 144.781426 -289.893871) (xy 144.727469 -289.907977) (xy 144.672032 -289.914077) (xy 144.616298 -289.91204)
			(xy 144.561455 -289.90191) (xy 144.508671 -289.883903) (xy 144.459071 -289.858402) (xy 144.413713 -289.825951)
			(xy 144.373564 -289.787242) (xy 144.339478 -289.743099) (xy 144.312182 -289.694464) (xy 144.292259 -289.642373)
			(xy 144.280133 -289.587936) (xy 144.276062 -289.532314) (xy 144.150588 -289.532314) (xy 144.150079 -289.5602)
			(xy 144.141959 -289.615376) (xy 144.125891 -289.668783) (xy 144.102219 -289.71928) (xy 144.071446 -289.765793)
			(xy 144.034229 -289.80733) (xy 143.991361 -289.843005) (xy 143.943755 -289.872059) (xy 143.892426 -289.893871)
			(xy 143.838469 -289.907977) (xy 143.783032 -289.914077) (xy 143.727298 -289.91204) (xy 143.672455 -289.90191)
			(xy 143.619671 -289.883903) (xy 143.570071 -289.858402) (xy 143.524713 -289.825951) (xy 143.484564 -289.787242)
			(xy 143.450478 -289.743099) (xy 143.423182 -289.694464) (xy 143.403259 -289.642373) (xy 143.391133 -289.587936)
			(xy 143.387062 -289.532314) (xy 142.675102 -289.532314) (xy 142.674593 -289.5602) (xy 142.666473 -289.615376)
			(xy 142.650405 -289.668783) (xy 142.626733 -289.71928) (xy 142.59596 -289.765793) (xy 142.558743 -289.80733)
			(xy 142.515875 -289.843005) (xy 142.468269 -289.872059) (xy 142.41694 -289.893871) (xy 142.362983 -289.907977)
			(xy 142.307546 -289.914077) (xy 142.251812 -289.91204) (xy 142.196969 -289.90191) (xy 142.144185 -289.883903)
			(xy 142.094585 -289.858402) (xy 142.049227 -289.825951) (xy 142.009078 -289.787242) (xy 141.974992 -289.743099)
			(xy 141.947696 -289.694464) (xy 141.927773 -289.642373) (xy 141.915647 -289.587936) (xy 141.911576 -289.532314)
			(xy 135.153908 -289.532314) (xy 135.153908 -291.430456) (xy 141.911576 -291.430456) (xy 141.915647 -291.374834)
			(xy 141.927773 -291.320397) (xy 141.947696 -291.268306) (xy 141.974992 -291.219671) (xy 142.009078 -291.175528)
			(xy 142.049227 -291.136819) (xy 142.094585 -291.104368) (xy 142.144185 -291.078867) (xy 142.196969 -291.06086)
			(xy 142.251812 -291.05073) (xy 142.307546 -291.048693) (xy 142.362983 -291.054793) (xy 142.41694 -291.068899)
			(xy 142.468269 -291.090711) (xy 142.515875 -291.119765) (xy 142.558743 -291.15544) (xy 142.59596 -291.196977)
			(xy 142.626733 -291.24349) (xy 142.650405 -291.293987) (xy 142.666473 -291.347394) (xy 142.674593 -291.40257)
			(xy 142.675102 -291.430456) (xy 143.396714 -291.430456) (xy 143.400785 -291.374834) (xy 143.412911 -291.320397)
			(xy 143.432834 -291.268306) (xy 143.46013 -291.219671) (xy 143.494216 -291.175528) (xy 143.534365 -291.136819)
			(xy 143.579723 -291.104368) (xy 143.629323 -291.078867) (xy 143.682107 -291.06086) (xy 143.73695 -291.05073)
			(xy 143.792684 -291.048693) (xy 143.848121 -291.054793) (xy 143.902078 -291.068899) (xy 143.953407 -291.090711)
			(xy 144.001013 -291.119765) (xy 144.043881 -291.15544) (xy 144.081098 -291.196977) (xy 144.111871 -291.24349)
			(xy 144.135543 -291.293987) (xy 144.151611 -291.347394) (xy 144.159731 -291.40257) (xy 144.16024 -291.430456)
			(xy 144.159731 -291.458342) (xy 144.151611 -291.513518) (xy 144.135543 -291.566925) (xy 144.111871 -291.617422)
			(xy 144.081098 -291.663935) (xy 144.043881 -291.705472) (xy 144.001013 -291.741147) (xy 143.953407 -291.770201)
			(xy 143.902078 -291.792013) (xy 143.848121 -291.806119) (xy 143.792684 -291.812219) (xy 143.73695 -291.810182)
			(xy 143.682107 -291.800052) (xy 143.629323 -291.782045) (xy 143.579723 -291.756544) (xy 143.534365 -291.724093)
			(xy 143.494216 -291.685384) (xy 143.46013 -291.641241) (xy 143.432834 -291.592606) (xy 143.412911 -291.540515)
			(xy 143.400785 -291.486078) (xy 143.396714 -291.430456) (xy 142.675102 -291.430456) (xy 142.674593 -291.458342)
			(xy 142.666473 -291.513518) (xy 142.650405 -291.566925) (xy 142.626733 -291.617422) (xy 142.59596 -291.663935)
			(xy 142.558743 -291.705472) (xy 142.515875 -291.741147) (xy 142.468269 -291.770201) (xy 142.41694 -291.792013)
			(xy 142.362983 -291.806119) (xy 142.307546 -291.812219) (xy 142.251812 -291.810182) (xy 142.196969 -291.800052)
			(xy 142.144185 -291.782045) (xy 142.094585 -291.756544) (xy 142.049227 -291.724093) (xy 142.009078 -291.685384)
			(xy 141.974992 -291.641241) (xy 141.947696 -291.592606) (xy 141.927773 -291.540515) (xy 141.915647 -291.486078)
			(xy 141.911576 -291.430456) (xy 135.153908 -291.430456) (xy 135.153908 -292.732714) (xy 141.911576 -292.732714)
			(xy 141.915647 -292.677092) (xy 141.927773 -292.622655) (xy 141.947696 -292.570564) (xy 141.974992 -292.521929)
			(xy 142.009078 -292.477786) (xy 142.049227 -292.439077) (xy 142.094585 -292.406626) (xy 142.144185 -292.381125)
			(xy 142.196969 -292.363118) (xy 142.251812 -292.352988) (xy 142.307546 -292.350951) (xy 142.362983 -292.357051)
			(xy 142.41694 -292.371157) (xy 142.468269 -292.392969) (xy 142.515875 -292.422023) (xy 142.558743 -292.457698)
			(xy 142.59596 -292.499235) (xy 142.626733 -292.545748) (xy 142.650405 -292.596245) (xy 142.666473 -292.649652)
			(xy 142.674593 -292.704828) (xy 142.675102 -292.732714) (xy 143.387062 -292.732714) (xy 143.391133 -292.677092)
			(xy 143.403259 -292.622655) (xy 143.423182 -292.570564) (xy 143.450478 -292.521929) (xy 143.484564 -292.477786)
			(xy 143.524713 -292.439077) (xy 143.570071 -292.406626) (xy 143.619671 -292.381125) (xy 143.672455 -292.363118)
			(xy 143.727298 -292.352988) (xy 143.783032 -292.350951) (xy 143.838469 -292.357051) (xy 143.892426 -292.371157)
			(xy 143.943755 -292.392969) (xy 143.991361 -292.422023) (xy 144.034229 -292.457698) (xy 144.071446 -292.499235)
			(xy 144.102219 -292.545748) (xy 144.125891 -292.596245) (xy 144.141959 -292.649652) (xy 144.150079 -292.704828)
			(xy 144.150588 -292.732714) (xy 144.276062 -292.732714) (xy 144.280133 -292.677092) (xy 144.292259 -292.622655)
			(xy 144.312182 -292.570564) (xy 144.339478 -292.521929) (xy 144.373564 -292.477786) (xy 144.413713 -292.439077)
			(xy 144.459071 -292.406626) (xy 144.508671 -292.381125) (xy 144.561455 -292.363118) (xy 144.616298 -292.352988)
			(xy 144.672032 -292.350951) (xy 144.727469 -292.357051) (xy 144.781426 -292.371157) (xy 144.832755 -292.392969)
			(xy 144.880361 -292.422023) (xy 144.923229 -292.457698) (xy 144.960446 -292.499235) (xy 144.991219 -292.545748)
			(xy 145.014891 -292.596245) (xy 145.030959 -292.649652) (xy 145.039079 -292.704828) (xy 145.039588 -292.732714)
			(xy 145.039079 -292.7606) (xy 145.030959 -292.815776) (xy 145.014891 -292.869183) (xy 144.991219 -292.91968)
			(xy 144.960446 -292.966193) (xy 144.923229 -293.00773) (xy 144.880361 -293.043405) (xy 144.832755 -293.072459)
			(xy 144.781426 -293.094271) (xy 144.727469 -293.108377) (xy 144.672032 -293.114477) (xy 144.616298 -293.11244)
			(xy 144.561455 -293.10231) (xy 144.508671 -293.084303) (xy 144.459071 -293.058802) (xy 144.413713 -293.026351)
			(xy 144.373564 -292.987642) (xy 144.339478 -292.943499) (xy 144.312182 -292.894864) (xy 144.292259 -292.842773)
			(xy 144.280133 -292.788336) (xy 144.276062 -292.732714) (xy 144.150588 -292.732714) (xy 144.150079 -292.7606)
			(xy 144.141959 -292.815776) (xy 144.125891 -292.869183) (xy 144.102219 -292.91968) (xy 144.071446 -292.966193)
			(xy 144.034229 -293.00773) (xy 143.991361 -293.043405) (xy 143.943755 -293.072459) (xy 143.892426 -293.094271)
			(xy 143.838469 -293.108377) (xy 143.783032 -293.114477) (xy 143.727298 -293.11244) (xy 143.672455 -293.10231)
			(xy 143.619671 -293.084303) (xy 143.570071 -293.058802) (xy 143.524713 -293.026351) (xy 143.484564 -292.987642)
			(xy 143.450478 -292.943499) (xy 143.423182 -292.894864) (xy 143.403259 -292.842773) (xy 143.391133 -292.788336)
			(xy 143.387062 -292.732714) (xy 142.675102 -292.732714) (xy 142.674593 -292.7606) (xy 142.666473 -292.815776)
			(xy 142.650405 -292.869183) (xy 142.626733 -292.91968) (xy 142.59596 -292.966193) (xy 142.558743 -293.00773)
			(xy 142.515875 -293.043405) (xy 142.468269 -293.072459) (xy 142.41694 -293.094271) (xy 142.362983 -293.108377)
			(xy 142.307546 -293.114477) (xy 142.251812 -293.11244) (xy 142.196969 -293.10231) (xy 142.144185 -293.084303)
			(xy 142.094585 -293.058802) (xy 142.049227 -293.026351) (xy 142.009078 -292.987642) (xy 141.974992 -292.943499)
			(xy 141.947696 -292.894864) (xy 141.927773 -292.842773) (xy 141.915647 -292.788336) (xy 141.911576 -292.732714)
			(xy 135.153908 -292.732714) (xy 135.153908 -294.630856) (xy 141.911576 -294.630856) (xy 141.915647 -294.575234)
			(xy 141.927773 -294.520797) (xy 141.947696 -294.468706) (xy 141.974992 -294.420071) (xy 142.009078 -294.375928)
			(xy 142.049227 -294.337219) (xy 142.094585 -294.304768) (xy 142.144185 -294.279267) (xy 142.196969 -294.26126)
			(xy 142.251812 -294.25113) (xy 142.307546 -294.249093) (xy 142.362983 -294.255193) (xy 142.41694 -294.269299)
			(xy 142.468269 -294.291111) (xy 142.515875 -294.320165) (xy 142.558743 -294.35584) (xy 142.59596 -294.397377)
			(xy 142.626733 -294.44389) (xy 142.650405 -294.494387) (xy 142.666473 -294.547794) (xy 142.674593 -294.60297)
			(xy 142.675102 -294.630856) (xy 143.396714 -294.630856) (xy 143.400785 -294.575234) (xy 143.412911 -294.520797)
			(xy 143.432834 -294.468706) (xy 143.46013 -294.420071) (xy 143.494216 -294.375928) (xy 143.534365 -294.337219)
			(xy 143.579723 -294.304768) (xy 143.629323 -294.279267) (xy 143.682107 -294.26126) (xy 143.73695 -294.25113)
			(xy 143.792684 -294.249093) (xy 143.848121 -294.255193) (xy 143.902078 -294.269299) (xy 143.953407 -294.291111)
			(xy 144.001013 -294.320165) (xy 144.043881 -294.35584) (xy 144.081098 -294.397377) (xy 144.111871 -294.44389)
			(xy 144.135543 -294.494387) (xy 144.151611 -294.547794) (xy 144.159731 -294.60297) (xy 144.16024 -294.630856)
			(xy 144.159731 -294.658742) (xy 144.151611 -294.713918) (xy 144.135543 -294.767325) (xy 144.111871 -294.817822)
			(xy 144.081098 -294.864335) (xy 144.043881 -294.905872) (xy 144.001013 -294.941547) (xy 143.953407 -294.970601)
			(xy 143.902078 -294.992413) (xy 143.848121 -295.006519) (xy 143.792684 -295.012619) (xy 143.73695 -295.010582)
			(xy 143.682107 -295.000452) (xy 143.629323 -294.982445) (xy 143.579723 -294.956944) (xy 143.534365 -294.924493)
			(xy 143.494216 -294.885784) (xy 143.46013 -294.841641) (xy 143.432834 -294.793006) (xy 143.412911 -294.740915)
			(xy 143.400785 -294.686478) (xy 143.396714 -294.630856) (xy 142.675102 -294.630856) (xy 142.674593 -294.658742)
			(xy 142.666473 -294.713918) (xy 142.650405 -294.767325) (xy 142.626733 -294.817822) (xy 142.59596 -294.864335)
			(xy 142.558743 -294.905872) (xy 142.515875 -294.941547) (xy 142.468269 -294.970601) (xy 142.41694 -294.992413)
			(xy 142.362983 -295.006519) (xy 142.307546 -295.012619) (xy 142.251812 -295.010582) (xy 142.196969 -295.000452)
			(xy 142.144185 -294.982445) (xy 142.094585 -294.956944) (xy 142.049227 -294.924493) (xy 142.009078 -294.885784)
			(xy 141.974992 -294.841641) (xy 141.947696 -294.793006) (xy 141.927773 -294.740915) (xy 141.915647 -294.686478)
			(xy 141.911576 -294.630856) (xy 135.153908 -294.630856) (xy 135.153908 -295.933114) (xy 141.911576 -295.933114)
			(xy 141.915647 -295.877492) (xy 141.927773 -295.823055) (xy 141.947696 -295.770964) (xy 141.974992 -295.722329)
			(xy 142.009078 -295.678186) (xy 142.049227 -295.639477) (xy 142.094585 -295.607026) (xy 142.144185 -295.581525)
			(xy 142.196969 -295.563518) (xy 142.251812 -295.553388) (xy 142.307546 -295.551351) (xy 142.362983 -295.557451)
			(xy 142.41694 -295.571557) (xy 142.468269 -295.593369) (xy 142.515875 -295.622423) (xy 142.558743 -295.658098)
			(xy 142.59596 -295.699635) (xy 142.626733 -295.746148) (xy 142.650405 -295.796645) (xy 142.666473 -295.850052)
			(xy 142.674593 -295.905228) (xy 142.675102 -295.933114) (xy 143.387062 -295.933114) (xy 143.391133 -295.877492)
			(xy 143.403259 -295.823055) (xy 143.423182 -295.770964) (xy 143.450478 -295.722329) (xy 143.484564 -295.678186)
			(xy 143.524713 -295.639477) (xy 143.570071 -295.607026) (xy 143.619671 -295.581525) (xy 143.672455 -295.563518)
			(xy 143.727298 -295.553388) (xy 143.783032 -295.551351) (xy 143.838469 -295.557451) (xy 143.892426 -295.571557)
			(xy 143.943755 -295.593369) (xy 143.991361 -295.622423) (xy 144.034229 -295.658098) (xy 144.071446 -295.699635)
			(xy 144.102219 -295.746148) (xy 144.125891 -295.796645) (xy 144.141959 -295.850052) (xy 144.150079 -295.905228)
			(xy 144.150588 -295.933114) (xy 144.150079 -295.961) (xy 144.141959 -296.016176) (xy 144.125891 -296.069583)
			(xy 144.102219 -296.12008) (xy 144.071446 -296.166593) (xy 144.034229 -296.20813) (xy 143.991361 -296.243805)
			(xy 143.943755 -296.272859) (xy 143.892426 -296.294671) (xy 143.838469 -296.308777) (xy 143.783032 -296.314877)
			(xy 143.727298 -296.31284) (xy 143.672455 -296.30271) (xy 143.619671 -296.284703) (xy 143.570071 -296.259202)
			(xy 143.524713 -296.226751) (xy 143.484564 -296.188042) (xy 143.450478 -296.143899) (xy 143.423182 -296.095264)
			(xy 143.403259 -296.043173) (xy 143.391133 -295.988736) (xy 143.387062 -295.933114) (xy 142.675102 -295.933114)
			(xy 142.674593 -295.961) (xy 142.666473 -296.016176) (xy 142.650405 -296.069583) (xy 142.626733 -296.12008)
			(xy 142.59596 -296.166593) (xy 142.558743 -296.20813) (xy 142.515875 -296.243805) (xy 142.468269 -296.272859)
			(xy 142.41694 -296.294671) (xy 142.362983 -296.308777) (xy 142.307546 -296.314877) (xy 142.251812 -296.31284)
			(xy 142.196969 -296.30271) (xy 142.144185 -296.284703) (xy 142.094585 -296.259202) (xy 142.049227 -296.226751)
			(xy 142.009078 -296.188042) (xy 141.974992 -296.143899) (xy 141.947696 -296.095264) (xy 141.927773 -296.043173)
			(xy 141.915647 -295.988736) (xy 141.911576 -295.933114) (xy 135.153908 -295.933114) (xy 135.153908 -297.831256)
			(xy 141.911576 -297.831256) (xy 141.915647 -297.775634) (xy 141.927773 -297.721197) (xy 141.947696 -297.669106)
			(xy 141.974992 -297.620471) (xy 142.009078 -297.576328) (xy 142.049227 -297.537619) (xy 142.094585 -297.505168)
			(xy 142.144185 -297.479667) (xy 142.196969 -297.46166) (xy 142.251812 -297.45153) (xy 142.307546 -297.449493)
			(xy 142.362983 -297.455593) (xy 142.41694 -297.469699) (xy 142.468269 -297.491511) (xy 142.515875 -297.520565)
			(xy 142.558743 -297.55624) (xy 142.59596 -297.597777) (xy 142.626733 -297.64429) (xy 142.650405 -297.694787)
			(xy 142.666473 -297.748194) (xy 142.674593 -297.80337) (xy 142.675102 -297.831256) (xy 143.396714 -297.831256)
			(xy 143.400785 -297.775634) (xy 143.412911 -297.721197) (xy 143.432834 -297.669106) (xy 143.46013 -297.620471)
			(xy 143.494216 -297.576328) (xy 143.534365 -297.537619) (xy 143.579723 -297.505168) (xy 143.629323 -297.479667)
			(xy 143.682107 -297.46166) (xy 143.73695 -297.45153) (xy 143.792684 -297.449493) (xy 143.848121 -297.455593)
			(xy 143.902078 -297.469699) (xy 143.953407 -297.491511) (xy 144.001013 -297.520565) (xy 144.043881 -297.55624)
			(xy 144.081098 -297.597777) (xy 144.111871 -297.64429) (xy 144.135543 -297.694787) (xy 144.151611 -297.748194)
			(xy 144.159731 -297.80337) (xy 144.16024 -297.831256) (xy 144.159731 -297.859142) (xy 144.151611 -297.914318)
			(xy 144.135543 -297.967725) (xy 144.111871 -298.018222) (xy 144.081098 -298.064735) (xy 144.043881 -298.106272)
			(xy 144.001013 -298.141947) (xy 143.953407 -298.171001) (xy 143.902078 -298.192813) (xy 143.848121 -298.206919)
			(xy 143.792684 -298.213019) (xy 143.73695 -298.210982) (xy 143.682107 -298.200852) (xy 143.629323 -298.182845)
			(xy 143.579723 -298.157344) (xy 143.534365 -298.124893) (xy 143.494216 -298.086184) (xy 143.46013 -298.042041)
			(xy 143.432834 -297.993406) (xy 143.412911 -297.941315) (xy 143.400785 -297.886878) (xy 143.396714 -297.831256)
			(xy 142.675102 -297.831256) (xy 142.674593 -297.859142) (xy 142.666473 -297.914318) (xy 142.650405 -297.967725)
			(xy 142.626733 -298.018222) (xy 142.59596 -298.064735) (xy 142.558743 -298.106272) (xy 142.515875 -298.141947)
			(xy 142.468269 -298.171001) (xy 142.41694 -298.192813) (xy 142.362983 -298.206919) (xy 142.307546 -298.213019)
			(xy 142.251812 -298.210982) (xy 142.196969 -298.200852) (xy 142.144185 -298.182845) (xy 142.094585 -298.157344)
			(xy 142.049227 -298.124893) (xy 142.009078 -298.086184) (xy 141.974992 -298.042041) (xy 141.947696 -297.993406)
			(xy 141.927773 -297.941315) (xy 141.915647 -297.886878) (xy 141.911576 -297.831256) (xy 135.153908 -297.831256)
			(xy 135.153908 -299.133514) (xy 141.911576 -299.133514) (xy 141.915647 -299.077892) (xy 141.927773 -299.023455)
			(xy 141.947696 -298.971364) (xy 141.974992 -298.922729) (xy 142.009078 -298.878586) (xy 142.049227 -298.839877)
			(xy 142.094585 -298.807426) (xy 142.144185 -298.781925) (xy 142.196969 -298.763918) (xy 142.251812 -298.753788)
			(xy 142.307546 -298.751751) (xy 142.362983 -298.757851) (xy 142.41694 -298.771957) (xy 142.468269 -298.793769)
			(xy 142.515875 -298.822823) (xy 142.558743 -298.858498) (xy 142.59596 -298.900035) (xy 142.626733 -298.946548)
			(xy 142.650405 -298.997045) (xy 142.666473 -299.050452) (xy 142.674593 -299.105628) (xy 142.675102 -299.133514)
			(xy 143.387062 -299.133514) (xy 143.391133 -299.077892) (xy 143.403259 -299.023455) (xy 143.423182 -298.971364)
			(xy 143.450478 -298.922729) (xy 143.484564 -298.878586) (xy 143.524713 -298.839877) (xy 143.570071 -298.807426)
			(xy 143.619671 -298.781925) (xy 143.672455 -298.763918) (xy 143.727298 -298.753788) (xy 143.783032 -298.751751)
			(xy 143.838469 -298.757851) (xy 143.892426 -298.771957) (xy 143.943755 -298.793769) (xy 143.991361 -298.822823)
			(xy 144.034229 -298.858498) (xy 144.071446 -298.900035) (xy 144.102219 -298.946548) (xy 144.125891 -298.997045)
			(xy 144.141959 -299.050452) (xy 144.150079 -299.105628) (xy 144.150588 -299.133511) (xy 144.275956 -299.133511)
			(xy 144.280324 -299.075887) (xy 144.293331 -299.019581) (xy 144.31468 -298.96588) (xy 144.343882 -298.916012)
			(xy 144.361662 -298.89323) (xy 144.368289 -298.884219) (xy 144.373658 -298.862528) (xy 144.369329 -298.840604)
			(xy 144.363186 -298.831254) (xy 144.34439 -298.802044) (xy 144.332369 -298.780175) (xy 144.314889 -298.733437)
			(xy 144.305262 -298.684474) (xy 144.304004 -298.65955) (xy 144.304004 -296.55516) (xy 144.305254 -296.529134)
			(xy 144.315491 -296.47805) (xy 144.334261 -296.429449) (xy 144.347184 -296.406824) (xy 144.355625 -296.393128)
			(xy 144.37497 -296.36742) (xy 144.385792 -296.355516) (xy 144.417034 -296.32402) (xy 144.429734 -296.31132)
			(xy 144.436541 -296.303956) (xy 144.44426 -296.285464) (xy 144.444317 -296.265425) (xy 144.436704 -296.246889)
			(xy 144.429988 -296.239438) (xy 144.427702 -296.237152) (xy 144.424908 -296.23512) (xy 144.402229 -296.216954)
			(xy 144.362168 -296.174867) (xy 144.328948 -296.127194) (xy 144.303336 -296.075037) (xy 144.285925 -296.019601)
			(xy 144.277117 -295.962167) (xy 144.276572 -295.933114) (xy 144.277091 -295.905864) (xy 144.284845 -295.851919)
			(xy 144.300198 -295.799626) (xy 144.322836 -295.75005) (xy 144.352299 -295.704201) (xy 144.387987 -295.663011)
			(xy 144.429173 -295.627319) (xy 144.47502 -295.597852) (xy 144.524594 -295.57521) (xy 144.576885 -295.559853)
			(xy 144.63083 -295.552094) (xy 144.65808 -295.551606) (xy 144.685887 -295.552107) (xy 144.740908 -295.560206)
			(xy 144.794171 -295.576205) (xy 144.844548 -295.599767) (xy 144.890971 -295.630391) (xy 144.932457 -295.66743)
			(xy 144.968127 -295.710098) (xy 144.997225 -295.757492) (xy 145.019137 -295.808608) (xy 145.033396 -295.862363)
			(xy 145.037048 -295.889934) (xy 145.037048 -295.890188) (xy 145.038627 -295.899304) (xy 145.047241 -295.915656)
			(xy 145.061078 -295.927908) (xy 145.078354 -295.934477) (xy 145.087594 -295.934892) (xy 147.401534 -295.934892)
			(xy 147.410796 -295.934559) (xy 147.428126 -295.928023) (xy 147.441995 -295.915746) (xy 147.450584 -295.899336)
			(xy 147.45208 -295.890188) (xy 147.45208 -295.889934) (xy 147.455886 -295.861341) (xy 147.47095 -295.805663)
			(xy 147.494232 -295.752891) (xy 147.5252 -295.70423) (xy 147.543774 -295.682162) (xy 147.549674 -295.674794)
			(xy 147.556076 -295.657055) (xy 147.55622 -295.647618) (xy 147.555204 -295.596056) (xy 147.54987 -295.590976)
			(xy 147.38223 -295.423336) (xy 147.365537 -295.40608) (xy 147.337285 -295.367263) (xy 147.315453 -295.324503)
			(xy 147.300581 -295.278854) (xy 147.293033 -295.231441) (xy 147.292568 -295.207436) (xy 147.292568 -293.1795)
			(xy 147.29314 -293.153815) (xy 147.301834 -293.103184) (xy 147.318876 -293.054721) (xy 147.343785 -293.009791)
			(xy 147.37586 -292.969663) (xy 147.394676 -292.95217) (xy 147.463764 -292.890448) (xy 147.471638 -292.861492)
			(xy 147.467066 -292.847268) (xy 147.458864 -292.819343) (xy 147.450067 -292.761814) (xy 147.44954 -292.732714)
			(xy 147.449782 -292.712235) (xy 147.454105 -292.671506) (xy 147.458176 -292.651434) (xy 147.459857 -292.641911)
			(xy 147.456707 -292.622843) (xy 147.45208 -292.61435) (xy 147.411186 -292.546278) (xy 147.395692 -292.534594)
			(xy 147.386548 -292.532054) (xy 147.36155 -292.524507) (xy 147.31441 -292.502053) (xy 147.27177 -292.471917)
			(xy 147.252944 -292.453822) (xy 147.184364 -292.385242) (xy 147.167772 -292.367943) (xy 147.139604 -292.329165)
			(xy 147.117835 -292.286466) (xy 147.102997 -292.240891) (xy 147.095454 -292.19356) (xy 147.094956 -292.169596)
			(xy 147.094956 -289.830256) (xy 147.095379 -289.806607) (xy 147.102645 -289.759872) (xy 147.117041 -289.714819)
			(xy 147.138223 -289.67253) (xy 147.165682 -289.63402) (xy 147.198759 -289.600214) (xy 147.236661 -289.571921)
			(xy 147.278477 -289.549821) (xy 147.300696 -289.541712) (xy 147.435824 -289.49523) (xy 147.453604 -289.474656)
			(xy 147.456144 -289.461194) (xy 147.461558 -289.435123) (xy 147.478651 -289.384695) (xy 147.502591 -289.337134)
			(xy 147.532915 -289.293365) (xy 147.550632 -289.273488) (xy 147.564602 -289.258502) (xy 147.56384 -289.217608)
			(xy 147.251674 -288.905696) (xy 147.244836 -288.898295) (xy 147.237116 -288.879696) (xy 147.236688 -288.869628)
			(xy 147.236688 -286.741362) (xy 147.23707 -286.731287) (xy 147.244818 -286.712688) (xy 147.251674 -286.705294)
			(xy 147.465796 -286.491172) (xy 147.4724 -286.463232) (xy 147.468082 -286.44977) (xy 147.459456 -286.421267)
			(xy 147.45015 -286.36245) (xy 147.44954 -286.332676) (xy 147.44954 -286.331914) (xy 147.449962 -286.306914)
			(xy 147.456501 -286.257344) (xy 147.469456 -286.209051) (xy 147.488604 -286.162863) (xy 147.513618 -286.119571)
			(xy 147.528534 -286.099504) (xy 147.528788 -286.09925) (xy 147.534015 -286.091704) (xy 147.53932 -286.074151)
			(xy 147.53808 -286.055855) (xy 147.530454 -286.039179) (xy 147.524216 -286.032448) (xy 147.287234 -285.795466)
			(xy 147.280391 -285.788068) (xy 147.272672 -285.769467) (xy 147.272248 -285.759398) (xy 147.272248 -283.627068)
			(xy 147.272644 -283.616995) (xy 147.280384 -283.598397) (xy 147.287234 -283.591) (xy 147.35556 -283.522674)
			(xy 147.505674 -283.372306) (xy 147.509992 -283.33827) (xy 147.501356 -283.323284) (xy 147.489061 -283.301364)
			(xy 147.469702 -283.254983) (xy 147.456592 -283.206463) (xy 147.44996 -283.156643) (xy 147.44954 -283.131514)
			(xy 147.449969 -283.104259) (xy 147.457725 -283.050305) (xy 147.473081 -282.998003) (xy 147.495726 -282.94842)
			(xy 147.525197 -282.902564) (xy 147.560894 -282.86137) (xy 147.602092 -282.825676) (xy 147.64795 -282.79621)
			(xy 147.697535 -282.77357) (xy 147.749838 -282.758218) (xy 147.803793 -282.750466) (xy 147.831048 -282.750006)
			(xy 147.857871 -282.750535) (xy 147.910985 -282.758065) (xy 147.962523 -282.772954) (xy 148.01147 -282.794912)
			(xy 148.056861 -282.823504) (xy 148.097803 -282.858168) (xy 148.13349 -282.898221) (xy 148.16322 -282.942876)
			(xy 148.186406 -282.991252) (xy 148.202593 -283.042397) (xy 148.207476 -283.068776) (xy 148.210524 -283.087318)
			(xy 148.238718 -283.111448) (xy 152.119076 -283.111448) (xy 152.128844 -283.111079) (xy 152.146968 -283.103785)
			(xy 152.161053 -283.090246) (xy 152.169055 -283.072424) (xy 152.169876 -283.06268) (xy 152.171328 -283.038105)
			(xy 152.18116 -282.989869) (xy 152.198604 -282.943836) (xy 152.223208 -282.901199) (xy 152.254335 -282.863061)
			(xy 152.291177 -282.830412) (xy 152.33278 -282.804096) (xy 152.378066 -282.784797) (xy 152.425862 -282.773013)
			(xy 152.47493 -282.769051) (xy 152.523998 -282.773013) (xy 152.571794 -282.784797) (xy 152.61708 -282.804096)
			(xy 152.658683 -282.830412) (xy 152.695525 -282.863061) (xy 152.726652 -282.901199) (xy 152.751256 -282.943836)
			(xy 152.7687 -282.989869) (xy 152.778532 -283.038105) (xy 152.779984 -283.06268) (xy 152.780831 -283.072411)
			(xy 152.788847 -283.090203) (xy 152.802923 -283.10372) (xy 152.821027 -283.111007) (xy 152.830784 -283.111448)
			(xy 153.069036 -283.111448) (xy 153.078802 -283.111046) (xy 153.096925 -283.103765) (xy 153.11101 -283.090236)
			(xy 153.119014 -283.072421) (xy 153.119836 -283.06268) (xy 153.121288 -283.038105) (xy 153.13112 -282.989869)
			(xy 153.148564 -282.943836) (xy 153.173168 -282.901199) (xy 153.204295 -282.863061) (xy 153.241137 -282.830412)
			(xy 153.28274 -282.804096) (xy 153.328026 -282.784797) (xy 153.375822 -282.773013) (xy 153.42489 -282.769051)
			(xy 153.473958 -282.773013) (xy 153.521754 -282.784797) (xy 153.56704 -282.804096) (xy 153.608643 -282.830412)
			(xy 153.645485 -282.863061) (xy 153.676612 -282.901199) (xy 153.701216 -282.943836) (xy 153.71866 -282.989869)
			(xy 153.728492 -283.038105) (xy 153.729944 -283.06268) (xy 153.730829 -283.072405) (xy 153.738838 -283.09019)
			(xy 153.752902 -283.103706) (xy 153.770992 -283.111001) (xy 153.780744 -283.111448) (xy 153.800302 -283.111448)
			(xy 153.819038 -283.111725) (xy 153.856227 -283.116312) (xy 153.87447 -283.120592) (xy 153.887963 -283.124095)
			(xy 153.914293 -283.133254) (xy 153.927048 -283.13888) (xy 153.938478 -283.144214) (xy 153.963116 -283.142944)
			(xy 154.04592 -283.093922) (xy 154.056135 -283.086922) (xy 154.069015 -283.065822) (xy 154.070558 -283.053536)
			(xy 154.072889 -283.028165) (xy 154.084825 -282.97864) (xy 154.104817 -282.931784) (xy 154.132311 -282.888897)
			(xy 154.166543 -282.85117) (xy 154.206563 -282.81965) (xy 154.251261 -282.79521) (xy 154.299396 -282.778531)
			(xy 154.349633 -282.770074) (xy 154.375104 -282.769564) (xy 154.400357 -282.770142) (xy 154.450173 -282.778455)
			(xy 154.497942 -282.794855) (xy 154.542361 -282.818893) (xy 154.582216 -282.849915) (xy 154.616423 -282.887073)
			(xy 154.644046 -282.929355) (xy 154.664334 -282.975607) (xy 154.676732 -283.024567) (xy 154.680901 -283.074872)
			(xy 155.01926 -283.074872) (xy 155.02322 -283.025818) (xy 155.034997 -282.978034) (xy 155.054288 -282.932758)
			(xy 155.080591 -282.891162) (xy 155.113226 -282.854325) (xy 155.151347 -282.8232) (xy 155.193968 -282.798593)
			(xy 155.239984 -282.781141) (xy 155.288203 -282.771297) (xy 155.337378 -282.769316) (xy 155.386233 -282.775248)
			(xy 155.433504 -282.78894) (xy 155.477966 -282.810038) (xy 155.518469 -282.837994) (xy 155.553962 -282.872086)
			(xy 155.583527 -282.91143) (xy 155.606398 -282.955007) (xy 155.621982 -283.001688) (xy 155.629877 -283.050265)
			(xy 155.630372 -283.074872) (xy 155.96922 -283.074872) (xy 155.97318 -283.025818) (xy 155.984957 -282.978034)
			(xy 156.004248 -282.932758) (xy 156.030551 -282.891162) (xy 156.063186 -282.854325) (xy 156.101307 -282.8232)
			(xy 156.143928 -282.798593) (xy 156.189944 -282.781141) (xy 156.238163 -282.771297) (xy 156.287338 -282.769316)
			(xy 156.336193 -282.775248) (xy 156.383464 -282.78894) (xy 156.427926 -282.810038) (xy 156.468429 -282.837994)
			(xy 156.503922 -282.872086) (xy 156.533487 -282.91143) (xy 156.556358 -282.955007) (xy 156.571942 -283.001688)
			(xy 156.579837 -283.050265) (xy 156.580332 -283.074872) (xy 156.91918 -283.074872) (xy 156.92314 -283.025818)
			(xy 156.934917 -282.978034) (xy 156.954208 -282.932758) (xy 156.980511 -282.891162) (xy 157.013146 -282.854325)
			(xy 157.051267 -282.8232) (xy 157.093888 -282.798593) (xy 157.139904 -282.781141) (xy 157.188123 -282.771297)
			(xy 157.237298 -282.769316) (xy 157.286153 -282.775248) (xy 157.333424 -282.78894) (xy 157.377886 -282.810038)
			(xy 157.418389 -282.837994) (xy 157.453882 -282.872086) (xy 157.483447 -282.91143) (xy 157.506318 -282.955007)
			(xy 157.521902 -283.001688) (xy 157.529797 -283.050265) (xy 157.530292 -283.074872) (xy 157.86914 -283.074872)
			(xy 157.8731 -283.025818) (xy 157.884877 -282.978034) (xy 157.904168 -282.932758) (xy 157.930471 -282.891162)
			(xy 157.963106 -282.854325) (xy 158.001227 -282.8232) (xy 158.043848 -282.798593) (xy 158.089864 -282.781141)
			(xy 158.138083 -282.771297) (xy 158.187258 -282.769316) (xy 158.236113 -282.775248) (xy 158.283384 -282.78894)
			(xy 158.327846 -282.810038) (xy 158.368349 -282.837994) (xy 158.403842 -282.872086) (xy 158.433407 -282.91143)
			(xy 158.456278 -282.955007) (xy 158.471862 -283.001688) (xy 158.479757 -283.050265) (xy 158.480252 -283.074872)
			(xy 158.8191 -283.074872) (xy 158.82306 -283.025818) (xy 158.834837 -282.978034) (xy 158.854128 -282.932758)
			(xy 158.880431 -282.891162) (xy 158.913066 -282.854325) (xy 158.951187 -282.8232) (xy 158.993808 -282.798593)
			(xy 159.039824 -282.781141) (xy 159.088043 -282.771297) (xy 159.137218 -282.769316) (xy 159.186073 -282.775248)
			(xy 159.233344 -282.78894) (xy 159.277806 -282.810038) (xy 159.318309 -282.837994) (xy 159.353802 -282.872086)
			(xy 159.383367 -282.91143) (xy 159.406238 -282.955007) (xy 159.421822 -283.001688) (xy 159.429717 -283.050265)
			(xy 159.430212 -283.074872) (xy 159.76906 -283.074872) (xy 159.77302 -283.025818) (xy 159.784797 -282.978034)
			(xy 159.804088 -282.932758) (xy 159.830391 -282.891162) (xy 159.863026 -282.854325) (xy 159.901147 -282.8232)
			(xy 159.943768 -282.798593) (xy 159.989784 -282.781141) (xy 160.038003 -282.771297) (xy 160.087178 -282.769316)
			(xy 160.136033 -282.775248) (xy 160.183304 -282.78894) (xy 160.227766 -282.810038) (xy 160.268269 -282.837994)
			(xy 160.303762 -282.872086) (xy 160.333327 -282.91143) (xy 160.356198 -282.955007) (xy 160.371782 -283.001688)
			(xy 160.379677 -283.050265) (xy 160.380172 -283.074872) (xy 160.719274 -283.074872) (xy 160.723234 -283.025818)
			(xy 160.735011 -282.978034) (xy 160.754302 -282.932758) (xy 160.780605 -282.891162) (xy 160.81324 -282.854325)
			(xy 160.851361 -282.8232) (xy 160.893982 -282.798593) (xy 160.939998 -282.781141) (xy 160.988217 -282.771297)
			(xy 161.037392 -282.769316) (xy 161.086247 -282.775248) (xy 161.133518 -282.78894) (xy 161.17798 -282.810038)
			(xy 161.218483 -282.837994) (xy 161.253976 -282.872086) (xy 161.283541 -282.91143) (xy 161.306412 -282.955007)
			(xy 161.321996 -283.001688) (xy 161.329891 -283.050265) (xy 161.330386 -283.074872) (xy 161.669234 -283.074872)
			(xy 161.673194 -283.025818) (xy 161.684971 -282.978034) (xy 161.704262 -282.932758) (xy 161.730565 -282.891162)
			(xy 161.7632 -282.854325) (xy 161.801321 -282.8232) (xy 161.843942 -282.798593) (xy 161.889958 -282.781141)
			(xy 161.938177 -282.771297) (xy 161.987352 -282.769316) (xy 162.036207 -282.775248) (xy 162.083478 -282.78894)
			(xy 162.12794 -282.810038) (xy 162.168443 -282.837994) (xy 162.203936 -282.872086) (xy 162.233501 -282.91143)
			(xy 162.256372 -282.955007) (xy 162.271956 -283.001688) (xy 162.279851 -283.050265) (xy 162.280346 -283.074872)
			(xy 162.619194 -283.074872) (xy 162.623154 -283.025818) (xy 162.634931 -282.978034) (xy 162.654222 -282.932758)
			(xy 162.680525 -282.891162) (xy 162.71316 -282.854325) (xy 162.751281 -282.8232) (xy 162.793902 -282.798593)
			(xy 162.839918 -282.781141) (xy 162.888137 -282.771297) (xy 162.937312 -282.769316) (xy 162.986167 -282.775248)
			(xy 163.033438 -282.78894) (xy 163.0779 -282.810038) (xy 163.118403 -282.837994) (xy 163.153896 -282.872086)
			(xy 163.183461 -282.91143) (xy 163.206332 -282.955007) (xy 163.221916 -283.001688) (xy 163.229811 -283.050265)
			(xy 163.230306 -283.074872) (xy 163.569154 -283.074872) (xy 163.573114 -283.025818) (xy 163.584891 -282.978034)
			(xy 163.604182 -282.932758) (xy 163.630485 -282.891162) (xy 163.66312 -282.854325) (xy 163.701241 -282.8232)
			(xy 163.743862 -282.798593) (xy 163.789878 -282.781141) (xy 163.838097 -282.771297) (xy 163.887272 -282.769316)
			(xy 163.936127 -282.775248) (xy 163.983398 -282.78894) (xy 164.02786 -282.810038) (xy 164.068363 -282.837994)
			(xy 164.103856 -282.872086) (xy 164.133421 -282.91143) (xy 164.156292 -282.955007) (xy 164.171876 -283.001688)
			(xy 164.179771 -283.050265) (xy 164.180266 -283.074872) (xy 164.519114 -283.074872) (xy 164.523074 -283.025818)
			(xy 164.534851 -282.978034) (xy 164.554142 -282.932758) (xy 164.580445 -282.891162) (xy 164.61308 -282.854325)
			(xy 164.651201 -282.8232) (xy 164.693822 -282.798593) (xy 164.739838 -282.781141) (xy 164.788057 -282.771297)
			(xy 164.837232 -282.769316) (xy 164.886087 -282.775248) (xy 164.933358 -282.78894) (xy 164.97782 -282.810038)
			(xy 165.018323 -282.837994) (xy 165.053816 -282.872086) (xy 165.083381 -282.91143) (xy 165.106252 -282.955007)
			(xy 165.121836 -283.001688) (xy 165.129731 -283.050265) (xy 165.130226 -283.074872) (xy 165.469074 -283.074872)
			(xy 165.473034 -283.025818) (xy 165.484811 -282.978034) (xy 165.504102 -282.932758) (xy 165.530405 -282.891162)
			(xy 165.56304 -282.854325) (xy 165.601161 -282.8232) (xy 165.643782 -282.798593) (xy 165.689798 -282.781141)
			(xy 165.738017 -282.771297) (xy 165.787192 -282.769316) (xy 165.836047 -282.775248) (xy 165.883318 -282.78894)
			(xy 165.92778 -282.810038) (xy 165.968283 -282.837994) (xy 166.003776 -282.872086) (xy 166.033341 -282.91143)
			(xy 166.056212 -282.955007) (xy 166.071796 -283.001688) (xy 166.079691 -283.050265) (xy 166.080186 -283.074872)
			(xy 166.419288 -283.074872) (xy 166.423248 -283.025818) (xy 166.435025 -282.978034) (xy 166.454316 -282.932758)
			(xy 166.480619 -282.891162) (xy 166.513254 -282.854325) (xy 166.551375 -282.8232) (xy 166.593996 -282.798593)
			(xy 166.640012 -282.781141) (xy 166.688231 -282.771297) (xy 166.737406 -282.769316) (xy 166.786261 -282.775248)
			(xy 166.833532 -282.78894) (xy 166.877994 -282.810038) (xy 166.918497 -282.837994) (xy 166.95399 -282.872086)
			(xy 166.983555 -282.91143) (xy 167.006426 -282.955007) (xy 167.02201 -283.001688) (xy 167.029905 -283.050265)
			(xy 167.0304 -283.074872) (xy 167.369248 -283.074872) (xy 167.373208 -283.025818) (xy 167.384985 -282.978034)
			(xy 167.404276 -282.932758) (xy 167.430579 -282.891162) (xy 167.463214 -282.854325) (xy 167.501335 -282.8232)
			(xy 167.543956 -282.798593) (xy 167.589972 -282.781141) (xy 167.638191 -282.771297) (xy 167.687366 -282.769316)
			(xy 167.736221 -282.775248) (xy 167.783492 -282.78894) (xy 167.827954 -282.810038) (xy 167.868457 -282.837994)
			(xy 167.90395 -282.872086) (xy 167.933515 -282.91143) (xy 167.956386 -282.955007) (xy 167.97197 -283.001688)
			(xy 167.979865 -283.050265) (xy 167.98036 -283.074872) (xy 168.319208 -283.074872) (xy 168.323168 -283.025818)
			(xy 168.334945 -282.978034) (xy 168.354236 -282.932758) (xy 168.380539 -282.891162) (xy 168.413174 -282.854325)
			(xy 168.451295 -282.8232) (xy 168.493916 -282.798593) (xy 168.539932 -282.781141) (xy 168.588151 -282.771297)
			(xy 168.637326 -282.769316) (xy 168.686181 -282.775248) (xy 168.733452 -282.78894) (xy 168.777914 -282.810038)
			(xy 168.818417 -282.837994) (xy 168.85391 -282.872086) (xy 168.883475 -282.91143) (xy 168.906346 -282.955007)
			(xy 168.92193 -283.001688) (xy 168.929825 -283.050265) (xy 168.93032 -283.074872) (xy 169.269168 -283.074872)
			(xy 169.273128 -283.025818) (xy 169.284905 -282.978034) (xy 169.304196 -282.932758) (xy 169.330499 -282.891162)
			(xy 169.363134 -282.854325) (xy 169.401255 -282.8232) (xy 169.443876 -282.798593) (xy 169.489892 -282.781141)
			(xy 169.538111 -282.771297) (xy 169.587286 -282.769316) (xy 169.636141 -282.775248) (xy 169.683412 -282.78894)
			(xy 169.727874 -282.810038) (xy 169.768377 -282.837994) (xy 169.80387 -282.872086) (xy 169.833435 -282.91143)
			(xy 169.856306 -282.955007) (xy 169.87189 -283.001688) (xy 169.879785 -283.050265) (xy 169.88028 -283.074872)
			(xy 170.219128 -283.074872) (xy 170.223088 -283.025818) (xy 170.234865 -282.978034) (xy 170.254156 -282.932758)
			(xy 170.280459 -282.891162) (xy 170.313094 -282.854325) (xy 170.351215 -282.8232) (xy 170.393836 -282.798593)
			(xy 170.439852 -282.781141) (xy 170.488071 -282.771297) (xy 170.537246 -282.769316) (xy 170.586101 -282.775248)
			(xy 170.633372 -282.78894) (xy 170.677834 -282.810038) (xy 170.718337 -282.837994) (xy 170.75383 -282.872086)
			(xy 170.783395 -282.91143) (xy 170.806266 -282.955007) (xy 170.82185 -283.001688) (xy 170.829745 -283.050265)
			(xy 170.83024 -283.074872) (xy 171.169088 -283.074872) (xy 171.173048 -283.025818) (xy 171.184825 -282.978034)
			(xy 171.204116 -282.932758) (xy 171.230419 -282.891162) (xy 171.263054 -282.854325) (xy 171.301175 -282.8232)
			(xy 171.343796 -282.798593) (xy 171.389812 -282.781141) (xy 171.438031 -282.771297) (xy 171.487206 -282.769316)
			(xy 171.536061 -282.775248) (xy 171.583332 -282.78894) (xy 171.627794 -282.810038) (xy 171.668297 -282.837994)
			(xy 171.70379 -282.872086) (xy 171.733355 -282.91143) (xy 171.756226 -282.955007) (xy 171.77181 -283.001688)
			(xy 171.779705 -283.050265) (xy 171.7802 -283.074872) (xy 172.119302 -283.074872) (xy 172.123262 -283.025818)
			(xy 172.135039 -282.978034) (xy 172.15433 -282.932758) (xy 172.180633 -282.891162) (xy 172.213268 -282.854325)
			(xy 172.251389 -282.8232) (xy 172.29401 -282.798593) (xy 172.340026 -282.781141) (xy 172.388245 -282.771297)
			(xy 172.43742 -282.769316) (xy 172.486275 -282.775248) (xy 172.533546 -282.78894) (xy 172.578008 -282.810038)
			(xy 172.618511 -282.837994) (xy 172.654004 -282.872086) (xy 172.683569 -282.91143) (xy 172.70644 -282.955007)
			(xy 172.722024 -283.001688) (xy 172.729919 -283.050265) (xy 172.730414 -283.074872) (xy 173.069262 -283.074872)
			(xy 173.073222 -283.025818) (xy 173.084999 -282.978034) (xy 173.10429 -282.932758) (xy 173.130593 -282.891162)
			(xy 173.163228 -282.854325) (xy 173.201349 -282.8232) (xy 173.24397 -282.798593) (xy 173.289986 -282.781141)
			(xy 173.338205 -282.771297) (xy 173.38738 -282.769316) (xy 173.436235 -282.775248) (xy 173.483506 -282.78894)
			(xy 173.527968 -282.810038) (xy 173.568471 -282.837994) (xy 173.603964 -282.872086) (xy 173.633529 -282.91143)
			(xy 173.6564 -282.955007) (xy 173.671984 -283.001688) (xy 173.679879 -283.050265) (xy 173.680374 -283.074872)
			(xy 174.019222 -283.074872) (xy 174.023182 -283.025818) (xy 174.034959 -282.978034) (xy 174.05425 -282.932758)
			(xy 174.080553 -282.891162) (xy 174.113188 -282.854325) (xy 174.151309 -282.8232) (xy 174.19393 -282.798593)
			(xy 174.239946 -282.781141) (xy 174.288165 -282.771297) (xy 174.33734 -282.769316) (xy 174.386195 -282.775248)
			(xy 174.433466 -282.78894) (xy 174.477928 -282.810038) (xy 174.518431 -282.837994) (xy 174.553924 -282.872086)
			(xy 174.583489 -282.91143) (xy 174.60636 -282.955007) (xy 174.621944 -283.001688) (xy 174.629839 -283.050265)
			(xy 174.630334 -283.074872) (xy 175.919142 -283.074872) (xy 175.923102 -283.025818) (xy 175.934879 -282.978034)
			(xy 175.95417 -282.932758) (xy 175.980473 -282.891162) (xy 176.013108 -282.854325) (xy 176.051229 -282.8232)
			(xy 176.09385 -282.798593) (xy 176.139866 -282.781141) (xy 176.188085 -282.771297) (xy 176.23726 -282.769316)
			(xy 176.286115 -282.775248) (xy 176.333386 -282.78894) (xy 176.377848 -282.810038) (xy 176.418351 -282.837994)
			(xy 176.453844 -282.872086) (xy 176.483409 -282.91143) (xy 176.50628 -282.955007) (xy 176.521864 -283.001688)
			(xy 176.529759 -283.050265) (xy 176.530254 -283.074872) (xy 176.869102 -283.074872) (xy 176.873062 -283.025818)
			(xy 176.884839 -282.978034) (xy 176.90413 -282.932758) (xy 176.930433 -282.891162) (xy 176.963068 -282.854325)
			(xy 177.001189 -282.8232) (xy 177.04381 -282.798593) (xy 177.089826 -282.781141) (xy 177.138045 -282.771297)
			(xy 177.18722 -282.769316) (xy 177.236075 -282.775248) (xy 177.283346 -282.78894) (xy 177.327808 -282.810038)
			(xy 177.368311 -282.837994) (xy 177.403804 -282.872086) (xy 177.433369 -282.91143) (xy 177.45624 -282.955007)
			(xy 177.471824 -283.001688) (xy 177.479719 -283.050265) (xy 177.480214 -283.074872) (xy 177.819062 -283.074872)
			(xy 177.823022 -283.025818) (xy 177.834799 -282.978034) (xy 177.85409 -282.932758) (xy 177.880393 -282.891162)
			(xy 177.913028 -282.854325) (xy 177.951149 -282.8232) (xy 177.99377 -282.798593) (xy 178.039786 -282.781141)
			(xy 178.088005 -282.771297) (xy 178.13718 -282.769316) (xy 178.186035 -282.775248) (xy 178.233306 -282.78894)
			(xy 178.277768 -282.810038) (xy 178.318271 -282.837994) (xy 178.353764 -282.872086) (xy 178.383329 -282.91143)
			(xy 178.4062 -282.955007) (xy 178.421784 -283.001688) (xy 178.429679 -283.050265) (xy 178.430174 -283.074872)
			(xy 178.769276 -283.074872) (xy 178.773236 -283.025818) (xy 178.785013 -282.978034) (xy 178.804304 -282.932758)
			(xy 178.830607 -282.891162) (xy 178.863242 -282.854325) (xy 178.901363 -282.8232) (xy 178.943984 -282.798593)
			(xy 178.99 -282.781141) (xy 179.038219 -282.771297) (xy 179.087394 -282.769316) (xy 179.136249 -282.775248)
			(xy 179.18352 -282.78894) (xy 179.227982 -282.810038) (xy 179.268485 -282.837994) (xy 179.303978 -282.872086)
			(xy 179.333543 -282.91143) (xy 179.356414 -282.955007) (xy 179.371998 -283.001688) (xy 179.379893 -283.050265)
			(xy 179.380388 -283.074872) (xy 179.719236 -283.074872) (xy 179.723196 -283.025818) (xy 179.734973 -282.978034)
			(xy 179.754264 -282.932758) (xy 179.780567 -282.891162) (xy 179.813202 -282.854325) (xy 179.851323 -282.8232)
			(xy 179.893944 -282.798593) (xy 179.93996 -282.781141) (xy 179.988179 -282.771297) (xy 180.037354 -282.769316)
			(xy 180.086209 -282.775248) (xy 180.13348 -282.78894) (xy 180.177942 -282.810038) (xy 180.218445 -282.837994)
			(xy 180.253938 -282.872086) (xy 180.283503 -282.91143) (xy 180.306374 -282.955007) (xy 180.321958 -283.001688)
			(xy 180.329853 -283.050265) (xy 180.330348 -283.074872) (xy 180.669196 -283.074872) (xy 180.673156 -283.025818)
			(xy 180.684933 -282.978034) (xy 180.704224 -282.932758) (xy 180.730527 -282.891162) (xy 180.763162 -282.854325)
			(xy 180.801283 -282.8232) (xy 180.843904 -282.798593) (xy 180.88992 -282.781141) (xy 180.938139 -282.771297)
			(xy 180.987314 -282.769316) (xy 181.036169 -282.775248) (xy 181.08344 -282.78894) (xy 181.127902 -282.810038)
			(xy 181.168405 -282.837994) (xy 181.203898 -282.872086) (xy 181.233463 -282.91143) (xy 181.256334 -282.955007)
			(xy 181.271918 -283.001688) (xy 181.279813 -283.050265) (xy 181.280308 -283.074872) (xy 181.619156 -283.074872)
			(xy 181.623116 -283.025818) (xy 181.634893 -282.978034) (xy 181.654184 -282.932758) (xy 181.680487 -282.891162)
			(xy 181.713122 -282.854325) (xy 181.751243 -282.8232) (xy 181.793864 -282.798593) (xy 181.83988 -282.781141)
			(xy 181.888099 -282.771297) (xy 181.937274 -282.769316) (xy 181.986129 -282.775248) (xy 182.0334 -282.78894)
			(xy 182.077862 -282.810038) (xy 182.118365 -282.837994) (xy 182.153858 -282.872086) (xy 182.183423 -282.91143)
			(xy 182.206294 -282.955007) (xy 182.221878 -283.001688) (xy 182.229773 -283.050265) (xy 182.230268 -283.074872)
			(xy 182.569116 -283.074872) (xy 182.573076 -283.025818) (xy 182.584853 -282.978034) (xy 182.604144 -282.932758)
			(xy 182.630447 -282.891162) (xy 182.663082 -282.854325) (xy 182.701203 -282.8232) (xy 182.743824 -282.798593)
			(xy 182.78984 -282.781141) (xy 182.838059 -282.771297) (xy 182.887234 -282.769316) (xy 182.936089 -282.775248)
			(xy 182.98336 -282.78894) (xy 183.027822 -282.810038) (xy 183.068325 -282.837994) (xy 183.103818 -282.872086)
			(xy 183.133383 -282.91143) (xy 183.156254 -282.955007) (xy 183.171838 -283.001688) (xy 183.179733 -283.050265)
			(xy 183.180228 -283.074872) (xy 184.469036 -283.074872) (xy 184.472996 -283.025818) (xy 184.484773 -282.978034)
			(xy 184.504064 -282.932758) (xy 184.530367 -282.891162) (xy 184.563002 -282.854325) (xy 184.601123 -282.8232)
			(xy 184.643744 -282.798593) (xy 184.68976 -282.781141) (xy 184.737979 -282.771297) (xy 184.787154 -282.769316)
			(xy 184.836009 -282.775248) (xy 184.88328 -282.78894) (xy 184.927742 -282.810038) (xy 184.968245 -282.837994)
			(xy 185.003738 -282.872086) (xy 185.033303 -282.91143) (xy 185.056174 -282.955007) (xy 185.071758 -283.001688)
			(xy 185.079653 -283.050265) (xy 185.080148 -283.074872) (xy 185.079653 -283.099479) (xy 185.071758 -283.148056)
			(xy 185.056174 -283.194737) (xy 185.033303 -283.238314) (xy 185.003738 -283.277658) (xy 184.968245 -283.31175)
			(xy 184.927742 -283.339706) (xy 184.88328 -283.360804) (xy 184.836009 -283.374496) (xy 184.787154 -283.380428)
			(xy 184.737979 -283.378447) (xy 184.68976 -283.368603) (xy 184.643744 -283.351151) (xy 184.601123 -283.326544)
			(xy 184.563002 -283.295419) (xy 184.530367 -283.258582) (xy 184.504064 -283.216986) (xy 184.484773 -283.17171)
			(xy 184.472996 -283.123926) (xy 184.469036 -283.074872) (xy 183.180228 -283.074872) (xy 183.179733 -283.099479)
			(xy 183.171838 -283.148056) (xy 183.156254 -283.194737) (xy 183.133383 -283.238314) (xy 183.103818 -283.277658)
			(xy 183.068325 -283.31175) (xy 183.027822 -283.339706) (xy 182.98336 -283.360804) (xy 182.936089 -283.374496)
			(xy 182.887234 -283.380428) (xy 182.838059 -283.378447) (xy 182.78984 -283.368603) (xy 182.743824 -283.351151)
			(xy 182.701203 -283.326544) (xy 182.663082 -283.295419) (xy 182.630447 -283.258582) (xy 182.604144 -283.216986)
			(xy 182.584853 -283.17171) (xy 182.573076 -283.123926) (xy 182.569116 -283.074872) (xy 182.230268 -283.074872)
			(xy 182.229773 -283.099479) (xy 182.221878 -283.148056) (xy 182.206294 -283.194737) (xy 182.183423 -283.238314)
			(xy 182.153858 -283.277658) (xy 182.118365 -283.31175) (xy 182.077862 -283.339706) (xy 182.0334 -283.360804)
			(xy 181.986129 -283.374496) (xy 181.937274 -283.380428) (xy 181.888099 -283.378447) (xy 181.83988 -283.368603)
			(xy 181.793864 -283.351151) (xy 181.751243 -283.326544) (xy 181.713122 -283.295419) (xy 181.680487 -283.258582)
			(xy 181.654184 -283.216986) (xy 181.634893 -283.17171) (xy 181.623116 -283.123926) (xy 181.619156 -283.074872)
			(xy 181.280308 -283.074872) (xy 181.279813 -283.099479) (xy 181.271918 -283.148056) (xy 181.256334 -283.194737)
			(xy 181.233463 -283.238314) (xy 181.203898 -283.277658) (xy 181.168405 -283.31175) (xy 181.127902 -283.339706)
			(xy 181.08344 -283.360804) (xy 181.036169 -283.374496) (xy 180.987314 -283.380428) (xy 180.938139 -283.378447)
			(xy 180.88992 -283.368603) (xy 180.843904 -283.351151) (xy 180.801283 -283.326544) (xy 180.763162 -283.295419)
			(xy 180.730527 -283.258582) (xy 180.704224 -283.216986) (xy 180.684933 -283.17171) (xy 180.673156 -283.123926)
			(xy 180.669196 -283.074872) (xy 180.330348 -283.074872) (xy 180.329853 -283.099479) (xy 180.321958 -283.148056)
			(xy 180.306374 -283.194737) (xy 180.283503 -283.238314) (xy 180.253938 -283.277658) (xy 180.218445 -283.31175)
			(xy 180.177942 -283.339706) (xy 180.13348 -283.360804) (xy 180.086209 -283.374496) (xy 180.037354 -283.380428)
			(xy 179.988179 -283.378447) (xy 179.93996 -283.368603) (xy 179.893944 -283.351151) (xy 179.851323 -283.326544)
			(xy 179.813202 -283.295419) (xy 179.780567 -283.258582) (xy 179.754264 -283.216986) (xy 179.734973 -283.17171)
			(xy 179.723196 -283.123926) (xy 179.719236 -283.074872) (xy 179.380388 -283.074872) (xy 179.379893 -283.099479)
			(xy 179.371998 -283.148056) (xy 179.356414 -283.194737) (xy 179.333543 -283.238314) (xy 179.303978 -283.277658)
			(xy 179.268485 -283.31175) (xy 179.227982 -283.339706) (xy 179.18352 -283.360804) (xy 179.136249 -283.374496)
			(xy 179.087394 -283.380428) (xy 179.038219 -283.378447) (xy 178.99 -283.368603) (xy 178.943984 -283.351151)
			(xy 178.901363 -283.326544) (xy 178.863242 -283.295419) (xy 178.830607 -283.258582) (xy 178.804304 -283.216986)
			(xy 178.785013 -283.17171) (xy 178.773236 -283.123926) (xy 178.769276 -283.074872) (xy 178.430174 -283.074872)
			(xy 178.429679 -283.099479) (xy 178.421784 -283.148056) (xy 178.4062 -283.194737) (xy 178.383329 -283.238314)
			(xy 178.353764 -283.277658) (xy 178.318271 -283.31175) (xy 178.277768 -283.339706) (xy 178.233306 -283.360804)
			(xy 178.186035 -283.374496) (xy 178.13718 -283.380428) (xy 178.088005 -283.378447) (xy 178.039786 -283.368603)
			(xy 177.99377 -283.351151) (xy 177.951149 -283.326544) (xy 177.913028 -283.295419) (xy 177.880393 -283.258582)
			(xy 177.85409 -283.216986) (xy 177.834799 -283.17171) (xy 177.823022 -283.123926) (xy 177.819062 -283.074872)
			(xy 177.480214 -283.074872) (xy 177.479719 -283.099479) (xy 177.471824 -283.148056) (xy 177.45624 -283.194737)
			(xy 177.433369 -283.238314) (xy 177.403804 -283.277658) (xy 177.368311 -283.31175) (xy 177.327808 -283.339706)
			(xy 177.283346 -283.360804) (xy 177.236075 -283.374496) (xy 177.18722 -283.380428) (xy 177.138045 -283.378447)
			(xy 177.089826 -283.368603) (xy 177.04381 -283.351151) (xy 177.001189 -283.326544) (xy 176.963068 -283.295419)
			(xy 176.930433 -283.258582) (xy 176.90413 -283.216986) (xy 176.884839 -283.17171) (xy 176.873062 -283.123926)
			(xy 176.869102 -283.074872) (xy 176.530254 -283.074872) (xy 176.529759 -283.099479) (xy 176.521864 -283.148056)
			(xy 176.50628 -283.194737) (xy 176.483409 -283.238314) (xy 176.453844 -283.277658) (xy 176.418351 -283.31175)
			(xy 176.377848 -283.339706) (xy 176.333386 -283.360804) (xy 176.286115 -283.374496) (xy 176.23726 -283.380428)
			(xy 176.188085 -283.378447) (xy 176.139866 -283.368603) (xy 176.09385 -283.351151) (xy 176.051229 -283.326544)
			(xy 176.013108 -283.295419) (xy 175.980473 -283.258582) (xy 175.95417 -283.216986) (xy 175.934879 -283.17171)
			(xy 175.923102 -283.123926) (xy 175.919142 -283.074872) (xy 174.630334 -283.074872) (xy 174.629839 -283.099479)
			(xy 174.621944 -283.148056) (xy 174.60636 -283.194737) (xy 174.583489 -283.238314) (xy 174.553924 -283.277658)
			(xy 174.518431 -283.31175) (xy 174.477928 -283.339706) (xy 174.433466 -283.360804) (xy 174.386195 -283.374496)
			(xy 174.33734 -283.380428) (xy 174.288165 -283.378447) (xy 174.239946 -283.368603) (xy 174.19393 -283.351151)
			(xy 174.151309 -283.326544) (xy 174.113188 -283.295419) (xy 174.080553 -283.258582) (xy 174.05425 -283.216986)
			(xy 174.034959 -283.17171) (xy 174.023182 -283.123926) (xy 174.019222 -283.074872) (xy 173.680374 -283.074872)
			(xy 173.679879 -283.099479) (xy 173.671984 -283.148056) (xy 173.6564 -283.194737) (xy 173.633529 -283.238314)
			(xy 173.603964 -283.277658) (xy 173.568471 -283.31175) (xy 173.527968 -283.339706) (xy 173.483506 -283.360804)
			(xy 173.436235 -283.374496) (xy 173.38738 -283.380428) (xy 173.338205 -283.378447) (xy 173.289986 -283.368603)
			(xy 173.24397 -283.351151) (xy 173.201349 -283.326544) (xy 173.163228 -283.295419) (xy 173.130593 -283.258582)
			(xy 173.10429 -283.216986) (xy 173.084999 -283.17171) (xy 173.073222 -283.123926) (xy 173.069262 -283.074872)
			(xy 172.730414 -283.074872) (xy 172.729919 -283.099479) (xy 172.722024 -283.148056) (xy 172.70644 -283.194737)
			(xy 172.683569 -283.238314) (xy 172.654004 -283.277658) (xy 172.618511 -283.31175) (xy 172.578008 -283.339706)
			(xy 172.533546 -283.360804) (xy 172.486275 -283.374496) (xy 172.43742 -283.380428) (xy 172.388245 -283.378447)
			(xy 172.340026 -283.368603) (xy 172.29401 -283.351151) (xy 172.251389 -283.326544) (xy 172.213268 -283.295419)
			(xy 172.180633 -283.258582) (xy 172.15433 -283.216986) (xy 172.135039 -283.17171) (xy 172.123262 -283.123926)
			(xy 172.119302 -283.074872) (xy 171.7802 -283.074872) (xy 171.779705 -283.099479) (xy 171.77181 -283.148056)
			(xy 171.756226 -283.194737) (xy 171.733355 -283.238314) (xy 171.70379 -283.277658) (xy 171.668297 -283.31175)
			(xy 171.627794 -283.339706) (xy 171.583332 -283.360804) (xy 171.536061 -283.374496) (xy 171.487206 -283.380428)
			(xy 171.438031 -283.378447) (xy 171.389812 -283.368603) (xy 171.343796 -283.351151) (xy 171.301175 -283.326544)
			(xy 171.263054 -283.295419) (xy 171.230419 -283.258582) (xy 171.204116 -283.216986) (xy 171.184825 -283.17171)
			(xy 171.173048 -283.123926) (xy 171.169088 -283.074872) (xy 170.83024 -283.074872) (xy 170.829745 -283.099479)
			(xy 170.82185 -283.148056) (xy 170.806266 -283.194737) (xy 170.783395 -283.238314) (xy 170.75383 -283.277658)
			(xy 170.718337 -283.31175) (xy 170.677834 -283.339706) (xy 170.633372 -283.360804) (xy 170.586101 -283.374496)
			(xy 170.537246 -283.380428) (xy 170.488071 -283.378447) (xy 170.439852 -283.368603) (xy 170.393836 -283.351151)
			(xy 170.351215 -283.326544) (xy 170.313094 -283.295419) (xy 170.280459 -283.258582) (xy 170.254156 -283.216986)
			(xy 170.234865 -283.17171) (xy 170.223088 -283.123926) (xy 170.219128 -283.074872) (xy 169.88028 -283.074872)
			(xy 169.879785 -283.099479) (xy 169.87189 -283.148056) (xy 169.856306 -283.194737) (xy 169.833435 -283.238314)
			(xy 169.80387 -283.277658) (xy 169.768377 -283.31175) (xy 169.727874 -283.339706) (xy 169.683412 -283.360804)
			(xy 169.636141 -283.374496) (xy 169.587286 -283.380428) (xy 169.538111 -283.378447) (xy 169.489892 -283.368603)
			(xy 169.443876 -283.351151) (xy 169.401255 -283.326544) (xy 169.363134 -283.295419) (xy 169.330499 -283.258582)
			(xy 169.304196 -283.216986) (xy 169.284905 -283.17171) (xy 169.273128 -283.123926) (xy 169.269168 -283.074872)
			(xy 168.93032 -283.074872) (xy 168.929825 -283.099479) (xy 168.92193 -283.148056) (xy 168.906346 -283.194737)
			(xy 168.883475 -283.238314) (xy 168.85391 -283.277658) (xy 168.818417 -283.31175) (xy 168.777914 -283.339706)
			(xy 168.733452 -283.360804) (xy 168.686181 -283.374496) (xy 168.637326 -283.380428) (xy 168.588151 -283.378447)
			(xy 168.539932 -283.368603) (xy 168.493916 -283.351151) (xy 168.451295 -283.326544) (xy 168.413174 -283.295419)
			(xy 168.380539 -283.258582) (xy 168.354236 -283.216986) (xy 168.334945 -283.17171) (xy 168.323168 -283.123926)
			(xy 168.319208 -283.074872) (xy 167.98036 -283.074872) (xy 167.979865 -283.099479) (xy 167.97197 -283.148056)
			(xy 167.956386 -283.194737) (xy 167.933515 -283.238314) (xy 167.90395 -283.277658) (xy 167.868457 -283.31175)
			(xy 167.827954 -283.339706) (xy 167.783492 -283.360804) (xy 167.736221 -283.374496) (xy 167.687366 -283.380428)
			(xy 167.638191 -283.378447) (xy 167.589972 -283.368603) (xy 167.543956 -283.351151) (xy 167.501335 -283.326544)
			(xy 167.463214 -283.295419) (xy 167.430579 -283.258582) (xy 167.404276 -283.216986) (xy 167.384985 -283.17171)
			(xy 167.373208 -283.123926) (xy 167.369248 -283.074872) (xy 167.0304 -283.074872) (xy 167.029905 -283.099479)
			(xy 167.02201 -283.148056) (xy 167.006426 -283.194737) (xy 166.983555 -283.238314) (xy 166.95399 -283.277658)
			(xy 166.918497 -283.31175) (xy 166.877994 -283.339706) (xy 166.833532 -283.360804) (xy 166.786261 -283.374496)
			(xy 166.737406 -283.380428) (xy 166.688231 -283.378447) (xy 166.640012 -283.368603) (xy 166.593996 -283.351151)
			(xy 166.551375 -283.326544) (xy 166.513254 -283.295419) (xy 166.480619 -283.258582) (xy 166.454316 -283.216986)
			(xy 166.435025 -283.17171) (xy 166.423248 -283.123926) (xy 166.419288 -283.074872) (xy 166.080186 -283.074872)
			(xy 166.079691 -283.099479) (xy 166.071796 -283.148056) (xy 166.056212 -283.194737) (xy 166.033341 -283.238314)
			(xy 166.003776 -283.277658) (xy 165.968283 -283.31175) (xy 165.92778 -283.339706) (xy 165.883318 -283.360804)
			(xy 165.836047 -283.374496) (xy 165.787192 -283.380428) (xy 165.738017 -283.378447) (xy 165.689798 -283.368603)
			(xy 165.643782 -283.351151) (xy 165.601161 -283.326544) (xy 165.56304 -283.295419) (xy 165.530405 -283.258582)
			(xy 165.504102 -283.216986) (xy 165.484811 -283.17171) (xy 165.473034 -283.123926) (xy 165.469074 -283.074872)
			(xy 165.130226 -283.074872) (xy 165.129731 -283.099479) (xy 165.121836 -283.148056) (xy 165.106252 -283.194737)
			(xy 165.083381 -283.238314) (xy 165.053816 -283.277658) (xy 165.018323 -283.31175) (xy 164.97782 -283.339706)
			(xy 164.933358 -283.360804) (xy 164.886087 -283.374496) (xy 164.837232 -283.380428) (xy 164.788057 -283.378447)
			(xy 164.739838 -283.368603) (xy 164.693822 -283.351151) (xy 164.651201 -283.326544) (xy 164.61308 -283.295419)
			(xy 164.580445 -283.258582) (xy 164.554142 -283.216986) (xy 164.534851 -283.17171) (xy 164.523074 -283.123926)
			(xy 164.519114 -283.074872) (xy 164.180266 -283.074872) (xy 164.179771 -283.099479) (xy 164.171876 -283.148056)
			(xy 164.156292 -283.194737) (xy 164.133421 -283.238314) (xy 164.103856 -283.277658) (xy 164.068363 -283.31175)
			(xy 164.02786 -283.339706) (xy 163.983398 -283.360804) (xy 163.936127 -283.374496) (xy 163.887272 -283.380428)
			(xy 163.838097 -283.378447) (xy 163.789878 -283.368603) (xy 163.743862 -283.351151) (xy 163.701241 -283.326544)
			(xy 163.66312 -283.295419) (xy 163.630485 -283.258582) (xy 163.604182 -283.216986) (xy 163.584891 -283.17171)
			(xy 163.573114 -283.123926) (xy 163.569154 -283.074872) (xy 163.230306 -283.074872) (xy 163.229811 -283.099479)
			(xy 163.221916 -283.148056) (xy 163.206332 -283.194737) (xy 163.183461 -283.238314) (xy 163.153896 -283.277658)
			(xy 163.118403 -283.31175) (xy 163.0779 -283.339706) (xy 163.033438 -283.360804) (xy 162.986167 -283.374496)
			(xy 162.937312 -283.380428) (xy 162.888137 -283.378447) (xy 162.839918 -283.368603) (xy 162.793902 -283.351151)
			(xy 162.751281 -283.326544) (xy 162.71316 -283.295419) (xy 162.680525 -283.258582) (xy 162.654222 -283.216986)
			(xy 162.634931 -283.17171) (xy 162.623154 -283.123926) (xy 162.619194 -283.074872) (xy 162.280346 -283.074872)
			(xy 162.279851 -283.099479) (xy 162.271956 -283.148056) (xy 162.256372 -283.194737) (xy 162.233501 -283.238314)
			(xy 162.203936 -283.277658) (xy 162.168443 -283.31175) (xy 162.12794 -283.339706) (xy 162.083478 -283.360804)
			(xy 162.036207 -283.374496) (xy 161.987352 -283.380428) (xy 161.938177 -283.378447) (xy 161.889958 -283.368603)
			(xy 161.843942 -283.351151) (xy 161.801321 -283.326544) (xy 161.7632 -283.295419) (xy 161.730565 -283.258582)
			(xy 161.704262 -283.216986) (xy 161.684971 -283.17171) (xy 161.673194 -283.123926) (xy 161.669234 -283.074872)
			(xy 161.330386 -283.074872) (xy 161.329891 -283.099479) (xy 161.321996 -283.148056) (xy 161.306412 -283.194737)
			(xy 161.283541 -283.238314) (xy 161.253976 -283.277658) (xy 161.218483 -283.31175) (xy 161.17798 -283.339706)
			(xy 161.133518 -283.360804) (xy 161.086247 -283.374496) (xy 161.037392 -283.380428) (xy 160.988217 -283.378447)
			(xy 160.939998 -283.368603) (xy 160.893982 -283.351151) (xy 160.851361 -283.326544) (xy 160.81324 -283.295419)
			(xy 160.780605 -283.258582) (xy 160.754302 -283.216986) (xy 160.735011 -283.17171) (xy 160.723234 -283.123926)
			(xy 160.719274 -283.074872) (xy 160.380172 -283.074872) (xy 160.379677 -283.099479) (xy 160.371782 -283.148056)
			(xy 160.356198 -283.194737) (xy 160.333327 -283.238314) (xy 160.303762 -283.277658) (xy 160.268269 -283.31175)
			(xy 160.227766 -283.339706) (xy 160.183304 -283.360804) (xy 160.136033 -283.374496) (xy 160.087178 -283.380428)
			(xy 160.038003 -283.378447) (xy 159.989784 -283.368603) (xy 159.943768 -283.351151) (xy 159.901147 -283.326544)
			(xy 159.863026 -283.295419) (xy 159.830391 -283.258582) (xy 159.804088 -283.216986) (xy 159.784797 -283.17171)
			(xy 159.77302 -283.123926) (xy 159.76906 -283.074872) (xy 159.430212 -283.074872) (xy 159.429717 -283.099479)
			(xy 159.421822 -283.148056) (xy 159.406238 -283.194737) (xy 159.383367 -283.238314) (xy 159.353802 -283.277658)
			(xy 159.318309 -283.31175) (xy 159.277806 -283.339706) (xy 159.233344 -283.360804) (xy 159.186073 -283.374496)
			(xy 159.137218 -283.380428) (xy 159.088043 -283.378447) (xy 159.039824 -283.368603) (xy 158.993808 -283.351151)
			(xy 158.951187 -283.326544) (xy 158.913066 -283.295419) (xy 158.880431 -283.258582) (xy 158.854128 -283.216986)
			(xy 158.834837 -283.17171) (xy 158.82306 -283.123926) (xy 158.8191 -283.074872) (xy 158.480252 -283.074872)
			(xy 158.479757 -283.099479) (xy 158.471862 -283.148056) (xy 158.456278 -283.194737) (xy 158.433407 -283.238314)
			(xy 158.403842 -283.277658) (xy 158.368349 -283.31175) (xy 158.327846 -283.339706) (xy 158.283384 -283.360804)
			(xy 158.236113 -283.374496) (xy 158.187258 -283.380428) (xy 158.138083 -283.378447) (xy 158.089864 -283.368603)
			(xy 158.043848 -283.351151) (xy 158.001227 -283.326544) (xy 157.963106 -283.295419) (xy 157.930471 -283.258582)
			(xy 157.904168 -283.216986) (xy 157.884877 -283.17171) (xy 157.8731 -283.123926) (xy 157.86914 -283.074872)
			(xy 157.530292 -283.074872) (xy 157.529797 -283.099479) (xy 157.521902 -283.148056) (xy 157.506318 -283.194737)
			(xy 157.483447 -283.238314) (xy 157.453882 -283.277658) (xy 157.418389 -283.31175) (xy 157.377886 -283.339706)
			(xy 157.333424 -283.360804) (xy 157.286153 -283.374496) (xy 157.237298 -283.380428) (xy 157.188123 -283.378447)
			(xy 157.139904 -283.368603) (xy 157.093888 -283.351151) (xy 157.051267 -283.326544) (xy 157.013146 -283.295419)
			(xy 156.980511 -283.258582) (xy 156.954208 -283.216986) (xy 156.934917 -283.17171) (xy 156.92314 -283.123926)
			(xy 156.91918 -283.074872) (xy 156.580332 -283.074872) (xy 156.579837 -283.099479) (xy 156.571942 -283.148056)
			(xy 156.556358 -283.194737) (xy 156.533487 -283.238314) (xy 156.503922 -283.277658) (xy 156.468429 -283.31175)
			(xy 156.427926 -283.339706) (xy 156.383464 -283.360804) (xy 156.336193 -283.374496) (xy 156.287338 -283.380428)
			(xy 156.238163 -283.378447) (xy 156.189944 -283.368603) (xy 156.143928 -283.351151) (xy 156.101307 -283.326544)
			(xy 156.063186 -283.295419) (xy 156.030551 -283.258582) (xy 156.004248 -283.216986) (xy 155.984957 -283.17171)
			(xy 155.97318 -283.123926) (xy 155.96922 -283.074872) (xy 155.630372 -283.074872) (xy 155.629877 -283.099479)
			(xy 155.621982 -283.148056) (xy 155.606398 -283.194737) (xy 155.583527 -283.238314) (xy 155.553962 -283.277658)
			(xy 155.518469 -283.31175) (xy 155.477966 -283.339706) (xy 155.433504 -283.360804) (xy 155.386233 -283.374496)
			(xy 155.337378 -283.380428) (xy 155.288203 -283.378447) (xy 155.239984 -283.368603) (xy 155.193968 -283.351151)
			(xy 155.151347 -283.326544) (xy 155.113226 -283.295419) (xy 155.080591 -283.258582) (xy 155.054288 -283.216986)
			(xy 155.034997 -283.17171) (xy 155.02322 -283.123926) (xy 155.01926 -283.074872) (xy 154.680901 -283.074872)
			(xy 154.680903 -283.0749) (xy 154.676732 -283.125233) (xy 154.664334 -283.174193) (xy 154.644046 -283.220445)
			(xy 154.616423 -283.262727) (xy 154.582216 -283.299885) (xy 154.542361 -283.330907) (xy 154.497942 -283.354945)
			(xy 154.450173 -283.371345) (xy 154.400357 -283.379658) (xy 154.375104 -283.38018) (xy 154.361568 -283.380031)
			(xy 154.334604 -283.377611) (xy 154.321256 -283.375354) (xy 154.309064 -283.373322) (xy 154.285442 -283.380688)
			(xy 154.261312 -283.404564) (xy 154.261312 -283.44622) (xy 154.302714 -283.487368) (xy 154.319162 -283.504476)
			(xy 154.347073 -283.542859) (xy 154.368709 -283.585097) (xy 154.383551 -283.630173) (xy 154.391242 -283.677003)
			(xy 154.391868 -283.700728) (xy 154.391868 -283.701744) (xy 154.392376 -283.720032) (xy 154.417049 -283.721877)
			(xy 154.465349 -283.732606) (xy 154.511286 -283.750983) (xy 154.553658 -283.776527) (xy 154.591357 -283.80857)
			(xy 154.623395 -283.846273) (xy 154.648934 -283.888648) (xy 154.667305 -283.934588) (xy 154.678029 -283.982888)
			(xy 154.679904 -284.00756) (xy 154.699208 -284.008068) (xy 154.69997 -284.008068) (xy 154.723619 -284.008707)
			(xy 154.770286 -284.016475) (xy 154.815196 -284.031348) (xy 154.857273 -284.052971) (xy 154.895512 -284.080826)
			(xy 154.912568 -284.097222) (xy 154.93873 -284.123638) (xy 154.946121 -284.130489) (xy 154.964727 -284.138201)
			(xy 154.974798 -284.138624) (xy 154.995372 -284.138624) (xy 155.019248 -284.114494) (xy 155.026614 -284.090872)
			(xy 155.024582 -284.07868) (xy 155.022339 -284.06533) (xy 155.01992 -284.038367) (xy 155.019756 -284.024832)
			(xy 155.020243 -284.000007) (xy 155.028271 -283.951011) (xy 155.04412 -283.90396) (xy 155.067372 -283.860092)
			(xy 155.097416 -283.820564) (xy 155.133459 -283.786418) (xy 155.174551 -283.758553) (xy 155.219611 -283.737704)
			(xy 155.26745 -283.724419) (xy 155.316808 -283.719049) (xy 155.366384 -283.721736) (xy 155.414873 -283.732408)
			(xy 155.460996 -283.750785) (xy 155.503539 -283.776381) (xy 155.541379 -283.808524) (xy 155.573521 -283.846365)
			(xy 155.599117 -283.888907) (xy 155.617493 -283.935031) (xy 155.628165 -283.98352) (xy 155.630402 -284.024832)
			(xy 155.96922 -284.024832) (xy 155.97318 -283.975778) (xy 155.984957 -283.927994) (xy 156.004248 -283.882718)
			(xy 156.030551 -283.841122) (xy 156.063186 -283.804285) (xy 156.101307 -283.77316) (xy 156.143928 -283.748553)
			(xy 156.189944 -283.731101) (xy 156.238163 -283.721257) (xy 156.287338 -283.719276) (xy 156.336193 -283.725208)
			(xy 156.383464 -283.7389) (xy 156.427926 -283.759998) (xy 156.468429 -283.787954) (xy 156.503922 -283.822046)
			(xy 156.533487 -283.86139) (xy 156.556358 -283.904967) (xy 156.571942 -283.951648) (xy 156.579837 -284.000225)
			(xy 156.580332 -284.024832) (xy 156.91918 -284.024832) (xy 156.92314 -283.975778) (xy 156.934917 -283.927994)
			(xy 156.954208 -283.882718) (xy 156.980511 -283.841122) (xy 157.013146 -283.804285) (xy 157.051267 -283.77316)
			(xy 157.093888 -283.748553) (xy 157.139904 -283.731101) (xy 157.188123 -283.721257) (xy 157.237298 -283.719276)
			(xy 157.286153 -283.725208) (xy 157.333424 -283.7389) (xy 157.377886 -283.759998) (xy 157.418389 -283.787954)
			(xy 157.453882 -283.822046) (xy 157.483447 -283.86139) (xy 157.506318 -283.904967) (xy 157.521902 -283.951648)
			(xy 157.529797 -284.000225) (xy 157.530292 -284.024832) (xy 157.86914 -284.024832) (xy 157.8731 -283.975778)
			(xy 157.884877 -283.927994) (xy 157.904168 -283.882718) (xy 157.930471 -283.841122) (xy 157.963106 -283.804285)
			(xy 158.001227 -283.77316) (xy 158.043848 -283.748553) (xy 158.089864 -283.731101) (xy 158.138083 -283.721257)
			(xy 158.187258 -283.719276) (xy 158.236113 -283.725208) (xy 158.283384 -283.7389) (xy 158.327846 -283.759998)
			(xy 158.368349 -283.787954) (xy 158.403842 -283.822046) (xy 158.433407 -283.86139) (xy 158.456278 -283.904967)
			(xy 158.471862 -283.951648) (xy 158.479757 -284.000225) (xy 158.480252 -284.024832) (xy 158.8191 -284.024832)
			(xy 158.82306 -283.975778) (xy 158.834837 -283.927994) (xy 158.854128 -283.882718) (xy 158.880431 -283.841122)
			(xy 158.913066 -283.804285) (xy 158.951187 -283.77316) (xy 158.993808 -283.748553) (xy 159.039824 -283.731101)
			(xy 159.088043 -283.721257) (xy 159.137218 -283.719276) (xy 159.186073 -283.725208) (xy 159.233344 -283.7389)
			(xy 159.277806 -283.759998) (xy 159.318309 -283.787954) (xy 159.353802 -283.822046) (xy 159.383367 -283.86139)
			(xy 159.406238 -283.904967) (xy 159.421822 -283.951648) (xy 159.429717 -284.000225) (xy 159.430212 -284.024832)
			(xy 159.76906 -284.024832) (xy 159.77302 -283.975778) (xy 159.784797 -283.927994) (xy 159.804088 -283.882718)
			(xy 159.830391 -283.841122) (xy 159.863026 -283.804285) (xy 159.901147 -283.77316) (xy 159.943768 -283.748553)
			(xy 159.989784 -283.731101) (xy 160.038003 -283.721257) (xy 160.087178 -283.719276) (xy 160.136033 -283.725208)
			(xy 160.183304 -283.7389) (xy 160.227766 -283.759998) (xy 160.268269 -283.787954) (xy 160.303762 -283.822046)
			(xy 160.333327 -283.86139) (xy 160.356198 -283.904967) (xy 160.371782 -283.951648) (xy 160.379677 -284.000225)
			(xy 160.380172 -284.024832) (xy 160.719274 -284.024832) (xy 160.723234 -283.975778) (xy 160.735011 -283.927994)
			(xy 160.754302 -283.882718) (xy 160.780605 -283.841122) (xy 160.81324 -283.804285) (xy 160.851361 -283.77316)
			(xy 160.893982 -283.748553) (xy 160.939998 -283.731101) (xy 160.988217 -283.721257) (xy 161.037392 -283.719276)
			(xy 161.086247 -283.725208) (xy 161.133518 -283.7389) (xy 161.17798 -283.759998) (xy 161.218483 -283.787954)
			(xy 161.253976 -283.822046) (xy 161.283541 -283.86139) (xy 161.306412 -283.904967) (xy 161.321996 -283.951648)
			(xy 161.329891 -284.000225) (xy 161.330386 -284.024832) (xy 161.669234 -284.024832) (xy 161.673194 -283.975778)
			(xy 161.684971 -283.927994) (xy 161.704262 -283.882718) (xy 161.730565 -283.841122) (xy 161.7632 -283.804285)
			(xy 161.801321 -283.77316) (xy 161.843942 -283.748553) (xy 161.889958 -283.731101) (xy 161.938177 -283.721257)
			(xy 161.987352 -283.719276) (xy 162.036207 -283.725208) (xy 162.083478 -283.7389) (xy 162.12794 -283.759998)
			(xy 162.168443 -283.787954) (xy 162.203936 -283.822046) (xy 162.233501 -283.86139) (xy 162.256372 -283.904967)
			(xy 162.271956 -283.951648) (xy 162.279851 -284.000225) (xy 162.280346 -284.024832) (xy 162.619194 -284.024832)
			(xy 162.623154 -283.975778) (xy 162.634931 -283.927994) (xy 162.654222 -283.882718) (xy 162.680525 -283.841122)
			(xy 162.71316 -283.804285) (xy 162.751281 -283.77316) (xy 162.793902 -283.748553) (xy 162.839918 -283.731101)
			(xy 162.888137 -283.721257) (xy 162.937312 -283.719276) (xy 162.986167 -283.725208) (xy 163.033438 -283.7389)
			(xy 163.0779 -283.759998) (xy 163.118403 -283.787954) (xy 163.153896 -283.822046) (xy 163.183461 -283.86139)
			(xy 163.206332 -283.904967) (xy 163.221916 -283.951648) (xy 163.229811 -284.000225) (xy 163.230306 -284.024832)
			(xy 163.569154 -284.024832) (xy 163.573114 -283.975778) (xy 163.584891 -283.927994) (xy 163.604182 -283.882718)
			(xy 163.630485 -283.841122) (xy 163.66312 -283.804285) (xy 163.701241 -283.77316) (xy 163.743862 -283.748553)
			(xy 163.789878 -283.731101) (xy 163.838097 -283.721257) (xy 163.887272 -283.719276) (xy 163.936127 -283.725208)
			(xy 163.983398 -283.7389) (xy 164.02786 -283.759998) (xy 164.068363 -283.787954) (xy 164.103856 -283.822046)
			(xy 164.133421 -283.86139) (xy 164.156292 -283.904967) (xy 164.171876 -283.951648) (xy 164.179771 -284.000225)
			(xy 164.180266 -284.024832) (xy 164.519114 -284.024832) (xy 164.523074 -283.975778) (xy 164.534851 -283.927994)
			(xy 164.554142 -283.882718) (xy 164.580445 -283.841122) (xy 164.61308 -283.804285) (xy 164.651201 -283.77316)
			(xy 164.693822 -283.748553) (xy 164.739838 -283.731101) (xy 164.788057 -283.721257) (xy 164.837232 -283.719276)
			(xy 164.886087 -283.725208) (xy 164.933358 -283.7389) (xy 164.97782 -283.759998) (xy 165.018323 -283.787954)
			(xy 165.053816 -283.822046) (xy 165.083381 -283.86139) (xy 165.106252 -283.904967) (xy 165.121836 -283.951648)
			(xy 165.129731 -284.000225) (xy 165.130226 -284.024832) (xy 165.469074 -284.024832) (xy 165.473034 -283.975778)
			(xy 165.484811 -283.927994) (xy 165.504102 -283.882718) (xy 165.530405 -283.841122) (xy 165.56304 -283.804285)
			(xy 165.601161 -283.77316) (xy 165.643782 -283.748553) (xy 165.689798 -283.731101) (xy 165.738017 -283.721257)
			(xy 165.787192 -283.719276) (xy 165.836047 -283.725208) (xy 165.883318 -283.7389) (xy 165.92778 -283.759998)
			(xy 165.968283 -283.787954) (xy 166.003776 -283.822046) (xy 166.033341 -283.86139) (xy 166.056212 -283.904967)
			(xy 166.071796 -283.951648) (xy 166.079691 -284.000225) (xy 166.080186 -284.024832) (xy 166.419288 -284.024832)
			(xy 166.423248 -283.975778) (xy 166.435025 -283.927994) (xy 166.454316 -283.882718) (xy 166.480619 -283.841122)
			(xy 166.513254 -283.804285) (xy 166.551375 -283.77316) (xy 166.593996 -283.748553) (xy 166.640012 -283.731101)
			(xy 166.688231 -283.721257) (xy 166.737406 -283.719276) (xy 166.786261 -283.725208) (xy 166.833532 -283.7389)
			(xy 166.877994 -283.759998) (xy 166.918497 -283.787954) (xy 166.95399 -283.822046) (xy 166.983555 -283.86139)
			(xy 167.006426 -283.904967) (xy 167.02201 -283.951648) (xy 167.029905 -284.000225) (xy 167.0304 -284.024832)
			(xy 167.369248 -284.024832) (xy 167.373208 -283.975778) (xy 167.384985 -283.927994) (xy 167.404276 -283.882718)
			(xy 167.430579 -283.841122) (xy 167.463214 -283.804285) (xy 167.501335 -283.77316) (xy 167.543956 -283.748553)
			(xy 167.589972 -283.731101) (xy 167.638191 -283.721257) (xy 167.687366 -283.719276) (xy 167.736221 -283.725208)
			(xy 167.783492 -283.7389) (xy 167.827954 -283.759998) (xy 167.868457 -283.787954) (xy 167.90395 -283.822046)
			(xy 167.933515 -283.86139) (xy 167.956386 -283.904967) (xy 167.97197 -283.951648) (xy 167.979865 -284.000225)
			(xy 167.98036 -284.024832) (xy 168.319208 -284.024832) (xy 168.323168 -283.975778) (xy 168.334945 -283.927994)
			(xy 168.354236 -283.882718) (xy 168.380539 -283.841122) (xy 168.413174 -283.804285) (xy 168.451295 -283.77316)
			(xy 168.493916 -283.748553) (xy 168.539932 -283.731101) (xy 168.588151 -283.721257) (xy 168.637326 -283.719276)
			(xy 168.686181 -283.725208) (xy 168.733452 -283.7389) (xy 168.777914 -283.759998) (xy 168.818417 -283.787954)
			(xy 168.85391 -283.822046) (xy 168.883475 -283.86139) (xy 168.906346 -283.904967) (xy 168.92193 -283.951648)
			(xy 168.929825 -284.000225) (xy 168.93032 -284.024832) (xy 169.269168 -284.024832) (xy 169.273128 -283.975778)
			(xy 169.284905 -283.927994) (xy 169.304196 -283.882718) (xy 169.330499 -283.841122) (xy 169.363134 -283.804285)
			(xy 169.401255 -283.77316) (xy 169.443876 -283.748553) (xy 169.489892 -283.731101) (xy 169.538111 -283.721257)
			(xy 169.587286 -283.719276) (xy 169.636141 -283.725208) (xy 169.683412 -283.7389) (xy 169.727874 -283.759998)
			(xy 169.768377 -283.787954) (xy 169.80387 -283.822046) (xy 169.833435 -283.86139) (xy 169.856306 -283.904967)
			(xy 169.87189 -283.951648) (xy 169.879785 -284.000225) (xy 169.88028 -284.024832) (xy 170.219128 -284.024832)
			(xy 170.223088 -283.975778) (xy 170.234865 -283.927994) (xy 170.254156 -283.882718) (xy 170.280459 -283.841122)
			(xy 170.313094 -283.804285) (xy 170.351215 -283.77316) (xy 170.393836 -283.748553) (xy 170.439852 -283.731101)
			(xy 170.488071 -283.721257) (xy 170.537246 -283.719276) (xy 170.586101 -283.725208) (xy 170.633372 -283.7389)
			(xy 170.677834 -283.759998) (xy 170.718337 -283.787954) (xy 170.75383 -283.822046) (xy 170.783395 -283.86139)
			(xy 170.806266 -283.904967) (xy 170.82185 -283.951648) (xy 170.829745 -284.000225) (xy 170.83024 -284.024832)
			(xy 171.169088 -284.024832) (xy 171.173048 -283.975778) (xy 171.184825 -283.927994) (xy 171.204116 -283.882718)
			(xy 171.230419 -283.841122) (xy 171.263054 -283.804285) (xy 171.301175 -283.77316) (xy 171.343796 -283.748553)
			(xy 171.389812 -283.731101) (xy 171.438031 -283.721257) (xy 171.487206 -283.719276) (xy 171.536061 -283.725208)
			(xy 171.583332 -283.7389) (xy 171.627794 -283.759998) (xy 171.668297 -283.787954) (xy 171.70379 -283.822046)
			(xy 171.733355 -283.86139) (xy 171.756226 -283.904967) (xy 171.77181 -283.951648) (xy 171.779705 -284.000225)
			(xy 171.7802 -284.024832) (xy 172.119048 -284.024832) (xy 172.123008 -283.975778) (xy 172.134785 -283.927994)
			(xy 172.154076 -283.882718) (xy 172.180379 -283.841122) (xy 172.213014 -283.804285) (xy 172.251135 -283.77316)
			(xy 172.293756 -283.748553) (xy 172.339772 -283.731101) (xy 172.387991 -283.721257) (xy 172.437166 -283.719276)
			(xy 172.486021 -283.725208) (xy 172.533292 -283.7389) (xy 172.577754 -283.759998) (xy 172.618257 -283.787954)
			(xy 172.65375 -283.822046) (xy 172.683315 -283.86139) (xy 172.706186 -283.904967) (xy 172.72177 -283.951648)
			(xy 172.729665 -284.000225) (xy 172.73016 -284.024832) (xy 173.069262 -284.024832) (xy 173.073222 -283.975778)
			(xy 173.084999 -283.927994) (xy 173.10429 -283.882718) (xy 173.130593 -283.841122) (xy 173.163228 -283.804285)
			(xy 173.201349 -283.77316) (xy 173.24397 -283.748553) (xy 173.289986 -283.731101) (xy 173.338205 -283.721257)
			(xy 173.38738 -283.719276) (xy 173.436235 -283.725208) (xy 173.483506 -283.7389) (xy 173.527968 -283.759998)
			(xy 173.568471 -283.787954) (xy 173.603964 -283.822046) (xy 173.633529 -283.86139) (xy 173.6564 -283.904967)
			(xy 173.671984 -283.951648) (xy 173.679879 -284.000225) (xy 173.680374 -284.024832) (xy 174.019222 -284.024832)
			(xy 174.023182 -283.975778) (xy 174.034959 -283.927994) (xy 174.05425 -283.882718) (xy 174.080553 -283.841122)
			(xy 174.113188 -283.804285) (xy 174.151309 -283.77316) (xy 174.19393 -283.748553) (xy 174.239946 -283.731101)
			(xy 174.288165 -283.721257) (xy 174.33734 -283.719276) (xy 174.386195 -283.725208) (xy 174.433466 -283.7389)
			(xy 174.477928 -283.759998) (xy 174.518431 -283.787954) (xy 174.553924 -283.822046) (xy 174.583489 -283.86139)
			(xy 174.60636 -283.904967) (xy 174.621944 -283.951648) (xy 174.629839 -284.000225) (xy 174.630334 -284.024832)
			(xy 175.919142 -284.024832) (xy 175.923102 -283.975778) (xy 175.934879 -283.927994) (xy 175.95417 -283.882718)
			(xy 175.980473 -283.841122) (xy 176.013108 -283.804285) (xy 176.051229 -283.77316) (xy 176.09385 -283.748553)
			(xy 176.139866 -283.731101) (xy 176.188085 -283.721257) (xy 176.23726 -283.719276) (xy 176.286115 -283.725208)
			(xy 176.333386 -283.7389) (xy 176.377848 -283.759998) (xy 176.418351 -283.787954) (xy 176.453844 -283.822046)
			(xy 176.483409 -283.86139) (xy 176.50628 -283.904967) (xy 176.521864 -283.951648) (xy 176.529759 -284.000225)
			(xy 176.530254 -284.024832) (xy 176.869102 -284.024832) (xy 176.873062 -283.975778) (xy 176.884839 -283.927994)
			(xy 176.90413 -283.882718) (xy 176.930433 -283.841122) (xy 176.963068 -283.804285) (xy 177.001189 -283.77316)
			(xy 177.04381 -283.748553) (xy 177.089826 -283.731101) (xy 177.138045 -283.721257) (xy 177.18722 -283.719276)
			(xy 177.236075 -283.725208) (xy 177.283346 -283.7389) (xy 177.327808 -283.759998) (xy 177.368311 -283.787954)
			(xy 177.403804 -283.822046) (xy 177.433369 -283.86139) (xy 177.45624 -283.904967) (xy 177.471824 -283.951648)
			(xy 177.479719 -284.000225) (xy 177.480214 -284.024832) (xy 177.819062 -284.024832) (xy 177.823022 -283.975778)
			(xy 177.834799 -283.927994) (xy 177.85409 -283.882718) (xy 177.880393 -283.841122) (xy 177.913028 -283.804285)
			(xy 177.951149 -283.77316) (xy 177.99377 -283.748553) (xy 178.039786 -283.731101) (xy 178.088005 -283.721257)
			(xy 178.13718 -283.719276) (xy 178.186035 -283.725208) (xy 178.233306 -283.7389) (xy 178.277768 -283.759998)
			(xy 178.318271 -283.787954) (xy 178.353764 -283.822046) (xy 178.383329 -283.86139) (xy 178.4062 -283.904967)
			(xy 178.421784 -283.951648) (xy 178.429679 -284.000225) (xy 178.430174 -284.024832) (xy 178.769276 -284.024832)
			(xy 178.773236 -283.975778) (xy 178.785013 -283.927994) (xy 178.804304 -283.882718) (xy 178.830607 -283.841122)
			(xy 178.863242 -283.804285) (xy 178.901363 -283.77316) (xy 178.943984 -283.748553) (xy 178.99 -283.731101)
			(xy 179.038219 -283.721257) (xy 179.087394 -283.719276) (xy 179.136249 -283.725208) (xy 179.18352 -283.7389)
			(xy 179.227982 -283.759998) (xy 179.268485 -283.787954) (xy 179.303978 -283.822046) (xy 179.333543 -283.86139)
			(xy 179.356414 -283.904967) (xy 179.371998 -283.951648) (xy 179.379893 -284.000225) (xy 179.380388 -284.024832)
			(xy 179.719236 -284.024832) (xy 179.723196 -283.975778) (xy 179.734973 -283.927994) (xy 179.754264 -283.882718)
			(xy 179.780567 -283.841122) (xy 179.813202 -283.804285) (xy 179.851323 -283.77316) (xy 179.893944 -283.748553)
			(xy 179.93996 -283.731101) (xy 179.988179 -283.721257) (xy 180.037354 -283.719276) (xy 180.086209 -283.725208)
			(xy 180.13348 -283.7389) (xy 180.177942 -283.759998) (xy 180.218445 -283.787954) (xy 180.253938 -283.822046)
			(xy 180.283503 -283.86139) (xy 180.306374 -283.904967) (xy 180.321958 -283.951648) (xy 180.329853 -284.000225)
			(xy 180.330348 -284.024832) (xy 180.669196 -284.024832) (xy 180.673156 -283.975778) (xy 180.684933 -283.927994)
			(xy 180.704224 -283.882718) (xy 180.730527 -283.841122) (xy 180.763162 -283.804285) (xy 180.801283 -283.77316)
			(xy 180.843904 -283.748553) (xy 180.88992 -283.731101) (xy 180.938139 -283.721257) (xy 180.987314 -283.719276)
			(xy 181.036169 -283.725208) (xy 181.08344 -283.7389) (xy 181.127902 -283.759998) (xy 181.168405 -283.787954)
			(xy 181.203898 -283.822046) (xy 181.233463 -283.86139) (xy 181.256334 -283.904967) (xy 181.271918 -283.951648)
			(xy 181.279813 -284.000225) (xy 181.280308 -284.024832) (xy 181.619156 -284.024832) (xy 181.623116 -283.975778)
			(xy 181.634893 -283.927994) (xy 181.654184 -283.882718) (xy 181.680487 -283.841122) (xy 181.713122 -283.804285)
			(xy 181.751243 -283.77316) (xy 181.793864 -283.748553) (xy 181.83988 -283.731101) (xy 181.888099 -283.721257)
			(xy 181.937274 -283.719276) (xy 181.986129 -283.725208) (xy 182.0334 -283.7389) (xy 182.077862 -283.759998)
			(xy 182.118365 -283.787954) (xy 182.153858 -283.822046) (xy 182.183423 -283.86139) (xy 182.206294 -283.904967)
			(xy 182.221878 -283.951648) (xy 182.229773 -284.000225) (xy 182.230268 -284.024832) (xy 182.569116 -284.024832)
			(xy 182.573076 -283.975778) (xy 182.584853 -283.927994) (xy 182.604144 -283.882718) (xy 182.630447 -283.841122)
			(xy 182.663082 -283.804285) (xy 182.701203 -283.77316) (xy 182.743824 -283.748553) (xy 182.78984 -283.731101)
			(xy 182.838059 -283.721257) (xy 182.887234 -283.719276) (xy 182.936089 -283.725208) (xy 182.98336 -283.7389)
			(xy 183.027822 -283.759998) (xy 183.068325 -283.787954) (xy 183.103818 -283.822046) (xy 183.133383 -283.86139)
			(xy 183.156254 -283.904967) (xy 183.171838 -283.951648) (xy 183.179733 -284.000225) (xy 183.180228 -284.024832)
			(xy 184.469036 -284.024832) (xy 184.472996 -283.975778) (xy 184.484773 -283.927994) (xy 184.504064 -283.882718)
			(xy 184.530367 -283.841122) (xy 184.563002 -283.804285) (xy 184.601123 -283.77316) (xy 184.643744 -283.748553)
			(xy 184.68976 -283.731101) (xy 184.737979 -283.721257) (xy 184.787154 -283.719276) (xy 184.836009 -283.725208)
			(xy 184.88328 -283.7389) (xy 184.927742 -283.759998) (xy 184.968245 -283.787954) (xy 185.003738 -283.822046)
			(xy 185.033303 -283.86139) (xy 185.056174 -283.904967) (xy 185.071758 -283.951648) (xy 185.079653 -284.000225)
			(xy 185.080148 -284.024832) (xy 185.079653 -284.049439) (xy 185.071758 -284.098016) (xy 185.056174 -284.144697)
			(xy 185.033303 -284.188274) (xy 185.003738 -284.227618) (xy 184.968245 -284.26171) (xy 184.927742 -284.289666)
			(xy 184.88328 -284.310764) (xy 184.836009 -284.324456) (xy 184.787154 -284.330388) (xy 184.737979 -284.328407)
			(xy 184.68976 -284.318563) (xy 184.643744 -284.301111) (xy 184.601123 -284.276504) (xy 184.563002 -284.245379)
			(xy 184.530367 -284.208542) (xy 184.504064 -284.166946) (xy 184.484773 -284.12167) (xy 184.472996 -284.073886)
			(xy 184.469036 -284.024832) (xy 183.180228 -284.024832) (xy 183.179733 -284.049439) (xy 183.171838 -284.098016)
			(xy 183.156254 -284.144697) (xy 183.133383 -284.188274) (xy 183.103818 -284.227618) (xy 183.068325 -284.26171)
			(xy 183.027822 -284.289666) (xy 182.98336 -284.310764) (xy 182.936089 -284.324456) (xy 182.887234 -284.330388)
			(xy 182.838059 -284.328407) (xy 182.78984 -284.318563) (xy 182.743824 -284.301111) (xy 182.701203 -284.276504)
			(xy 182.663082 -284.245379) (xy 182.630447 -284.208542) (xy 182.604144 -284.166946) (xy 182.584853 -284.12167)
			(xy 182.573076 -284.073886) (xy 182.569116 -284.024832) (xy 182.230268 -284.024832) (xy 182.229773 -284.049439)
			(xy 182.221878 -284.098016) (xy 182.206294 -284.144697) (xy 182.183423 -284.188274) (xy 182.153858 -284.227618)
			(xy 182.118365 -284.26171) (xy 182.077862 -284.289666) (xy 182.0334 -284.310764) (xy 181.986129 -284.324456)
			(xy 181.937274 -284.330388) (xy 181.888099 -284.328407) (xy 181.83988 -284.318563) (xy 181.793864 -284.301111)
			(xy 181.751243 -284.276504) (xy 181.713122 -284.245379) (xy 181.680487 -284.208542) (xy 181.654184 -284.166946)
			(xy 181.634893 -284.12167) (xy 181.623116 -284.073886) (xy 181.619156 -284.024832) (xy 181.280308 -284.024832)
			(xy 181.279813 -284.049439) (xy 181.271918 -284.098016) (xy 181.256334 -284.144697) (xy 181.233463 -284.188274)
			(xy 181.203898 -284.227618) (xy 181.168405 -284.26171) (xy 181.127902 -284.289666) (xy 181.08344 -284.310764)
			(xy 181.036169 -284.324456) (xy 180.987314 -284.330388) (xy 180.938139 -284.328407) (xy 180.88992 -284.318563)
			(xy 180.843904 -284.301111) (xy 180.801283 -284.276504) (xy 180.763162 -284.245379) (xy 180.730527 -284.208542)
			(xy 180.704224 -284.166946) (xy 180.684933 -284.12167) (xy 180.673156 -284.073886) (xy 180.669196 -284.024832)
			(xy 180.330348 -284.024832) (xy 180.329853 -284.049439) (xy 180.321958 -284.098016) (xy 180.306374 -284.144697)
			(xy 180.283503 -284.188274) (xy 180.253938 -284.227618) (xy 180.218445 -284.26171) (xy 180.177942 -284.289666)
			(xy 180.13348 -284.310764) (xy 180.086209 -284.324456) (xy 180.037354 -284.330388) (xy 179.988179 -284.328407)
			(xy 179.93996 -284.318563) (xy 179.893944 -284.301111) (xy 179.851323 -284.276504) (xy 179.813202 -284.245379)
			(xy 179.780567 -284.208542) (xy 179.754264 -284.166946) (xy 179.734973 -284.12167) (xy 179.723196 -284.073886)
			(xy 179.719236 -284.024832) (xy 179.380388 -284.024832) (xy 179.379893 -284.049439) (xy 179.371998 -284.098016)
			(xy 179.356414 -284.144697) (xy 179.333543 -284.188274) (xy 179.303978 -284.227618) (xy 179.268485 -284.26171)
			(xy 179.227982 -284.289666) (xy 179.18352 -284.310764) (xy 179.136249 -284.324456) (xy 179.087394 -284.330388)
			(xy 179.038219 -284.328407) (xy 178.99 -284.318563) (xy 178.943984 -284.301111) (xy 178.901363 -284.276504)
			(xy 178.863242 -284.245379) (xy 178.830607 -284.208542) (xy 178.804304 -284.166946) (xy 178.785013 -284.12167)
			(xy 178.773236 -284.073886) (xy 178.769276 -284.024832) (xy 178.430174 -284.024832) (xy 178.429679 -284.049439)
			(xy 178.421784 -284.098016) (xy 178.4062 -284.144697) (xy 178.383329 -284.188274) (xy 178.353764 -284.227618)
			(xy 178.318271 -284.26171) (xy 178.277768 -284.289666) (xy 178.233306 -284.310764) (xy 178.186035 -284.324456)
			(xy 178.13718 -284.330388) (xy 178.088005 -284.328407) (xy 178.039786 -284.318563) (xy 177.99377 -284.301111)
			(xy 177.951149 -284.276504) (xy 177.913028 -284.245379) (xy 177.880393 -284.208542) (xy 177.85409 -284.166946)
			(xy 177.834799 -284.12167) (xy 177.823022 -284.073886) (xy 177.819062 -284.024832) (xy 177.480214 -284.024832)
			(xy 177.479719 -284.049439) (xy 177.471824 -284.098016) (xy 177.45624 -284.144697) (xy 177.433369 -284.188274)
			(xy 177.403804 -284.227618) (xy 177.368311 -284.26171) (xy 177.327808 -284.289666) (xy 177.283346 -284.310764)
			(xy 177.236075 -284.324456) (xy 177.18722 -284.330388) (xy 177.138045 -284.328407) (xy 177.089826 -284.318563)
			(xy 177.04381 -284.301111) (xy 177.001189 -284.276504) (xy 176.963068 -284.245379) (xy 176.930433 -284.208542)
			(xy 176.90413 -284.166946) (xy 176.884839 -284.12167) (xy 176.873062 -284.073886) (xy 176.869102 -284.024832)
			(xy 176.530254 -284.024832) (xy 176.529759 -284.049439) (xy 176.521864 -284.098016) (xy 176.50628 -284.144697)
			(xy 176.483409 -284.188274) (xy 176.453844 -284.227618) (xy 176.418351 -284.26171) (xy 176.377848 -284.289666)
			(xy 176.333386 -284.310764) (xy 176.286115 -284.324456) (xy 176.23726 -284.330388) (xy 176.188085 -284.328407)
			(xy 176.139866 -284.318563) (xy 176.09385 -284.301111) (xy 176.051229 -284.276504) (xy 176.013108 -284.245379)
			(xy 175.980473 -284.208542) (xy 175.95417 -284.166946) (xy 175.934879 -284.12167) (xy 175.923102 -284.073886)
			(xy 175.919142 -284.024832) (xy 174.630334 -284.024832) (xy 174.629839 -284.049439) (xy 174.621944 -284.098016)
			(xy 174.60636 -284.144697) (xy 174.583489 -284.188274) (xy 174.553924 -284.227618) (xy 174.518431 -284.26171)
			(xy 174.477928 -284.289666) (xy 174.433466 -284.310764) (xy 174.386195 -284.324456) (xy 174.33734 -284.330388)
			(xy 174.288165 -284.328407) (xy 174.239946 -284.318563) (xy 174.19393 -284.301111) (xy 174.151309 -284.276504)
			(xy 174.113188 -284.245379) (xy 174.080553 -284.208542) (xy 174.05425 -284.166946) (xy 174.034959 -284.12167)
			(xy 174.023182 -284.073886) (xy 174.019222 -284.024832) (xy 173.680374 -284.024832) (xy 173.679879 -284.049439)
			(xy 173.671984 -284.098016) (xy 173.6564 -284.144697) (xy 173.633529 -284.188274) (xy 173.603964 -284.227618)
			(xy 173.568471 -284.26171) (xy 173.527968 -284.289666) (xy 173.483506 -284.310764) (xy 173.436235 -284.324456)
			(xy 173.38738 -284.330388) (xy 173.338205 -284.328407) (xy 173.289986 -284.318563) (xy 173.24397 -284.301111)
			(xy 173.201349 -284.276504) (xy 173.163228 -284.245379) (xy 173.130593 -284.208542) (xy 173.10429 -284.166946)
			(xy 173.084999 -284.12167) (xy 173.073222 -284.073886) (xy 173.069262 -284.024832) (xy 172.73016 -284.024832)
			(xy 172.729665 -284.049439) (xy 172.72177 -284.098016) (xy 172.706186 -284.144697) (xy 172.683315 -284.188274)
			(xy 172.65375 -284.227618) (xy 172.618257 -284.26171) (xy 172.577754 -284.289666) (xy 172.533292 -284.310764)
			(xy 172.486021 -284.324456) (xy 172.437166 -284.330388) (xy 172.387991 -284.328407) (xy 172.339772 -284.318563)
			(xy 172.293756 -284.301111) (xy 172.251135 -284.276504) (xy 172.213014 -284.245379) (xy 172.180379 -284.208542)
			(xy 172.154076 -284.166946) (xy 172.134785 -284.12167) (xy 172.123008 -284.073886) (xy 172.119048 -284.024832)
			(xy 171.7802 -284.024832) (xy 171.779705 -284.049439) (xy 171.77181 -284.098016) (xy 171.756226 -284.144697)
			(xy 171.733355 -284.188274) (xy 171.70379 -284.227618) (xy 171.668297 -284.26171) (xy 171.627794 -284.289666)
			(xy 171.583332 -284.310764) (xy 171.536061 -284.324456) (xy 171.487206 -284.330388) (xy 171.438031 -284.328407)
			(xy 171.389812 -284.318563) (xy 171.343796 -284.301111) (xy 171.301175 -284.276504) (xy 171.263054 -284.245379)
			(xy 171.230419 -284.208542) (xy 171.204116 -284.166946) (xy 171.184825 -284.12167) (xy 171.173048 -284.073886)
			(xy 171.169088 -284.024832) (xy 170.83024 -284.024832) (xy 170.829745 -284.049439) (xy 170.82185 -284.098016)
			(xy 170.806266 -284.144697) (xy 170.783395 -284.188274) (xy 170.75383 -284.227618) (xy 170.718337 -284.26171)
			(xy 170.677834 -284.289666) (xy 170.633372 -284.310764) (xy 170.586101 -284.324456) (xy 170.537246 -284.330388)
			(xy 170.488071 -284.328407) (xy 170.439852 -284.318563) (xy 170.393836 -284.301111) (xy 170.351215 -284.276504)
			(xy 170.313094 -284.245379) (xy 170.280459 -284.208542) (xy 170.254156 -284.166946) (xy 170.234865 -284.12167)
			(xy 170.223088 -284.073886) (xy 170.219128 -284.024832) (xy 169.88028 -284.024832) (xy 169.879785 -284.049439)
			(xy 169.87189 -284.098016) (xy 169.856306 -284.144697) (xy 169.833435 -284.188274) (xy 169.80387 -284.227618)
			(xy 169.768377 -284.26171) (xy 169.727874 -284.289666) (xy 169.683412 -284.310764) (xy 169.636141 -284.324456)
			(xy 169.587286 -284.330388) (xy 169.538111 -284.328407) (xy 169.489892 -284.318563) (xy 169.443876 -284.301111)
			(xy 169.401255 -284.276504) (xy 169.363134 -284.245379) (xy 169.330499 -284.208542) (xy 169.304196 -284.166946)
			(xy 169.284905 -284.12167) (xy 169.273128 -284.073886) (xy 169.269168 -284.024832) (xy 168.93032 -284.024832)
			(xy 168.929825 -284.049439) (xy 168.92193 -284.098016) (xy 168.906346 -284.144697) (xy 168.883475 -284.188274)
			(xy 168.85391 -284.227618) (xy 168.818417 -284.26171) (xy 168.777914 -284.289666) (xy 168.733452 -284.310764)
			(xy 168.686181 -284.324456) (xy 168.637326 -284.330388) (xy 168.588151 -284.328407) (xy 168.539932 -284.318563)
			(xy 168.493916 -284.301111) (xy 168.451295 -284.276504) (xy 168.413174 -284.245379) (xy 168.380539 -284.208542)
			(xy 168.354236 -284.166946) (xy 168.334945 -284.12167) (xy 168.323168 -284.073886) (xy 168.319208 -284.024832)
			(xy 167.98036 -284.024832) (xy 167.979865 -284.049439) (xy 167.97197 -284.098016) (xy 167.956386 -284.144697)
			(xy 167.933515 -284.188274) (xy 167.90395 -284.227618) (xy 167.868457 -284.26171) (xy 167.827954 -284.289666)
			(xy 167.783492 -284.310764) (xy 167.736221 -284.324456) (xy 167.687366 -284.330388) (xy 167.638191 -284.328407)
			(xy 167.589972 -284.318563) (xy 167.543956 -284.301111) (xy 167.501335 -284.276504) (xy 167.463214 -284.245379)
			(xy 167.430579 -284.208542) (xy 167.404276 -284.166946) (xy 167.384985 -284.12167) (xy 167.373208 -284.073886)
			(xy 167.369248 -284.024832) (xy 167.0304 -284.024832) (xy 167.029905 -284.049439) (xy 167.02201 -284.098016)
			(xy 167.006426 -284.144697) (xy 166.983555 -284.188274) (xy 166.95399 -284.227618) (xy 166.918497 -284.26171)
			(xy 166.877994 -284.289666) (xy 166.833532 -284.310764) (xy 166.786261 -284.324456) (xy 166.737406 -284.330388)
			(xy 166.688231 -284.328407) (xy 166.640012 -284.318563) (xy 166.593996 -284.301111) (xy 166.551375 -284.276504)
			(xy 166.513254 -284.245379) (xy 166.480619 -284.208542) (xy 166.454316 -284.166946) (xy 166.435025 -284.12167)
			(xy 166.423248 -284.073886) (xy 166.419288 -284.024832) (xy 166.080186 -284.024832) (xy 166.079691 -284.049439)
			(xy 166.071796 -284.098016) (xy 166.056212 -284.144697) (xy 166.033341 -284.188274) (xy 166.003776 -284.227618)
			(xy 165.968283 -284.26171) (xy 165.92778 -284.289666) (xy 165.883318 -284.310764) (xy 165.836047 -284.324456)
			(xy 165.787192 -284.330388) (xy 165.738017 -284.328407) (xy 165.689798 -284.318563) (xy 165.643782 -284.301111)
			(xy 165.601161 -284.276504) (xy 165.56304 -284.245379) (xy 165.530405 -284.208542) (xy 165.504102 -284.166946)
			(xy 165.484811 -284.12167) (xy 165.473034 -284.073886) (xy 165.469074 -284.024832) (xy 165.130226 -284.024832)
			(xy 165.129731 -284.049439) (xy 165.121836 -284.098016) (xy 165.106252 -284.144697) (xy 165.083381 -284.188274)
			(xy 165.053816 -284.227618) (xy 165.018323 -284.26171) (xy 164.97782 -284.289666) (xy 164.933358 -284.310764)
			(xy 164.886087 -284.324456) (xy 164.837232 -284.330388) (xy 164.788057 -284.328407) (xy 164.739838 -284.318563)
			(xy 164.693822 -284.301111) (xy 164.651201 -284.276504) (xy 164.61308 -284.245379) (xy 164.580445 -284.208542)
			(xy 164.554142 -284.166946) (xy 164.534851 -284.12167) (xy 164.523074 -284.073886) (xy 164.519114 -284.024832)
			(xy 164.180266 -284.024832) (xy 164.179771 -284.049439) (xy 164.171876 -284.098016) (xy 164.156292 -284.144697)
			(xy 164.133421 -284.188274) (xy 164.103856 -284.227618) (xy 164.068363 -284.26171) (xy 164.02786 -284.289666)
			(xy 163.983398 -284.310764) (xy 163.936127 -284.324456) (xy 163.887272 -284.330388) (xy 163.838097 -284.328407)
			(xy 163.789878 -284.318563) (xy 163.743862 -284.301111) (xy 163.701241 -284.276504) (xy 163.66312 -284.245379)
			(xy 163.630485 -284.208542) (xy 163.604182 -284.166946) (xy 163.584891 -284.12167) (xy 163.573114 -284.073886)
			(xy 163.569154 -284.024832) (xy 163.230306 -284.024832) (xy 163.229811 -284.049439) (xy 163.221916 -284.098016)
			(xy 163.206332 -284.144697) (xy 163.183461 -284.188274) (xy 163.153896 -284.227618) (xy 163.118403 -284.26171)
			(xy 163.0779 -284.289666) (xy 163.033438 -284.310764) (xy 162.986167 -284.324456) (xy 162.937312 -284.330388)
			(xy 162.888137 -284.328407) (xy 162.839918 -284.318563) (xy 162.793902 -284.301111) (xy 162.751281 -284.276504)
			(xy 162.71316 -284.245379) (xy 162.680525 -284.208542) (xy 162.654222 -284.166946) (xy 162.634931 -284.12167)
			(xy 162.623154 -284.073886) (xy 162.619194 -284.024832) (xy 162.280346 -284.024832) (xy 162.279851 -284.049439)
			(xy 162.271956 -284.098016) (xy 162.256372 -284.144697) (xy 162.233501 -284.188274) (xy 162.203936 -284.227618)
			(xy 162.168443 -284.26171) (xy 162.12794 -284.289666) (xy 162.083478 -284.310764) (xy 162.036207 -284.324456)
			(xy 161.987352 -284.330388) (xy 161.938177 -284.328407) (xy 161.889958 -284.318563) (xy 161.843942 -284.301111)
			(xy 161.801321 -284.276504) (xy 161.7632 -284.245379) (xy 161.730565 -284.208542) (xy 161.704262 -284.166946)
			(xy 161.684971 -284.12167) (xy 161.673194 -284.073886) (xy 161.669234 -284.024832) (xy 161.330386 -284.024832)
			(xy 161.329891 -284.049439) (xy 161.321996 -284.098016) (xy 161.306412 -284.144697) (xy 161.283541 -284.188274)
			(xy 161.253976 -284.227618) (xy 161.218483 -284.26171) (xy 161.17798 -284.289666) (xy 161.133518 -284.310764)
			(xy 161.086247 -284.324456) (xy 161.037392 -284.330388) (xy 160.988217 -284.328407) (xy 160.939998 -284.318563)
			(xy 160.893982 -284.301111) (xy 160.851361 -284.276504) (xy 160.81324 -284.245379) (xy 160.780605 -284.208542)
			(xy 160.754302 -284.166946) (xy 160.735011 -284.12167) (xy 160.723234 -284.073886) (xy 160.719274 -284.024832)
			(xy 160.380172 -284.024832) (xy 160.379677 -284.049439) (xy 160.371782 -284.098016) (xy 160.356198 -284.144697)
			(xy 160.333327 -284.188274) (xy 160.303762 -284.227618) (xy 160.268269 -284.26171) (xy 160.227766 -284.289666)
			(xy 160.183304 -284.310764) (xy 160.136033 -284.324456) (xy 160.087178 -284.330388) (xy 160.038003 -284.328407)
			(xy 159.989784 -284.318563) (xy 159.943768 -284.301111) (xy 159.901147 -284.276504) (xy 159.863026 -284.245379)
			(xy 159.830391 -284.208542) (xy 159.804088 -284.166946) (xy 159.784797 -284.12167) (xy 159.77302 -284.073886)
			(xy 159.76906 -284.024832) (xy 159.430212 -284.024832) (xy 159.429717 -284.049439) (xy 159.421822 -284.098016)
			(xy 159.406238 -284.144697) (xy 159.383367 -284.188274) (xy 159.353802 -284.227618) (xy 159.318309 -284.26171)
			(xy 159.277806 -284.289666) (xy 159.233344 -284.310764) (xy 159.186073 -284.324456) (xy 159.137218 -284.330388)
			(xy 159.088043 -284.328407) (xy 159.039824 -284.318563) (xy 158.993808 -284.301111) (xy 158.951187 -284.276504)
			(xy 158.913066 -284.245379) (xy 158.880431 -284.208542) (xy 158.854128 -284.166946) (xy 158.834837 -284.12167)
			(xy 158.82306 -284.073886) (xy 158.8191 -284.024832) (xy 158.480252 -284.024832) (xy 158.479757 -284.049439)
			(xy 158.471862 -284.098016) (xy 158.456278 -284.144697) (xy 158.433407 -284.188274) (xy 158.403842 -284.227618)
			(xy 158.368349 -284.26171) (xy 158.327846 -284.289666) (xy 158.283384 -284.310764) (xy 158.236113 -284.324456)
			(xy 158.187258 -284.330388) (xy 158.138083 -284.328407) (xy 158.089864 -284.318563) (xy 158.043848 -284.301111)
			(xy 158.001227 -284.276504) (xy 157.963106 -284.245379) (xy 157.930471 -284.208542) (xy 157.904168 -284.166946)
			(xy 157.884877 -284.12167) (xy 157.8731 -284.073886) (xy 157.86914 -284.024832) (xy 157.530292 -284.024832)
			(xy 157.529797 -284.049439) (xy 157.521902 -284.098016) (xy 157.506318 -284.144697) (xy 157.483447 -284.188274)
			(xy 157.453882 -284.227618) (xy 157.418389 -284.26171) (xy 157.377886 -284.289666) (xy 157.333424 -284.310764)
			(xy 157.286153 -284.324456) (xy 157.237298 -284.330388) (xy 157.188123 -284.328407) (xy 157.139904 -284.318563)
			(xy 157.093888 -284.301111) (xy 157.051267 -284.276504) (xy 157.013146 -284.245379) (xy 156.980511 -284.208542)
			(xy 156.954208 -284.166946) (xy 156.934917 -284.12167) (xy 156.92314 -284.073886) (xy 156.91918 -284.024832)
			(xy 156.580332 -284.024832) (xy 156.579837 -284.049439) (xy 156.571942 -284.098016) (xy 156.556358 -284.144697)
			(xy 156.533487 -284.188274) (xy 156.503922 -284.227618) (xy 156.468429 -284.26171) (xy 156.427926 -284.289666)
			(xy 156.383464 -284.310764) (xy 156.336193 -284.324456) (xy 156.287338 -284.330388) (xy 156.238163 -284.328407)
			(xy 156.189944 -284.318563) (xy 156.143928 -284.301111) (xy 156.101307 -284.276504) (xy 156.063186 -284.245379)
			(xy 156.030551 -284.208542) (xy 156.004248 -284.166946) (xy 155.984957 -284.12167) (xy 155.97318 -284.073886)
			(xy 155.96922 -284.024832) (xy 155.630402 -284.024832) (xy 155.63085 -284.033096) (xy 155.62548 -284.082454)
			(xy 155.612195 -284.130293) (xy 155.591345 -284.175352) (xy 155.563479 -284.216444) (xy 155.529333 -284.252487)
			(xy 155.489805 -284.28253) (xy 155.445937 -284.305782) (xy 155.398885 -284.32163) (xy 155.349889 -284.329657)
			(xy 155.325064 -284.33014) (xy 155.311528 -284.329982) (xy 155.284564 -284.327568) (xy 155.271216 -284.325314)
			(xy 155.259024 -284.323282) (xy 155.235402 -284.330648) (xy 155.211272 -284.354524) (xy 155.211272 -284.39618)
			(xy 155.252674 -284.437328) (xy 155.269114 -284.454444) (xy 155.297023 -284.492825) (xy 155.31866 -284.535062)
			(xy 155.333504 -284.580136) (xy 155.341199 -284.626964) (xy 155.341828 -284.650688) (xy 155.341828 -284.651704)
			(xy 155.342336 -284.669992) (xy 155.367002 -284.671908) (xy 155.415297 -284.682629) (xy 155.461231 -284.700998)
			(xy 155.503602 -284.726533) (xy 155.5413 -284.758567) (xy 155.57334 -284.79626) (xy 155.598881 -284.838627)
			(xy 155.617257 -284.884558) (xy 155.627985 -284.932852) (xy 155.629864 -284.95752) (xy 155.649168 -284.958028)
			(xy 155.64993 -284.958028) (xy 155.673577 -284.958703) (xy 155.720242 -284.966464) (xy 155.765151 -284.981329)
			(xy 155.807229 -285.002944) (xy 155.84547 -285.03079) (xy 155.862528 -285.047182) (xy 155.88869 -285.073598)
			(xy 155.8961 -285.080426) (xy 155.914692 -285.088153) (xy 155.924758 -285.088584) (xy 155.945332 -285.088584)
			(xy 155.969208 -285.064454) (xy 155.976574 -285.040832) (xy 155.974542 -285.02864) (xy 155.972294 -285.015291)
			(xy 155.969878 -284.988328) (xy 155.969716 -284.974792) (xy 155.970186 -284.949972) (xy 155.978218 -284.900987)
			(xy 155.994069 -284.853947) (xy 156.017321 -284.81009) (xy 156.047362 -284.770573) (xy 156.0834 -284.736436)
			(xy 156.124486 -284.708579) (xy 156.169538 -284.687737) (xy 156.217368 -284.674456) (xy 156.266716 -284.669089)
			(xy 156.316283 -284.671776) (xy 156.364761 -284.682446) (xy 156.410876 -284.700819) (xy 156.45341 -284.72641)
			(xy 156.491244 -284.758545) (xy 156.523381 -284.796377) (xy 156.548974 -284.83891) (xy 156.567349 -284.885023)
			(xy 156.578022 -284.933502) (xy 156.580262 -284.974792) (xy 156.91918 -284.974792) (xy 156.92314 -284.925738)
			(xy 156.934917 -284.877954) (xy 156.954208 -284.832678) (xy 156.980511 -284.791082) (xy 157.013146 -284.754245)
			(xy 157.051267 -284.72312) (xy 157.093888 -284.698513) (xy 157.139904 -284.681061) (xy 157.188123 -284.671217)
			(xy 157.237298 -284.669236) (xy 157.286153 -284.675168) (xy 157.333424 -284.68886) (xy 157.377886 -284.709958)
			(xy 157.418389 -284.737914) (xy 157.453882 -284.772006) (xy 157.483447 -284.81135) (xy 157.506318 -284.854927)
			(xy 157.521902 -284.901608) (xy 157.529797 -284.950185) (xy 157.530292 -284.974792) (xy 158.8191 -284.974792)
			(xy 158.82306 -284.925738) (xy 158.834837 -284.877954) (xy 158.854128 -284.832678) (xy 158.880431 -284.791082)
			(xy 158.913066 -284.754245) (xy 158.951187 -284.72312) (xy 158.993808 -284.698513) (xy 159.039824 -284.681061)
			(xy 159.088043 -284.671217) (xy 159.137218 -284.669236) (xy 159.186073 -284.675168) (xy 159.233344 -284.68886)
			(xy 159.277806 -284.709958) (xy 159.318309 -284.737914) (xy 159.353802 -284.772006) (xy 159.383367 -284.81135)
			(xy 159.406238 -284.854927) (xy 159.421822 -284.901608) (xy 159.429717 -284.950185) (xy 159.430212 -284.974792)
			(xy 160.719274 -284.974792) (xy 160.723234 -284.925738) (xy 160.735011 -284.877954) (xy 160.754302 -284.832678)
			(xy 160.780605 -284.791082) (xy 160.81324 -284.754245) (xy 160.851361 -284.72312) (xy 160.893982 -284.698513)
			(xy 160.939998 -284.681061) (xy 160.988217 -284.671217) (xy 161.037392 -284.669236) (xy 161.086247 -284.675168)
			(xy 161.133518 -284.68886) (xy 161.17798 -284.709958) (xy 161.218483 -284.737914) (xy 161.253976 -284.772006)
			(xy 161.283541 -284.81135) (xy 161.306412 -284.854927) (xy 161.321996 -284.901608) (xy 161.329891 -284.950185)
			(xy 161.330386 -284.974792) (xy 161.669234 -284.974792) (xy 161.673194 -284.925738) (xy 161.684971 -284.877954)
			(xy 161.704262 -284.832678) (xy 161.730565 -284.791082) (xy 161.7632 -284.754245) (xy 161.801321 -284.72312)
			(xy 161.843942 -284.698513) (xy 161.889958 -284.681061) (xy 161.938177 -284.671217) (xy 161.987352 -284.669236)
			(xy 162.036207 -284.675168) (xy 162.083478 -284.68886) (xy 162.12794 -284.709958) (xy 162.168443 -284.737914)
			(xy 162.203936 -284.772006) (xy 162.233501 -284.81135) (xy 162.256372 -284.854927) (xy 162.271956 -284.901608)
			(xy 162.279851 -284.950185) (xy 162.280346 -284.974792) (xy 162.619194 -284.974792) (xy 162.623154 -284.925738)
			(xy 162.634931 -284.877954) (xy 162.654222 -284.832678) (xy 162.680525 -284.791082) (xy 162.71316 -284.754245)
			(xy 162.751281 -284.72312) (xy 162.793902 -284.698513) (xy 162.839918 -284.681061) (xy 162.888137 -284.671217)
			(xy 162.937312 -284.669236) (xy 162.986167 -284.675168) (xy 163.033438 -284.68886) (xy 163.0779 -284.709958)
			(xy 163.118403 -284.737914) (xy 163.153896 -284.772006) (xy 163.183461 -284.81135) (xy 163.206332 -284.854927)
			(xy 163.221916 -284.901608) (xy 163.229811 -284.950185) (xy 163.230306 -284.974792) (xy 163.569154 -284.974792)
			(xy 163.573114 -284.925738) (xy 163.584891 -284.877954) (xy 163.604182 -284.832678) (xy 163.630485 -284.791082)
			(xy 163.66312 -284.754245) (xy 163.701241 -284.72312) (xy 163.743862 -284.698513) (xy 163.789878 -284.681061)
			(xy 163.838097 -284.671217) (xy 163.887272 -284.669236) (xy 163.936127 -284.675168) (xy 163.983398 -284.68886)
			(xy 164.02786 -284.709958) (xy 164.068363 -284.737914) (xy 164.103856 -284.772006) (xy 164.133421 -284.81135)
			(xy 164.156292 -284.854927) (xy 164.171876 -284.901608) (xy 164.179771 -284.950185) (xy 164.180266 -284.974792)
			(xy 164.519114 -284.974792) (xy 164.523074 -284.925738) (xy 164.534851 -284.877954) (xy 164.554142 -284.832678)
			(xy 164.580445 -284.791082) (xy 164.61308 -284.754245) (xy 164.651201 -284.72312) (xy 164.693822 -284.698513)
			(xy 164.739838 -284.681061) (xy 164.788057 -284.671217) (xy 164.837232 -284.669236) (xy 164.886087 -284.675168)
			(xy 164.933358 -284.68886) (xy 164.97782 -284.709958) (xy 165.018323 -284.737914) (xy 165.053816 -284.772006)
			(xy 165.083381 -284.81135) (xy 165.106252 -284.854927) (xy 165.121836 -284.901608) (xy 165.129731 -284.950185)
			(xy 165.130226 -284.974792) (xy 165.469074 -284.974792) (xy 165.473034 -284.925738) (xy 165.484811 -284.877954)
			(xy 165.504102 -284.832678) (xy 165.530405 -284.791082) (xy 165.56304 -284.754245) (xy 165.601161 -284.72312)
			(xy 165.643782 -284.698513) (xy 165.689798 -284.681061) (xy 165.738017 -284.671217) (xy 165.787192 -284.669236)
			(xy 165.836047 -284.675168) (xy 165.883318 -284.68886) (xy 165.92778 -284.709958) (xy 165.968283 -284.737914)
			(xy 166.003776 -284.772006) (xy 166.033341 -284.81135) (xy 166.056212 -284.854927) (xy 166.071796 -284.901608)
			(xy 166.079691 -284.950185) (xy 166.080186 -284.974792) (xy 166.419288 -284.974792) (xy 166.423248 -284.925738)
			(xy 166.435025 -284.877954) (xy 166.454316 -284.832678) (xy 166.480619 -284.791082) (xy 166.513254 -284.754245)
			(xy 166.551375 -284.72312) (xy 166.593996 -284.698513) (xy 166.640012 -284.681061) (xy 166.688231 -284.671217)
			(xy 166.737406 -284.669236) (xy 166.786261 -284.675168) (xy 166.833532 -284.68886) (xy 166.877994 -284.709958)
			(xy 166.918497 -284.737914) (xy 166.95399 -284.772006) (xy 166.983555 -284.81135) (xy 167.006426 -284.854927)
			(xy 167.02201 -284.901608) (xy 167.029905 -284.950185) (xy 167.0304 -284.974792) (xy 167.369248 -284.974792)
			(xy 167.373208 -284.925738) (xy 167.384985 -284.877954) (xy 167.404276 -284.832678) (xy 167.430579 -284.791082)
			(xy 167.463214 -284.754245) (xy 167.501335 -284.72312) (xy 167.543956 -284.698513) (xy 167.589972 -284.681061)
			(xy 167.638191 -284.671217) (xy 167.687366 -284.669236) (xy 167.736221 -284.675168) (xy 167.783492 -284.68886)
			(xy 167.827954 -284.709958) (xy 167.868457 -284.737914) (xy 167.90395 -284.772006) (xy 167.933515 -284.81135)
			(xy 167.956386 -284.854927) (xy 167.97197 -284.901608) (xy 167.979865 -284.950185) (xy 167.98036 -284.974792)
			(xy 168.319208 -284.974792) (xy 168.323168 -284.925738) (xy 168.334945 -284.877954) (xy 168.354236 -284.832678)
			(xy 168.380539 -284.791082) (xy 168.413174 -284.754245) (xy 168.451295 -284.72312) (xy 168.493916 -284.698513)
			(xy 168.539932 -284.681061) (xy 168.588151 -284.671217) (xy 168.637326 -284.669236) (xy 168.686181 -284.675168)
			(xy 168.733452 -284.68886) (xy 168.777914 -284.709958) (xy 168.818417 -284.737914) (xy 168.85391 -284.772006)
			(xy 168.883475 -284.81135) (xy 168.906346 -284.854927) (xy 168.92193 -284.901608) (xy 168.929825 -284.950185)
			(xy 168.93032 -284.974792) (xy 169.269168 -284.974792) (xy 169.273128 -284.925738) (xy 169.284905 -284.877954)
			(xy 169.304196 -284.832678) (xy 169.330499 -284.791082) (xy 169.363134 -284.754245) (xy 169.401255 -284.72312)
			(xy 169.443876 -284.698513) (xy 169.489892 -284.681061) (xy 169.538111 -284.671217) (xy 169.587286 -284.669236)
			(xy 169.636141 -284.675168) (xy 169.683412 -284.68886) (xy 169.727874 -284.709958) (xy 169.768377 -284.737914)
			(xy 169.80387 -284.772006) (xy 169.833435 -284.81135) (xy 169.856306 -284.854927) (xy 169.87189 -284.901608)
			(xy 169.879785 -284.950185) (xy 169.88028 -284.974792) (xy 170.219128 -284.974792) (xy 170.223088 -284.925738)
			(xy 170.234865 -284.877954) (xy 170.254156 -284.832678) (xy 170.280459 -284.791082) (xy 170.313094 -284.754245)
			(xy 170.351215 -284.72312) (xy 170.393836 -284.698513) (xy 170.439852 -284.681061) (xy 170.488071 -284.671217)
			(xy 170.537246 -284.669236) (xy 170.586101 -284.675168) (xy 170.633372 -284.68886) (xy 170.677834 -284.709958)
			(xy 170.718337 -284.737914) (xy 170.75383 -284.772006) (xy 170.783395 -284.81135) (xy 170.806266 -284.854927)
			(xy 170.82185 -284.901608) (xy 170.829745 -284.950185) (xy 170.83024 -284.974792) (xy 171.169088 -284.974792)
			(xy 171.173048 -284.925738) (xy 171.184825 -284.877954) (xy 171.204116 -284.832678) (xy 171.230419 -284.791082)
			(xy 171.263054 -284.754245) (xy 171.301175 -284.72312) (xy 171.343796 -284.698513) (xy 171.389812 -284.681061)
			(xy 171.438031 -284.671217) (xy 171.487206 -284.669236) (xy 171.536061 -284.675168) (xy 171.583332 -284.68886)
			(xy 171.627794 -284.709958) (xy 171.668297 -284.737914) (xy 171.70379 -284.772006) (xy 171.733355 -284.81135)
			(xy 171.756226 -284.854927) (xy 171.77181 -284.901608) (xy 171.779705 -284.950185) (xy 171.7802 -284.974792)
			(xy 172.119048 -284.974792) (xy 172.123008 -284.925738) (xy 172.134785 -284.877954) (xy 172.154076 -284.832678)
			(xy 172.180379 -284.791082) (xy 172.213014 -284.754245) (xy 172.251135 -284.72312) (xy 172.293756 -284.698513)
			(xy 172.339772 -284.681061) (xy 172.387991 -284.671217) (xy 172.437166 -284.669236) (xy 172.486021 -284.675168)
			(xy 172.533292 -284.68886) (xy 172.577754 -284.709958) (xy 172.618257 -284.737914) (xy 172.65375 -284.772006)
			(xy 172.683315 -284.81135) (xy 172.706186 -284.854927) (xy 172.72177 -284.901608) (xy 172.729665 -284.950185)
			(xy 172.73016 -284.974792) (xy 173.069262 -284.974792) (xy 173.073222 -284.925738) (xy 173.084999 -284.877954)
			(xy 173.10429 -284.832678) (xy 173.130593 -284.791082) (xy 173.163228 -284.754245) (xy 173.201349 -284.72312)
			(xy 173.24397 -284.698513) (xy 173.289986 -284.681061) (xy 173.338205 -284.671217) (xy 173.38738 -284.669236)
			(xy 173.436235 -284.675168) (xy 173.483506 -284.68886) (xy 173.527968 -284.709958) (xy 173.568471 -284.737914)
			(xy 173.603964 -284.772006) (xy 173.633529 -284.81135) (xy 173.6564 -284.854927) (xy 173.671984 -284.901608)
			(xy 173.679879 -284.950185) (xy 173.680374 -284.974792) (xy 174.019222 -284.974792) (xy 174.023182 -284.925738)
			(xy 174.034959 -284.877954) (xy 174.05425 -284.832678) (xy 174.080553 -284.791082) (xy 174.113188 -284.754245)
			(xy 174.151309 -284.72312) (xy 174.19393 -284.698513) (xy 174.239946 -284.681061) (xy 174.288165 -284.671217)
			(xy 174.33734 -284.669236) (xy 174.386195 -284.675168) (xy 174.433466 -284.68886) (xy 174.477928 -284.709958)
			(xy 174.518431 -284.737914) (xy 174.553924 -284.772006) (xy 174.583489 -284.81135) (xy 174.60636 -284.854927)
			(xy 174.621944 -284.901608) (xy 174.629839 -284.950185) (xy 174.630334 -284.974792) (xy 175.919142 -284.974792)
			(xy 175.923102 -284.925738) (xy 175.934879 -284.877954) (xy 175.95417 -284.832678) (xy 175.980473 -284.791082)
			(xy 176.013108 -284.754245) (xy 176.051229 -284.72312) (xy 176.09385 -284.698513) (xy 176.139866 -284.681061)
			(xy 176.188085 -284.671217) (xy 176.23726 -284.669236) (xy 176.286115 -284.675168) (xy 176.333386 -284.68886)
			(xy 176.377848 -284.709958) (xy 176.418351 -284.737914) (xy 176.453844 -284.772006) (xy 176.483409 -284.81135)
			(xy 176.50628 -284.854927) (xy 176.521864 -284.901608) (xy 176.529759 -284.950185) (xy 176.530254 -284.974792)
			(xy 176.869102 -284.974792) (xy 176.873062 -284.925738) (xy 176.884839 -284.877954) (xy 176.90413 -284.832678)
			(xy 176.930433 -284.791082) (xy 176.963068 -284.754245) (xy 177.001189 -284.72312) (xy 177.04381 -284.698513)
			(xy 177.089826 -284.681061) (xy 177.138045 -284.671217) (xy 177.18722 -284.669236) (xy 177.236075 -284.675168)
			(xy 177.283346 -284.68886) (xy 177.327808 -284.709958) (xy 177.368311 -284.737914) (xy 177.403804 -284.772006)
			(xy 177.433369 -284.81135) (xy 177.45624 -284.854927) (xy 177.471824 -284.901608) (xy 177.479719 -284.950185)
			(xy 177.480214 -284.974792) (xy 177.819062 -284.974792) (xy 177.823022 -284.925738) (xy 177.834799 -284.877954)
			(xy 177.85409 -284.832678) (xy 177.880393 -284.791082) (xy 177.913028 -284.754245) (xy 177.951149 -284.72312)
			(xy 177.99377 -284.698513) (xy 178.039786 -284.681061) (xy 178.088005 -284.671217) (xy 178.13718 -284.669236)
			(xy 178.186035 -284.675168) (xy 178.233306 -284.68886) (xy 178.277768 -284.709958) (xy 178.318271 -284.737914)
			(xy 178.353764 -284.772006) (xy 178.383329 -284.81135) (xy 178.4062 -284.854927) (xy 178.421784 -284.901608)
			(xy 178.429679 -284.950185) (xy 178.430174 -284.974792) (xy 178.769276 -284.974792) (xy 178.773236 -284.925738)
			(xy 178.785013 -284.877954) (xy 178.804304 -284.832678) (xy 178.830607 -284.791082) (xy 178.863242 -284.754245)
			(xy 178.901363 -284.72312) (xy 178.943984 -284.698513) (xy 178.99 -284.681061) (xy 179.038219 -284.671217)
			(xy 179.087394 -284.669236) (xy 179.136249 -284.675168) (xy 179.18352 -284.68886) (xy 179.227982 -284.709958)
			(xy 179.268485 -284.737914) (xy 179.303978 -284.772006) (xy 179.333543 -284.81135) (xy 179.356414 -284.854927)
			(xy 179.371998 -284.901608) (xy 179.379893 -284.950185) (xy 179.380388 -284.974792) (xy 179.719236 -284.974792)
			(xy 179.723196 -284.925738) (xy 179.734973 -284.877954) (xy 179.754264 -284.832678) (xy 179.780567 -284.791082)
			(xy 179.813202 -284.754245) (xy 179.851323 -284.72312) (xy 179.893944 -284.698513) (xy 179.93996 -284.681061)
			(xy 179.988179 -284.671217) (xy 180.037354 -284.669236) (xy 180.086209 -284.675168) (xy 180.13348 -284.68886)
			(xy 180.177942 -284.709958) (xy 180.218445 -284.737914) (xy 180.253938 -284.772006) (xy 180.283503 -284.81135)
			(xy 180.306374 -284.854927) (xy 180.321958 -284.901608) (xy 180.329853 -284.950185) (xy 180.330348 -284.974792)
			(xy 180.669196 -284.974792) (xy 180.673156 -284.925738) (xy 180.684933 -284.877954) (xy 180.704224 -284.832678)
			(xy 180.730527 -284.791082) (xy 180.763162 -284.754245) (xy 180.801283 -284.72312) (xy 180.843904 -284.698513)
			(xy 180.88992 -284.681061) (xy 180.938139 -284.671217) (xy 180.987314 -284.669236) (xy 181.036169 -284.675168)
			(xy 181.08344 -284.68886) (xy 181.127902 -284.709958) (xy 181.168405 -284.737914) (xy 181.203898 -284.772006)
			(xy 181.233463 -284.81135) (xy 181.256334 -284.854927) (xy 181.271918 -284.901608) (xy 181.279813 -284.950185)
			(xy 181.280308 -284.974792) (xy 181.619156 -284.974792) (xy 181.623116 -284.925738) (xy 181.634893 -284.877954)
			(xy 181.654184 -284.832678) (xy 181.680487 -284.791082) (xy 181.713122 -284.754245) (xy 181.751243 -284.72312)
			(xy 181.793864 -284.698513) (xy 181.83988 -284.681061) (xy 181.888099 -284.671217) (xy 181.937274 -284.669236)
			(xy 181.986129 -284.675168) (xy 182.0334 -284.68886) (xy 182.077862 -284.709958) (xy 182.118365 -284.737914)
			(xy 182.153858 -284.772006) (xy 182.183423 -284.81135) (xy 182.206294 -284.854927) (xy 182.221878 -284.901608)
			(xy 182.229773 -284.950185) (xy 182.230268 -284.974792) (xy 182.569116 -284.974792) (xy 182.573076 -284.925738)
			(xy 182.584853 -284.877954) (xy 182.604144 -284.832678) (xy 182.630447 -284.791082) (xy 182.663082 -284.754245)
			(xy 182.701203 -284.72312) (xy 182.743824 -284.698513) (xy 182.78984 -284.681061) (xy 182.838059 -284.671217)
			(xy 182.887234 -284.669236) (xy 182.936089 -284.675168) (xy 182.98336 -284.68886) (xy 183.027822 -284.709958)
			(xy 183.068325 -284.737914) (xy 183.103818 -284.772006) (xy 183.133383 -284.81135) (xy 183.156254 -284.854927)
			(xy 183.171838 -284.901608) (xy 183.179733 -284.950185) (xy 183.180228 -284.974792) (xy 183.519076 -284.974792)
			(xy 183.523036 -284.925738) (xy 183.534813 -284.877954) (xy 183.554104 -284.832678) (xy 183.580407 -284.791082)
			(xy 183.613042 -284.754245) (xy 183.651163 -284.72312) (xy 183.693784 -284.698513) (xy 183.7398 -284.681061)
			(xy 183.788019 -284.671217) (xy 183.837194 -284.669236) (xy 183.886049 -284.675168) (xy 183.93332 -284.68886)
			(xy 183.977782 -284.709958) (xy 184.018285 -284.737914) (xy 184.053778 -284.772006) (xy 184.083343 -284.81135)
			(xy 184.106214 -284.854927) (xy 184.121798 -284.901608) (xy 184.129693 -284.950185) (xy 184.130188 -284.974792)
			(xy 184.469036 -284.974792) (xy 184.472996 -284.925738) (xy 184.484773 -284.877954) (xy 184.504064 -284.832678)
			(xy 184.530367 -284.791082) (xy 184.563002 -284.754245) (xy 184.601123 -284.72312) (xy 184.643744 -284.698513)
			(xy 184.68976 -284.681061) (xy 184.737979 -284.671217) (xy 184.787154 -284.669236) (xy 184.836009 -284.675168)
			(xy 184.88328 -284.68886) (xy 184.927742 -284.709958) (xy 184.968245 -284.737914) (xy 185.003738 -284.772006)
			(xy 185.033303 -284.81135) (xy 185.056174 -284.854927) (xy 185.071758 -284.901608) (xy 185.079653 -284.950185)
			(xy 185.080148 -284.974792) (xy 185.079653 -284.999399) (xy 185.071758 -285.047976) (xy 185.056174 -285.094657)
			(xy 185.033303 -285.138234) (xy 185.003738 -285.177578) (xy 184.968245 -285.21167) (xy 184.927742 -285.239626)
			(xy 184.88328 -285.260724) (xy 184.836009 -285.274416) (xy 184.787154 -285.280348) (xy 184.737979 -285.278367)
			(xy 184.68976 -285.268523) (xy 184.643744 -285.251071) (xy 184.601123 -285.226464) (xy 184.563002 -285.195339)
			(xy 184.530367 -285.158502) (xy 184.504064 -285.116906) (xy 184.484773 -285.07163) (xy 184.472996 -285.023846)
			(xy 184.469036 -284.974792) (xy 184.130188 -284.974792) (xy 184.129693 -284.999399) (xy 184.121798 -285.047976)
			(xy 184.106214 -285.094657) (xy 184.083343 -285.138234) (xy 184.053778 -285.177578) (xy 184.018285 -285.21167)
			(xy 183.977782 -285.239626) (xy 183.93332 -285.260724) (xy 183.886049 -285.274416) (xy 183.837194 -285.280348)
			(xy 183.788019 -285.278367) (xy 183.7398 -285.268523) (xy 183.693784 -285.251071) (xy 183.651163 -285.226464)
			(xy 183.613042 -285.195339) (xy 183.580407 -285.158502) (xy 183.554104 -285.116906) (xy 183.534813 -285.07163)
			(xy 183.523036 -285.023846) (xy 183.519076 -284.974792) (xy 183.180228 -284.974792) (xy 183.179733 -284.999399)
			(xy 183.171838 -285.047976) (xy 183.156254 -285.094657) (xy 183.133383 -285.138234) (xy 183.103818 -285.177578)
			(xy 183.068325 -285.21167) (xy 183.027822 -285.239626) (xy 182.98336 -285.260724) (xy 182.936089 -285.274416)
			(xy 182.887234 -285.280348) (xy 182.838059 -285.278367) (xy 182.78984 -285.268523) (xy 182.743824 -285.251071)
			(xy 182.701203 -285.226464) (xy 182.663082 -285.195339) (xy 182.630447 -285.158502) (xy 182.604144 -285.116906)
			(xy 182.584853 -285.07163) (xy 182.573076 -285.023846) (xy 182.569116 -284.974792) (xy 182.230268 -284.974792)
			(xy 182.229773 -284.999399) (xy 182.221878 -285.047976) (xy 182.206294 -285.094657) (xy 182.183423 -285.138234)
			(xy 182.153858 -285.177578) (xy 182.118365 -285.21167) (xy 182.077862 -285.239626) (xy 182.0334 -285.260724)
			(xy 181.986129 -285.274416) (xy 181.937274 -285.280348) (xy 181.888099 -285.278367) (xy 181.83988 -285.268523)
			(xy 181.793864 -285.251071) (xy 181.751243 -285.226464) (xy 181.713122 -285.195339) (xy 181.680487 -285.158502)
			(xy 181.654184 -285.116906) (xy 181.634893 -285.07163) (xy 181.623116 -285.023846) (xy 181.619156 -284.974792)
			(xy 181.280308 -284.974792) (xy 181.279813 -284.999399) (xy 181.271918 -285.047976) (xy 181.256334 -285.094657)
			(xy 181.233463 -285.138234) (xy 181.203898 -285.177578) (xy 181.168405 -285.21167) (xy 181.127902 -285.239626)
			(xy 181.08344 -285.260724) (xy 181.036169 -285.274416) (xy 180.987314 -285.280348) (xy 180.938139 -285.278367)
			(xy 180.88992 -285.268523) (xy 180.843904 -285.251071) (xy 180.801283 -285.226464) (xy 180.763162 -285.195339)
			(xy 180.730527 -285.158502) (xy 180.704224 -285.116906) (xy 180.684933 -285.07163) (xy 180.673156 -285.023846)
			(xy 180.669196 -284.974792) (xy 180.330348 -284.974792) (xy 180.329853 -284.999399) (xy 180.321958 -285.047976)
			(xy 180.306374 -285.094657) (xy 180.283503 -285.138234) (xy 180.253938 -285.177578) (xy 180.218445 -285.21167)
			(xy 180.177942 -285.239626) (xy 180.13348 -285.260724) (xy 180.086209 -285.274416) (xy 180.037354 -285.280348)
			(xy 179.988179 -285.278367) (xy 179.93996 -285.268523) (xy 179.893944 -285.251071) (xy 179.851323 -285.226464)
			(xy 179.813202 -285.195339) (xy 179.780567 -285.158502) (xy 179.754264 -285.116906) (xy 179.734973 -285.07163)
			(xy 179.723196 -285.023846) (xy 179.719236 -284.974792) (xy 179.380388 -284.974792) (xy 179.379893 -284.999399)
			(xy 179.371998 -285.047976) (xy 179.356414 -285.094657) (xy 179.333543 -285.138234) (xy 179.303978 -285.177578)
			(xy 179.268485 -285.21167) (xy 179.227982 -285.239626) (xy 179.18352 -285.260724) (xy 179.136249 -285.274416)
			(xy 179.087394 -285.280348) (xy 179.038219 -285.278367) (xy 178.99 -285.268523) (xy 178.943984 -285.251071)
			(xy 178.901363 -285.226464) (xy 178.863242 -285.195339) (xy 178.830607 -285.158502) (xy 178.804304 -285.116906)
			(xy 178.785013 -285.07163) (xy 178.773236 -285.023846) (xy 178.769276 -284.974792) (xy 178.430174 -284.974792)
			(xy 178.429679 -284.999399) (xy 178.421784 -285.047976) (xy 178.4062 -285.094657) (xy 178.383329 -285.138234)
			(xy 178.353764 -285.177578) (xy 178.318271 -285.21167) (xy 178.277768 -285.239626) (xy 178.233306 -285.260724)
			(xy 178.186035 -285.274416) (xy 178.13718 -285.280348) (xy 178.088005 -285.278367) (xy 178.039786 -285.268523)
			(xy 177.99377 -285.251071) (xy 177.951149 -285.226464) (xy 177.913028 -285.195339) (xy 177.880393 -285.158502)
			(xy 177.85409 -285.116906) (xy 177.834799 -285.07163) (xy 177.823022 -285.023846) (xy 177.819062 -284.974792)
			(xy 177.480214 -284.974792) (xy 177.479719 -284.999399) (xy 177.471824 -285.047976) (xy 177.45624 -285.094657)
			(xy 177.433369 -285.138234) (xy 177.403804 -285.177578) (xy 177.368311 -285.21167) (xy 177.327808 -285.239626)
			(xy 177.283346 -285.260724) (xy 177.236075 -285.274416) (xy 177.18722 -285.280348) (xy 177.138045 -285.278367)
			(xy 177.089826 -285.268523) (xy 177.04381 -285.251071) (xy 177.001189 -285.226464) (xy 176.963068 -285.195339)
			(xy 176.930433 -285.158502) (xy 176.90413 -285.116906) (xy 176.884839 -285.07163) (xy 176.873062 -285.023846)
			(xy 176.869102 -284.974792) (xy 176.530254 -284.974792) (xy 176.529759 -284.999399) (xy 176.521864 -285.047976)
			(xy 176.50628 -285.094657) (xy 176.483409 -285.138234) (xy 176.453844 -285.177578) (xy 176.418351 -285.21167)
			(xy 176.377848 -285.239626) (xy 176.333386 -285.260724) (xy 176.286115 -285.274416) (xy 176.23726 -285.280348)
			(xy 176.188085 -285.278367) (xy 176.139866 -285.268523) (xy 176.09385 -285.251071) (xy 176.051229 -285.226464)
			(xy 176.013108 -285.195339) (xy 175.980473 -285.158502) (xy 175.95417 -285.116906) (xy 175.934879 -285.07163)
			(xy 175.923102 -285.023846) (xy 175.919142 -284.974792) (xy 174.630334 -284.974792) (xy 174.629839 -284.999399)
			(xy 174.621944 -285.047976) (xy 174.60636 -285.094657) (xy 174.583489 -285.138234) (xy 174.553924 -285.177578)
			(xy 174.518431 -285.21167) (xy 174.477928 -285.239626) (xy 174.433466 -285.260724) (xy 174.386195 -285.274416)
			(xy 174.33734 -285.280348) (xy 174.288165 -285.278367) (xy 174.239946 -285.268523) (xy 174.19393 -285.251071)
			(xy 174.151309 -285.226464) (xy 174.113188 -285.195339) (xy 174.080553 -285.158502) (xy 174.05425 -285.116906)
			(xy 174.034959 -285.07163) (xy 174.023182 -285.023846) (xy 174.019222 -284.974792) (xy 173.680374 -284.974792)
			(xy 173.679879 -284.999399) (xy 173.671984 -285.047976) (xy 173.6564 -285.094657) (xy 173.633529 -285.138234)
			(xy 173.603964 -285.177578) (xy 173.568471 -285.21167) (xy 173.527968 -285.239626) (xy 173.483506 -285.260724)
			(xy 173.436235 -285.274416) (xy 173.38738 -285.280348) (xy 173.338205 -285.278367) (xy 173.289986 -285.268523)
			(xy 173.24397 -285.251071) (xy 173.201349 -285.226464) (xy 173.163228 -285.195339) (xy 173.130593 -285.158502)
			(xy 173.10429 -285.116906) (xy 173.084999 -285.07163) (xy 173.073222 -285.023846) (xy 173.069262 -284.974792)
			(xy 172.73016 -284.974792) (xy 172.729665 -284.999399) (xy 172.72177 -285.047976) (xy 172.706186 -285.094657)
			(xy 172.683315 -285.138234) (xy 172.65375 -285.177578) (xy 172.618257 -285.21167) (xy 172.577754 -285.239626)
			(xy 172.533292 -285.260724) (xy 172.486021 -285.274416) (xy 172.437166 -285.280348) (xy 172.387991 -285.278367)
			(xy 172.339772 -285.268523) (xy 172.293756 -285.251071) (xy 172.251135 -285.226464) (xy 172.213014 -285.195339)
			(xy 172.180379 -285.158502) (xy 172.154076 -285.116906) (xy 172.134785 -285.07163) (xy 172.123008 -285.023846)
			(xy 172.119048 -284.974792) (xy 171.7802 -284.974792) (xy 171.779705 -284.999399) (xy 171.77181 -285.047976)
			(xy 171.756226 -285.094657) (xy 171.733355 -285.138234) (xy 171.70379 -285.177578) (xy 171.668297 -285.21167)
			(xy 171.627794 -285.239626) (xy 171.583332 -285.260724) (xy 171.536061 -285.274416) (xy 171.487206 -285.280348)
			(xy 171.438031 -285.278367) (xy 171.389812 -285.268523) (xy 171.343796 -285.251071) (xy 171.301175 -285.226464)
			(xy 171.263054 -285.195339) (xy 171.230419 -285.158502) (xy 171.204116 -285.116906) (xy 171.184825 -285.07163)
			(xy 171.173048 -285.023846) (xy 171.169088 -284.974792) (xy 170.83024 -284.974792) (xy 170.829745 -284.999399)
			(xy 170.82185 -285.047976) (xy 170.806266 -285.094657) (xy 170.783395 -285.138234) (xy 170.75383 -285.177578)
			(xy 170.718337 -285.21167) (xy 170.677834 -285.239626) (xy 170.633372 -285.260724) (xy 170.586101 -285.274416)
			(xy 170.537246 -285.280348) (xy 170.488071 -285.278367) (xy 170.439852 -285.268523) (xy 170.393836 -285.251071)
			(xy 170.351215 -285.226464) (xy 170.313094 -285.195339) (xy 170.280459 -285.158502) (xy 170.254156 -285.116906)
			(xy 170.234865 -285.07163) (xy 170.223088 -285.023846) (xy 170.219128 -284.974792) (xy 169.88028 -284.974792)
			(xy 169.879785 -284.999399) (xy 169.87189 -285.047976) (xy 169.856306 -285.094657) (xy 169.833435 -285.138234)
			(xy 169.80387 -285.177578) (xy 169.768377 -285.21167) (xy 169.727874 -285.239626) (xy 169.683412 -285.260724)
			(xy 169.636141 -285.274416) (xy 169.587286 -285.280348) (xy 169.538111 -285.278367) (xy 169.489892 -285.268523)
			(xy 169.443876 -285.251071) (xy 169.401255 -285.226464) (xy 169.363134 -285.195339) (xy 169.330499 -285.158502)
			(xy 169.304196 -285.116906) (xy 169.284905 -285.07163) (xy 169.273128 -285.023846) (xy 169.269168 -284.974792)
			(xy 168.93032 -284.974792) (xy 168.929825 -284.999399) (xy 168.92193 -285.047976) (xy 168.906346 -285.094657)
			(xy 168.883475 -285.138234) (xy 168.85391 -285.177578) (xy 168.818417 -285.21167) (xy 168.777914 -285.239626)
			(xy 168.733452 -285.260724) (xy 168.686181 -285.274416) (xy 168.637326 -285.280348) (xy 168.588151 -285.278367)
			(xy 168.539932 -285.268523) (xy 168.493916 -285.251071) (xy 168.451295 -285.226464) (xy 168.413174 -285.195339)
			(xy 168.380539 -285.158502) (xy 168.354236 -285.116906) (xy 168.334945 -285.07163) (xy 168.323168 -285.023846)
			(xy 168.319208 -284.974792) (xy 167.98036 -284.974792) (xy 167.979865 -284.999399) (xy 167.97197 -285.047976)
			(xy 167.956386 -285.094657) (xy 167.933515 -285.138234) (xy 167.90395 -285.177578) (xy 167.868457 -285.21167)
			(xy 167.827954 -285.239626) (xy 167.783492 -285.260724) (xy 167.736221 -285.274416) (xy 167.687366 -285.280348)
			(xy 167.638191 -285.278367) (xy 167.589972 -285.268523) (xy 167.543956 -285.251071) (xy 167.501335 -285.226464)
			(xy 167.463214 -285.195339) (xy 167.430579 -285.158502) (xy 167.404276 -285.116906) (xy 167.384985 -285.07163)
			(xy 167.373208 -285.023846) (xy 167.369248 -284.974792) (xy 167.0304 -284.974792) (xy 167.029905 -284.999399)
			(xy 167.02201 -285.047976) (xy 167.006426 -285.094657) (xy 166.983555 -285.138234) (xy 166.95399 -285.177578)
			(xy 166.918497 -285.21167) (xy 166.877994 -285.239626) (xy 166.833532 -285.260724) (xy 166.786261 -285.274416)
			(xy 166.737406 -285.280348) (xy 166.688231 -285.278367) (xy 166.640012 -285.268523) (xy 166.593996 -285.251071)
			(xy 166.551375 -285.226464) (xy 166.513254 -285.195339) (xy 166.480619 -285.158502) (xy 166.454316 -285.116906)
			(xy 166.435025 -285.07163) (xy 166.423248 -285.023846) (xy 166.419288 -284.974792) (xy 166.080186 -284.974792)
			(xy 166.079691 -284.999399) (xy 166.071796 -285.047976) (xy 166.056212 -285.094657) (xy 166.033341 -285.138234)
			(xy 166.003776 -285.177578) (xy 165.968283 -285.21167) (xy 165.92778 -285.239626) (xy 165.883318 -285.260724)
			(xy 165.836047 -285.274416) (xy 165.787192 -285.280348) (xy 165.738017 -285.278367) (xy 165.689798 -285.268523)
			(xy 165.643782 -285.251071) (xy 165.601161 -285.226464) (xy 165.56304 -285.195339) (xy 165.530405 -285.158502)
			(xy 165.504102 -285.116906) (xy 165.484811 -285.07163) (xy 165.473034 -285.023846) (xy 165.469074 -284.974792)
			(xy 165.130226 -284.974792) (xy 165.129731 -284.999399) (xy 165.121836 -285.047976) (xy 165.106252 -285.094657)
			(xy 165.083381 -285.138234) (xy 165.053816 -285.177578) (xy 165.018323 -285.21167) (xy 164.97782 -285.239626)
			(xy 164.933358 -285.260724) (xy 164.886087 -285.274416) (xy 164.837232 -285.280348) (xy 164.788057 -285.278367)
			(xy 164.739838 -285.268523) (xy 164.693822 -285.251071) (xy 164.651201 -285.226464) (xy 164.61308 -285.195339)
			(xy 164.580445 -285.158502) (xy 164.554142 -285.116906) (xy 164.534851 -285.07163) (xy 164.523074 -285.023846)
			(xy 164.519114 -284.974792) (xy 164.180266 -284.974792) (xy 164.179771 -284.999399) (xy 164.171876 -285.047976)
			(xy 164.156292 -285.094657) (xy 164.133421 -285.138234) (xy 164.103856 -285.177578) (xy 164.068363 -285.21167)
			(xy 164.02786 -285.239626) (xy 163.983398 -285.260724) (xy 163.936127 -285.274416) (xy 163.887272 -285.280348)
			(xy 163.838097 -285.278367) (xy 163.789878 -285.268523) (xy 163.743862 -285.251071) (xy 163.701241 -285.226464)
			(xy 163.66312 -285.195339) (xy 163.630485 -285.158502) (xy 163.604182 -285.116906) (xy 163.584891 -285.07163)
			(xy 163.573114 -285.023846) (xy 163.569154 -284.974792) (xy 163.230306 -284.974792) (xy 163.229811 -284.999399)
			(xy 163.221916 -285.047976) (xy 163.206332 -285.094657) (xy 163.183461 -285.138234) (xy 163.153896 -285.177578)
			(xy 163.118403 -285.21167) (xy 163.0779 -285.239626) (xy 163.033438 -285.260724) (xy 162.986167 -285.274416)
			(xy 162.937312 -285.280348) (xy 162.888137 -285.278367) (xy 162.839918 -285.268523) (xy 162.793902 -285.251071)
			(xy 162.751281 -285.226464) (xy 162.71316 -285.195339) (xy 162.680525 -285.158502) (xy 162.654222 -285.116906)
			(xy 162.634931 -285.07163) (xy 162.623154 -285.023846) (xy 162.619194 -284.974792) (xy 162.280346 -284.974792)
			(xy 162.279851 -284.999399) (xy 162.271956 -285.047976) (xy 162.256372 -285.094657) (xy 162.233501 -285.138234)
			(xy 162.203936 -285.177578) (xy 162.168443 -285.21167) (xy 162.12794 -285.239626) (xy 162.083478 -285.260724)
			(xy 162.036207 -285.274416) (xy 161.987352 -285.280348) (xy 161.938177 -285.278367) (xy 161.889958 -285.268523)
			(xy 161.843942 -285.251071) (xy 161.801321 -285.226464) (xy 161.7632 -285.195339) (xy 161.730565 -285.158502)
			(xy 161.704262 -285.116906) (xy 161.684971 -285.07163) (xy 161.673194 -285.023846) (xy 161.669234 -284.974792)
			(xy 161.330386 -284.974792) (xy 161.329891 -284.999399) (xy 161.321996 -285.047976) (xy 161.306412 -285.094657)
			(xy 161.283541 -285.138234) (xy 161.253976 -285.177578) (xy 161.218483 -285.21167) (xy 161.17798 -285.239626)
			(xy 161.133518 -285.260724) (xy 161.086247 -285.274416) (xy 161.037392 -285.280348) (xy 160.988217 -285.278367)
			(xy 160.939998 -285.268523) (xy 160.893982 -285.251071) (xy 160.851361 -285.226464) (xy 160.81324 -285.195339)
			(xy 160.780605 -285.158502) (xy 160.754302 -285.116906) (xy 160.735011 -285.07163) (xy 160.723234 -285.023846)
			(xy 160.719274 -284.974792) (xy 159.430212 -284.974792) (xy 159.429717 -284.999399) (xy 159.421822 -285.047976)
			(xy 159.406238 -285.094657) (xy 159.383367 -285.138234) (xy 159.353802 -285.177578) (xy 159.318309 -285.21167)
			(xy 159.277806 -285.239626) (xy 159.233344 -285.260724) (xy 159.186073 -285.274416) (xy 159.137218 -285.280348)
			(xy 159.088043 -285.278367) (xy 159.039824 -285.268523) (xy 158.993808 -285.251071) (xy 158.951187 -285.226464)
			(xy 158.913066 -285.195339) (xy 158.880431 -285.158502) (xy 158.854128 -285.116906) (xy 158.834837 -285.07163)
			(xy 158.82306 -285.023846) (xy 158.8191 -284.974792) (xy 157.530292 -284.974792) (xy 157.529797 -284.999399)
			(xy 157.521902 -285.047976) (xy 157.506318 -285.094657) (xy 157.483447 -285.138234) (xy 157.453882 -285.177578)
			(xy 157.418389 -285.21167) (xy 157.377886 -285.239626) (xy 157.333424 -285.260724) (xy 157.286153 -285.274416)
			(xy 157.237298 -285.280348) (xy 157.188123 -285.278367) (xy 157.139904 -285.268523) (xy 157.093888 -285.251071)
			(xy 157.051267 -285.226464) (xy 157.013146 -285.195339) (xy 156.980511 -285.158502) (xy 156.954208 -285.116906)
			(xy 156.934917 -285.07163) (xy 156.92314 -285.023846) (xy 156.91918 -284.974792) (xy 156.580262 -284.974792)
			(xy 156.580711 -284.983068) (xy 156.575347 -285.032417) (xy 156.562069 -285.080247) (xy 156.541228 -285.1253)
			(xy 156.513374 -285.166387) (xy 156.479239 -285.202427) (xy 156.439723 -285.23247) (xy 156.395868 -285.255725)
			(xy 156.348828 -285.271578) (xy 156.299844 -285.279612) (xy 156.275024 -285.2801) (xy 156.261488 -285.279948)
			(xy 156.234524 -285.27753) (xy 156.221176 -285.275274) (xy 156.208984 -285.273242) (xy 156.185362 -285.280608)
			(xy 156.161232 -285.304484) (xy 156.161232 -285.34614) (xy 156.202634 -285.387288) (xy 156.219095 -285.404384)
			(xy 156.247003 -285.44277) (xy 156.268637 -285.485011) (xy 156.283476 -285.530091) (xy 156.291163 -285.576923)
			(xy 156.291788 -285.600648) (xy 156.291788 -285.601664) (xy 156.292296 -285.619952) (xy 156.316963 -285.621854)
			(xy 156.365256 -285.632582) (xy 156.411187 -285.650956) (xy 156.453555 -285.676495) (xy 156.491252 -285.70853)
			(xy 156.52329 -285.746224) (xy 156.548832 -285.78859) (xy 156.56721 -285.83452) (xy 156.577943 -285.882812)
			(xy 156.579824 -285.90748) (xy 156.599128 -285.907988) (xy 156.59989 -285.907988) (xy 156.623535 -285.9087)
			(xy 156.670198 -285.916453) (xy 156.715106 -285.93131) (xy 156.757185 -285.952917) (xy 156.795428 -285.980755)
			(xy 156.812488 -285.997142) (xy 156.83865 -286.023558) (xy 156.846078 -286.030363) (xy 156.864656 -286.038104)
			(xy 156.874718 -286.038544) (xy 156.895292 -286.038544) (xy 156.919168 -286.014414) (xy 156.926534 -285.990792)
			(xy 156.924502 -285.9786) (xy 156.922249 -285.965252) (xy 156.919836 -285.938288) (xy 156.919676 -285.924752)
			(xy 156.92023 -285.899936) (xy 156.928267 -285.850958) (xy 156.944122 -285.803926) (xy 156.967377 -285.760078)
			(xy 156.997419 -285.72057) (xy 157.033457 -285.686442) (xy 157.074541 -285.658595) (xy 157.119589 -285.63776)
			(xy 157.167415 -285.624488) (xy 157.216757 -285.619128) (xy 157.266317 -285.621821) (xy 157.314788 -285.632496)
			(xy 157.360894 -285.650873) (xy 157.403419 -285.676466) (xy 157.441244 -285.708601) (xy 157.473372 -285.746433)
			(xy 157.498956 -285.788964) (xy 157.517322 -285.835073) (xy 157.527987 -285.883547) (xy 157.530218 -285.924752)
			(xy 160.719274 -285.924752) (xy 160.723234 -285.875698) (xy 160.735011 -285.827914) (xy 160.754302 -285.782638)
			(xy 160.780605 -285.741042) (xy 160.81324 -285.704205) (xy 160.851361 -285.67308) (xy 160.893982 -285.648473)
			(xy 160.939998 -285.631021) (xy 160.988217 -285.621177) (xy 161.037392 -285.619196) (xy 161.086247 -285.625128)
			(xy 161.133518 -285.63882) (xy 161.17798 -285.659918) (xy 161.218483 -285.687874) (xy 161.253976 -285.721966)
			(xy 161.283541 -285.76131) (xy 161.306412 -285.804887) (xy 161.321996 -285.851568) (xy 161.329891 -285.900145)
			(xy 161.330386 -285.924752) (xy 161.669234 -285.924752) (xy 161.673194 -285.875698) (xy 161.684971 -285.827914)
			(xy 161.704262 -285.782638) (xy 161.730565 -285.741042) (xy 161.7632 -285.704205) (xy 161.801321 -285.67308)
			(xy 161.843942 -285.648473) (xy 161.889958 -285.631021) (xy 161.938177 -285.621177) (xy 161.987352 -285.619196)
			(xy 162.036207 -285.625128) (xy 162.083478 -285.63882) (xy 162.12794 -285.659918) (xy 162.168443 -285.687874)
			(xy 162.203936 -285.721966) (xy 162.233501 -285.76131) (xy 162.256372 -285.804887) (xy 162.271956 -285.851568)
			(xy 162.279851 -285.900145) (xy 162.280346 -285.924752) (xy 162.619194 -285.924752) (xy 162.623154 -285.875698)
			(xy 162.634931 -285.827914) (xy 162.654222 -285.782638) (xy 162.680525 -285.741042) (xy 162.71316 -285.704205)
			(xy 162.751281 -285.67308) (xy 162.793902 -285.648473) (xy 162.839918 -285.631021) (xy 162.888137 -285.621177)
			(xy 162.937312 -285.619196) (xy 162.986167 -285.625128) (xy 163.033438 -285.63882) (xy 163.0779 -285.659918)
			(xy 163.118403 -285.687874) (xy 163.153896 -285.721966) (xy 163.183461 -285.76131) (xy 163.206332 -285.804887)
			(xy 163.221916 -285.851568) (xy 163.229811 -285.900145) (xy 163.230306 -285.924752) (xy 163.569154 -285.924752)
			(xy 163.573114 -285.875698) (xy 163.584891 -285.827914) (xy 163.604182 -285.782638) (xy 163.630485 -285.741042)
			(xy 163.66312 -285.704205) (xy 163.701241 -285.67308) (xy 163.743862 -285.648473) (xy 163.789878 -285.631021)
			(xy 163.838097 -285.621177) (xy 163.887272 -285.619196) (xy 163.936127 -285.625128) (xy 163.983398 -285.63882)
			(xy 164.02786 -285.659918) (xy 164.068363 -285.687874) (xy 164.103856 -285.721966) (xy 164.133421 -285.76131)
			(xy 164.156292 -285.804887) (xy 164.171876 -285.851568) (xy 164.179771 -285.900145) (xy 164.180266 -285.924752)
			(xy 164.519114 -285.924752) (xy 164.523074 -285.875698) (xy 164.534851 -285.827914) (xy 164.554142 -285.782638)
			(xy 164.580445 -285.741042) (xy 164.61308 -285.704205) (xy 164.651201 -285.67308) (xy 164.693822 -285.648473)
			(xy 164.739838 -285.631021) (xy 164.788057 -285.621177) (xy 164.837232 -285.619196) (xy 164.886087 -285.625128)
			(xy 164.933358 -285.63882) (xy 164.97782 -285.659918) (xy 165.018323 -285.687874) (xy 165.053816 -285.721966)
			(xy 165.083381 -285.76131) (xy 165.106252 -285.804887) (xy 165.121836 -285.851568) (xy 165.129731 -285.900145)
			(xy 165.130226 -285.924752) (xy 165.469074 -285.924752) (xy 165.473034 -285.875698) (xy 165.484811 -285.827914)
			(xy 165.504102 -285.782638) (xy 165.530405 -285.741042) (xy 165.56304 -285.704205) (xy 165.601161 -285.67308)
			(xy 165.643782 -285.648473) (xy 165.689798 -285.631021) (xy 165.738017 -285.621177) (xy 165.787192 -285.619196)
			(xy 165.836047 -285.625128) (xy 165.883318 -285.63882) (xy 165.92778 -285.659918) (xy 165.968283 -285.687874)
			(xy 166.003776 -285.721966) (xy 166.033341 -285.76131) (xy 166.056212 -285.804887) (xy 166.071796 -285.851568)
			(xy 166.079691 -285.900145) (xy 166.080186 -285.924752) (xy 166.419288 -285.924752) (xy 166.423248 -285.875698)
			(xy 166.435025 -285.827914) (xy 166.454316 -285.782638) (xy 166.480619 -285.741042) (xy 166.513254 -285.704205)
			(xy 166.551375 -285.67308) (xy 166.593996 -285.648473) (xy 166.640012 -285.631021) (xy 166.688231 -285.621177)
			(xy 166.737406 -285.619196) (xy 166.786261 -285.625128) (xy 166.833532 -285.63882) (xy 166.877994 -285.659918)
			(xy 166.918497 -285.687874) (xy 166.95399 -285.721966) (xy 166.983555 -285.76131) (xy 167.006426 -285.804887)
			(xy 167.02201 -285.851568) (xy 167.029905 -285.900145) (xy 167.0304 -285.924752) (xy 167.369248 -285.924752)
			(xy 167.373208 -285.875698) (xy 167.384985 -285.827914) (xy 167.404276 -285.782638) (xy 167.430579 -285.741042)
			(xy 167.463214 -285.704205) (xy 167.501335 -285.67308) (xy 167.543956 -285.648473) (xy 167.589972 -285.631021)
			(xy 167.638191 -285.621177) (xy 167.687366 -285.619196) (xy 167.736221 -285.625128) (xy 167.783492 -285.63882)
			(xy 167.827954 -285.659918) (xy 167.868457 -285.687874) (xy 167.90395 -285.721966) (xy 167.933515 -285.76131)
			(xy 167.956386 -285.804887) (xy 167.97197 -285.851568) (xy 167.979865 -285.900145) (xy 167.98036 -285.924752)
			(xy 168.319208 -285.924752) (xy 168.323168 -285.875698) (xy 168.334945 -285.827914) (xy 168.354236 -285.782638)
			(xy 168.380539 -285.741042) (xy 168.413174 -285.704205) (xy 168.451295 -285.67308) (xy 168.493916 -285.648473)
			(xy 168.539932 -285.631021) (xy 168.588151 -285.621177) (xy 168.637326 -285.619196) (xy 168.686181 -285.625128)
			(xy 168.733452 -285.63882) (xy 168.777914 -285.659918) (xy 168.818417 -285.687874) (xy 168.85391 -285.721966)
			(xy 168.883475 -285.76131) (xy 168.906346 -285.804887) (xy 168.92193 -285.851568) (xy 168.929825 -285.900145)
			(xy 168.93032 -285.924752) (xy 169.269168 -285.924752) (xy 169.273128 -285.875698) (xy 169.284905 -285.827914)
			(xy 169.304196 -285.782638) (xy 169.330499 -285.741042) (xy 169.363134 -285.704205) (xy 169.401255 -285.67308)
			(xy 169.443876 -285.648473) (xy 169.489892 -285.631021) (xy 169.538111 -285.621177) (xy 169.587286 -285.619196)
			(xy 169.636141 -285.625128) (xy 169.683412 -285.63882) (xy 169.727874 -285.659918) (xy 169.768377 -285.687874)
			(xy 169.80387 -285.721966) (xy 169.833435 -285.76131) (xy 169.856306 -285.804887) (xy 169.87189 -285.851568)
			(xy 169.879785 -285.900145) (xy 169.88028 -285.924752) (xy 170.219128 -285.924752) (xy 170.223088 -285.875698)
			(xy 170.234865 -285.827914) (xy 170.254156 -285.782638) (xy 170.280459 -285.741042) (xy 170.313094 -285.704205)
			(xy 170.351215 -285.67308) (xy 170.393836 -285.648473) (xy 170.439852 -285.631021) (xy 170.488071 -285.621177)
			(xy 170.537246 -285.619196) (xy 170.586101 -285.625128) (xy 170.633372 -285.63882) (xy 170.677834 -285.659918)
			(xy 170.718337 -285.687874) (xy 170.75383 -285.721966) (xy 170.783395 -285.76131) (xy 170.806266 -285.804887)
			(xy 170.82185 -285.851568) (xy 170.829745 -285.900145) (xy 170.83024 -285.924752) (xy 171.169088 -285.924752)
			(xy 171.173048 -285.875698) (xy 171.184825 -285.827914) (xy 171.204116 -285.782638) (xy 171.230419 -285.741042)
			(xy 171.263054 -285.704205) (xy 171.301175 -285.67308) (xy 171.343796 -285.648473) (xy 171.389812 -285.631021)
			(xy 171.438031 -285.621177) (xy 171.487206 -285.619196) (xy 171.536061 -285.625128) (xy 171.583332 -285.63882)
			(xy 171.627794 -285.659918) (xy 171.668297 -285.687874) (xy 171.70379 -285.721966) (xy 171.733355 -285.76131)
			(xy 171.756226 -285.804887) (xy 171.77181 -285.851568) (xy 171.779705 -285.900145) (xy 171.7802 -285.924752)
			(xy 172.119048 -285.924752) (xy 172.123008 -285.875698) (xy 172.134785 -285.827914) (xy 172.154076 -285.782638)
			(xy 172.180379 -285.741042) (xy 172.213014 -285.704205) (xy 172.251135 -285.67308) (xy 172.293756 -285.648473)
			(xy 172.339772 -285.631021) (xy 172.387991 -285.621177) (xy 172.437166 -285.619196) (xy 172.486021 -285.625128)
			(xy 172.533292 -285.63882) (xy 172.577754 -285.659918) (xy 172.618257 -285.687874) (xy 172.65375 -285.721966)
			(xy 172.683315 -285.76131) (xy 172.706186 -285.804887) (xy 172.72177 -285.851568) (xy 172.729665 -285.900145)
			(xy 172.73016 -285.924752) (xy 173.069262 -285.924752) (xy 173.073222 -285.875698) (xy 173.084999 -285.827914)
			(xy 173.10429 -285.782638) (xy 173.130593 -285.741042) (xy 173.163228 -285.704205) (xy 173.201349 -285.67308)
			(xy 173.24397 -285.648473) (xy 173.289986 -285.631021) (xy 173.338205 -285.621177) (xy 173.38738 -285.619196)
			(xy 173.436235 -285.625128) (xy 173.483506 -285.63882) (xy 173.527968 -285.659918) (xy 173.568471 -285.687874)
			(xy 173.603964 -285.721966) (xy 173.633529 -285.76131) (xy 173.6564 -285.804887) (xy 173.671984 -285.851568)
			(xy 173.679879 -285.900145) (xy 173.680374 -285.924752) (xy 174.019222 -285.924752) (xy 174.023182 -285.875698)
			(xy 174.034959 -285.827914) (xy 174.05425 -285.782638) (xy 174.080553 -285.741042) (xy 174.113188 -285.704205)
			(xy 174.151309 -285.67308) (xy 174.19393 -285.648473) (xy 174.239946 -285.631021) (xy 174.288165 -285.621177)
			(xy 174.33734 -285.619196) (xy 174.386195 -285.625128) (xy 174.433466 -285.63882) (xy 174.477928 -285.659918)
			(xy 174.518431 -285.687874) (xy 174.553924 -285.721966) (xy 174.583489 -285.76131) (xy 174.60636 -285.804887)
			(xy 174.621944 -285.851568) (xy 174.629839 -285.900145) (xy 174.630334 -285.924752) (xy 175.919142 -285.924752)
			(xy 175.923102 -285.875698) (xy 175.934879 -285.827914) (xy 175.95417 -285.782638) (xy 175.980473 -285.741042)
			(xy 176.013108 -285.704205) (xy 176.051229 -285.67308) (xy 176.09385 -285.648473) (xy 176.139866 -285.631021)
			(xy 176.188085 -285.621177) (xy 176.23726 -285.619196) (xy 176.286115 -285.625128) (xy 176.333386 -285.63882)
			(xy 176.377848 -285.659918) (xy 176.418351 -285.687874) (xy 176.453844 -285.721966) (xy 176.483409 -285.76131)
			(xy 176.50628 -285.804887) (xy 176.521864 -285.851568) (xy 176.529759 -285.900145) (xy 176.530254 -285.924752)
			(xy 176.869102 -285.924752) (xy 176.873062 -285.875698) (xy 176.884839 -285.827914) (xy 176.90413 -285.782638)
			(xy 176.930433 -285.741042) (xy 176.963068 -285.704205) (xy 177.001189 -285.67308) (xy 177.04381 -285.648473)
			(xy 177.089826 -285.631021) (xy 177.138045 -285.621177) (xy 177.18722 -285.619196) (xy 177.236075 -285.625128)
			(xy 177.283346 -285.63882) (xy 177.327808 -285.659918) (xy 177.368311 -285.687874) (xy 177.403804 -285.721966)
			(xy 177.433369 -285.76131) (xy 177.45624 -285.804887) (xy 177.471824 -285.851568) (xy 177.479719 -285.900145)
			(xy 177.480214 -285.924752) (xy 177.819062 -285.924752) (xy 177.823022 -285.875698) (xy 177.834799 -285.827914)
			(xy 177.85409 -285.782638) (xy 177.880393 -285.741042) (xy 177.913028 -285.704205) (xy 177.951149 -285.67308)
			(xy 177.99377 -285.648473) (xy 178.039786 -285.631021) (xy 178.088005 -285.621177) (xy 178.13718 -285.619196)
			(xy 178.186035 -285.625128) (xy 178.233306 -285.63882) (xy 178.277768 -285.659918) (xy 178.318271 -285.687874)
			(xy 178.353764 -285.721966) (xy 178.383329 -285.76131) (xy 178.4062 -285.804887) (xy 178.421784 -285.851568)
			(xy 178.429679 -285.900145) (xy 178.430174 -285.924752) (xy 178.769276 -285.924752) (xy 178.773236 -285.875698)
			(xy 178.785013 -285.827914) (xy 178.804304 -285.782638) (xy 178.830607 -285.741042) (xy 178.863242 -285.704205)
			(xy 178.901363 -285.67308) (xy 178.943984 -285.648473) (xy 178.99 -285.631021) (xy 179.038219 -285.621177)
			(xy 179.087394 -285.619196) (xy 179.136249 -285.625128) (xy 179.18352 -285.63882) (xy 179.227982 -285.659918)
			(xy 179.268485 -285.687874) (xy 179.303978 -285.721966) (xy 179.333543 -285.76131) (xy 179.356414 -285.804887)
			(xy 179.371998 -285.851568) (xy 179.379893 -285.900145) (xy 179.380388 -285.924752) (xy 179.719236 -285.924752)
			(xy 179.723196 -285.875698) (xy 179.734973 -285.827914) (xy 179.754264 -285.782638) (xy 179.780567 -285.741042)
			(xy 179.813202 -285.704205) (xy 179.851323 -285.67308) (xy 179.893944 -285.648473) (xy 179.93996 -285.631021)
			(xy 179.988179 -285.621177) (xy 180.037354 -285.619196) (xy 180.086209 -285.625128) (xy 180.13348 -285.63882)
			(xy 180.177942 -285.659918) (xy 180.218445 -285.687874) (xy 180.253938 -285.721966) (xy 180.283503 -285.76131)
			(xy 180.306374 -285.804887) (xy 180.321958 -285.851568) (xy 180.329853 -285.900145) (xy 180.330348 -285.924752)
			(xy 180.669196 -285.924752) (xy 180.673156 -285.875698) (xy 180.684933 -285.827914) (xy 180.704224 -285.782638)
			(xy 180.730527 -285.741042) (xy 180.763162 -285.704205) (xy 180.801283 -285.67308) (xy 180.843904 -285.648473)
			(xy 180.88992 -285.631021) (xy 180.938139 -285.621177) (xy 180.987314 -285.619196) (xy 181.036169 -285.625128)
			(xy 181.08344 -285.63882) (xy 181.127902 -285.659918) (xy 181.168405 -285.687874) (xy 181.203898 -285.721966)
			(xy 181.233463 -285.76131) (xy 181.256334 -285.804887) (xy 181.271918 -285.851568) (xy 181.279813 -285.900145)
			(xy 181.280308 -285.924752) (xy 181.619156 -285.924752) (xy 181.623116 -285.875698) (xy 181.634893 -285.827914)
			(xy 181.654184 -285.782638) (xy 181.680487 -285.741042) (xy 181.713122 -285.704205) (xy 181.751243 -285.67308)
			(xy 181.793864 -285.648473) (xy 181.83988 -285.631021) (xy 181.888099 -285.621177) (xy 181.937274 -285.619196)
			(xy 181.986129 -285.625128) (xy 182.0334 -285.63882) (xy 182.077862 -285.659918) (xy 182.118365 -285.687874)
			(xy 182.153858 -285.721966) (xy 182.183423 -285.76131) (xy 182.206294 -285.804887) (xy 182.221878 -285.851568)
			(xy 182.229773 -285.900145) (xy 182.230268 -285.924752) (xy 182.569116 -285.924752) (xy 182.573076 -285.875698)
			(xy 182.584853 -285.827914) (xy 182.604144 -285.782638) (xy 182.630447 -285.741042) (xy 182.663082 -285.704205)
			(xy 182.701203 -285.67308) (xy 182.743824 -285.648473) (xy 182.78984 -285.631021) (xy 182.838059 -285.621177)
			(xy 182.887234 -285.619196) (xy 182.936089 -285.625128) (xy 182.98336 -285.63882) (xy 183.027822 -285.659918)
			(xy 183.068325 -285.687874) (xy 183.103818 -285.721966) (xy 183.133383 -285.76131) (xy 183.156254 -285.804887)
			(xy 183.171838 -285.851568) (xy 183.179733 -285.900145) (xy 183.180228 -285.924752) (xy 183.519076 -285.924752)
			(xy 183.523036 -285.875698) (xy 183.534813 -285.827914) (xy 183.554104 -285.782638) (xy 183.580407 -285.741042)
			(xy 183.613042 -285.704205) (xy 183.651163 -285.67308) (xy 183.693784 -285.648473) (xy 183.7398 -285.631021)
			(xy 183.788019 -285.621177) (xy 183.837194 -285.619196) (xy 183.886049 -285.625128) (xy 183.93332 -285.63882)
			(xy 183.977782 -285.659918) (xy 184.018285 -285.687874) (xy 184.053778 -285.721966) (xy 184.083343 -285.76131)
			(xy 184.106214 -285.804887) (xy 184.121798 -285.851568) (xy 184.129693 -285.900145) (xy 184.130188 -285.924752)
			(xy 184.469036 -285.924752) (xy 184.472996 -285.875698) (xy 184.484773 -285.827914) (xy 184.504064 -285.782638)
			(xy 184.530367 -285.741042) (xy 184.563002 -285.704205) (xy 184.601123 -285.67308) (xy 184.643744 -285.648473)
			(xy 184.68976 -285.631021) (xy 184.737979 -285.621177) (xy 184.787154 -285.619196) (xy 184.836009 -285.625128)
			(xy 184.88328 -285.63882) (xy 184.927742 -285.659918) (xy 184.968245 -285.687874) (xy 185.003738 -285.721966)
			(xy 185.033303 -285.76131) (xy 185.056174 -285.804887) (xy 185.071758 -285.851568) (xy 185.079653 -285.900145)
			(xy 185.080148 -285.924752) (xy 185.079653 -285.949359) (xy 185.071758 -285.997936) (xy 185.056174 -286.044617)
			(xy 185.033303 -286.088194) (xy 185.003738 -286.127538) (xy 184.968245 -286.16163) (xy 184.927742 -286.189586)
			(xy 184.88328 -286.210684) (xy 184.836009 -286.224376) (xy 184.787154 -286.230308) (xy 184.737979 -286.228327)
			(xy 184.68976 -286.218483) (xy 184.643744 -286.201031) (xy 184.601123 -286.176424) (xy 184.563002 -286.145299)
			(xy 184.530367 -286.108462) (xy 184.504064 -286.066866) (xy 184.484773 -286.02159) (xy 184.472996 -285.973806)
			(xy 184.469036 -285.924752) (xy 184.130188 -285.924752) (xy 184.129693 -285.949359) (xy 184.121798 -285.997936)
			(xy 184.106214 -286.044617) (xy 184.083343 -286.088194) (xy 184.053778 -286.127538) (xy 184.018285 -286.16163)
			(xy 183.977782 -286.189586) (xy 183.93332 -286.210684) (xy 183.886049 -286.224376) (xy 183.837194 -286.230308)
			(xy 183.788019 -286.228327) (xy 183.7398 -286.218483) (xy 183.693784 -286.201031) (xy 183.651163 -286.176424)
			(xy 183.613042 -286.145299) (xy 183.580407 -286.108462) (xy 183.554104 -286.066866) (xy 183.534813 -286.02159)
			(xy 183.523036 -285.973806) (xy 183.519076 -285.924752) (xy 183.180228 -285.924752) (xy 183.179733 -285.949359)
			(xy 183.171838 -285.997936) (xy 183.156254 -286.044617) (xy 183.133383 -286.088194) (xy 183.103818 -286.127538)
			(xy 183.068325 -286.16163) (xy 183.027822 -286.189586) (xy 182.98336 -286.210684) (xy 182.936089 -286.224376)
			(xy 182.887234 -286.230308) (xy 182.838059 -286.228327) (xy 182.78984 -286.218483) (xy 182.743824 -286.201031)
			(xy 182.701203 -286.176424) (xy 182.663082 -286.145299) (xy 182.630447 -286.108462) (xy 182.604144 -286.066866)
			(xy 182.584853 -286.02159) (xy 182.573076 -285.973806) (xy 182.569116 -285.924752) (xy 182.230268 -285.924752)
			(xy 182.229773 -285.949359) (xy 182.221878 -285.997936) (xy 182.206294 -286.044617) (xy 182.183423 -286.088194)
			(xy 182.153858 -286.127538) (xy 182.118365 -286.16163) (xy 182.077862 -286.189586) (xy 182.0334 -286.210684)
			(xy 181.986129 -286.224376) (xy 181.937274 -286.230308) (xy 181.888099 -286.228327) (xy 181.83988 -286.218483)
			(xy 181.793864 -286.201031) (xy 181.751243 -286.176424) (xy 181.713122 -286.145299) (xy 181.680487 -286.108462)
			(xy 181.654184 -286.066866) (xy 181.634893 -286.02159) (xy 181.623116 -285.973806) (xy 181.619156 -285.924752)
			(xy 181.280308 -285.924752) (xy 181.279813 -285.949359) (xy 181.271918 -285.997936) (xy 181.256334 -286.044617)
			(xy 181.233463 -286.088194) (xy 181.203898 -286.127538) (xy 181.168405 -286.16163) (xy 181.127902 -286.189586)
			(xy 181.08344 -286.210684) (xy 181.036169 -286.224376) (xy 180.987314 -286.230308) (xy 180.938139 -286.228327)
			(xy 180.88992 -286.218483) (xy 180.843904 -286.201031) (xy 180.801283 -286.176424) (xy 180.763162 -286.145299)
			(xy 180.730527 -286.108462) (xy 180.704224 -286.066866) (xy 180.684933 -286.02159) (xy 180.673156 -285.973806)
			(xy 180.669196 -285.924752) (xy 180.330348 -285.924752) (xy 180.329853 -285.949359) (xy 180.321958 -285.997936)
			(xy 180.306374 -286.044617) (xy 180.283503 -286.088194) (xy 180.253938 -286.127538) (xy 180.218445 -286.16163)
			(xy 180.177942 -286.189586) (xy 180.13348 -286.210684) (xy 180.086209 -286.224376) (xy 180.037354 -286.230308)
			(xy 179.988179 -286.228327) (xy 179.93996 -286.218483) (xy 179.893944 -286.201031) (xy 179.851323 -286.176424)
			(xy 179.813202 -286.145299) (xy 179.780567 -286.108462) (xy 179.754264 -286.066866) (xy 179.734973 -286.02159)
			(xy 179.723196 -285.973806) (xy 179.719236 -285.924752) (xy 179.380388 -285.924752) (xy 179.379893 -285.949359)
			(xy 179.371998 -285.997936) (xy 179.356414 -286.044617) (xy 179.333543 -286.088194) (xy 179.303978 -286.127538)
			(xy 179.268485 -286.16163) (xy 179.227982 -286.189586) (xy 179.18352 -286.210684) (xy 179.136249 -286.224376)
			(xy 179.087394 -286.230308) (xy 179.038219 -286.228327) (xy 178.99 -286.218483) (xy 178.943984 -286.201031)
			(xy 178.901363 -286.176424) (xy 178.863242 -286.145299) (xy 178.830607 -286.108462) (xy 178.804304 -286.066866)
			(xy 178.785013 -286.02159) (xy 178.773236 -285.973806) (xy 178.769276 -285.924752) (xy 178.430174 -285.924752)
			(xy 178.429679 -285.949359) (xy 178.421784 -285.997936) (xy 178.4062 -286.044617) (xy 178.383329 -286.088194)
			(xy 178.353764 -286.127538) (xy 178.318271 -286.16163) (xy 178.277768 -286.189586) (xy 178.233306 -286.210684)
			(xy 178.186035 -286.224376) (xy 178.13718 -286.230308) (xy 178.088005 -286.228327) (xy 178.039786 -286.218483)
			(xy 177.99377 -286.201031) (xy 177.951149 -286.176424) (xy 177.913028 -286.145299) (xy 177.880393 -286.108462)
			(xy 177.85409 -286.066866) (xy 177.834799 -286.02159) (xy 177.823022 -285.973806) (xy 177.819062 -285.924752)
			(xy 177.480214 -285.924752) (xy 177.479719 -285.949359) (xy 177.471824 -285.997936) (xy 177.45624 -286.044617)
			(xy 177.433369 -286.088194) (xy 177.403804 -286.127538) (xy 177.368311 -286.16163) (xy 177.327808 -286.189586)
			(xy 177.283346 -286.210684) (xy 177.236075 -286.224376) (xy 177.18722 -286.230308) (xy 177.138045 -286.228327)
			(xy 177.089826 -286.218483) (xy 177.04381 -286.201031) (xy 177.001189 -286.176424) (xy 176.963068 -286.145299)
			(xy 176.930433 -286.108462) (xy 176.90413 -286.066866) (xy 176.884839 -286.02159) (xy 176.873062 -285.973806)
			(xy 176.869102 -285.924752) (xy 176.530254 -285.924752) (xy 176.529759 -285.949359) (xy 176.521864 -285.997936)
			(xy 176.50628 -286.044617) (xy 176.483409 -286.088194) (xy 176.453844 -286.127538) (xy 176.418351 -286.16163)
			(xy 176.377848 -286.189586) (xy 176.333386 -286.210684) (xy 176.286115 -286.224376) (xy 176.23726 -286.230308)
			(xy 176.188085 -286.228327) (xy 176.139866 -286.218483) (xy 176.09385 -286.201031) (xy 176.051229 -286.176424)
			(xy 176.013108 -286.145299) (xy 175.980473 -286.108462) (xy 175.95417 -286.066866) (xy 175.934879 -286.02159)
			(xy 175.923102 -285.973806) (xy 175.919142 -285.924752) (xy 174.630334 -285.924752) (xy 174.629839 -285.949359)
			(xy 174.621944 -285.997936) (xy 174.60636 -286.044617) (xy 174.583489 -286.088194) (xy 174.553924 -286.127538)
			(xy 174.518431 -286.16163) (xy 174.477928 -286.189586) (xy 174.433466 -286.210684) (xy 174.386195 -286.224376)
			(xy 174.33734 -286.230308) (xy 174.288165 -286.228327) (xy 174.239946 -286.218483) (xy 174.19393 -286.201031)
			(xy 174.151309 -286.176424) (xy 174.113188 -286.145299) (xy 174.080553 -286.108462) (xy 174.05425 -286.066866)
			(xy 174.034959 -286.02159) (xy 174.023182 -285.973806) (xy 174.019222 -285.924752) (xy 173.680374 -285.924752)
			(xy 173.679879 -285.949359) (xy 173.671984 -285.997936) (xy 173.6564 -286.044617) (xy 173.633529 -286.088194)
			(xy 173.603964 -286.127538) (xy 173.568471 -286.16163) (xy 173.527968 -286.189586) (xy 173.483506 -286.210684)
			(xy 173.436235 -286.224376) (xy 173.38738 -286.230308) (xy 173.338205 -286.228327) (xy 173.289986 -286.218483)
			(xy 173.24397 -286.201031) (xy 173.201349 -286.176424) (xy 173.163228 -286.145299) (xy 173.130593 -286.108462)
			(xy 173.10429 -286.066866) (xy 173.084999 -286.02159) (xy 173.073222 -285.973806) (xy 173.069262 -285.924752)
			(xy 172.73016 -285.924752) (xy 172.729665 -285.949359) (xy 172.72177 -285.997936) (xy 172.706186 -286.044617)
			(xy 172.683315 -286.088194) (xy 172.65375 -286.127538) (xy 172.618257 -286.16163) (xy 172.577754 -286.189586)
			(xy 172.533292 -286.210684) (xy 172.486021 -286.224376) (xy 172.437166 -286.230308) (xy 172.387991 -286.228327)
			(xy 172.339772 -286.218483) (xy 172.293756 -286.201031) (xy 172.251135 -286.176424) (xy 172.213014 -286.145299)
			(xy 172.180379 -286.108462) (xy 172.154076 -286.066866) (xy 172.134785 -286.02159) (xy 172.123008 -285.973806)
			(xy 172.119048 -285.924752) (xy 171.7802 -285.924752) (xy 171.779705 -285.949359) (xy 171.77181 -285.997936)
			(xy 171.756226 -286.044617) (xy 171.733355 -286.088194) (xy 171.70379 -286.127538) (xy 171.668297 -286.16163)
			(xy 171.627794 -286.189586) (xy 171.583332 -286.210684) (xy 171.536061 -286.224376) (xy 171.487206 -286.230308)
			(xy 171.438031 -286.228327) (xy 171.389812 -286.218483) (xy 171.343796 -286.201031) (xy 171.301175 -286.176424)
			(xy 171.263054 -286.145299) (xy 171.230419 -286.108462) (xy 171.204116 -286.066866) (xy 171.184825 -286.02159)
			(xy 171.173048 -285.973806) (xy 171.169088 -285.924752) (xy 170.83024 -285.924752) (xy 170.829745 -285.949359)
			(xy 170.82185 -285.997936) (xy 170.806266 -286.044617) (xy 170.783395 -286.088194) (xy 170.75383 -286.127538)
			(xy 170.718337 -286.16163) (xy 170.677834 -286.189586) (xy 170.633372 -286.210684) (xy 170.586101 -286.224376)
			(xy 170.537246 -286.230308) (xy 170.488071 -286.228327) (xy 170.439852 -286.218483) (xy 170.393836 -286.201031)
			(xy 170.351215 -286.176424) (xy 170.313094 -286.145299) (xy 170.280459 -286.108462) (xy 170.254156 -286.066866)
			(xy 170.234865 -286.02159) (xy 170.223088 -285.973806) (xy 170.219128 -285.924752) (xy 169.88028 -285.924752)
			(xy 169.879785 -285.949359) (xy 169.87189 -285.997936) (xy 169.856306 -286.044617) (xy 169.833435 -286.088194)
			(xy 169.80387 -286.127538) (xy 169.768377 -286.16163) (xy 169.727874 -286.189586) (xy 169.683412 -286.210684)
			(xy 169.636141 -286.224376) (xy 169.587286 -286.230308) (xy 169.538111 -286.228327) (xy 169.489892 -286.218483)
			(xy 169.443876 -286.201031) (xy 169.401255 -286.176424) (xy 169.363134 -286.145299) (xy 169.330499 -286.108462)
			(xy 169.304196 -286.066866) (xy 169.284905 -286.02159) (xy 169.273128 -285.973806) (xy 169.269168 -285.924752)
			(xy 168.93032 -285.924752) (xy 168.929825 -285.949359) (xy 168.92193 -285.997936) (xy 168.906346 -286.044617)
			(xy 168.883475 -286.088194) (xy 168.85391 -286.127538) (xy 168.818417 -286.16163) (xy 168.777914 -286.189586)
			(xy 168.733452 -286.210684) (xy 168.686181 -286.224376) (xy 168.637326 -286.230308) (xy 168.588151 -286.228327)
			(xy 168.539932 -286.218483) (xy 168.493916 -286.201031) (xy 168.451295 -286.176424) (xy 168.413174 -286.145299)
			(xy 168.380539 -286.108462) (xy 168.354236 -286.066866) (xy 168.334945 -286.02159) (xy 168.323168 -285.973806)
			(xy 168.319208 -285.924752) (xy 167.98036 -285.924752) (xy 167.979865 -285.949359) (xy 167.97197 -285.997936)
			(xy 167.956386 -286.044617) (xy 167.933515 -286.088194) (xy 167.90395 -286.127538) (xy 167.868457 -286.16163)
			(xy 167.827954 -286.189586) (xy 167.783492 -286.210684) (xy 167.736221 -286.224376) (xy 167.687366 -286.230308)
			(xy 167.638191 -286.228327) (xy 167.589972 -286.218483) (xy 167.543956 -286.201031) (xy 167.501335 -286.176424)
			(xy 167.463214 -286.145299) (xy 167.430579 -286.108462) (xy 167.404276 -286.066866) (xy 167.384985 -286.02159)
			(xy 167.373208 -285.973806) (xy 167.369248 -285.924752) (xy 167.0304 -285.924752) (xy 167.029905 -285.949359)
			(xy 167.02201 -285.997936) (xy 167.006426 -286.044617) (xy 166.983555 -286.088194) (xy 166.95399 -286.127538)
			(xy 166.918497 -286.16163) (xy 166.877994 -286.189586) (xy 166.833532 -286.210684) (xy 166.786261 -286.224376)
			(xy 166.737406 -286.230308) (xy 166.688231 -286.228327) (xy 166.640012 -286.218483) (xy 166.593996 -286.201031)
			(xy 166.551375 -286.176424) (xy 166.513254 -286.145299) (xy 166.480619 -286.108462) (xy 166.454316 -286.066866)
			(xy 166.435025 -286.02159) (xy 166.423248 -285.973806) (xy 166.419288 -285.924752) (xy 166.080186 -285.924752)
			(xy 166.079691 -285.949359) (xy 166.071796 -285.997936) (xy 166.056212 -286.044617) (xy 166.033341 -286.088194)
			(xy 166.003776 -286.127538) (xy 165.968283 -286.16163) (xy 165.92778 -286.189586) (xy 165.883318 -286.210684)
			(xy 165.836047 -286.224376) (xy 165.787192 -286.230308) (xy 165.738017 -286.228327) (xy 165.689798 -286.218483)
			(xy 165.643782 -286.201031) (xy 165.601161 -286.176424) (xy 165.56304 -286.145299) (xy 165.530405 -286.108462)
			(xy 165.504102 -286.066866) (xy 165.484811 -286.02159) (xy 165.473034 -285.973806) (xy 165.469074 -285.924752)
			(xy 165.130226 -285.924752) (xy 165.129731 -285.949359) (xy 165.121836 -285.997936) (xy 165.106252 -286.044617)
			(xy 165.083381 -286.088194) (xy 165.053816 -286.127538) (xy 165.018323 -286.16163) (xy 164.97782 -286.189586)
			(xy 164.933358 -286.210684) (xy 164.886087 -286.224376) (xy 164.837232 -286.230308) (xy 164.788057 -286.228327)
			(xy 164.739838 -286.218483) (xy 164.693822 -286.201031) (xy 164.651201 -286.176424) (xy 164.61308 -286.145299)
			(xy 164.580445 -286.108462) (xy 164.554142 -286.066866) (xy 164.534851 -286.02159) (xy 164.523074 -285.973806)
			(xy 164.519114 -285.924752) (xy 164.180266 -285.924752) (xy 164.179771 -285.949359) (xy 164.171876 -285.997936)
			(xy 164.156292 -286.044617) (xy 164.133421 -286.088194) (xy 164.103856 -286.127538) (xy 164.068363 -286.16163)
			(xy 164.02786 -286.189586) (xy 163.983398 -286.210684) (xy 163.936127 -286.224376) (xy 163.887272 -286.230308)
			(xy 163.838097 -286.228327) (xy 163.789878 -286.218483) (xy 163.743862 -286.201031) (xy 163.701241 -286.176424)
			(xy 163.66312 -286.145299) (xy 163.630485 -286.108462) (xy 163.604182 -286.066866) (xy 163.584891 -286.02159)
			(xy 163.573114 -285.973806) (xy 163.569154 -285.924752) (xy 163.230306 -285.924752) (xy 163.229811 -285.949359)
			(xy 163.221916 -285.997936) (xy 163.206332 -286.044617) (xy 163.183461 -286.088194) (xy 163.153896 -286.127538)
			(xy 163.118403 -286.16163) (xy 163.0779 -286.189586) (xy 163.033438 -286.210684) (xy 162.986167 -286.224376)
			(xy 162.937312 -286.230308) (xy 162.888137 -286.228327) (xy 162.839918 -286.218483) (xy 162.793902 -286.201031)
			(xy 162.751281 -286.176424) (xy 162.71316 -286.145299) (xy 162.680525 -286.108462) (xy 162.654222 -286.066866)
			(xy 162.634931 -286.02159) (xy 162.623154 -285.973806) (xy 162.619194 -285.924752) (xy 162.280346 -285.924752)
			(xy 162.279851 -285.949359) (xy 162.271956 -285.997936) (xy 162.256372 -286.044617) (xy 162.233501 -286.088194)
			(xy 162.203936 -286.127538) (xy 162.168443 -286.16163) (xy 162.12794 -286.189586) (xy 162.083478 -286.210684)
			(xy 162.036207 -286.224376) (xy 161.987352 -286.230308) (xy 161.938177 -286.228327) (xy 161.889958 -286.218483)
			(xy 161.843942 -286.201031) (xy 161.801321 -286.176424) (xy 161.7632 -286.145299) (xy 161.730565 -286.108462)
			(xy 161.704262 -286.066866) (xy 161.684971 -286.02159) (xy 161.673194 -285.973806) (xy 161.669234 -285.924752)
			(xy 161.330386 -285.924752) (xy 161.329891 -285.949359) (xy 161.321996 -285.997936) (xy 161.306412 -286.044617)
			(xy 161.283541 -286.088194) (xy 161.253976 -286.127538) (xy 161.218483 -286.16163) (xy 161.17798 -286.189586)
			(xy 161.133518 -286.210684) (xy 161.086247 -286.224376) (xy 161.037392 -286.230308) (xy 160.988217 -286.228327)
			(xy 160.939998 -286.218483) (xy 160.893982 -286.201031) (xy 160.851361 -286.176424) (xy 160.81324 -286.145299)
			(xy 160.780605 -286.108462) (xy 160.754302 -286.066866) (xy 160.735011 -286.02159) (xy 160.723234 -285.973806)
			(xy 160.719274 -285.924752) (xy 157.530218 -285.924752) (xy 157.53067 -285.933107) (xy 157.5253 -285.982448)
			(xy 157.512018 -286.030271) (xy 157.491174 -286.075315) (xy 157.463318 -286.116393) (xy 157.429183 -286.152424)
			(xy 157.389668 -286.182458) (xy 157.345816 -286.205704) (xy 157.29878 -286.221549) (xy 157.2498 -286.229576)
			(xy 157.224984 -286.23006) (xy 157.211448 -286.229899) (xy 157.184484 -286.227487) (xy 157.171136 -286.225234)
			(xy 157.158944 -286.223202) (xy 157.135322 -286.230568) (xy 157.126432 -286.239458) (xy 157.119722 -286.246895)
			(xy 157.112094 -286.265394) (xy 157.112093 -286.285404) (xy 157.119722 -286.303903) (xy 157.126432 -286.31134)
			(xy 157.152086 -286.336994) (xy 157.15234 -286.336994) (xy 157.16885 -286.354141) (xy 157.196919 -286.392581)
			(xy 157.218685 -286.434911) (xy 157.233621 -286.480104) (xy 157.241365 -286.527067) (xy 157.242002 -286.550862)
			(xy 157.242002 -286.551878) (xy 157.24251 -286.570166) (xy 157.267147 -286.572106) (xy 157.31538 -286.582848)
			(xy 157.361254 -286.601219) (xy 157.40357 -286.626738) (xy 157.441223 -286.658739) (xy 157.473231 -286.696387)
			(xy 157.498758 -286.738699) (xy 157.517136 -286.784569) (xy 157.527887 -286.832801) (xy 157.529784 -286.85744)
			(xy 157.549596 -286.857948) (xy 157.550104 -286.857948) (xy 157.573798 -286.858631) (xy 157.620546 -286.866464)
			(xy 157.665522 -286.881427) (xy 157.707645 -286.903162) (xy 157.745903 -286.931146) (xy 157.762956 -286.94761)
			(xy 157.762956 -286.947864) (xy 157.78353 -286.968438) (xy 157.78861 -286.973264) (xy 157.796022 -286.979948)
			(xy 157.814455 -286.987545) (xy 157.834393 -286.987545) (xy 157.852826 -286.979948) (xy 157.860238 -286.973264)
			(xy 157.869128 -286.964374) (xy 157.876494 -286.940752) (xy 157.874462 -286.92856) (xy 157.872226 -286.915274)
			(xy 157.869807 -286.888438) (xy 157.869636 -286.874966) (xy 157.870158 -286.849711) (xy 157.878471 -286.799889)
			(xy 157.894872 -286.752115) (xy 157.918913 -286.707692) (xy 157.949937 -286.667832) (xy 157.987099 -286.633622)
			(xy 158.029385 -286.605996) (xy 158.075641 -286.585706) (xy 158.124606 -286.573306) (xy 158.174944 -286.569135)
			(xy 158.225282 -286.573306) (xy 158.274247 -286.585706) (xy 158.320503 -286.605996) (xy 158.362789 -286.633622)
			(xy 158.399951 -286.667832) (xy 158.430975 -286.707692) (xy 158.455016 -286.752115) (xy 158.471417 -286.799889)
			(xy 158.47973 -286.849711) (xy 158.480247 -286.874712) (xy 158.8191 -286.874712) (xy 158.82306 -286.825658)
			(xy 158.834837 -286.777874) (xy 158.854128 -286.732598) (xy 158.880431 -286.691002) (xy 158.913066 -286.654165)
			(xy 158.951187 -286.62304) (xy 158.993808 -286.598433) (xy 159.039824 -286.580981) (xy 159.088043 -286.571137)
			(xy 159.137218 -286.569156) (xy 159.186073 -286.575088) (xy 159.233344 -286.58878) (xy 159.277806 -286.609878)
			(xy 159.318309 -286.637834) (xy 159.353802 -286.671926) (xy 159.383367 -286.71127) (xy 159.406238 -286.754847)
			(xy 159.421822 -286.801528) (xy 159.429717 -286.850105) (xy 159.430212 -286.874712) (xy 159.76906 -286.874712)
			(xy 159.77302 -286.825658) (xy 159.784797 -286.777874) (xy 159.804088 -286.732598) (xy 159.830391 -286.691002)
			(xy 159.863026 -286.654165) (xy 159.901147 -286.62304) (xy 159.943768 -286.598433) (xy 159.989784 -286.580981)
			(xy 160.038003 -286.571137) (xy 160.087178 -286.569156) (xy 160.136033 -286.575088) (xy 160.183304 -286.58878)
			(xy 160.227766 -286.609878) (xy 160.268269 -286.637834) (xy 160.303762 -286.671926) (xy 160.333327 -286.71127)
			(xy 160.356198 -286.754847) (xy 160.371782 -286.801528) (xy 160.379677 -286.850105) (xy 160.380172 -286.874712)
			(xy 160.380167 -286.874966) (xy 160.719274 -286.874966) (xy 160.723234 -286.825912) (xy 160.735011 -286.778128)
			(xy 160.754302 -286.732852) (xy 160.780605 -286.691256) (xy 160.81324 -286.654419) (xy 160.851361 -286.623294)
			(xy 160.893982 -286.598687) (xy 160.939998 -286.581235) (xy 160.988217 -286.571391) (xy 161.037392 -286.56941)
			(xy 161.086247 -286.575342) (xy 161.133518 -286.589034) (xy 161.17798 -286.610132) (xy 161.218483 -286.638088)
			(xy 161.253976 -286.67218) (xy 161.283541 -286.711524) (xy 161.306412 -286.755101) (xy 161.321996 -286.801782)
			(xy 161.329891 -286.850359) (xy 161.330386 -286.874966) (xy 161.669234 -286.874966) (xy 161.673194 -286.825912)
			(xy 161.684971 -286.778128) (xy 161.704262 -286.732852) (xy 161.730565 -286.691256) (xy 161.7632 -286.654419)
			(xy 161.801321 -286.623294) (xy 161.843942 -286.598687) (xy 161.889958 -286.581235) (xy 161.938177 -286.571391)
			(xy 161.987352 -286.56941) (xy 162.036207 -286.575342) (xy 162.083478 -286.589034) (xy 162.12794 -286.610132)
			(xy 162.168443 -286.638088) (xy 162.203936 -286.67218) (xy 162.233501 -286.711524) (xy 162.256372 -286.755101)
			(xy 162.271956 -286.801782) (xy 162.279851 -286.850359) (xy 162.280346 -286.874966) (xy 162.619194 -286.874966)
			(xy 162.623154 -286.825912) (xy 162.634931 -286.778128) (xy 162.654222 -286.732852) (xy 162.680525 -286.691256)
			(xy 162.71316 -286.654419) (xy 162.751281 -286.623294) (xy 162.793902 -286.598687) (xy 162.839918 -286.581235)
			(xy 162.888137 -286.571391) (xy 162.937312 -286.56941) (xy 162.986167 -286.575342) (xy 163.033438 -286.589034)
			(xy 163.0779 -286.610132) (xy 163.118403 -286.638088) (xy 163.153896 -286.67218) (xy 163.183461 -286.711524)
			(xy 163.206332 -286.755101) (xy 163.221916 -286.801782) (xy 163.229811 -286.850359) (xy 163.230306 -286.874966)
			(xy 163.569154 -286.874966) (xy 163.573114 -286.825912) (xy 163.584891 -286.778128) (xy 163.604182 -286.732852)
			(xy 163.630485 -286.691256) (xy 163.66312 -286.654419) (xy 163.701241 -286.623294) (xy 163.743862 -286.598687)
			(xy 163.789878 -286.581235) (xy 163.838097 -286.571391) (xy 163.887272 -286.56941) (xy 163.936127 -286.575342)
			(xy 163.983398 -286.589034) (xy 164.02786 -286.610132) (xy 164.068363 -286.638088) (xy 164.103856 -286.67218)
			(xy 164.133421 -286.711524) (xy 164.156292 -286.755101) (xy 164.171876 -286.801782) (xy 164.179771 -286.850359)
			(xy 164.180266 -286.874966) (xy 164.519114 -286.874966) (xy 164.523074 -286.825912) (xy 164.534851 -286.778128)
			(xy 164.554142 -286.732852) (xy 164.580445 -286.691256) (xy 164.61308 -286.654419) (xy 164.651201 -286.623294)
			(xy 164.693822 -286.598687) (xy 164.739838 -286.581235) (xy 164.788057 -286.571391) (xy 164.837232 -286.56941)
			(xy 164.886087 -286.575342) (xy 164.933358 -286.589034) (xy 164.97782 -286.610132) (xy 165.018323 -286.638088)
			(xy 165.053816 -286.67218) (xy 165.083381 -286.711524) (xy 165.106252 -286.755101) (xy 165.121836 -286.801782)
			(xy 165.129731 -286.850359) (xy 165.130226 -286.874966) (xy 165.469074 -286.874966) (xy 165.473034 -286.825912)
			(xy 165.484811 -286.778128) (xy 165.504102 -286.732852) (xy 165.530405 -286.691256) (xy 165.56304 -286.654419)
			(xy 165.601161 -286.623294) (xy 165.643782 -286.598687) (xy 165.689798 -286.581235) (xy 165.738017 -286.571391)
			(xy 165.787192 -286.56941) (xy 165.836047 -286.575342) (xy 165.883318 -286.589034) (xy 165.92778 -286.610132)
			(xy 165.968283 -286.638088) (xy 166.003776 -286.67218) (xy 166.033341 -286.711524) (xy 166.056212 -286.755101)
			(xy 166.071796 -286.801782) (xy 166.079691 -286.850359) (xy 166.080186 -286.874966) (xy 166.419288 -286.874966)
			(xy 166.423248 -286.825912) (xy 166.435025 -286.778128) (xy 166.454316 -286.732852) (xy 166.480619 -286.691256)
			(xy 166.513254 -286.654419) (xy 166.551375 -286.623294) (xy 166.593996 -286.598687) (xy 166.640012 -286.581235)
			(xy 166.688231 -286.571391) (xy 166.737406 -286.56941) (xy 166.786261 -286.575342) (xy 166.833532 -286.589034)
			(xy 166.877994 -286.610132) (xy 166.918497 -286.638088) (xy 166.95399 -286.67218) (xy 166.983555 -286.711524)
			(xy 167.006426 -286.755101) (xy 167.02201 -286.801782) (xy 167.029905 -286.850359) (xy 167.0304 -286.874966)
			(xy 167.369248 -286.874966) (xy 167.373208 -286.825912) (xy 167.384985 -286.778128) (xy 167.404276 -286.732852)
			(xy 167.430579 -286.691256) (xy 167.463214 -286.654419) (xy 167.501335 -286.623294) (xy 167.543956 -286.598687)
			(xy 167.589972 -286.581235) (xy 167.638191 -286.571391) (xy 167.687366 -286.56941) (xy 167.736221 -286.575342)
			(xy 167.783492 -286.589034) (xy 167.827954 -286.610132) (xy 167.868457 -286.638088) (xy 167.90395 -286.67218)
			(xy 167.933515 -286.711524) (xy 167.956386 -286.755101) (xy 167.97197 -286.801782) (xy 167.979865 -286.850359)
			(xy 167.98036 -286.874966) (xy 168.319208 -286.874966) (xy 168.323168 -286.825912) (xy 168.334945 -286.778128)
			(xy 168.354236 -286.732852) (xy 168.380539 -286.691256) (xy 168.413174 -286.654419) (xy 168.451295 -286.623294)
			(xy 168.493916 -286.598687) (xy 168.539932 -286.581235) (xy 168.588151 -286.571391) (xy 168.637326 -286.56941)
			(xy 168.686181 -286.575342) (xy 168.733452 -286.589034) (xy 168.777914 -286.610132) (xy 168.818417 -286.638088)
			(xy 168.85391 -286.67218) (xy 168.883475 -286.711524) (xy 168.906346 -286.755101) (xy 168.92193 -286.801782)
			(xy 168.929825 -286.850359) (xy 168.93032 -286.874966) (xy 169.269168 -286.874966) (xy 169.273128 -286.825912)
			(xy 169.284905 -286.778128) (xy 169.304196 -286.732852) (xy 169.330499 -286.691256) (xy 169.363134 -286.654419)
			(xy 169.401255 -286.623294) (xy 169.443876 -286.598687) (xy 169.489892 -286.581235) (xy 169.538111 -286.571391)
			(xy 169.587286 -286.56941) (xy 169.636141 -286.575342) (xy 169.683412 -286.589034) (xy 169.727874 -286.610132)
			(xy 169.768377 -286.638088) (xy 169.80387 -286.67218) (xy 169.833435 -286.711524) (xy 169.856306 -286.755101)
			(xy 169.87189 -286.801782) (xy 169.879785 -286.850359) (xy 169.88028 -286.874966) (xy 170.219128 -286.874966)
			(xy 170.223088 -286.825912) (xy 170.234865 -286.778128) (xy 170.254156 -286.732852) (xy 170.280459 -286.691256)
			(xy 170.313094 -286.654419) (xy 170.351215 -286.623294) (xy 170.393836 -286.598687) (xy 170.439852 -286.581235)
			(xy 170.488071 -286.571391) (xy 170.537246 -286.56941) (xy 170.586101 -286.575342) (xy 170.633372 -286.589034)
			(xy 170.677834 -286.610132) (xy 170.718337 -286.638088) (xy 170.75383 -286.67218) (xy 170.783395 -286.711524)
			(xy 170.806266 -286.755101) (xy 170.82185 -286.801782) (xy 170.829745 -286.850359) (xy 170.83024 -286.874966)
			(xy 171.169088 -286.874966) (xy 171.173048 -286.825912) (xy 171.184825 -286.778128) (xy 171.204116 -286.732852)
			(xy 171.230419 -286.691256) (xy 171.263054 -286.654419) (xy 171.301175 -286.623294) (xy 171.343796 -286.598687)
			(xy 171.389812 -286.581235) (xy 171.438031 -286.571391) (xy 171.487206 -286.56941) (xy 171.536061 -286.575342)
			(xy 171.583332 -286.589034) (xy 171.627794 -286.610132) (xy 171.668297 -286.638088) (xy 171.70379 -286.67218)
			(xy 171.733355 -286.711524) (xy 171.756226 -286.755101) (xy 171.77181 -286.801782) (xy 171.779705 -286.850359)
			(xy 171.7802 -286.874966) (xy 172.119048 -286.874966) (xy 172.123008 -286.825912) (xy 172.134785 -286.778128)
			(xy 172.154076 -286.732852) (xy 172.180379 -286.691256) (xy 172.213014 -286.654419) (xy 172.251135 -286.623294)
			(xy 172.293756 -286.598687) (xy 172.339772 -286.581235) (xy 172.387991 -286.571391) (xy 172.437166 -286.56941)
			(xy 172.486021 -286.575342) (xy 172.533292 -286.589034) (xy 172.577754 -286.610132) (xy 172.618257 -286.638088)
			(xy 172.65375 -286.67218) (xy 172.683315 -286.711524) (xy 172.706186 -286.755101) (xy 172.72177 -286.801782)
			(xy 172.729665 -286.850359) (xy 172.73016 -286.874966) (xy 173.069262 -286.874966) (xy 173.073222 -286.825912)
			(xy 173.084999 -286.778128) (xy 173.10429 -286.732852) (xy 173.130593 -286.691256) (xy 173.163228 -286.654419)
			(xy 173.201349 -286.623294) (xy 173.24397 -286.598687) (xy 173.289986 -286.581235) (xy 173.338205 -286.571391)
			(xy 173.38738 -286.56941) (xy 173.436235 -286.575342) (xy 173.483506 -286.589034) (xy 173.527968 -286.610132)
			(xy 173.568471 -286.638088) (xy 173.603964 -286.67218) (xy 173.633529 -286.711524) (xy 173.6564 -286.755101)
			(xy 173.671984 -286.801782) (xy 173.679879 -286.850359) (xy 173.680374 -286.874966) (xy 174.019222 -286.874966)
			(xy 174.023182 -286.825912) (xy 174.034959 -286.778128) (xy 174.05425 -286.732852) (xy 174.080553 -286.691256)
			(xy 174.113188 -286.654419) (xy 174.151309 -286.623294) (xy 174.19393 -286.598687) (xy 174.239946 -286.581235)
			(xy 174.288165 -286.571391) (xy 174.33734 -286.56941) (xy 174.386195 -286.575342) (xy 174.433466 -286.589034)
			(xy 174.477928 -286.610132) (xy 174.518431 -286.638088) (xy 174.553924 -286.67218) (xy 174.583489 -286.711524)
			(xy 174.60636 -286.755101) (xy 174.621944 -286.801782) (xy 174.629839 -286.850359) (xy 174.630334 -286.874966)
			(xy 175.919142 -286.874966) (xy 175.923102 -286.825912) (xy 175.934879 -286.778128) (xy 175.95417 -286.732852)
			(xy 175.980473 -286.691256) (xy 176.013108 -286.654419) (xy 176.051229 -286.623294) (xy 176.09385 -286.598687)
			(xy 176.139866 -286.581235) (xy 176.188085 -286.571391) (xy 176.23726 -286.56941) (xy 176.286115 -286.575342)
			(xy 176.333386 -286.589034) (xy 176.377848 -286.610132) (xy 176.418351 -286.638088) (xy 176.453844 -286.67218)
			(xy 176.483409 -286.711524) (xy 176.50628 -286.755101) (xy 176.521864 -286.801782) (xy 176.529759 -286.850359)
			(xy 176.530254 -286.874966) (xy 176.869102 -286.874966) (xy 176.873062 -286.825912) (xy 176.884839 -286.778128)
			(xy 176.90413 -286.732852) (xy 176.930433 -286.691256) (xy 176.963068 -286.654419) (xy 177.001189 -286.623294)
			(xy 177.04381 -286.598687) (xy 177.089826 -286.581235) (xy 177.138045 -286.571391) (xy 177.18722 -286.56941)
			(xy 177.236075 -286.575342) (xy 177.283346 -286.589034) (xy 177.327808 -286.610132) (xy 177.368311 -286.638088)
			(xy 177.403804 -286.67218) (xy 177.433369 -286.711524) (xy 177.45624 -286.755101) (xy 177.471824 -286.801782)
			(xy 177.479719 -286.850359) (xy 177.480214 -286.874966) (xy 177.819062 -286.874966) (xy 177.823022 -286.825912)
			(xy 177.834799 -286.778128) (xy 177.85409 -286.732852) (xy 177.880393 -286.691256) (xy 177.913028 -286.654419)
			(xy 177.951149 -286.623294) (xy 177.99377 -286.598687) (xy 178.039786 -286.581235) (xy 178.088005 -286.571391)
			(xy 178.13718 -286.56941) (xy 178.186035 -286.575342) (xy 178.233306 -286.589034) (xy 178.277768 -286.610132)
			(xy 178.318271 -286.638088) (xy 178.353764 -286.67218) (xy 178.383329 -286.711524) (xy 178.4062 -286.755101)
			(xy 178.421784 -286.801782) (xy 178.429679 -286.850359) (xy 178.430174 -286.874966) (xy 178.769276 -286.874966)
			(xy 178.773236 -286.825912) (xy 178.785013 -286.778128) (xy 178.804304 -286.732852) (xy 178.830607 -286.691256)
			(xy 178.863242 -286.654419) (xy 178.901363 -286.623294) (xy 178.943984 -286.598687) (xy 178.99 -286.581235)
			(xy 179.038219 -286.571391) (xy 179.087394 -286.56941) (xy 179.136249 -286.575342) (xy 179.18352 -286.589034)
			(xy 179.227982 -286.610132) (xy 179.268485 -286.638088) (xy 179.303978 -286.67218) (xy 179.333543 -286.711524)
			(xy 179.356414 -286.755101) (xy 179.371998 -286.801782) (xy 179.379893 -286.850359) (xy 179.380388 -286.874966)
			(xy 179.719236 -286.874966) (xy 179.723196 -286.825912) (xy 179.734973 -286.778128) (xy 179.754264 -286.732852)
			(xy 179.780567 -286.691256) (xy 179.813202 -286.654419) (xy 179.851323 -286.623294) (xy 179.893944 -286.598687)
			(xy 179.93996 -286.581235) (xy 179.988179 -286.571391) (xy 180.037354 -286.56941) (xy 180.086209 -286.575342)
			(xy 180.13348 -286.589034) (xy 180.177942 -286.610132) (xy 180.218445 -286.638088) (xy 180.253938 -286.67218)
			(xy 180.283503 -286.711524) (xy 180.306374 -286.755101) (xy 180.321958 -286.801782) (xy 180.329853 -286.850359)
			(xy 180.330348 -286.874966) (xy 180.669196 -286.874966) (xy 180.673156 -286.825912) (xy 180.684933 -286.778128)
			(xy 180.704224 -286.732852) (xy 180.730527 -286.691256) (xy 180.763162 -286.654419) (xy 180.801283 -286.623294)
			(xy 180.843904 -286.598687) (xy 180.88992 -286.581235) (xy 180.938139 -286.571391) (xy 180.987314 -286.56941)
			(xy 181.036169 -286.575342) (xy 181.08344 -286.589034) (xy 181.127902 -286.610132) (xy 181.168405 -286.638088)
			(xy 181.203898 -286.67218) (xy 181.233463 -286.711524) (xy 181.256334 -286.755101) (xy 181.271918 -286.801782)
			(xy 181.279813 -286.850359) (xy 181.280308 -286.874966) (xy 181.619156 -286.874966) (xy 181.623116 -286.825912)
			(xy 181.634893 -286.778128) (xy 181.654184 -286.732852) (xy 181.680487 -286.691256) (xy 181.713122 -286.654419)
			(xy 181.751243 -286.623294) (xy 181.793864 -286.598687) (xy 181.83988 -286.581235) (xy 181.888099 -286.571391)
			(xy 181.937274 -286.56941) (xy 181.986129 -286.575342) (xy 182.0334 -286.589034) (xy 182.077862 -286.610132)
			(xy 182.118365 -286.638088) (xy 182.153858 -286.67218) (xy 182.183423 -286.711524) (xy 182.206294 -286.755101)
			(xy 182.221878 -286.801782) (xy 182.229773 -286.850359) (xy 182.230268 -286.874966) (xy 182.569116 -286.874966)
			(xy 182.573076 -286.825912) (xy 182.584853 -286.778128) (xy 182.604144 -286.732852) (xy 182.630447 -286.691256)
			(xy 182.663082 -286.654419) (xy 182.701203 -286.623294) (xy 182.743824 -286.598687) (xy 182.78984 -286.581235)
			(xy 182.838059 -286.571391) (xy 182.887234 -286.56941) (xy 182.936089 -286.575342) (xy 182.98336 -286.589034)
			(xy 183.027822 -286.610132) (xy 183.068325 -286.638088) (xy 183.103818 -286.67218) (xy 183.133383 -286.711524)
			(xy 183.156254 -286.755101) (xy 183.171838 -286.801782) (xy 183.179733 -286.850359) (xy 183.180228 -286.874966)
			(xy 183.519076 -286.874966) (xy 183.523036 -286.825912) (xy 183.534813 -286.778128) (xy 183.554104 -286.732852)
			(xy 183.580407 -286.691256) (xy 183.613042 -286.654419) (xy 183.651163 -286.623294) (xy 183.693784 -286.598687)
			(xy 183.7398 -286.581235) (xy 183.788019 -286.571391) (xy 183.837194 -286.56941) (xy 183.886049 -286.575342)
			(xy 183.93332 -286.589034) (xy 183.977782 -286.610132) (xy 184.018285 -286.638088) (xy 184.053778 -286.67218)
			(xy 184.083343 -286.711524) (xy 184.106214 -286.755101) (xy 184.121798 -286.801782) (xy 184.129693 -286.850359)
			(xy 184.130188 -286.874966) (xy 184.469036 -286.874966) (xy 184.472996 -286.825912) (xy 184.484773 -286.778128)
			(xy 184.504064 -286.732852) (xy 184.530367 -286.691256) (xy 184.563002 -286.654419) (xy 184.601123 -286.623294)
			(xy 184.643744 -286.598687) (xy 184.68976 -286.581235) (xy 184.737979 -286.571391) (xy 184.787154 -286.56941)
			(xy 184.836009 -286.575342) (xy 184.88328 -286.589034) (xy 184.927742 -286.610132) (xy 184.968245 -286.638088)
			(xy 185.003738 -286.67218) (xy 185.033303 -286.711524) (xy 185.056174 -286.755101) (xy 185.071758 -286.801782)
			(xy 185.079653 -286.850359) (xy 185.080148 -286.874966) (xy 185.079653 -286.899573) (xy 185.071758 -286.94815)
			(xy 185.056174 -286.994831) (xy 185.033303 -287.038408) (xy 185.003738 -287.077752) (xy 184.968245 -287.111844)
			(xy 184.927742 -287.1398) (xy 184.88328 -287.160898) (xy 184.836009 -287.17459) (xy 184.787154 -287.180522)
			(xy 184.737979 -287.178541) (xy 184.68976 -287.168697) (xy 184.643744 -287.151245) (xy 184.601123 -287.126638)
			(xy 184.563002 -287.095513) (xy 184.530367 -287.058676) (xy 184.504064 -287.01708) (xy 184.484773 -286.971804)
			(xy 184.472996 -286.92402) (xy 184.469036 -286.874966) (xy 184.130188 -286.874966) (xy 184.129693 -286.899573)
			(xy 184.121798 -286.94815) (xy 184.106214 -286.994831) (xy 184.083343 -287.038408) (xy 184.053778 -287.077752)
			(xy 184.018285 -287.111844) (xy 183.977782 -287.1398) (xy 183.93332 -287.160898) (xy 183.886049 -287.17459)
			(xy 183.837194 -287.180522) (xy 183.788019 -287.178541) (xy 183.7398 -287.168697) (xy 183.693784 -287.151245)
			(xy 183.651163 -287.126638) (xy 183.613042 -287.095513) (xy 183.580407 -287.058676) (xy 183.554104 -287.01708)
			(xy 183.534813 -286.971804) (xy 183.523036 -286.92402) (xy 183.519076 -286.874966) (xy 183.180228 -286.874966)
			(xy 183.179733 -286.899573) (xy 183.171838 -286.94815) (xy 183.156254 -286.994831) (xy 183.133383 -287.038408)
			(xy 183.103818 -287.077752) (xy 183.068325 -287.111844) (xy 183.027822 -287.1398) (xy 182.98336 -287.160898)
			(xy 182.936089 -287.17459) (xy 182.887234 -287.180522) (xy 182.838059 -287.178541) (xy 182.78984 -287.168697)
			(xy 182.743824 -287.151245) (xy 182.701203 -287.126638) (xy 182.663082 -287.095513) (xy 182.630447 -287.058676)
			(xy 182.604144 -287.01708) (xy 182.584853 -286.971804) (xy 182.573076 -286.92402) (xy 182.569116 -286.874966)
			(xy 182.230268 -286.874966) (xy 182.229773 -286.899573) (xy 182.221878 -286.94815) (xy 182.206294 -286.994831)
			(xy 182.183423 -287.038408) (xy 182.153858 -287.077752) (xy 182.118365 -287.111844) (xy 182.077862 -287.1398)
			(xy 182.0334 -287.160898) (xy 181.986129 -287.17459) (xy 181.937274 -287.180522) (xy 181.888099 -287.178541)
			(xy 181.83988 -287.168697) (xy 181.793864 -287.151245) (xy 181.751243 -287.126638) (xy 181.713122 -287.095513)
			(xy 181.680487 -287.058676) (xy 181.654184 -287.01708) (xy 181.634893 -286.971804) (xy 181.623116 -286.92402)
			(xy 181.619156 -286.874966) (xy 181.280308 -286.874966) (xy 181.279813 -286.899573) (xy 181.271918 -286.94815)
			(xy 181.256334 -286.994831) (xy 181.233463 -287.038408) (xy 181.203898 -287.077752) (xy 181.168405 -287.111844)
			(xy 181.127902 -287.1398) (xy 181.08344 -287.160898) (xy 181.036169 -287.17459) (xy 180.987314 -287.180522)
			(xy 180.938139 -287.178541) (xy 180.88992 -287.168697) (xy 180.843904 -287.151245) (xy 180.801283 -287.126638)
			(xy 180.763162 -287.095513) (xy 180.730527 -287.058676) (xy 180.704224 -287.01708) (xy 180.684933 -286.971804)
			(xy 180.673156 -286.92402) (xy 180.669196 -286.874966) (xy 180.330348 -286.874966) (xy 180.329853 -286.899573)
			(xy 180.321958 -286.94815) (xy 180.306374 -286.994831) (xy 180.283503 -287.038408) (xy 180.253938 -287.077752)
			(xy 180.218445 -287.111844) (xy 180.177942 -287.1398) (xy 180.13348 -287.160898) (xy 180.086209 -287.17459)
			(xy 180.037354 -287.180522) (xy 179.988179 -287.178541) (xy 179.93996 -287.168697) (xy 179.893944 -287.151245)
			(xy 179.851323 -287.126638) (xy 179.813202 -287.095513) (xy 179.780567 -287.058676) (xy 179.754264 -287.01708)
			(xy 179.734973 -286.971804) (xy 179.723196 -286.92402) (xy 179.719236 -286.874966) (xy 179.380388 -286.874966)
			(xy 179.379893 -286.899573) (xy 179.371998 -286.94815) (xy 179.356414 -286.994831) (xy 179.333543 -287.038408)
			(xy 179.303978 -287.077752) (xy 179.268485 -287.111844) (xy 179.227982 -287.1398) (xy 179.18352 -287.160898)
			(xy 179.136249 -287.17459) (xy 179.087394 -287.180522) (xy 179.038219 -287.178541) (xy 178.99 -287.168697)
			(xy 178.943984 -287.151245) (xy 178.901363 -287.126638) (xy 178.863242 -287.095513) (xy 178.830607 -287.058676)
			(xy 178.804304 -287.01708) (xy 178.785013 -286.971804) (xy 178.773236 -286.92402) (xy 178.769276 -286.874966)
			(xy 178.430174 -286.874966) (xy 178.429679 -286.899573) (xy 178.421784 -286.94815) (xy 178.4062 -286.994831)
			(xy 178.383329 -287.038408) (xy 178.353764 -287.077752) (xy 178.318271 -287.111844) (xy 178.277768 -287.1398)
			(xy 178.233306 -287.160898) (xy 178.186035 -287.17459) (xy 178.13718 -287.180522) (xy 178.088005 -287.178541)
			(xy 178.039786 -287.168697) (xy 177.99377 -287.151245) (xy 177.951149 -287.126638) (xy 177.913028 -287.095513)
			(xy 177.880393 -287.058676) (xy 177.85409 -287.01708) (xy 177.834799 -286.971804) (xy 177.823022 -286.92402)
			(xy 177.819062 -286.874966) (xy 177.480214 -286.874966) (xy 177.479719 -286.899573) (xy 177.471824 -286.94815)
			(xy 177.45624 -286.994831) (xy 177.433369 -287.038408) (xy 177.403804 -287.077752) (xy 177.368311 -287.111844)
			(xy 177.327808 -287.1398) (xy 177.283346 -287.160898) (xy 177.236075 -287.17459) (xy 177.18722 -287.180522)
			(xy 177.138045 -287.178541) (xy 177.089826 -287.168697) (xy 177.04381 -287.151245) (xy 177.001189 -287.126638)
			(xy 176.963068 -287.095513) (xy 176.930433 -287.058676) (xy 176.90413 -287.01708) (xy 176.884839 -286.971804)
			(xy 176.873062 -286.92402) (xy 176.869102 -286.874966) (xy 176.530254 -286.874966) (xy 176.529759 -286.899573)
			(xy 176.521864 -286.94815) (xy 176.50628 -286.994831) (xy 176.483409 -287.038408) (xy 176.453844 -287.077752)
			(xy 176.418351 -287.111844) (xy 176.377848 -287.1398) (xy 176.333386 -287.160898) (xy 176.286115 -287.17459)
			(xy 176.23726 -287.180522) (xy 176.188085 -287.178541) (xy 176.139866 -287.168697) (xy 176.09385 -287.151245)
			(xy 176.051229 -287.126638) (xy 176.013108 -287.095513) (xy 175.980473 -287.058676) (xy 175.95417 -287.01708)
			(xy 175.934879 -286.971804) (xy 175.923102 -286.92402) (xy 175.919142 -286.874966) (xy 174.630334 -286.874966)
			(xy 174.629839 -286.899573) (xy 174.621944 -286.94815) (xy 174.60636 -286.994831) (xy 174.583489 -287.038408)
			(xy 174.553924 -287.077752) (xy 174.518431 -287.111844) (xy 174.477928 -287.1398) (xy 174.433466 -287.160898)
			(xy 174.386195 -287.17459) (xy 174.33734 -287.180522) (xy 174.288165 -287.178541) (xy 174.239946 -287.168697)
			(xy 174.19393 -287.151245) (xy 174.151309 -287.126638) (xy 174.113188 -287.095513) (xy 174.080553 -287.058676)
			(xy 174.05425 -287.01708) (xy 174.034959 -286.971804) (xy 174.023182 -286.92402) (xy 174.019222 -286.874966)
			(xy 173.680374 -286.874966) (xy 173.679879 -286.899573) (xy 173.671984 -286.94815) (xy 173.6564 -286.994831)
			(xy 173.633529 -287.038408) (xy 173.603964 -287.077752) (xy 173.568471 -287.111844) (xy 173.527968 -287.1398)
			(xy 173.483506 -287.160898) (xy 173.436235 -287.17459) (xy 173.38738 -287.180522) (xy 173.338205 -287.178541)
			(xy 173.289986 -287.168697) (xy 173.24397 -287.151245) (xy 173.201349 -287.126638) (xy 173.163228 -287.095513)
			(xy 173.130593 -287.058676) (xy 173.10429 -287.01708) (xy 173.084999 -286.971804) (xy 173.073222 -286.92402)
			(xy 173.069262 -286.874966) (xy 172.73016 -286.874966) (xy 172.729665 -286.899573) (xy 172.72177 -286.94815)
			(xy 172.706186 -286.994831) (xy 172.683315 -287.038408) (xy 172.65375 -287.077752) (xy 172.618257 -287.111844)
			(xy 172.577754 -287.1398) (xy 172.533292 -287.160898) (xy 172.486021 -287.17459) (xy 172.437166 -287.180522)
			(xy 172.387991 -287.178541) (xy 172.339772 -287.168697) (xy 172.293756 -287.151245) (xy 172.251135 -287.126638)
			(xy 172.213014 -287.095513) (xy 172.180379 -287.058676) (xy 172.154076 -287.01708) (xy 172.134785 -286.971804)
			(xy 172.123008 -286.92402) (xy 172.119048 -286.874966) (xy 171.7802 -286.874966) (xy 171.779705 -286.899573)
			(xy 171.77181 -286.94815) (xy 171.756226 -286.994831) (xy 171.733355 -287.038408) (xy 171.70379 -287.077752)
			(xy 171.668297 -287.111844) (xy 171.627794 -287.1398) (xy 171.583332 -287.160898) (xy 171.536061 -287.17459)
			(xy 171.487206 -287.180522) (xy 171.438031 -287.178541) (xy 171.389812 -287.168697) (xy 171.343796 -287.151245)
			(xy 171.301175 -287.126638) (xy 171.263054 -287.095513) (xy 171.230419 -287.058676) (xy 171.204116 -287.01708)
			(xy 171.184825 -286.971804) (xy 171.173048 -286.92402) (xy 171.169088 -286.874966) (xy 170.83024 -286.874966)
			(xy 170.829745 -286.899573) (xy 170.82185 -286.94815) (xy 170.806266 -286.994831) (xy 170.783395 -287.038408)
			(xy 170.75383 -287.077752) (xy 170.718337 -287.111844) (xy 170.677834 -287.1398) (xy 170.633372 -287.160898)
			(xy 170.586101 -287.17459) (xy 170.537246 -287.180522) (xy 170.488071 -287.178541) (xy 170.439852 -287.168697)
			(xy 170.393836 -287.151245) (xy 170.351215 -287.126638) (xy 170.313094 -287.095513) (xy 170.280459 -287.058676)
			(xy 170.254156 -287.01708) (xy 170.234865 -286.971804) (xy 170.223088 -286.92402) (xy 170.219128 -286.874966)
			(xy 169.88028 -286.874966) (xy 169.879785 -286.899573) (xy 169.87189 -286.94815) (xy 169.856306 -286.994831)
			(xy 169.833435 -287.038408) (xy 169.80387 -287.077752) (xy 169.768377 -287.111844) (xy 169.727874 -287.1398)
			(xy 169.683412 -287.160898) (xy 169.636141 -287.17459) (xy 169.587286 -287.180522) (xy 169.538111 -287.178541)
			(xy 169.489892 -287.168697) (xy 169.443876 -287.151245) (xy 169.401255 -287.126638) (xy 169.363134 -287.095513)
			(xy 169.330499 -287.058676) (xy 169.304196 -287.01708) (xy 169.284905 -286.971804) (xy 169.273128 -286.92402)
			(xy 169.269168 -286.874966) (xy 168.93032 -286.874966) (xy 168.929825 -286.899573) (xy 168.92193 -286.94815)
			(xy 168.906346 -286.994831) (xy 168.883475 -287.038408) (xy 168.85391 -287.077752) (xy 168.818417 -287.111844)
			(xy 168.777914 -287.1398) (xy 168.733452 -287.160898) (xy 168.686181 -287.17459) (xy 168.637326 -287.180522)
			(xy 168.588151 -287.178541) (xy 168.539932 -287.168697) (xy 168.493916 -287.151245) (xy 168.451295 -287.126638)
			(xy 168.413174 -287.095513) (xy 168.380539 -287.058676) (xy 168.354236 -287.01708) (xy 168.334945 -286.971804)
			(xy 168.323168 -286.92402) (xy 168.319208 -286.874966) (xy 167.98036 -286.874966) (xy 167.979865 -286.899573)
			(xy 167.97197 -286.94815) (xy 167.956386 -286.994831) (xy 167.933515 -287.038408) (xy 167.90395 -287.077752)
			(xy 167.868457 -287.111844) (xy 167.827954 -287.1398) (xy 167.783492 -287.160898) (xy 167.736221 -287.17459)
			(xy 167.687366 -287.180522) (xy 167.638191 -287.178541) (xy 167.589972 -287.168697) (xy 167.543956 -287.151245)
			(xy 167.501335 -287.126638) (xy 167.463214 -287.095513) (xy 167.430579 -287.058676) (xy 167.404276 -287.01708)
			(xy 167.384985 -286.971804) (xy 167.373208 -286.92402) (xy 167.369248 -286.874966) (xy 167.0304 -286.874966)
			(xy 167.029905 -286.899573) (xy 167.02201 -286.94815) (xy 167.006426 -286.994831) (xy 166.983555 -287.038408)
			(xy 166.95399 -287.077752) (xy 166.918497 -287.111844) (xy 166.877994 -287.1398) (xy 166.833532 -287.160898)
			(xy 166.786261 -287.17459) (xy 166.737406 -287.180522) (xy 166.688231 -287.178541) (xy 166.640012 -287.168697)
			(xy 166.593996 -287.151245) (xy 166.551375 -287.126638) (xy 166.513254 -287.095513) (xy 166.480619 -287.058676)
			(xy 166.454316 -287.01708) (xy 166.435025 -286.971804) (xy 166.423248 -286.92402) (xy 166.419288 -286.874966)
			(xy 166.080186 -286.874966) (xy 166.079691 -286.899573) (xy 166.071796 -286.94815) (xy 166.056212 -286.994831)
			(xy 166.033341 -287.038408) (xy 166.003776 -287.077752) (xy 165.968283 -287.111844) (xy 165.92778 -287.1398)
			(xy 165.883318 -287.160898) (xy 165.836047 -287.17459) (xy 165.787192 -287.180522) (xy 165.738017 -287.178541)
			(xy 165.689798 -287.168697) (xy 165.643782 -287.151245) (xy 165.601161 -287.126638) (xy 165.56304 -287.095513)
			(xy 165.530405 -287.058676) (xy 165.504102 -287.01708) (xy 165.484811 -286.971804) (xy 165.473034 -286.92402)
			(xy 165.469074 -286.874966) (xy 165.130226 -286.874966) (xy 165.129731 -286.899573) (xy 165.121836 -286.94815)
			(xy 165.106252 -286.994831) (xy 165.083381 -287.038408) (xy 165.053816 -287.077752) (xy 165.018323 -287.111844)
			(xy 164.97782 -287.1398) (xy 164.933358 -287.160898) (xy 164.886087 -287.17459) (xy 164.837232 -287.180522)
			(xy 164.788057 -287.178541) (xy 164.739838 -287.168697) (xy 164.693822 -287.151245) (xy 164.651201 -287.126638)
			(xy 164.61308 -287.095513) (xy 164.580445 -287.058676) (xy 164.554142 -287.01708) (xy 164.534851 -286.971804)
			(xy 164.523074 -286.92402) (xy 164.519114 -286.874966) (xy 164.180266 -286.874966) (xy 164.179771 -286.899573)
			(xy 164.171876 -286.94815) (xy 164.156292 -286.994831) (xy 164.133421 -287.038408) (xy 164.103856 -287.077752)
			(xy 164.068363 -287.111844) (xy 164.02786 -287.1398) (xy 163.983398 -287.160898) (xy 163.936127 -287.17459)
			(xy 163.887272 -287.180522) (xy 163.838097 -287.178541) (xy 163.789878 -287.168697) (xy 163.743862 -287.151245)
			(xy 163.701241 -287.126638) (xy 163.66312 -287.095513) (xy 163.630485 -287.058676) (xy 163.604182 -287.01708)
			(xy 163.584891 -286.971804) (xy 163.573114 -286.92402) (xy 163.569154 -286.874966) (xy 163.230306 -286.874966)
			(xy 163.229811 -286.899573) (xy 163.221916 -286.94815) (xy 163.206332 -286.994831) (xy 163.183461 -287.038408)
			(xy 163.153896 -287.077752) (xy 163.118403 -287.111844) (xy 163.0779 -287.1398) (xy 163.033438 -287.160898)
			(xy 162.986167 -287.17459) (xy 162.937312 -287.180522) (xy 162.888137 -287.178541) (xy 162.839918 -287.168697)
			(xy 162.793902 -287.151245) (xy 162.751281 -287.126638) (xy 162.71316 -287.095513) (xy 162.680525 -287.058676)
			(xy 162.654222 -287.01708) (xy 162.634931 -286.971804) (xy 162.623154 -286.92402) (xy 162.619194 -286.874966)
			(xy 162.280346 -286.874966) (xy 162.279851 -286.899573) (xy 162.271956 -286.94815) (xy 162.256372 -286.994831)
			(xy 162.233501 -287.038408) (xy 162.203936 -287.077752) (xy 162.168443 -287.111844) (xy 162.12794 -287.1398)
			(xy 162.083478 -287.160898) (xy 162.036207 -287.17459) (xy 161.987352 -287.180522) (xy 161.938177 -287.178541)
			(xy 161.889958 -287.168697) (xy 161.843942 -287.151245) (xy 161.801321 -287.126638) (xy 161.7632 -287.095513)
			(xy 161.730565 -287.058676) (xy 161.704262 -287.01708) (xy 161.684971 -286.971804) (xy 161.673194 -286.92402)
			(xy 161.669234 -286.874966) (xy 161.330386 -286.874966) (xy 161.329891 -286.899573) (xy 161.321996 -286.94815)
			(xy 161.306412 -286.994831) (xy 161.283541 -287.038408) (xy 161.253976 -287.077752) (xy 161.218483 -287.111844)
			(xy 161.17798 -287.1398) (xy 161.133518 -287.160898) (xy 161.086247 -287.17459) (xy 161.037392 -287.180522)
			(xy 160.988217 -287.178541) (xy 160.939998 -287.168697) (xy 160.893982 -287.151245) (xy 160.851361 -287.126638)
			(xy 160.81324 -287.095513) (xy 160.780605 -287.058676) (xy 160.754302 -287.01708) (xy 160.735011 -286.971804)
			(xy 160.723234 -286.92402) (xy 160.719274 -286.874966) (xy 160.380167 -286.874966) (xy 160.379677 -286.899319)
			(xy 160.371782 -286.947896) (xy 160.356198 -286.994577) (xy 160.333327 -287.038154) (xy 160.303762 -287.077498)
			(xy 160.268269 -287.11159) (xy 160.227766 -287.139546) (xy 160.183304 -287.160644) (xy 160.136033 -287.174336)
			(xy 160.087178 -287.180268) (xy 160.038003 -287.178287) (xy 159.989784 -287.168443) (xy 159.943768 -287.150991)
			(xy 159.901147 -287.126384) (xy 159.863026 -287.095259) (xy 159.830391 -287.058422) (xy 159.804088 -287.016826)
			(xy 159.784797 -286.97155) (xy 159.77302 -286.923766) (xy 159.76906 -286.874712) (xy 159.430212 -286.874712)
			(xy 159.429717 -286.899319) (xy 159.421822 -286.947896) (xy 159.406238 -286.994577) (xy 159.383367 -287.038154)
			(xy 159.353802 -287.077498) (xy 159.318309 -287.11159) (xy 159.277806 -287.139546) (xy 159.233344 -287.160644)
			(xy 159.186073 -287.174336) (xy 159.137218 -287.180268) (xy 159.088043 -287.178287) (xy 159.039824 -287.168443)
			(xy 158.993808 -287.150991) (xy 158.951187 -287.126384) (xy 158.913066 -287.095259) (xy 158.880431 -287.058422)
			(xy 158.854128 -287.016826) (xy 158.834837 -286.97155) (xy 158.82306 -286.923766) (xy 158.8191 -286.874712)
			(xy 158.480247 -286.874712) (xy 158.480252 -286.874966) (xy 158.479839 -286.899056) (xy 158.472248 -286.946635)
			(xy 158.457281 -286.992432) (xy 158.435308 -287.03531) (xy 158.406876 -287.074207) (xy 158.372689 -287.108157)
			(xy 158.333595 -287.136318) (xy 158.290565 -287.157992) (xy 158.244665 -287.17264) (xy 158.220918 -287.176718)
			(xy 158.220664 -287.176718) (xy 158.21153 -287.178581) (xy 158.195384 -287.18787) (xy 158.183602 -287.202298)
			(xy 158.180278 -287.211008) (xy 158.15183 -287.297368) (xy 158.14928 -287.306407) (xy 158.150244 -287.325148)
			(xy 158.157911 -287.342276) (xy 158.164276 -287.349184) (xy 158.640018 -287.824926) (xy 160.719274 -287.824926)
			(xy 160.723234 -287.775872) (xy 160.735011 -287.728088) (xy 160.754302 -287.682812) (xy 160.780605 -287.641216)
			(xy 160.81324 -287.604379) (xy 160.851361 -287.573254) (xy 160.893982 -287.548647) (xy 160.939998 -287.531195)
			(xy 160.988217 -287.521351) (xy 161.037392 -287.51937) (xy 161.086247 -287.525302) (xy 161.133518 -287.538994)
			(xy 161.17798 -287.560092) (xy 161.218483 -287.588048) (xy 161.253976 -287.62214) (xy 161.283541 -287.661484)
			(xy 161.306412 -287.705061) (xy 161.321996 -287.751742) (xy 161.329891 -287.800319) (xy 161.330386 -287.824926)
			(xy 161.669234 -287.824926) (xy 161.673194 -287.775872) (xy 161.684971 -287.728088) (xy 161.704262 -287.682812)
			(xy 161.730565 -287.641216) (xy 161.7632 -287.604379) (xy 161.801321 -287.573254) (xy 161.843942 -287.548647)
			(xy 161.889958 -287.531195) (xy 161.938177 -287.521351) (xy 161.987352 -287.51937) (xy 162.036207 -287.525302)
			(xy 162.083478 -287.538994) (xy 162.12794 -287.560092) (xy 162.168443 -287.588048) (xy 162.203936 -287.62214)
			(xy 162.233501 -287.661484) (xy 162.256372 -287.705061) (xy 162.271956 -287.751742) (xy 162.279851 -287.800319)
			(xy 162.280346 -287.824926) (xy 162.619194 -287.824926) (xy 162.623154 -287.775872) (xy 162.634931 -287.728088)
			(xy 162.654222 -287.682812) (xy 162.680525 -287.641216) (xy 162.71316 -287.604379) (xy 162.751281 -287.573254)
			(xy 162.793902 -287.548647) (xy 162.839918 -287.531195) (xy 162.888137 -287.521351) (xy 162.937312 -287.51937)
			(xy 162.986167 -287.525302) (xy 163.033438 -287.538994) (xy 163.0779 -287.560092) (xy 163.118403 -287.588048)
			(xy 163.153896 -287.62214) (xy 163.183461 -287.661484) (xy 163.206332 -287.705061) (xy 163.221916 -287.751742)
			(xy 163.229811 -287.800319) (xy 163.230306 -287.824926) (xy 163.569154 -287.824926) (xy 163.573114 -287.775872)
			(xy 163.584891 -287.728088) (xy 163.604182 -287.682812) (xy 163.630485 -287.641216) (xy 163.66312 -287.604379)
			(xy 163.701241 -287.573254) (xy 163.743862 -287.548647) (xy 163.789878 -287.531195) (xy 163.838097 -287.521351)
			(xy 163.887272 -287.51937) (xy 163.936127 -287.525302) (xy 163.983398 -287.538994) (xy 164.02786 -287.560092)
			(xy 164.068363 -287.588048) (xy 164.103856 -287.62214) (xy 164.133421 -287.661484) (xy 164.156292 -287.705061)
			(xy 164.171876 -287.751742) (xy 164.179771 -287.800319) (xy 164.180266 -287.824926) (xy 164.519114 -287.824926)
			(xy 164.523074 -287.775872) (xy 164.534851 -287.728088) (xy 164.554142 -287.682812) (xy 164.580445 -287.641216)
			(xy 164.61308 -287.604379) (xy 164.651201 -287.573254) (xy 164.693822 -287.548647) (xy 164.739838 -287.531195)
			(xy 164.788057 -287.521351) (xy 164.837232 -287.51937) (xy 164.886087 -287.525302) (xy 164.933358 -287.538994)
			(xy 164.97782 -287.560092) (xy 165.018323 -287.588048) (xy 165.053816 -287.62214) (xy 165.083381 -287.661484)
			(xy 165.106252 -287.705061) (xy 165.121836 -287.751742) (xy 165.129731 -287.800319) (xy 165.130226 -287.824926)
			(xy 165.469074 -287.824926) (xy 165.473034 -287.775872) (xy 165.484811 -287.728088) (xy 165.504102 -287.682812)
			(xy 165.530405 -287.641216) (xy 165.56304 -287.604379) (xy 165.601161 -287.573254) (xy 165.643782 -287.548647)
			(xy 165.689798 -287.531195) (xy 165.738017 -287.521351) (xy 165.787192 -287.51937) (xy 165.836047 -287.525302)
			(xy 165.883318 -287.538994) (xy 165.92778 -287.560092) (xy 165.968283 -287.588048) (xy 166.003776 -287.62214)
			(xy 166.033341 -287.661484) (xy 166.056212 -287.705061) (xy 166.071796 -287.751742) (xy 166.079691 -287.800319)
			(xy 166.080186 -287.824926) (xy 166.419288 -287.824926) (xy 166.423248 -287.775872) (xy 166.435025 -287.728088)
			(xy 166.454316 -287.682812) (xy 166.480619 -287.641216) (xy 166.513254 -287.604379) (xy 166.551375 -287.573254)
			(xy 166.593996 -287.548647) (xy 166.640012 -287.531195) (xy 166.688231 -287.521351) (xy 166.737406 -287.51937)
			(xy 166.786261 -287.525302) (xy 166.833532 -287.538994) (xy 166.877994 -287.560092) (xy 166.918497 -287.588048)
			(xy 166.95399 -287.62214) (xy 166.983555 -287.661484) (xy 167.006426 -287.705061) (xy 167.02201 -287.751742)
			(xy 167.029905 -287.800319) (xy 167.0304 -287.824926) (xy 167.369248 -287.824926) (xy 167.373208 -287.775872)
			(xy 167.384985 -287.728088) (xy 167.404276 -287.682812) (xy 167.430579 -287.641216) (xy 167.463214 -287.604379)
			(xy 167.501335 -287.573254) (xy 167.543956 -287.548647) (xy 167.589972 -287.531195) (xy 167.638191 -287.521351)
			(xy 167.687366 -287.51937) (xy 167.736221 -287.525302) (xy 167.783492 -287.538994) (xy 167.827954 -287.560092)
			(xy 167.868457 -287.588048) (xy 167.90395 -287.62214) (xy 167.933515 -287.661484) (xy 167.956386 -287.705061)
			(xy 167.97197 -287.751742) (xy 167.979865 -287.800319) (xy 167.98036 -287.824926) (xy 168.319208 -287.824926)
			(xy 168.323168 -287.775872) (xy 168.334945 -287.728088) (xy 168.354236 -287.682812) (xy 168.380539 -287.641216)
			(xy 168.413174 -287.604379) (xy 168.451295 -287.573254) (xy 168.493916 -287.548647) (xy 168.539932 -287.531195)
			(xy 168.588151 -287.521351) (xy 168.637326 -287.51937) (xy 168.686181 -287.525302) (xy 168.733452 -287.538994)
			(xy 168.777914 -287.560092) (xy 168.818417 -287.588048) (xy 168.85391 -287.62214) (xy 168.883475 -287.661484)
			(xy 168.906346 -287.705061) (xy 168.92193 -287.751742) (xy 168.929825 -287.800319) (xy 168.93032 -287.824926)
			(xy 169.269168 -287.824926) (xy 169.273128 -287.775872) (xy 169.284905 -287.728088) (xy 169.304196 -287.682812)
			(xy 169.330499 -287.641216) (xy 169.363134 -287.604379) (xy 169.401255 -287.573254) (xy 169.443876 -287.548647)
			(xy 169.489892 -287.531195) (xy 169.538111 -287.521351) (xy 169.587286 -287.51937) (xy 169.636141 -287.525302)
			(xy 169.683412 -287.538994) (xy 169.727874 -287.560092) (xy 169.768377 -287.588048) (xy 169.80387 -287.62214)
			(xy 169.833435 -287.661484) (xy 169.856306 -287.705061) (xy 169.87189 -287.751742) (xy 169.879785 -287.800319)
			(xy 169.88028 -287.824926) (xy 170.219128 -287.824926) (xy 170.223088 -287.775872) (xy 170.234865 -287.728088)
			(xy 170.254156 -287.682812) (xy 170.280459 -287.641216) (xy 170.313094 -287.604379) (xy 170.351215 -287.573254)
			(xy 170.393836 -287.548647) (xy 170.439852 -287.531195) (xy 170.488071 -287.521351) (xy 170.537246 -287.51937)
			(xy 170.586101 -287.525302) (xy 170.633372 -287.538994) (xy 170.677834 -287.560092) (xy 170.718337 -287.588048)
			(xy 170.75383 -287.62214) (xy 170.783395 -287.661484) (xy 170.806266 -287.705061) (xy 170.82185 -287.751742)
			(xy 170.829745 -287.800319) (xy 170.83024 -287.824926) (xy 171.169088 -287.824926) (xy 171.173048 -287.775872)
			(xy 171.184825 -287.728088) (xy 171.204116 -287.682812) (xy 171.230419 -287.641216) (xy 171.263054 -287.604379)
			(xy 171.301175 -287.573254) (xy 171.343796 -287.548647) (xy 171.389812 -287.531195) (xy 171.438031 -287.521351)
			(xy 171.487206 -287.51937) (xy 171.536061 -287.525302) (xy 171.583332 -287.538994) (xy 171.627794 -287.560092)
			(xy 171.668297 -287.588048) (xy 171.70379 -287.62214) (xy 171.733355 -287.661484) (xy 171.756226 -287.705061)
			(xy 171.77181 -287.751742) (xy 171.779705 -287.800319) (xy 171.7802 -287.824926) (xy 172.119048 -287.824926)
			(xy 172.123008 -287.775872) (xy 172.134785 -287.728088) (xy 172.154076 -287.682812) (xy 172.180379 -287.641216)
			(xy 172.213014 -287.604379) (xy 172.251135 -287.573254) (xy 172.293756 -287.548647) (xy 172.339772 -287.531195)
			(xy 172.387991 -287.521351) (xy 172.437166 -287.51937) (xy 172.486021 -287.525302) (xy 172.533292 -287.538994)
			(xy 172.577754 -287.560092) (xy 172.618257 -287.588048) (xy 172.65375 -287.62214) (xy 172.683315 -287.661484)
			(xy 172.706186 -287.705061) (xy 172.72177 -287.751742) (xy 172.729665 -287.800319) (xy 172.73016 -287.824926)
			(xy 173.069262 -287.824926) (xy 173.073222 -287.775872) (xy 173.084999 -287.728088) (xy 173.10429 -287.682812)
			(xy 173.130593 -287.641216) (xy 173.163228 -287.604379) (xy 173.201349 -287.573254) (xy 173.24397 -287.548647)
			(xy 173.289986 -287.531195) (xy 173.338205 -287.521351) (xy 173.38738 -287.51937) (xy 173.436235 -287.525302)
			(xy 173.483506 -287.538994) (xy 173.527968 -287.560092) (xy 173.568471 -287.588048) (xy 173.603964 -287.62214)
			(xy 173.633529 -287.661484) (xy 173.653722 -287.699958) (xy 174.044114 -287.699958) (xy 174.048074 -287.650904)
			(xy 174.059851 -287.60312) (xy 174.079142 -287.557844) (xy 174.105445 -287.516248) (xy 174.13808 -287.479411)
			(xy 174.176201 -287.448286) (xy 174.218822 -287.423679) (xy 174.264838 -287.406227) (xy 174.313057 -287.396383)
			(xy 174.362232 -287.394402) (xy 174.411087 -287.400334) (xy 174.458358 -287.414026) (xy 174.50282 -287.435124)
			(xy 174.543323 -287.46308) (xy 174.578816 -287.497172) (xy 174.608381 -287.536516) (xy 174.631252 -287.580093)
			(xy 174.646836 -287.626774) (xy 174.654731 -287.675351) (xy 174.655226 -287.699958) (xy 174.654731 -287.724565)
			(xy 174.646836 -287.773142) (xy 174.631252 -287.819823) (xy 174.608381 -287.8634) (xy 174.580986 -287.899856)
			(xy 175.919142 -287.899856) (xy 175.923102 -287.850802) (xy 175.934879 -287.803018) (xy 175.95417 -287.757742)
			(xy 175.980473 -287.716146) (xy 176.013108 -287.679309) (xy 176.051229 -287.648184) (xy 176.09385 -287.623577)
			(xy 176.139866 -287.606125) (xy 176.188085 -287.596281) (xy 176.23726 -287.5943) (xy 176.286115 -287.600232)
			(xy 176.333386 -287.613924) (xy 176.377848 -287.635022) (xy 176.418351 -287.662978) (xy 176.453844 -287.69707)
			(xy 176.483409 -287.736414) (xy 176.50628 -287.779991) (xy 176.521281 -287.824926) (xy 176.869102 -287.824926)
			(xy 176.873062 -287.775872) (xy 176.884839 -287.728088) (xy 176.90413 -287.682812) (xy 176.930433 -287.641216)
			(xy 176.963068 -287.604379) (xy 177.001189 -287.573254) (xy 177.04381 -287.548647) (xy 177.089826 -287.531195)
			(xy 177.138045 -287.521351) (xy 177.18722 -287.51937) (xy 177.236075 -287.525302) (xy 177.283346 -287.538994)
			(xy 177.327808 -287.560092) (xy 177.368311 -287.588048) (xy 177.403804 -287.62214) (xy 177.433369 -287.661484)
			(xy 177.45624 -287.705061) (xy 177.471824 -287.751742) (xy 177.479719 -287.800319) (xy 177.480214 -287.824926)
			(xy 177.819062 -287.824926) (xy 177.823022 -287.775872) (xy 177.834799 -287.728088) (xy 177.85409 -287.682812)
			(xy 177.880393 -287.641216) (xy 177.913028 -287.604379) (xy 177.951149 -287.573254) (xy 177.99377 -287.548647)
			(xy 178.039786 -287.531195) (xy 178.088005 -287.521351) (xy 178.13718 -287.51937) (xy 178.186035 -287.525302)
			(xy 178.233306 -287.538994) (xy 178.277768 -287.560092) (xy 178.318271 -287.588048) (xy 178.353764 -287.62214)
			(xy 178.383329 -287.661484) (xy 178.4062 -287.705061) (xy 178.421784 -287.751742) (xy 178.429679 -287.800319)
			(xy 178.430174 -287.824926) (xy 178.769276 -287.824926) (xy 178.773236 -287.775872) (xy 178.785013 -287.728088)
			(xy 178.804304 -287.682812) (xy 178.830607 -287.641216) (xy 178.863242 -287.604379) (xy 178.901363 -287.573254)
			(xy 178.943984 -287.548647) (xy 178.99 -287.531195) (xy 179.038219 -287.521351) (xy 179.087394 -287.51937)
			(xy 179.136249 -287.525302) (xy 179.18352 -287.538994) (xy 179.227982 -287.560092) (xy 179.268485 -287.588048)
			(xy 179.303978 -287.62214) (xy 179.333543 -287.661484) (xy 179.356414 -287.705061) (xy 179.371998 -287.751742)
			(xy 179.379893 -287.800319) (xy 179.380388 -287.824926) (xy 179.719236 -287.824926) (xy 179.723196 -287.775872)
			(xy 179.734973 -287.728088) (xy 179.754264 -287.682812) (xy 179.780567 -287.641216) (xy 179.813202 -287.604379)
			(xy 179.851323 -287.573254) (xy 179.893944 -287.548647) (xy 179.93996 -287.531195) (xy 179.988179 -287.521351)
			(xy 180.037354 -287.51937) (xy 180.086209 -287.525302) (xy 180.13348 -287.538994) (xy 180.177942 -287.560092)
			(xy 180.218445 -287.588048) (xy 180.253938 -287.62214) (xy 180.283503 -287.661484) (xy 180.306374 -287.705061)
			(xy 180.321958 -287.751742) (xy 180.329853 -287.800319) (xy 180.330348 -287.824926) (xy 180.669196 -287.824926)
			(xy 180.673156 -287.775872) (xy 180.684933 -287.728088) (xy 180.704224 -287.682812) (xy 180.730527 -287.641216)
			(xy 180.763162 -287.604379) (xy 180.801283 -287.573254) (xy 180.843904 -287.548647) (xy 180.88992 -287.531195)
			(xy 180.938139 -287.521351) (xy 180.987314 -287.51937) (xy 181.036169 -287.525302) (xy 181.08344 -287.538994)
			(xy 181.127902 -287.560092) (xy 181.168405 -287.588048) (xy 181.203898 -287.62214) (xy 181.233463 -287.661484)
			(xy 181.256334 -287.705061) (xy 181.271918 -287.751742) (xy 181.279813 -287.800319) (xy 181.280308 -287.824926)
			(xy 181.619156 -287.824926) (xy 181.623116 -287.775872) (xy 181.634893 -287.728088) (xy 181.654184 -287.682812)
			(xy 181.680487 -287.641216) (xy 181.713122 -287.604379) (xy 181.751243 -287.573254) (xy 181.793864 -287.548647)
			(xy 181.83988 -287.531195) (xy 181.888099 -287.521351) (xy 181.937274 -287.51937) (xy 181.986129 -287.525302)
			(xy 182.0334 -287.538994) (xy 182.077862 -287.560092) (xy 182.118365 -287.588048) (xy 182.153858 -287.62214)
			(xy 182.183423 -287.661484) (xy 182.206294 -287.705061) (xy 182.221878 -287.751742) (xy 182.229773 -287.800319)
			(xy 182.230268 -287.824926) (xy 182.569116 -287.824926) (xy 182.573076 -287.775872) (xy 182.584853 -287.728088)
			(xy 182.604144 -287.682812) (xy 182.630447 -287.641216) (xy 182.663082 -287.604379) (xy 182.701203 -287.573254)
			(xy 182.743824 -287.548647) (xy 182.78984 -287.531195) (xy 182.838059 -287.521351) (xy 182.887234 -287.51937)
			(xy 182.936089 -287.525302) (xy 182.98336 -287.538994) (xy 183.027822 -287.560092) (xy 183.068325 -287.588048)
			(xy 183.103818 -287.62214) (xy 183.133383 -287.661484) (xy 183.156254 -287.705061) (xy 183.171838 -287.751742)
			(xy 183.179733 -287.800319) (xy 183.180228 -287.824926) (xy 183.519076 -287.824926) (xy 183.523036 -287.775872)
			(xy 183.534813 -287.728088) (xy 183.554104 -287.682812) (xy 183.580407 -287.641216) (xy 183.613042 -287.604379)
			(xy 183.651163 -287.573254) (xy 183.693784 -287.548647) (xy 183.7398 -287.531195) (xy 183.788019 -287.521351)
			(xy 183.837194 -287.51937) (xy 183.886049 -287.525302) (xy 183.93332 -287.538994) (xy 183.977782 -287.560092)
			(xy 184.018285 -287.588048) (xy 184.053778 -287.62214) (xy 184.083343 -287.661484) (xy 184.106214 -287.705061)
			(xy 184.121798 -287.751742) (xy 184.129693 -287.800319) (xy 184.130188 -287.824926) (xy 184.469036 -287.824926)
			(xy 184.472996 -287.775872) (xy 184.484773 -287.728088) (xy 184.504064 -287.682812) (xy 184.530367 -287.641216)
			(xy 184.563002 -287.604379) (xy 184.601123 -287.573254) (xy 184.643744 -287.548647) (xy 184.68976 -287.531195)
			(xy 184.737979 -287.521351) (xy 184.787154 -287.51937) (xy 184.836009 -287.525302) (xy 184.88328 -287.538994)
			(xy 184.927742 -287.560092) (xy 184.968245 -287.588048) (xy 185.003738 -287.62214) (xy 185.033303 -287.661484)
			(xy 185.056174 -287.705061) (xy 185.071758 -287.751742) (xy 185.079653 -287.800319) (xy 185.080148 -287.824926)
			(xy 185.079653 -287.849533) (xy 185.071758 -287.89811) (xy 185.056174 -287.944791) (xy 185.033303 -287.988368)
			(xy 185.003738 -288.027712) (xy 184.968245 -288.061804) (xy 184.927742 -288.08976) (xy 184.88328 -288.110858)
			(xy 184.836009 -288.12455) (xy 184.787154 -288.130482) (xy 184.737979 -288.128501) (xy 184.68976 -288.118657)
			(xy 184.643744 -288.101205) (xy 184.601123 -288.076598) (xy 184.563002 -288.045473) (xy 184.530367 -288.008636)
			(xy 184.504064 -287.96704) (xy 184.484773 -287.921764) (xy 184.472996 -287.87398) (xy 184.469036 -287.824926)
			(xy 184.130188 -287.824926) (xy 184.129693 -287.849533) (xy 184.121798 -287.89811) (xy 184.106214 -287.944791)
			(xy 184.083343 -287.988368) (xy 184.053778 -288.027712) (xy 184.018285 -288.061804) (xy 183.977782 -288.08976)
			(xy 183.93332 -288.110858) (xy 183.886049 -288.12455) (xy 183.837194 -288.130482) (xy 183.788019 -288.128501)
			(xy 183.7398 -288.118657) (xy 183.693784 -288.101205) (xy 183.651163 -288.076598) (xy 183.613042 -288.045473)
			(xy 183.580407 -288.008636) (xy 183.554104 -287.96704) (xy 183.534813 -287.921764) (xy 183.523036 -287.87398)
			(xy 183.519076 -287.824926) (xy 183.180228 -287.824926) (xy 183.179733 -287.849533) (xy 183.171838 -287.89811)
			(xy 183.156254 -287.944791) (xy 183.133383 -287.988368) (xy 183.103818 -288.027712) (xy 183.068325 -288.061804)
			(xy 183.027822 -288.08976) (xy 182.98336 -288.110858) (xy 182.936089 -288.12455) (xy 182.887234 -288.130482)
			(xy 182.838059 -288.128501) (xy 182.78984 -288.118657) (xy 182.743824 -288.101205) (xy 182.701203 -288.076598)
			(xy 182.663082 -288.045473) (xy 182.630447 -288.008636) (xy 182.604144 -287.96704) (xy 182.584853 -287.921764)
			(xy 182.573076 -287.87398) (xy 182.569116 -287.824926) (xy 182.230268 -287.824926) (xy 182.229773 -287.849533)
			(xy 182.221878 -287.89811) (xy 182.206294 -287.944791) (xy 182.183423 -287.988368) (xy 182.153858 -288.027712)
			(xy 182.118365 -288.061804) (xy 182.077862 -288.08976) (xy 182.0334 -288.110858) (xy 181.986129 -288.12455)
			(xy 181.937274 -288.130482) (xy 181.888099 -288.128501) (xy 181.83988 -288.118657) (xy 181.793864 -288.101205)
			(xy 181.751243 -288.076598) (xy 181.713122 -288.045473) (xy 181.680487 -288.008636) (xy 181.654184 -287.96704)
			(xy 181.634893 -287.921764) (xy 181.623116 -287.87398) (xy 181.619156 -287.824926) (xy 181.280308 -287.824926)
			(xy 181.279813 -287.849533) (xy 181.271918 -287.89811) (xy 181.256334 -287.944791) (xy 181.233463 -287.988368)
			(xy 181.203898 -288.027712) (xy 181.168405 -288.061804) (xy 181.127902 -288.08976) (xy 181.08344 -288.110858)
			(xy 181.036169 -288.12455) (xy 180.987314 -288.130482) (xy 180.938139 -288.128501) (xy 180.88992 -288.118657)
			(xy 180.843904 -288.101205) (xy 180.801283 -288.076598) (xy 180.763162 -288.045473) (xy 180.730527 -288.008636)
			(xy 180.704224 -287.96704) (xy 180.684933 -287.921764) (xy 180.673156 -287.87398) (xy 180.669196 -287.824926)
			(xy 180.330348 -287.824926) (xy 180.329853 -287.849533) (xy 180.321958 -287.89811) (xy 180.306374 -287.944791)
			(xy 180.283503 -287.988368) (xy 180.253938 -288.027712) (xy 180.218445 -288.061804) (xy 180.177942 -288.08976)
			(xy 180.13348 -288.110858) (xy 180.086209 -288.12455) (xy 180.037354 -288.130482) (xy 179.988179 -288.128501)
			(xy 179.93996 -288.118657) (xy 179.893944 -288.101205) (xy 179.851323 -288.076598) (xy 179.813202 -288.045473)
			(xy 179.780567 -288.008636) (xy 179.754264 -287.96704) (xy 179.734973 -287.921764) (xy 179.723196 -287.87398)
			(xy 179.719236 -287.824926) (xy 179.380388 -287.824926) (xy 179.379893 -287.849533) (xy 179.371998 -287.89811)
			(xy 179.356414 -287.944791) (xy 179.333543 -287.988368) (xy 179.303978 -288.027712) (xy 179.268485 -288.061804)
			(xy 179.227982 -288.08976) (xy 179.18352 -288.110858) (xy 179.136249 -288.12455) (xy 179.087394 -288.130482)
			(xy 179.038219 -288.128501) (xy 178.99 -288.118657) (xy 178.943984 -288.101205) (xy 178.901363 -288.076598)
			(xy 178.863242 -288.045473) (xy 178.830607 -288.008636) (xy 178.804304 -287.96704) (xy 178.785013 -287.921764)
			(xy 178.773236 -287.87398) (xy 178.769276 -287.824926) (xy 178.430174 -287.824926) (xy 178.429679 -287.849533)
			(xy 178.421784 -287.89811) (xy 178.4062 -287.944791) (xy 178.383329 -287.988368) (xy 178.353764 -288.027712)
			(xy 178.318271 -288.061804) (xy 178.277768 -288.08976) (xy 178.233306 -288.110858) (xy 178.186035 -288.12455)
			(xy 178.13718 -288.130482) (xy 178.088005 -288.128501) (xy 178.039786 -288.118657) (xy 177.99377 -288.101205)
			(xy 177.951149 -288.076598) (xy 177.913028 -288.045473) (xy 177.880393 -288.008636) (xy 177.85409 -287.96704)
			(xy 177.834799 -287.921764) (xy 177.823022 -287.87398) (xy 177.819062 -287.824926) (xy 177.480214 -287.824926)
			(xy 177.479719 -287.849533) (xy 177.471824 -287.89811) (xy 177.45624 -287.944791) (xy 177.433369 -287.988368)
			(xy 177.403804 -288.027712) (xy 177.368311 -288.061804) (xy 177.327808 -288.08976) (xy 177.283346 -288.110858)
			(xy 177.236075 -288.12455) (xy 177.18722 -288.130482) (xy 177.138045 -288.128501) (xy 177.089826 -288.118657)
			(xy 177.04381 -288.101205) (xy 177.001189 -288.076598) (xy 176.963068 -288.045473) (xy 176.930433 -288.008636)
			(xy 176.90413 -287.96704) (xy 176.884839 -287.921764) (xy 176.873062 -287.87398) (xy 176.869102 -287.824926)
			(xy 176.521281 -287.824926) (xy 176.521864 -287.826672) (xy 176.529759 -287.875249) (xy 176.530254 -287.899856)
			(xy 176.529759 -287.924463) (xy 176.521864 -287.97304) (xy 176.50628 -288.019721) (xy 176.483409 -288.063298)
			(xy 176.453844 -288.102642) (xy 176.418351 -288.136734) (xy 176.377848 -288.16469) (xy 176.333386 -288.185788)
			(xy 176.286115 -288.19948) (xy 176.23726 -288.205412) (xy 176.188085 -288.203431) (xy 176.139866 -288.193587)
			(xy 176.09385 -288.176135) (xy 176.051229 -288.151528) (xy 176.013108 -288.120403) (xy 175.980473 -288.083566)
			(xy 175.95417 -288.04197) (xy 175.934879 -287.996694) (xy 175.923102 -287.94891) (xy 175.919142 -287.899856)
			(xy 174.580986 -287.899856) (xy 174.578816 -287.902744) (xy 174.543323 -287.936836) (xy 174.50282 -287.964792)
			(xy 174.458358 -287.98589) (xy 174.411087 -287.999582) (xy 174.362232 -288.005514) (xy 174.313057 -288.003533)
			(xy 174.264838 -287.993689) (xy 174.218822 -287.976237) (xy 174.176201 -287.95163) (xy 174.13808 -287.920505)
			(xy 174.105445 -287.883668) (xy 174.079142 -287.842072) (xy 174.059851 -287.796796) (xy 174.048074 -287.749012)
			(xy 174.044114 -287.699958) (xy 173.653722 -287.699958) (xy 173.6564 -287.705061) (xy 173.671984 -287.751742)
			(xy 173.679879 -287.800319) (xy 173.680374 -287.824926) (xy 173.679879 -287.849533) (xy 173.671984 -287.89811)
			(xy 173.6564 -287.944791) (xy 173.633529 -287.988368) (xy 173.603964 -288.027712) (xy 173.568471 -288.061804)
			(xy 173.527968 -288.08976) (xy 173.483506 -288.110858) (xy 173.436235 -288.12455) (xy 173.38738 -288.130482)
			(xy 173.338205 -288.128501) (xy 173.289986 -288.118657) (xy 173.24397 -288.101205) (xy 173.201349 -288.076598)
			(xy 173.163228 -288.045473) (xy 173.130593 -288.008636) (xy 173.10429 -287.96704) (xy 173.084999 -287.921764)
			(xy 173.073222 -287.87398) (xy 173.069262 -287.824926) (xy 172.73016 -287.824926) (xy 172.729665 -287.849533)
			(xy 172.72177 -287.89811) (xy 172.706186 -287.944791) (xy 172.683315 -287.988368) (xy 172.65375 -288.027712)
			(xy 172.618257 -288.061804) (xy 172.577754 -288.08976) (xy 172.533292 -288.110858) (xy 172.486021 -288.12455)
			(xy 172.437166 -288.130482) (xy 172.387991 -288.128501) (xy 172.339772 -288.118657) (xy 172.293756 -288.101205)
			(xy 172.251135 -288.076598) (xy 172.213014 -288.045473) (xy 172.180379 -288.008636) (xy 172.154076 -287.96704)
			(xy 172.134785 -287.921764) (xy 172.123008 -287.87398) (xy 172.119048 -287.824926) (xy 171.7802 -287.824926)
			(xy 171.779705 -287.849533) (xy 171.77181 -287.89811) (xy 171.756226 -287.944791) (xy 171.733355 -287.988368)
			(xy 171.70379 -288.027712) (xy 171.668297 -288.061804) (xy 171.627794 -288.08976) (xy 171.583332 -288.110858)
			(xy 171.536061 -288.12455) (xy 171.487206 -288.130482) (xy 171.438031 -288.128501) (xy 171.389812 -288.118657)
			(xy 171.343796 -288.101205) (xy 171.301175 -288.076598) (xy 171.263054 -288.045473) (xy 171.230419 -288.008636)
			(xy 171.204116 -287.96704) (xy 171.184825 -287.921764) (xy 171.173048 -287.87398) (xy 171.169088 -287.824926)
			(xy 170.83024 -287.824926) (xy 170.829745 -287.849533) (xy 170.82185 -287.89811) (xy 170.806266 -287.944791)
			(xy 170.783395 -287.988368) (xy 170.75383 -288.027712) (xy 170.718337 -288.061804) (xy 170.677834 -288.08976)
			(xy 170.633372 -288.110858) (xy 170.586101 -288.12455) (xy 170.537246 -288.130482) (xy 170.488071 -288.128501)
			(xy 170.439852 -288.118657) (xy 170.393836 -288.101205) (xy 170.351215 -288.076598) (xy 170.313094 -288.045473)
			(xy 170.280459 -288.008636) (xy 170.254156 -287.96704) (xy 170.234865 -287.921764) (xy 170.223088 -287.87398)
			(xy 170.219128 -287.824926) (xy 169.88028 -287.824926) (xy 169.879785 -287.849533) (xy 169.87189 -287.89811)
			(xy 169.856306 -287.944791) (xy 169.833435 -287.988368) (xy 169.80387 -288.027712) (xy 169.768377 -288.061804)
			(xy 169.727874 -288.08976) (xy 169.683412 -288.110858) (xy 169.636141 -288.12455) (xy 169.587286 -288.130482)
			(xy 169.538111 -288.128501) (xy 169.489892 -288.118657) (xy 169.443876 -288.101205) (xy 169.401255 -288.076598)
			(xy 169.363134 -288.045473) (xy 169.330499 -288.008636) (xy 169.304196 -287.96704) (xy 169.284905 -287.921764)
			(xy 169.273128 -287.87398) (xy 169.269168 -287.824926) (xy 168.93032 -287.824926) (xy 168.929825 -287.849533)
			(xy 168.92193 -287.89811) (xy 168.906346 -287.944791) (xy 168.883475 -287.988368) (xy 168.85391 -288.027712)
			(xy 168.818417 -288.061804) (xy 168.777914 -288.08976) (xy 168.733452 -288.110858) (xy 168.686181 -288.12455)
			(xy 168.637326 -288.130482) (xy 168.588151 -288.128501) (xy 168.539932 -288.118657) (xy 168.493916 -288.101205)
			(xy 168.451295 -288.076598) (xy 168.413174 -288.045473) (xy 168.380539 -288.008636) (xy 168.354236 -287.96704)
			(xy 168.334945 -287.921764) (xy 168.323168 -287.87398) (xy 168.319208 -287.824926) (xy 167.98036 -287.824926)
			(xy 167.979865 -287.849533) (xy 167.97197 -287.89811) (xy 167.956386 -287.944791) (xy 167.933515 -287.988368)
			(xy 167.90395 -288.027712) (xy 167.868457 -288.061804) (xy 167.827954 -288.08976) (xy 167.783492 -288.110858)
			(xy 167.736221 -288.12455) (xy 167.687366 -288.130482) (xy 167.638191 -288.128501) (xy 167.589972 -288.118657)
			(xy 167.543956 -288.101205) (xy 167.501335 -288.076598) (xy 167.463214 -288.045473) (xy 167.430579 -288.008636)
			(xy 167.404276 -287.96704) (xy 167.384985 -287.921764) (xy 167.373208 -287.87398) (xy 167.369248 -287.824926)
			(xy 167.0304 -287.824926) (xy 167.029905 -287.849533) (xy 167.02201 -287.89811) (xy 167.006426 -287.944791)
			(xy 166.983555 -287.988368) (xy 166.95399 -288.027712) (xy 166.918497 -288.061804) (xy 166.877994 -288.08976)
			(xy 166.833532 -288.110858) (xy 166.786261 -288.12455) (xy 166.737406 -288.130482) (xy 166.688231 -288.128501)
			(xy 166.640012 -288.118657) (xy 166.593996 -288.101205) (xy 166.551375 -288.076598) (xy 166.513254 -288.045473)
			(xy 166.480619 -288.008636) (xy 166.454316 -287.96704) (xy 166.435025 -287.921764) (xy 166.423248 -287.87398)
			(xy 166.419288 -287.824926) (xy 166.080186 -287.824926) (xy 166.079691 -287.849533) (xy 166.071796 -287.89811)
			(xy 166.056212 -287.944791) (xy 166.033341 -287.988368) (xy 166.003776 -288.027712) (xy 165.968283 -288.061804)
			(xy 165.92778 -288.08976) (xy 165.883318 -288.110858) (xy 165.836047 -288.12455) (xy 165.787192 -288.130482)
			(xy 165.738017 -288.128501) (xy 165.689798 -288.118657) (xy 165.643782 -288.101205) (xy 165.601161 -288.076598)
			(xy 165.56304 -288.045473) (xy 165.530405 -288.008636) (xy 165.504102 -287.96704) (xy 165.484811 -287.921764)
			(xy 165.473034 -287.87398) (xy 165.469074 -287.824926) (xy 165.130226 -287.824926) (xy 165.129731 -287.849533)
			(xy 165.121836 -287.89811) (xy 165.106252 -287.944791) (xy 165.083381 -287.988368) (xy 165.053816 -288.027712)
			(xy 165.018323 -288.061804) (xy 164.97782 -288.08976) (xy 164.933358 -288.110858) (xy 164.886087 -288.12455)
			(xy 164.837232 -288.130482) (xy 164.788057 -288.128501) (xy 164.739838 -288.118657) (xy 164.693822 -288.101205)
			(xy 164.651201 -288.076598) (xy 164.61308 -288.045473) (xy 164.580445 -288.008636) (xy 164.554142 -287.96704)
			(xy 164.534851 -287.921764) (xy 164.523074 -287.87398) (xy 164.519114 -287.824926) (xy 164.180266 -287.824926)
			(xy 164.179771 -287.849533) (xy 164.171876 -287.89811) (xy 164.156292 -287.944791) (xy 164.133421 -287.988368)
			(xy 164.103856 -288.027712) (xy 164.068363 -288.061804) (xy 164.02786 -288.08976) (xy 163.983398 -288.110858)
			(xy 163.936127 -288.12455) (xy 163.887272 -288.130482) (xy 163.838097 -288.128501) (xy 163.789878 -288.118657)
			(xy 163.743862 -288.101205) (xy 163.701241 -288.076598) (xy 163.66312 -288.045473) (xy 163.630485 -288.008636)
			(xy 163.604182 -287.96704) (xy 163.584891 -287.921764) (xy 163.573114 -287.87398) (xy 163.569154 -287.824926)
			(xy 163.230306 -287.824926) (xy 163.229811 -287.849533) (xy 163.221916 -287.89811) (xy 163.206332 -287.944791)
			(xy 163.183461 -287.988368) (xy 163.153896 -288.027712) (xy 163.118403 -288.061804) (xy 163.0779 -288.08976)
			(xy 163.033438 -288.110858) (xy 162.986167 -288.12455) (xy 162.937312 -288.130482) (xy 162.888137 -288.128501)
			(xy 162.839918 -288.118657) (xy 162.793902 -288.101205) (xy 162.751281 -288.076598) (xy 162.71316 -288.045473)
			(xy 162.680525 -288.008636) (xy 162.654222 -287.96704) (xy 162.634931 -287.921764) (xy 162.623154 -287.87398)
			(xy 162.619194 -287.824926) (xy 162.280346 -287.824926) (xy 162.279851 -287.849533) (xy 162.271956 -287.89811)
			(xy 162.256372 -287.944791) (xy 162.233501 -287.988368) (xy 162.203936 -288.027712) (xy 162.168443 -288.061804)
			(xy 162.12794 -288.08976) (xy 162.083478 -288.110858) (xy 162.036207 -288.12455) (xy 161.987352 -288.130482)
			(xy 161.938177 -288.128501) (xy 161.889958 -288.118657) (xy 161.843942 -288.101205) (xy 161.801321 -288.076598)
			(xy 161.7632 -288.045473) (xy 161.730565 -288.008636) (xy 161.704262 -287.96704) (xy 161.684971 -287.921764)
			(xy 161.673194 -287.87398) (xy 161.669234 -287.824926) (xy 161.330386 -287.824926) (xy 161.329891 -287.849533)
			(xy 161.321996 -287.89811) (xy 161.306412 -287.944791) (xy 161.283541 -287.988368) (xy 161.253976 -288.027712)
			(xy 161.218483 -288.061804) (xy 161.17798 -288.08976) (xy 161.133518 -288.110858) (xy 161.086247 -288.12455)
			(xy 161.037392 -288.130482) (xy 160.988217 -288.128501) (xy 160.939998 -288.118657) (xy 160.893982 -288.101205)
			(xy 160.851361 -288.076598) (xy 160.81324 -288.045473) (xy 160.780605 -288.008636) (xy 160.754302 -287.96704)
			(xy 160.735011 -287.921764) (xy 160.723234 -287.87398) (xy 160.719274 -287.824926) (xy 158.640018 -287.824926)
			(xy 159.052006 -288.236914) (xy 159.05226 -288.236914) (xy 159.068783 -288.254049) (xy 159.09685 -288.292493)
			(xy 159.118613 -288.334825) (xy 159.133545 -288.380021) (xy 159.141286 -288.426987) (xy 159.141922 -288.450782)
			(xy 159.141922 -288.451798) (xy 159.14243 -288.470086) (xy 159.16707 -288.47199) (xy 159.215306 -288.482737)
			(xy 159.261181 -288.501111) (xy 159.303498 -288.526635) (xy 159.341152 -288.558641) (xy 159.373159 -288.596293)
			(xy 159.398684 -288.638609) (xy 159.41706 -288.684484) (xy 159.427808 -288.732719) (xy 159.429704 -288.75736)
			(xy 159.449516 -288.757868) (xy 159.450024 -288.757868) (xy 159.473717 -288.758562) (xy 159.520464 -288.766395)
			(xy 159.565439 -288.781357) (xy 159.607562 -288.803089) (xy 159.645821 -288.831069) (xy 159.662876 -288.84753)
			(xy 159.662876 -288.847784) (xy 159.68091 -288.865818) (xy 159.688311 -288.872657) (xy 159.70691 -288.880377)
			(xy 159.716978 -288.880804) (xy 159.723074 -288.880804) (xy 159.733093 -288.880359) (xy 159.751609 -288.872698)
			(xy 159.765782 -288.858534) (xy 159.773453 -288.840023) (xy 159.773874 -288.830004) (xy 159.773874 -288.82594)
			(xy 159.773112 -288.82213) (xy 159.771424 -288.810392) (xy 159.76964 -288.786744) (xy 159.769556 -288.774886)
			(xy 159.770078 -288.749631) (xy 159.778391 -288.699809) (xy 159.794792 -288.652035) (xy 159.818833 -288.607612)
			(xy 159.849857 -288.567752) (xy 159.887019 -288.533542) (xy 159.929305 -288.505916) (xy 159.975561 -288.485626)
			(xy 160.024526 -288.473226) (xy 160.074864 -288.469055) (xy 160.125202 -288.473226) (xy 160.174167 -288.485626)
			(xy 160.220423 -288.505916) (xy 160.262709 -288.533542) (xy 160.299871 -288.567752) (xy 160.330895 -288.607612)
			(xy 160.354936 -288.652035) (xy 160.371337 -288.699809) (xy 160.37965 -288.749631) (xy 160.380172 -288.774886)
			(xy 160.380172 -288.778188) (xy 160.380502 -288.788238) (xy 160.388117 -288.806835) (xy 160.394904 -288.814256)
			(xy 160.44545 -288.865818) (xy 160.452924 -288.872667) (xy 160.471643 -288.880404) (xy 160.481772 -288.880804)
			(xy 160.61817 -288.880804) (xy 160.628309 -288.880454) (xy 160.647044 -288.872708) (xy 160.654492 -288.865818)
			(xy 160.705038 -288.814256) (xy 160.711739 -288.80678) (xy 160.719325 -288.788217) (xy 160.71977 -288.778188)
			(xy 160.71977 -288.774886) (xy 160.720292 -288.749631) (xy 160.728605 -288.699809) (xy 160.745006 -288.652035)
			(xy 160.769047 -288.607612) (xy 160.800071 -288.567752) (xy 160.837233 -288.533542) (xy 160.879519 -288.505916)
			(xy 160.925775 -288.485626) (xy 160.97474 -288.473226) (xy 161.025078 -288.469055) (xy 161.075416 -288.473226)
			(xy 161.124381 -288.485626) (xy 161.170637 -288.505916) (xy 161.212923 -288.533542) (xy 161.250085 -288.567752)
			(xy 161.281109 -288.607612) (xy 161.30515 -288.652035) (xy 161.321551 -288.699809) (xy 161.329864 -288.749631)
			(xy 161.330386 -288.774886) (xy 161.330386 -288.778188) (xy 161.330712 -288.788238) (xy 161.338329 -288.806835)
			(xy 161.345118 -288.814256) (xy 161.395664 -288.865818) (xy 161.403134 -288.872673) (xy 161.421856 -288.880406)
			(xy 161.431986 -288.880804) (xy 161.56813 -288.880804) (xy 161.578267 -288.880433) (xy 161.597002 -288.872702)
			(xy 161.604452 -288.865818) (xy 161.654998 -288.814256) (xy 161.661707 -288.806787) (xy 161.669286 -288.788218)
			(xy 161.66973 -288.778188) (xy 161.66973 -288.774886) (xy 161.670252 -288.749631) (xy 161.678565 -288.699809)
			(xy 161.694966 -288.652035) (xy 161.719007 -288.607612) (xy 161.750031 -288.567752) (xy 161.787193 -288.533542)
			(xy 161.829479 -288.505916) (xy 161.875735 -288.485626) (xy 161.9247 -288.473226) (xy 161.975038 -288.469055)
			(xy 162.025376 -288.473226) (xy 162.074341 -288.485626) (xy 162.120597 -288.505916) (xy 162.162883 -288.533542)
			(xy 162.200045 -288.567752) (xy 162.231069 -288.607612) (xy 162.25511 -288.652035) (xy 162.271511 -288.699809)
			(xy 162.279824 -288.749631) (xy 162.280346 -288.774886) (xy 162.280346 -288.778188) (xy 162.280683 -288.788237)
			(xy 162.288294 -288.806833) (xy 162.295078 -288.814256) (xy 162.345624 -288.865818) (xy 162.353073 -288.8727)
			(xy 162.371811 -288.880417) (xy 162.381946 -288.880804) (xy 162.51809 -288.880804) (xy 162.52823 -288.880465)
			(xy 162.546965 -288.872711) (xy 162.554412 -288.865818) (xy 162.604958 -288.814256) (xy 162.611661 -288.806782)
			(xy 162.619245 -288.788217) (xy 162.61969 -288.778188) (xy 162.61969 -288.774886) (xy 162.620212 -288.749631)
			(xy 162.628525 -288.699809) (xy 162.644926 -288.652035) (xy 162.668967 -288.607612) (xy 162.699991 -288.567752)
			(xy 162.737153 -288.533542) (xy 162.779439 -288.505916) (xy 162.825695 -288.485626) (xy 162.87466 -288.473226)
			(xy 162.924998 -288.469055) (xy 162.975336 -288.473226) (xy 163.024301 -288.485626) (xy 163.070557 -288.505916)
			(xy 163.112843 -288.533542) (xy 163.150005 -288.567752) (xy 163.181029 -288.607612) (xy 163.20507 -288.652035)
			(xy 163.221471 -288.699809) (xy 163.229784 -288.749631) (xy 163.230306 -288.774886) (xy 163.230306 -288.778188)
			(xy 163.230654 -288.788236) (xy 163.238258 -288.806831) (xy 163.245038 -288.814256) (xy 163.295584 -288.865818)
			(xy 163.303047 -288.872682) (xy 163.321775 -288.88041) (xy 163.331906 -288.880804) (xy 163.46805 -288.880804)
			(xy 163.478188 -288.880443) (xy 163.496923 -288.872705) (xy 163.504372 -288.865818) (xy 163.554918 -288.814256)
			(xy 163.561616 -288.806778) (xy 163.569204 -288.788216) (xy 163.56965 -288.778188) (xy 163.56965 -288.774886)
			(xy 163.570172 -288.749631) (xy 163.578485 -288.699809) (xy 163.594886 -288.652035) (xy 163.618927 -288.607612)
			(xy 163.649951 -288.567752) (xy 163.687113 -288.533542) (xy 163.729399 -288.505916) (xy 163.775655 -288.485626)
			(xy 163.82462 -288.473226) (xy 163.874958 -288.469055) (xy 163.925296 -288.473226) (xy 163.974261 -288.485626)
			(xy 164.020517 -288.505916) (xy 164.062803 -288.533542) (xy 164.099965 -288.567752) (xy 164.130989 -288.607612)
			(xy 164.15503 -288.652035) (xy 164.171431 -288.699809) (xy 164.179744 -288.749631) (xy 164.180266 -288.774886)
			(xy 164.519114 -288.774886) (xy 164.523074 -288.725832) (xy 164.534851 -288.678048) (xy 164.554142 -288.632772)
			(xy 164.580445 -288.591176) (xy 164.61308 -288.554339) (xy 164.651201 -288.523214) (xy 164.693822 -288.498607)
			(xy 164.739838 -288.481155) (xy 164.788057 -288.471311) (xy 164.837232 -288.46933) (xy 164.886087 -288.475262)
			(xy 164.933358 -288.488954) (xy 164.97782 -288.510052) (xy 165.018323 -288.538008) (xy 165.053816 -288.5721)
			(xy 165.083381 -288.611444) (xy 165.106252 -288.655021) (xy 165.121836 -288.701702) (xy 165.129731 -288.750279)
			(xy 165.130226 -288.774886) (xy 165.469074 -288.774886) (xy 165.473034 -288.725832) (xy 165.484811 -288.678048)
			(xy 165.504102 -288.632772) (xy 165.530405 -288.591176) (xy 165.56304 -288.554339) (xy 165.601161 -288.523214)
			(xy 165.643782 -288.498607) (xy 165.689798 -288.481155) (xy 165.738017 -288.471311) (xy 165.787192 -288.46933)
			(xy 165.836047 -288.475262) (xy 165.883318 -288.488954) (xy 165.92778 -288.510052) (xy 165.968283 -288.538008)
			(xy 166.003776 -288.5721) (xy 166.033341 -288.611444) (xy 166.056212 -288.655021) (xy 166.071796 -288.701702)
			(xy 166.079691 -288.750279) (xy 166.080186 -288.774886) (xy 166.419288 -288.774886) (xy 166.423248 -288.725832)
			(xy 166.435025 -288.678048) (xy 166.454316 -288.632772) (xy 166.480619 -288.591176) (xy 166.513254 -288.554339)
			(xy 166.551375 -288.523214) (xy 166.593996 -288.498607) (xy 166.640012 -288.481155) (xy 166.688231 -288.471311)
			(xy 166.737406 -288.46933) (xy 166.786261 -288.475262) (xy 166.833532 -288.488954) (xy 166.877994 -288.510052)
			(xy 166.918497 -288.538008) (xy 166.95399 -288.5721) (xy 166.983555 -288.611444) (xy 167.006426 -288.655021)
			(xy 167.02201 -288.701702) (xy 167.029905 -288.750279) (xy 167.0304 -288.774886) (xy 167.369248 -288.774886)
			(xy 167.373208 -288.725832) (xy 167.384985 -288.678048) (xy 167.404276 -288.632772) (xy 167.430579 -288.591176)
			(xy 167.463214 -288.554339) (xy 167.501335 -288.523214) (xy 167.543956 -288.498607) (xy 167.589972 -288.481155)
			(xy 167.638191 -288.471311) (xy 167.687366 -288.46933) (xy 167.736221 -288.475262) (xy 167.783492 -288.488954)
			(xy 167.827954 -288.510052) (xy 167.868457 -288.538008) (xy 167.90395 -288.5721) (xy 167.933515 -288.611444)
			(xy 167.956386 -288.655021) (xy 167.97197 -288.701702) (xy 167.979865 -288.750279) (xy 167.98036 -288.774886)
			(xy 168.319208 -288.774886) (xy 168.323168 -288.725832) (xy 168.334945 -288.678048) (xy 168.354236 -288.632772)
			(xy 168.380539 -288.591176) (xy 168.413174 -288.554339) (xy 168.451295 -288.523214) (xy 168.493916 -288.498607)
			(xy 168.539932 -288.481155) (xy 168.588151 -288.471311) (xy 168.637326 -288.46933) (xy 168.686181 -288.475262)
			(xy 168.733452 -288.488954) (xy 168.777914 -288.510052) (xy 168.818417 -288.538008) (xy 168.85391 -288.5721)
			(xy 168.883475 -288.611444) (xy 168.906346 -288.655021) (xy 168.92193 -288.701702) (xy 168.929825 -288.750279)
			(xy 168.93032 -288.774886) (xy 169.269168 -288.774886) (xy 169.273128 -288.725832) (xy 169.284905 -288.678048)
			(xy 169.304196 -288.632772) (xy 169.330499 -288.591176) (xy 169.363134 -288.554339) (xy 169.401255 -288.523214)
			(xy 169.443876 -288.498607) (xy 169.489892 -288.481155) (xy 169.538111 -288.471311) (xy 169.587286 -288.46933)
			(xy 169.636141 -288.475262) (xy 169.683412 -288.488954) (xy 169.727874 -288.510052) (xy 169.768377 -288.538008)
			(xy 169.80387 -288.5721) (xy 169.833435 -288.611444) (xy 169.856306 -288.655021) (xy 169.87189 -288.701702)
			(xy 169.879785 -288.750279) (xy 169.88028 -288.774886) (xy 170.219128 -288.774886) (xy 170.223088 -288.725832)
			(xy 170.234865 -288.678048) (xy 170.254156 -288.632772) (xy 170.280459 -288.591176) (xy 170.313094 -288.554339)
			(xy 170.351215 -288.523214) (xy 170.393836 -288.498607) (xy 170.439852 -288.481155) (xy 170.488071 -288.471311)
			(xy 170.537246 -288.46933) (xy 170.586101 -288.475262) (xy 170.633372 -288.488954) (xy 170.677834 -288.510052)
			(xy 170.718337 -288.538008) (xy 170.75383 -288.5721) (xy 170.783395 -288.611444) (xy 170.806266 -288.655021)
			(xy 170.82185 -288.701702) (xy 170.829745 -288.750279) (xy 170.83024 -288.774886) (xy 171.169088 -288.774886)
			(xy 171.173048 -288.725832) (xy 171.184825 -288.678048) (xy 171.204116 -288.632772) (xy 171.230419 -288.591176)
			(xy 171.263054 -288.554339) (xy 171.301175 -288.523214) (xy 171.343796 -288.498607) (xy 171.389812 -288.481155)
			(xy 171.438031 -288.471311) (xy 171.487206 -288.46933) (xy 171.536061 -288.475262) (xy 171.583332 -288.488954)
			(xy 171.627794 -288.510052) (xy 171.668297 -288.538008) (xy 171.70379 -288.5721) (xy 171.733355 -288.611444)
			(xy 171.756226 -288.655021) (xy 171.77181 -288.701702) (xy 171.779705 -288.750279) (xy 171.7802 -288.774886)
			(xy 172.119048 -288.774886) (xy 172.123008 -288.725832) (xy 172.134785 -288.678048) (xy 172.154076 -288.632772)
			(xy 172.180379 -288.591176) (xy 172.213014 -288.554339) (xy 172.251135 -288.523214) (xy 172.293756 -288.498607)
			(xy 172.339772 -288.481155) (xy 172.387991 -288.471311) (xy 172.437166 -288.46933) (xy 172.486021 -288.475262)
			(xy 172.533292 -288.488954) (xy 172.577754 -288.510052) (xy 172.618257 -288.538008) (xy 172.65375 -288.5721)
			(xy 172.683315 -288.611444) (xy 172.706186 -288.655021) (xy 172.72177 -288.701702) (xy 172.729665 -288.750279)
			(xy 172.73016 -288.774886) (xy 173.069262 -288.774886) (xy 173.073222 -288.725832) (xy 173.084999 -288.678048)
			(xy 173.10429 -288.632772) (xy 173.130593 -288.591176) (xy 173.163228 -288.554339) (xy 173.201349 -288.523214)
			(xy 173.24397 -288.498607) (xy 173.289986 -288.481155) (xy 173.338205 -288.471311) (xy 173.38738 -288.46933)
			(xy 173.436235 -288.475262) (xy 173.483506 -288.488954) (xy 173.527968 -288.510052) (xy 173.568471 -288.538008)
			(xy 173.603964 -288.5721) (xy 173.633529 -288.611444) (xy 173.6564 -288.655021) (xy 173.671984 -288.701702)
			(xy 173.679879 -288.750279) (xy 173.680374 -288.774886) (xy 174.019222 -288.774886) (xy 174.023182 -288.725832)
			(xy 174.034959 -288.678048) (xy 174.05425 -288.632772) (xy 174.080553 -288.591176) (xy 174.113188 -288.554339)
			(xy 174.151309 -288.523214) (xy 174.19393 -288.498607) (xy 174.239946 -288.481155) (xy 174.288165 -288.471311)
			(xy 174.33734 -288.46933) (xy 174.386195 -288.475262) (xy 174.433466 -288.488954) (xy 174.477928 -288.510052)
			(xy 174.518431 -288.538008) (xy 174.553924 -288.5721) (xy 174.583489 -288.611444) (xy 174.60636 -288.655021)
			(xy 174.621944 -288.701702) (xy 174.629839 -288.750279) (xy 174.630334 -288.774886) (xy 175.919142 -288.774886)
			(xy 175.923102 -288.725832) (xy 175.934879 -288.678048) (xy 175.95417 -288.632772) (xy 175.980473 -288.591176)
			(xy 176.013108 -288.554339) (xy 176.051229 -288.523214) (xy 176.09385 -288.498607) (xy 176.139866 -288.481155)
			(xy 176.188085 -288.471311) (xy 176.23726 -288.46933) (xy 176.286115 -288.475262) (xy 176.333386 -288.488954)
			(xy 176.377848 -288.510052) (xy 176.418351 -288.538008) (xy 176.453844 -288.5721) (xy 176.483409 -288.611444)
			(xy 176.50628 -288.655021) (xy 176.521864 -288.701702) (xy 176.529759 -288.750279) (xy 176.530254 -288.774886)
			(xy 176.869102 -288.774886) (xy 176.873062 -288.725832) (xy 176.884839 -288.678048) (xy 176.90413 -288.632772)
			(xy 176.930433 -288.591176) (xy 176.963068 -288.554339) (xy 177.001189 -288.523214) (xy 177.04381 -288.498607)
			(xy 177.089826 -288.481155) (xy 177.138045 -288.471311) (xy 177.18722 -288.46933) (xy 177.236075 -288.475262)
			(xy 177.283346 -288.488954) (xy 177.327808 -288.510052) (xy 177.368311 -288.538008) (xy 177.403804 -288.5721)
			(xy 177.433369 -288.611444) (xy 177.45624 -288.655021) (xy 177.471824 -288.701702) (xy 177.479719 -288.750279)
			(xy 177.480214 -288.774886) (xy 177.819062 -288.774886) (xy 177.823022 -288.725832) (xy 177.834799 -288.678048)
			(xy 177.85409 -288.632772) (xy 177.880393 -288.591176) (xy 177.913028 -288.554339) (xy 177.951149 -288.523214)
			(xy 177.99377 -288.498607) (xy 178.039786 -288.481155) (xy 178.088005 -288.471311) (xy 178.13718 -288.46933)
			(xy 178.186035 -288.475262) (xy 178.233306 -288.488954) (xy 178.277768 -288.510052) (xy 178.318271 -288.538008)
			(xy 178.353764 -288.5721) (xy 178.383329 -288.611444) (xy 178.4062 -288.655021) (xy 178.421784 -288.701702)
			(xy 178.429679 -288.750279) (xy 178.430174 -288.774886) (xy 178.769276 -288.774886) (xy 178.773236 -288.725832)
			(xy 178.785013 -288.678048) (xy 178.804304 -288.632772) (xy 178.830607 -288.591176) (xy 178.863242 -288.554339)
			(xy 178.901363 -288.523214) (xy 178.943984 -288.498607) (xy 178.99 -288.481155) (xy 179.038219 -288.471311)
			(xy 179.087394 -288.46933) (xy 179.136249 -288.475262) (xy 179.18352 -288.488954) (xy 179.227982 -288.510052)
			(xy 179.268485 -288.538008) (xy 179.303978 -288.5721) (xy 179.333543 -288.611444) (xy 179.356414 -288.655021)
			(xy 179.371998 -288.701702) (xy 179.379893 -288.750279) (xy 179.380388 -288.774886) (xy 179.719236 -288.774886)
			(xy 179.723196 -288.725832) (xy 179.734973 -288.678048) (xy 179.754264 -288.632772) (xy 179.780567 -288.591176)
			(xy 179.813202 -288.554339) (xy 179.851323 -288.523214) (xy 179.893944 -288.498607) (xy 179.93996 -288.481155)
			(xy 179.988179 -288.471311) (xy 180.037354 -288.46933) (xy 180.086209 -288.475262) (xy 180.13348 -288.488954)
			(xy 180.177942 -288.510052) (xy 180.218445 -288.538008) (xy 180.253938 -288.5721) (xy 180.283503 -288.611444)
			(xy 180.306374 -288.655021) (xy 180.321958 -288.701702) (xy 180.329853 -288.750279) (xy 180.330348 -288.774886)
			(xy 180.669196 -288.774886) (xy 180.673156 -288.725832) (xy 180.684933 -288.678048) (xy 180.704224 -288.632772)
			(xy 180.730527 -288.591176) (xy 180.763162 -288.554339) (xy 180.801283 -288.523214) (xy 180.843904 -288.498607)
			(xy 180.88992 -288.481155) (xy 180.938139 -288.471311) (xy 180.987314 -288.46933) (xy 181.036169 -288.475262)
			(xy 181.08344 -288.488954) (xy 181.127902 -288.510052) (xy 181.168405 -288.538008) (xy 181.203898 -288.5721)
			(xy 181.233463 -288.611444) (xy 181.256334 -288.655021) (xy 181.271918 -288.701702) (xy 181.279813 -288.750279)
			(xy 181.280308 -288.774886) (xy 181.619156 -288.774886) (xy 181.623116 -288.725832) (xy 181.634893 -288.678048)
			(xy 181.654184 -288.632772) (xy 181.680487 -288.591176) (xy 181.713122 -288.554339) (xy 181.751243 -288.523214)
			(xy 181.793864 -288.498607) (xy 181.83988 -288.481155) (xy 181.888099 -288.471311) (xy 181.937274 -288.46933)
			(xy 181.986129 -288.475262) (xy 182.0334 -288.488954) (xy 182.077862 -288.510052) (xy 182.118365 -288.538008)
			(xy 182.153858 -288.5721) (xy 182.183423 -288.611444) (xy 182.206294 -288.655021) (xy 182.221878 -288.701702)
			(xy 182.229773 -288.750279) (xy 182.230268 -288.774886) (xy 182.569116 -288.774886) (xy 182.573076 -288.725832)
			(xy 182.584853 -288.678048) (xy 182.604144 -288.632772) (xy 182.630447 -288.591176) (xy 182.663082 -288.554339)
			(xy 182.701203 -288.523214) (xy 182.743824 -288.498607) (xy 182.78984 -288.481155) (xy 182.838059 -288.471311)
			(xy 182.887234 -288.46933) (xy 182.936089 -288.475262) (xy 182.98336 -288.488954) (xy 183.027822 -288.510052)
			(xy 183.068325 -288.538008) (xy 183.103818 -288.5721) (xy 183.133383 -288.611444) (xy 183.156254 -288.655021)
			(xy 183.171838 -288.701702) (xy 183.179733 -288.750279) (xy 183.180228 -288.774886) (xy 183.519076 -288.774886)
			(xy 183.523036 -288.725832) (xy 183.534813 -288.678048) (xy 183.554104 -288.632772) (xy 183.580407 -288.591176)
			(xy 183.613042 -288.554339) (xy 183.651163 -288.523214) (xy 183.693784 -288.498607) (xy 183.7398 -288.481155)
			(xy 183.788019 -288.471311) (xy 183.837194 -288.46933) (xy 183.886049 -288.475262) (xy 183.93332 -288.488954)
			(xy 183.977782 -288.510052) (xy 184.018285 -288.538008) (xy 184.053778 -288.5721) (xy 184.083343 -288.611444)
			(xy 184.106214 -288.655021) (xy 184.121798 -288.701702) (xy 184.129693 -288.750279) (xy 184.130188 -288.774886)
			(xy 184.469036 -288.774886) (xy 184.472996 -288.725832) (xy 184.484773 -288.678048) (xy 184.504064 -288.632772)
			(xy 184.530367 -288.591176) (xy 184.563002 -288.554339) (xy 184.601123 -288.523214) (xy 184.643744 -288.498607)
			(xy 184.68976 -288.481155) (xy 184.737979 -288.471311) (xy 184.787154 -288.46933) (xy 184.836009 -288.475262)
			(xy 184.88328 -288.488954) (xy 184.927742 -288.510052) (xy 184.968245 -288.538008) (xy 185.003738 -288.5721)
			(xy 185.033303 -288.611444) (xy 185.056174 -288.655021) (xy 185.071758 -288.701702) (xy 185.079653 -288.750279)
			(xy 185.080148 -288.774886) (xy 185.079653 -288.799493) (xy 185.071758 -288.84807) (xy 185.056174 -288.894751)
			(xy 185.033303 -288.938328) (xy 185.003738 -288.977672) (xy 184.968245 -289.011764) (xy 184.927742 -289.03972)
			(xy 184.88328 -289.060818) (xy 184.836009 -289.07451) (xy 184.787154 -289.080442) (xy 184.737979 -289.078461)
			(xy 184.68976 -289.068617) (xy 184.643744 -289.051165) (xy 184.601123 -289.026558) (xy 184.563002 -288.995433)
			(xy 184.530367 -288.958596) (xy 184.504064 -288.917) (xy 184.484773 -288.871724) (xy 184.472996 -288.82394)
			(xy 184.469036 -288.774886) (xy 184.130188 -288.774886) (xy 184.129693 -288.799493) (xy 184.121798 -288.84807)
			(xy 184.106214 -288.894751) (xy 184.083343 -288.938328) (xy 184.053778 -288.977672) (xy 184.018285 -289.011764)
			(xy 183.977782 -289.03972) (xy 183.93332 -289.060818) (xy 183.886049 -289.07451) (xy 183.837194 -289.080442)
			(xy 183.788019 -289.078461) (xy 183.7398 -289.068617) (xy 183.693784 -289.051165) (xy 183.651163 -289.026558)
			(xy 183.613042 -288.995433) (xy 183.580407 -288.958596) (xy 183.554104 -288.917) (xy 183.534813 -288.871724)
			(xy 183.523036 -288.82394) (xy 183.519076 -288.774886) (xy 183.180228 -288.774886) (xy 183.179733 -288.799493)
			(xy 183.171838 -288.84807) (xy 183.156254 -288.894751) (xy 183.133383 -288.938328) (xy 183.103818 -288.977672)
			(xy 183.068325 -289.011764) (xy 183.027822 -289.03972) (xy 182.98336 -289.060818) (xy 182.936089 -289.07451)
			(xy 182.887234 -289.080442) (xy 182.838059 -289.078461) (xy 182.78984 -289.068617) (xy 182.743824 -289.051165)
			(xy 182.701203 -289.026558) (xy 182.663082 -288.995433) (xy 182.630447 -288.958596) (xy 182.604144 -288.917)
			(xy 182.584853 -288.871724) (xy 182.573076 -288.82394) (xy 182.569116 -288.774886) (xy 182.230268 -288.774886)
			(xy 182.229773 -288.799493) (xy 182.221878 -288.84807) (xy 182.206294 -288.894751) (xy 182.183423 -288.938328)
			(xy 182.153858 -288.977672) (xy 182.118365 -289.011764) (xy 182.077862 -289.03972) (xy 182.0334 -289.060818)
			(xy 181.986129 -289.07451) (xy 181.937274 -289.080442) (xy 181.888099 -289.078461) (xy 181.83988 -289.068617)
			(xy 181.793864 -289.051165) (xy 181.751243 -289.026558) (xy 181.713122 -288.995433) (xy 181.680487 -288.958596)
			(xy 181.654184 -288.917) (xy 181.634893 -288.871724) (xy 181.623116 -288.82394) (xy 181.619156 -288.774886)
			(xy 181.280308 -288.774886) (xy 181.279813 -288.799493) (xy 181.271918 -288.84807) (xy 181.256334 -288.894751)
			(xy 181.233463 -288.938328) (xy 181.203898 -288.977672) (xy 181.168405 -289.011764) (xy 181.127902 -289.03972)
			(xy 181.08344 -289.060818) (xy 181.036169 -289.07451) (xy 180.987314 -289.080442) (xy 180.938139 -289.078461)
			(xy 180.88992 -289.068617) (xy 180.843904 -289.051165) (xy 180.801283 -289.026558) (xy 180.763162 -288.995433)
			(xy 180.730527 -288.958596) (xy 180.704224 -288.917) (xy 180.684933 -288.871724) (xy 180.673156 -288.82394)
			(xy 180.669196 -288.774886) (xy 180.330348 -288.774886) (xy 180.329853 -288.799493) (xy 180.321958 -288.84807)
			(xy 180.306374 -288.894751) (xy 180.283503 -288.938328) (xy 180.253938 -288.977672) (xy 180.218445 -289.011764)
			(xy 180.177942 -289.03972) (xy 180.13348 -289.060818) (xy 180.086209 -289.07451) (xy 180.037354 -289.080442)
			(xy 179.988179 -289.078461) (xy 179.93996 -289.068617) (xy 179.893944 -289.051165) (xy 179.851323 -289.026558)
			(xy 179.813202 -288.995433) (xy 179.780567 -288.958596) (xy 179.754264 -288.917) (xy 179.734973 -288.871724)
			(xy 179.723196 -288.82394) (xy 179.719236 -288.774886) (xy 179.380388 -288.774886) (xy 179.379893 -288.799493)
			(xy 179.371998 -288.84807) (xy 179.356414 -288.894751) (xy 179.333543 -288.938328) (xy 179.303978 -288.977672)
			(xy 179.268485 -289.011764) (xy 179.227982 -289.03972) (xy 179.18352 -289.060818) (xy 179.136249 -289.07451)
			(xy 179.087394 -289.080442) (xy 179.038219 -289.078461) (xy 178.99 -289.068617) (xy 178.943984 -289.051165)
			(xy 178.901363 -289.026558) (xy 178.863242 -288.995433) (xy 178.830607 -288.958596) (xy 178.804304 -288.917)
			(xy 178.785013 -288.871724) (xy 178.773236 -288.82394) (xy 178.769276 -288.774886) (xy 178.430174 -288.774886)
			(xy 178.429679 -288.799493) (xy 178.421784 -288.84807) (xy 178.4062 -288.894751) (xy 178.383329 -288.938328)
			(xy 178.353764 -288.977672) (xy 178.318271 -289.011764) (xy 178.277768 -289.03972) (xy 178.233306 -289.060818)
			(xy 178.186035 -289.07451) (xy 178.13718 -289.080442) (xy 178.088005 -289.078461) (xy 178.039786 -289.068617)
			(xy 177.99377 -289.051165) (xy 177.951149 -289.026558) (xy 177.913028 -288.995433) (xy 177.880393 -288.958596)
			(xy 177.85409 -288.917) (xy 177.834799 -288.871724) (xy 177.823022 -288.82394) (xy 177.819062 -288.774886)
			(xy 177.480214 -288.774886) (xy 177.479719 -288.799493) (xy 177.471824 -288.84807) (xy 177.45624 -288.894751)
			(xy 177.433369 -288.938328) (xy 177.403804 -288.977672) (xy 177.368311 -289.011764) (xy 177.327808 -289.03972)
			(xy 177.283346 -289.060818) (xy 177.236075 -289.07451) (xy 177.18722 -289.080442) (xy 177.138045 -289.078461)
			(xy 177.089826 -289.068617) (xy 177.04381 -289.051165) (xy 177.001189 -289.026558) (xy 176.963068 -288.995433)
			(xy 176.930433 -288.958596) (xy 176.90413 -288.917) (xy 176.884839 -288.871724) (xy 176.873062 -288.82394)
			(xy 176.869102 -288.774886) (xy 176.530254 -288.774886) (xy 176.529759 -288.799493) (xy 176.521864 -288.84807)
			(xy 176.50628 -288.894751) (xy 176.483409 -288.938328) (xy 176.453844 -288.977672) (xy 176.418351 -289.011764)
			(xy 176.377848 -289.03972) (xy 176.333386 -289.060818) (xy 176.286115 -289.07451) (xy 176.23726 -289.080442)
			(xy 176.188085 -289.078461) (xy 176.139866 -289.068617) (xy 176.09385 -289.051165) (xy 176.051229 -289.026558)
			(xy 176.013108 -288.995433) (xy 175.980473 -288.958596) (xy 175.95417 -288.917) (xy 175.934879 -288.871724)
			(xy 175.923102 -288.82394) (xy 175.919142 -288.774886) (xy 174.630334 -288.774886) (xy 174.629839 -288.799493)
			(xy 174.621944 -288.84807) (xy 174.60636 -288.894751) (xy 174.583489 -288.938328) (xy 174.553924 -288.977672)
			(xy 174.518431 -289.011764) (xy 174.477928 -289.03972) (xy 174.433466 -289.060818) (xy 174.386195 -289.07451)
			(xy 174.33734 -289.080442) (xy 174.288165 -289.078461) (xy 174.239946 -289.068617) (xy 174.19393 -289.051165)
			(xy 174.151309 -289.026558) (xy 174.113188 -288.995433) (xy 174.080553 -288.958596) (xy 174.05425 -288.917)
			(xy 174.034959 -288.871724) (xy 174.023182 -288.82394) (xy 174.019222 -288.774886) (xy 173.680374 -288.774886)
			(xy 173.679879 -288.799493) (xy 173.671984 -288.84807) (xy 173.6564 -288.894751) (xy 173.633529 -288.938328)
			(xy 173.603964 -288.977672) (xy 173.568471 -289.011764) (xy 173.527968 -289.03972) (xy 173.483506 -289.060818)
			(xy 173.436235 -289.07451) (xy 173.38738 -289.080442) (xy 173.338205 -289.078461) (xy 173.289986 -289.068617)
			(xy 173.24397 -289.051165) (xy 173.201349 -289.026558) (xy 173.163228 -288.995433) (xy 173.130593 -288.958596)
			(xy 173.10429 -288.917) (xy 173.084999 -288.871724) (xy 173.073222 -288.82394) (xy 173.069262 -288.774886)
			(xy 172.73016 -288.774886) (xy 172.729665 -288.799493) (xy 172.72177 -288.84807) (xy 172.706186 -288.894751)
			(xy 172.683315 -288.938328) (xy 172.65375 -288.977672) (xy 172.618257 -289.011764) (xy 172.577754 -289.03972)
			(xy 172.533292 -289.060818) (xy 172.486021 -289.07451) (xy 172.437166 -289.080442) (xy 172.387991 -289.078461)
			(xy 172.339772 -289.068617) (xy 172.293756 -289.051165) (xy 172.251135 -289.026558) (xy 172.213014 -288.995433)
			(xy 172.180379 -288.958596) (xy 172.154076 -288.917) (xy 172.134785 -288.871724) (xy 172.123008 -288.82394)
			(xy 172.119048 -288.774886) (xy 171.7802 -288.774886) (xy 171.779705 -288.799493) (xy 171.77181 -288.84807)
			(xy 171.756226 -288.894751) (xy 171.733355 -288.938328) (xy 171.70379 -288.977672) (xy 171.668297 -289.011764)
			(xy 171.627794 -289.03972) (xy 171.583332 -289.060818) (xy 171.536061 -289.07451) (xy 171.487206 -289.080442)
			(xy 171.438031 -289.078461) (xy 171.389812 -289.068617) (xy 171.343796 -289.051165) (xy 171.301175 -289.026558)
			(xy 171.263054 -288.995433) (xy 171.230419 -288.958596) (xy 171.204116 -288.917) (xy 171.184825 -288.871724)
			(xy 171.173048 -288.82394) (xy 171.169088 -288.774886) (xy 170.83024 -288.774886) (xy 170.829745 -288.799493)
			(xy 170.82185 -288.84807) (xy 170.806266 -288.894751) (xy 170.783395 -288.938328) (xy 170.75383 -288.977672)
			(xy 170.718337 -289.011764) (xy 170.677834 -289.03972) (xy 170.633372 -289.060818) (xy 170.586101 -289.07451)
			(xy 170.537246 -289.080442) (xy 170.488071 -289.078461) (xy 170.439852 -289.068617) (xy 170.393836 -289.051165)
			(xy 170.351215 -289.026558) (xy 170.313094 -288.995433) (xy 170.280459 -288.958596) (xy 170.254156 -288.917)
			(xy 170.234865 -288.871724) (xy 170.223088 -288.82394) (xy 170.219128 -288.774886) (xy 169.88028 -288.774886)
			(xy 169.879785 -288.799493) (xy 169.87189 -288.84807) (xy 169.856306 -288.894751) (xy 169.833435 -288.938328)
			(xy 169.80387 -288.977672) (xy 169.768377 -289.011764) (xy 169.727874 -289.03972) (xy 169.683412 -289.060818)
			(xy 169.636141 -289.07451) (xy 169.587286 -289.080442) (xy 169.538111 -289.078461) (xy 169.489892 -289.068617)
			(xy 169.443876 -289.051165) (xy 169.401255 -289.026558) (xy 169.363134 -288.995433) (xy 169.330499 -288.958596)
			(xy 169.304196 -288.917) (xy 169.284905 -288.871724) (xy 169.273128 -288.82394) (xy 169.269168 -288.774886)
			(xy 168.93032 -288.774886) (xy 168.929825 -288.799493) (xy 168.92193 -288.84807) (xy 168.906346 -288.894751)
			(xy 168.883475 -288.938328) (xy 168.85391 -288.977672) (xy 168.818417 -289.011764) (xy 168.777914 -289.03972)
			(xy 168.733452 -289.060818) (xy 168.686181 -289.07451) (xy 168.637326 -289.080442) (xy 168.588151 -289.078461)
			(xy 168.539932 -289.068617) (xy 168.493916 -289.051165) (xy 168.451295 -289.026558) (xy 168.413174 -288.995433)
			(xy 168.380539 -288.958596) (xy 168.354236 -288.917) (xy 168.334945 -288.871724) (xy 168.323168 -288.82394)
			(xy 168.319208 -288.774886) (xy 167.98036 -288.774886) (xy 167.979865 -288.799493) (xy 167.97197 -288.84807)
			(xy 167.956386 -288.894751) (xy 167.933515 -288.938328) (xy 167.90395 -288.977672) (xy 167.868457 -289.011764)
			(xy 167.827954 -289.03972) (xy 167.783492 -289.060818) (xy 167.736221 -289.07451) (xy 167.687366 -289.080442)
			(xy 167.638191 -289.078461) (xy 167.589972 -289.068617) (xy 167.543956 -289.051165) (xy 167.501335 -289.026558)
			(xy 167.463214 -288.995433) (xy 167.430579 -288.958596) (xy 167.404276 -288.917) (xy 167.384985 -288.871724)
			(xy 167.373208 -288.82394) (xy 167.369248 -288.774886) (xy 167.0304 -288.774886) (xy 167.029905 -288.799493)
			(xy 167.02201 -288.84807) (xy 167.006426 -288.894751) (xy 166.983555 -288.938328) (xy 166.95399 -288.977672)
			(xy 166.918497 -289.011764) (xy 166.877994 -289.03972) (xy 166.833532 -289.060818) (xy 166.786261 -289.07451)
			(xy 166.737406 -289.080442) (xy 166.688231 -289.078461) (xy 166.640012 -289.068617) (xy 166.593996 -289.051165)
			(xy 166.551375 -289.026558) (xy 166.513254 -288.995433) (xy 166.480619 -288.958596) (xy 166.454316 -288.917)
			(xy 166.435025 -288.871724) (xy 166.423248 -288.82394) (xy 166.419288 -288.774886) (xy 166.080186 -288.774886)
			(xy 166.079691 -288.799493) (xy 166.071796 -288.84807) (xy 166.056212 -288.894751) (xy 166.033341 -288.938328)
			(xy 166.003776 -288.977672) (xy 165.968283 -289.011764) (xy 165.92778 -289.03972) (xy 165.883318 -289.060818)
			(xy 165.836047 -289.07451) (xy 165.787192 -289.080442) (xy 165.738017 -289.078461) (xy 165.689798 -289.068617)
			(xy 165.643782 -289.051165) (xy 165.601161 -289.026558) (xy 165.56304 -288.995433) (xy 165.530405 -288.958596)
			(xy 165.504102 -288.917) (xy 165.484811 -288.871724) (xy 165.473034 -288.82394) (xy 165.469074 -288.774886)
			(xy 165.130226 -288.774886) (xy 165.129731 -288.799493) (xy 165.121836 -288.84807) (xy 165.106252 -288.894751)
			(xy 165.083381 -288.938328) (xy 165.053816 -288.977672) (xy 165.018323 -289.011764) (xy 164.97782 -289.03972)
			(xy 164.933358 -289.060818) (xy 164.886087 -289.07451) (xy 164.837232 -289.080442) (xy 164.788057 -289.078461)
			(xy 164.739838 -289.068617) (xy 164.693822 -289.051165) (xy 164.651201 -289.026558) (xy 164.61308 -288.995433)
			(xy 164.580445 -288.958596) (xy 164.554142 -288.917) (xy 164.534851 -288.871724) (xy 164.523074 -288.82394)
			(xy 164.519114 -288.774886) (xy 164.180266 -288.774886) (xy 164.179838 -288.798107) (xy 164.172793 -288.844012)
			(xy 164.158878 -288.888321) (xy 164.138414 -288.930012) (xy 164.111874 -288.968124) (xy 164.079868 -289.001777)
			(xy 164.043136 -289.030196) (xy 164.02304 -289.04184) (xy 164.022786 -289.04184) (xy 164.014669 -289.046908)
			(xy 164.002662 -289.061793) (xy 163.999418 -289.070796) (xy 163.975288 -289.146996) (xy 163.976558 -289.165792)
			(xy 163.97859 -289.17011) (xy 163.979098 -289.171634) (xy 163.991639 -289.198115) (xy 164.007507 -289.254511)
			(xy 164.010594 -289.283648) (xy 164.011727 -289.300872) (xy 164.010584 -289.335372) (xy 164.008308 -289.352482)
			(xy 164.00018 -289.4076) (xy 163.999123 -289.417762) (xy 164.004252 -289.437523) (xy 164.016675 -289.453724)
			(xy 164.025326 -289.459162) (xy 164.045835 -289.471255) (xy 164.083133 -289.500844) (xy 164.115375 -289.535873)
			(xy 164.128958 -289.555428) (xy 164.1475 -289.549078) (xy 164.170298 -289.542472) (xy 164.217247 -289.535514)
			(xy 164.264707 -289.535899) (xy 164.311537 -289.543619) (xy 164.35661 -289.558486) (xy 164.398842 -289.580144)
			(xy 164.437217 -289.608071) (xy 164.454332 -289.624516) (xy 164.483796 -289.653726) (xy 164.488114 -289.658298)
			(xy 164.49421 -289.664394) (xy 164.537644 -289.621214) (xy 164.541454 -289.611308) (xy 164.551626 -289.587412)
			(xy 164.578823 -289.543174) (xy 164.613108 -289.504171) (xy 164.653493 -289.471525) (xy 164.698817 -289.446178)
			(xy 164.747773 -289.428858) (xy 164.798953 -289.420065) (xy 164.824918 -289.419538) (xy 164.850176 -289.419969)
			(xy 164.900003 -289.428286) (xy 164.947782 -289.444691) (xy 164.992209 -289.468736) (xy 165.032072 -289.499765)
			(xy 165.066285 -289.536932) (xy 165.093914 -289.579223) (xy 165.114205 -289.625485) (xy 165.126606 -289.674456)
			(xy 165.130778 -289.7248) (xy 165.130774 -289.724846) (xy 165.469074 -289.724846) (xy 165.473034 -289.675792)
			(xy 165.484811 -289.628008) (xy 165.504102 -289.582732) (xy 165.530405 -289.541136) (xy 165.56304 -289.504299)
			(xy 165.601161 -289.473174) (xy 165.643782 -289.448567) (xy 165.689798 -289.431115) (xy 165.738017 -289.421271)
			(xy 165.787192 -289.41929) (xy 165.836047 -289.425222) (xy 165.883318 -289.438914) (xy 165.92778 -289.460012)
			(xy 165.968283 -289.487968) (xy 166.003776 -289.52206) (xy 166.033341 -289.561404) (xy 166.056212 -289.604981)
			(xy 166.071796 -289.651662) (xy 166.079691 -289.700239) (xy 166.080186 -289.724846) (xy 166.419288 -289.724846)
			(xy 166.423248 -289.675792) (xy 166.435025 -289.628008) (xy 166.454316 -289.582732) (xy 166.480619 -289.541136)
			(xy 166.513254 -289.504299) (xy 166.551375 -289.473174) (xy 166.593996 -289.448567) (xy 166.640012 -289.431115)
			(xy 166.688231 -289.421271) (xy 166.737406 -289.41929) (xy 166.786261 -289.425222) (xy 166.833532 -289.438914)
			(xy 166.877994 -289.460012) (xy 166.918497 -289.487968) (xy 166.95399 -289.52206) (xy 166.983555 -289.561404)
			(xy 167.006426 -289.604981) (xy 167.02201 -289.651662) (xy 167.029905 -289.700239) (xy 167.0304 -289.724846)
			(xy 167.369248 -289.724846) (xy 167.373208 -289.675792) (xy 167.384985 -289.628008) (xy 167.404276 -289.582732)
			(xy 167.430579 -289.541136) (xy 167.463214 -289.504299) (xy 167.501335 -289.473174) (xy 167.543956 -289.448567)
			(xy 167.589972 -289.431115) (xy 167.638191 -289.421271) (xy 167.687366 -289.41929) (xy 167.736221 -289.425222)
			(xy 167.783492 -289.438914) (xy 167.827954 -289.460012) (xy 167.868457 -289.487968) (xy 167.90395 -289.52206)
			(xy 167.933515 -289.561404) (xy 167.956386 -289.604981) (xy 167.97197 -289.651662) (xy 167.979865 -289.700239)
			(xy 167.98036 -289.724846) (xy 168.319208 -289.724846) (xy 168.323168 -289.675792) (xy 168.334945 -289.628008)
			(xy 168.354236 -289.582732) (xy 168.380539 -289.541136) (xy 168.413174 -289.504299) (xy 168.451295 -289.473174)
			(xy 168.493916 -289.448567) (xy 168.539932 -289.431115) (xy 168.588151 -289.421271) (xy 168.637326 -289.41929)
			(xy 168.686181 -289.425222) (xy 168.733452 -289.438914) (xy 168.777914 -289.460012) (xy 168.818417 -289.487968)
			(xy 168.85391 -289.52206) (xy 168.883475 -289.561404) (xy 168.906346 -289.604981) (xy 168.92193 -289.651662)
			(xy 168.929825 -289.700239) (xy 168.93032 -289.724846) (xy 169.269168 -289.724846) (xy 169.273128 -289.675792)
			(xy 169.284905 -289.628008) (xy 169.304196 -289.582732) (xy 169.330499 -289.541136) (xy 169.363134 -289.504299)
			(xy 169.401255 -289.473174) (xy 169.443876 -289.448567) (xy 169.489892 -289.431115) (xy 169.538111 -289.421271)
			(xy 169.587286 -289.41929) (xy 169.636141 -289.425222) (xy 169.683412 -289.438914) (xy 169.727874 -289.460012)
			(xy 169.768377 -289.487968) (xy 169.80387 -289.52206) (xy 169.833435 -289.561404) (xy 169.856306 -289.604981)
			(xy 169.87189 -289.651662) (xy 169.879785 -289.700239) (xy 169.88028 -289.724846) (xy 170.219128 -289.724846)
			(xy 170.223088 -289.675792) (xy 170.234865 -289.628008) (xy 170.254156 -289.582732) (xy 170.280459 -289.541136)
			(xy 170.313094 -289.504299) (xy 170.351215 -289.473174) (xy 170.393836 -289.448567) (xy 170.439852 -289.431115)
			(xy 170.488071 -289.421271) (xy 170.537246 -289.41929) (xy 170.586101 -289.425222) (xy 170.633372 -289.438914)
			(xy 170.677834 -289.460012) (xy 170.718337 -289.487968) (xy 170.75383 -289.52206) (xy 170.783395 -289.561404)
			(xy 170.806266 -289.604981) (xy 170.82185 -289.651662) (xy 170.829745 -289.700239) (xy 170.83024 -289.724846)
			(xy 171.169088 -289.724846) (xy 171.173048 -289.675792) (xy 171.184825 -289.628008) (xy 171.204116 -289.582732)
			(xy 171.230419 -289.541136) (xy 171.263054 -289.504299) (xy 171.301175 -289.473174) (xy 171.343796 -289.448567)
			(xy 171.389812 -289.431115) (xy 171.438031 -289.421271) (xy 171.487206 -289.41929) (xy 171.536061 -289.425222)
			(xy 171.583332 -289.438914) (xy 171.627794 -289.460012) (xy 171.668297 -289.487968) (xy 171.70379 -289.52206)
			(xy 171.733355 -289.561404) (xy 171.756226 -289.604981) (xy 171.77181 -289.651662) (xy 171.779705 -289.700239)
			(xy 171.7802 -289.724846) (xy 172.119048 -289.724846) (xy 172.123008 -289.675792) (xy 172.134785 -289.628008)
			(xy 172.154076 -289.582732) (xy 172.180379 -289.541136) (xy 172.213014 -289.504299) (xy 172.251135 -289.473174)
			(xy 172.293756 -289.448567) (xy 172.339772 -289.431115) (xy 172.387991 -289.421271) (xy 172.437166 -289.41929)
			(xy 172.486021 -289.425222) (xy 172.533292 -289.438914) (xy 172.577754 -289.460012) (xy 172.618257 -289.487968)
			(xy 172.65375 -289.52206) (xy 172.683315 -289.561404) (xy 172.706186 -289.604981) (xy 172.72177 -289.651662)
			(xy 172.729665 -289.700239) (xy 172.73016 -289.724846) (xy 173.069262 -289.724846) (xy 173.073222 -289.675792)
			(xy 173.084999 -289.628008) (xy 173.10429 -289.582732) (xy 173.130593 -289.541136) (xy 173.163228 -289.504299)
			(xy 173.201349 -289.473174) (xy 173.24397 -289.448567) (xy 173.289986 -289.431115) (xy 173.338205 -289.421271)
			(xy 173.38738 -289.41929) (xy 173.436235 -289.425222) (xy 173.483506 -289.438914) (xy 173.527968 -289.460012)
			(xy 173.568471 -289.487968) (xy 173.603964 -289.52206) (xy 173.633529 -289.561404) (xy 173.6564 -289.604981)
			(xy 173.671984 -289.651662) (xy 173.679879 -289.700239) (xy 173.680374 -289.724846) (xy 174.019222 -289.724846)
			(xy 174.023182 -289.675792) (xy 174.034959 -289.628008) (xy 174.05425 -289.582732) (xy 174.080553 -289.541136)
			(xy 174.113188 -289.504299) (xy 174.151309 -289.473174) (xy 174.19393 -289.448567) (xy 174.239946 -289.431115)
			(xy 174.288165 -289.421271) (xy 174.33734 -289.41929) (xy 174.386195 -289.425222) (xy 174.433466 -289.438914)
			(xy 174.477928 -289.460012) (xy 174.518431 -289.487968) (xy 174.553924 -289.52206) (xy 174.583489 -289.561404)
			(xy 174.60636 -289.604981) (xy 174.621944 -289.651662) (xy 174.629839 -289.700239) (xy 174.630334 -289.724846)
			(xy 175.919142 -289.724846) (xy 175.923102 -289.675792) (xy 175.934879 -289.628008) (xy 175.95417 -289.582732)
			(xy 175.980473 -289.541136) (xy 176.013108 -289.504299) (xy 176.051229 -289.473174) (xy 176.09385 -289.448567)
			(xy 176.139866 -289.431115) (xy 176.188085 -289.421271) (xy 176.23726 -289.41929) (xy 176.286115 -289.425222)
			(xy 176.333386 -289.438914) (xy 176.377848 -289.460012) (xy 176.418351 -289.487968) (xy 176.453844 -289.52206)
			(xy 176.483409 -289.561404) (xy 176.50628 -289.604981) (xy 176.521864 -289.651662) (xy 176.529759 -289.700239)
			(xy 176.530254 -289.724846) (xy 176.869102 -289.724846) (xy 176.873062 -289.675792) (xy 176.884839 -289.628008)
			(xy 176.90413 -289.582732) (xy 176.930433 -289.541136) (xy 176.963068 -289.504299) (xy 177.001189 -289.473174)
			(xy 177.04381 -289.448567) (xy 177.089826 -289.431115) (xy 177.138045 -289.421271) (xy 177.18722 -289.41929)
			(xy 177.236075 -289.425222) (xy 177.283346 -289.438914) (xy 177.327808 -289.460012) (xy 177.368311 -289.487968)
			(xy 177.403804 -289.52206) (xy 177.433369 -289.561404) (xy 177.45624 -289.604981) (xy 177.471824 -289.651662)
			(xy 177.479719 -289.700239) (xy 177.480214 -289.724846) (xy 177.819062 -289.724846) (xy 177.823022 -289.675792)
			(xy 177.834799 -289.628008) (xy 177.85409 -289.582732) (xy 177.880393 -289.541136) (xy 177.913028 -289.504299)
			(xy 177.951149 -289.473174) (xy 177.99377 -289.448567) (xy 178.039786 -289.431115) (xy 178.088005 -289.421271)
			(xy 178.13718 -289.41929) (xy 178.186035 -289.425222) (xy 178.233306 -289.438914) (xy 178.277768 -289.460012)
			(xy 178.318271 -289.487968) (xy 178.353764 -289.52206) (xy 178.383329 -289.561404) (xy 178.4062 -289.604981)
			(xy 178.421784 -289.651662) (xy 178.429679 -289.700239) (xy 178.430174 -289.724846) (xy 178.769276 -289.724846)
			(xy 178.773236 -289.675792) (xy 178.785013 -289.628008) (xy 178.804304 -289.582732) (xy 178.830607 -289.541136)
			(xy 178.863242 -289.504299) (xy 178.901363 -289.473174) (xy 178.943984 -289.448567) (xy 178.99 -289.431115)
			(xy 179.038219 -289.421271) (xy 179.087394 -289.41929) (xy 179.136249 -289.425222) (xy 179.18352 -289.438914)
			(xy 179.227982 -289.460012) (xy 179.268485 -289.487968) (xy 179.303978 -289.52206) (xy 179.333543 -289.561404)
			(xy 179.356414 -289.604981) (xy 179.371998 -289.651662) (xy 179.379893 -289.700239) (xy 179.380388 -289.724846)
			(xy 179.719236 -289.724846) (xy 179.723196 -289.675792) (xy 179.734973 -289.628008) (xy 179.754264 -289.582732)
			(xy 179.780567 -289.541136) (xy 179.813202 -289.504299) (xy 179.851323 -289.473174) (xy 179.893944 -289.448567)
			(xy 179.93996 -289.431115) (xy 179.988179 -289.421271) (xy 180.037354 -289.41929) (xy 180.086209 -289.425222)
			(xy 180.13348 -289.438914) (xy 180.177942 -289.460012) (xy 180.218445 -289.487968) (xy 180.253938 -289.52206)
			(xy 180.283503 -289.561404) (xy 180.306374 -289.604981) (xy 180.321958 -289.651662) (xy 180.329853 -289.700239)
			(xy 180.330348 -289.724846) (xy 180.669196 -289.724846) (xy 180.673156 -289.675792) (xy 180.684933 -289.628008)
			(xy 180.704224 -289.582732) (xy 180.730527 -289.541136) (xy 180.763162 -289.504299) (xy 180.801283 -289.473174)
			(xy 180.843904 -289.448567) (xy 180.88992 -289.431115) (xy 180.938139 -289.421271) (xy 180.987314 -289.41929)
			(xy 181.036169 -289.425222) (xy 181.08344 -289.438914) (xy 181.127902 -289.460012) (xy 181.168405 -289.487968)
			(xy 181.203898 -289.52206) (xy 181.233463 -289.561404) (xy 181.256334 -289.604981) (xy 181.271918 -289.651662)
			(xy 181.279813 -289.700239) (xy 181.280308 -289.724846) (xy 181.619156 -289.724846) (xy 181.623116 -289.675792)
			(xy 181.634893 -289.628008) (xy 181.654184 -289.582732) (xy 181.680487 -289.541136) (xy 181.713122 -289.504299)
			(xy 181.751243 -289.473174) (xy 181.793864 -289.448567) (xy 181.83988 -289.431115) (xy 181.888099 -289.421271)
			(xy 181.937274 -289.41929) (xy 181.986129 -289.425222) (xy 182.0334 -289.438914) (xy 182.077862 -289.460012)
			(xy 182.118365 -289.487968) (xy 182.153858 -289.52206) (xy 182.183423 -289.561404) (xy 182.206294 -289.604981)
			(xy 182.221878 -289.651662) (xy 182.229773 -289.700239) (xy 182.230268 -289.724846) (xy 182.569116 -289.724846)
			(xy 182.573076 -289.675792) (xy 182.584853 -289.628008) (xy 182.604144 -289.582732) (xy 182.630447 -289.541136)
			(xy 182.663082 -289.504299) (xy 182.701203 -289.473174) (xy 182.743824 -289.448567) (xy 182.78984 -289.431115)
			(xy 182.838059 -289.421271) (xy 182.887234 -289.41929) (xy 182.936089 -289.425222) (xy 182.98336 -289.438914)
			(xy 183.027822 -289.460012) (xy 183.068325 -289.487968) (xy 183.103818 -289.52206) (xy 183.133383 -289.561404)
			(xy 183.156254 -289.604981) (xy 183.171838 -289.651662) (xy 183.179733 -289.700239) (xy 183.180228 -289.724846)
			(xy 183.519076 -289.724846) (xy 183.523036 -289.675792) (xy 183.534813 -289.628008) (xy 183.554104 -289.582732)
			(xy 183.580407 -289.541136) (xy 183.613042 -289.504299) (xy 183.651163 -289.473174) (xy 183.693784 -289.448567)
			(xy 183.7398 -289.431115) (xy 183.788019 -289.421271) (xy 183.837194 -289.41929) (xy 183.886049 -289.425222)
			(xy 183.93332 -289.438914) (xy 183.977782 -289.460012) (xy 184.018285 -289.487968) (xy 184.053778 -289.52206)
			(xy 184.083343 -289.561404) (xy 184.106214 -289.604981) (xy 184.121798 -289.651662) (xy 184.129693 -289.700239)
			(xy 184.130188 -289.724846) (xy 184.469036 -289.724846) (xy 184.472996 -289.675792) (xy 184.484773 -289.628008)
			(xy 184.504064 -289.582732) (xy 184.530367 -289.541136) (xy 184.563002 -289.504299) (xy 184.601123 -289.473174)
			(xy 184.643744 -289.448567) (xy 184.68976 -289.431115) (xy 184.737979 -289.421271) (xy 184.787154 -289.41929)
			(xy 184.836009 -289.425222) (xy 184.88328 -289.438914) (xy 184.927742 -289.460012) (xy 184.968245 -289.487968)
			(xy 185.003738 -289.52206) (xy 185.033303 -289.561404) (xy 185.056174 -289.604981) (xy 185.071758 -289.651662)
			(xy 185.079653 -289.700239) (xy 185.080148 -289.724846) (xy 185.079653 -289.749453) (xy 185.071758 -289.79803)
			(xy 185.056174 -289.844711) (xy 185.033303 -289.888288) (xy 185.003738 -289.927632) (xy 184.968245 -289.961724)
			(xy 184.927742 -289.98968) (xy 184.88328 -290.010778) (xy 184.836009 -290.02447) (xy 184.787154 -290.030402)
			(xy 184.737979 -290.028421) (xy 184.68976 -290.018577) (xy 184.643744 -290.001125) (xy 184.601123 -289.976518)
			(xy 184.563002 -289.945393) (xy 184.530367 -289.908556) (xy 184.504064 -289.86696) (xy 184.484773 -289.821684)
			(xy 184.472996 -289.7739) (xy 184.469036 -289.724846) (xy 184.130188 -289.724846) (xy 184.129693 -289.749453)
			(xy 184.121798 -289.79803) (xy 184.106214 -289.844711) (xy 184.083343 -289.888288) (xy 184.053778 -289.927632)
			(xy 184.018285 -289.961724) (xy 183.977782 -289.98968) (xy 183.93332 -290.010778) (xy 183.886049 -290.02447)
			(xy 183.837194 -290.030402) (xy 183.788019 -290.028421) (xy 183.7398 -290.018577) (xy 183.693784 -290.001125)
			(xy 183.651163 -289.976518) (xy 183.613042 -289.945393) (xy 183.580407 -289.908556) (xy 183.554104 -289.86696)
			(xy 183.534813 -289.821684) (xy 183.523036 -289.7739) (xy 183.519076 -289.724846) (xy 183.180228 -289.724846)
			(xy 183.179733 -289.749453) (xy 183.171838 -289.79803) (xy 183.156254 -289.844711) (xy 183.133383 -289.888288)
			(xy 183.103818 -289.927632) (xy 183.068325 -289.961724) (xy 183.027822 -289.98968) (xy 182.98336 -290.010778)
			(xy 182.936089 -290.02447) (xy 182.887234 -290.030402) (xy 182.838059 -290.028421) (xy 182.78984 -290.018577)
			(xy 182.743824 -290.001125) (xy 182.701203 -289.976518) (xy 182.663082 -289.945393) (xy 182.630447 -289.908556)
			(xy 182.604144 -289.86696) (xy 182.584853 -289.821684) (xy 182.573076 -289.7739) (xy 182.569116 -289.724846)
			(xy 182.230268 -289.724846) (xy 182.229773 -289.749453) (xy 182.221878 -289.79803) (xy 182.206294 -289.844711)
			(xy 182.183423 -289.888288) (xy 182.153858 -289.927632) (xy 182.118365 -289.961724) (xy 182.077862 -289.98968)
			(xy 182.0334 -290.010778) (xy 181.986129 -290.02447) (xy 181.937274 -290.030402) (xy 181.888099 -290.028421)
			(xy 181.83988 -290.018577) (xy 181.793864 -290.001125) (xy 181.751243 -289.976518) (xy 181.713122 -289.945393)
			(xy 181.680487 -289.908556) (xy 181.654184 -289.86696) (xy 181.634893 -289.821684) (xy 181.623116 -289.7739)
			(xy 181.619156 -289.724846) (xy 181.280308 -289.724846) (xy 181.279813 -289.749453) (xy 181.271918 -289.79803)
			(xy 181.256334 -289.844711) (xy 181.233463 -289.888288) (xy 181.203898 -289.927632) (xy 181.168405 -289.961724)
			(xy 181.127902 -289.98968) (xy 181.08344 -290.010778) (xy 181.036169 -290.02447) (xy 180.987314 -290.030402)
			(xy 180.938139 -290.028421) (xy 180.88992 -290.018577) (xy 180.843904 -290.001125) (xy 180.801283 -289.976518)
			(xy 180.763162 -289.945393) (xy 180.730527 -289.908556) (xy 180.704224 -289.86696) (xy 180.684933 -289.821684)
			(xy 180.673156 -289.7739) (xy 180.669196 -289.724846) (xy 180.330348 -289.724846) (xy 180.329853 -289.749453)
			(xy 180.321958 -289.79803) (xy 180.306374 -289.844711) (xy 180.283503 -289.888288) (xy 180.253938 -289.927632)
			(xy 180.218445 -289.961724) (xy 180.177942 -289.98968) (xy 180.13348 -290.010778) (xy 180.086209 -290.02447)
			(xy 180.037354 -290.030402) (xy 179.988179 -290.028421) (xy 179.93996 -290.018577) (xy 179.893944 -290.001125)
			(xy 179.851323 -289.976518) (xy 179.813202 -289.945393) (xy 179.780567 -289.908556) (xy 179.754264 -289.86696)
			(xy 179.734973 -289.821684) (xy 179.723196 -289.7739) (xy 179.719236 -289.724846) (xy 179.380388 -289.724846)
			(xy 179.379893 -289.749453) (xy 179.371998 -289.79803) (xy 179.356414 -289.844711) (xy 179.333543 -289.888288)
			(xy 179.303978 -289.927632) (xy 179.268485 -289.961724) (xy 179.227982 -289.98968) (xy 179.18352 -290.010778)
			(xy 179.136249 -290.02447) (xy 179.087394 -290.030402) (xy 179.038219 -290.028421) (xy 178.99 -290.018577)
			(xy 178.943984 -290.001125) (xy 178.901363 -289.976518) (xy 178.863242 -289.945393) (xy 178.830607 -289.908556)
			(xy 178.804304 -289.86696) (xy 178.785013 -289.821684) (xy 178.773236 -289.7739) (xy 178.769276 -289.724846)
			(xy 178.430174 -289.724846) (xy 178.429679 -289.749453) (xy 178.421784 -289.79803) (xy 178.4062 -289.844711)
			(xy 178.383329 -289.888288) (xy 178.353764 -289.927632) (xy 178.318271 -289.961724) (xy 178.277768 -289.98968)
			(xy 178.233306 -290.010778) (xy 178.186035 -290.02447) (xy 178.13718 -290.030402) (xy 178.088005 -290.028421)
			(xy 178.039786 -290.018577) (xy 177.99377 -290.001125) (xy 177.951149 -289.976518) (xy 177.913028 -289.945393)
			(xy 177.880393 -289.908556) (xy 177.85409 -289.86696) (xy 177.834799 -289.821684) (xy 177.823022 -289.7739)
			(xy 177.819062 -289.724846) (xy 177.480214 -289.724846) (xy 177.479719 -289.749453) (xy 177.471824 -289.79803)
			(xy 177.45624 -289.844711) (xy 177.433369 -289.888288) (xy 177.403804 -289.927632) (xy 177.368311 -289.961724)
			(xy 177.327808 -289.98968) (xy 177.283346 -290.010778) (xy 177.236075 -290.02447) (xy 177.18722 -290.030402)
			(xy 177.138045 -290.028421) (xy 177.089826 -290.018577) (xy 177.04381 -290.001125) (xy 177.001189 -289.976518)
			(xy 176.963068 -289.945393) (xy 176.930433 -289.908556) (xy 176.90413 -289.86696) (xy 176.884839 -289.821684)
			(xy 176.873062 -289.7739) (xy 176.869102 -289.724846) (xy 176.530254 -289.724846) (xy 176.529759 -289.749453)
			(xy 176.521864 -289.79803) (xy 176.50628 -289.844711) (xy 176.483409 -289.888288) (xy 176.453844 -289.927632)
			(xy 176.418351 -289.961724) (xy 176.377848 -289.98968) (xy 176.333386 -290.010778) (xy 176.286115 -290.02447)
			(xy 176.23726 -290.030402) (xy 176.188085 -290.028421) (xy 176.139866 -290.018577) (xy 176.09385 -290.001125)
			(xy 176.051229 -289.976518) (xy 176.013108 -289.945393) (xy 175.980473 -289.908556) (xy 175.95417 -289.86696)
			(xy 175.934879 -289.821684) (xy 175.923102 -289.7739) (xy 175.919142 -289.724846) (xy 174.630334 -289.724846)
			(xy 174.629839 -289.749453) (xy 174.621944 -289.79803) (xy 174.60636 -289.844711) (xy 174.583489 -289.888288)
			(xy 174.553924 -289.927632) (xy 174.518431 -289.961724) (xy 174.477928 -289.98968) (xy 174.433466 -290.010778)
			(xy 174.386195 -290.02447) (xy 174.33734 -290.030402) (xy 174.288165 -290.028421) (xy 174.239946 -290.018577)
			(xy 174.19393 -290.001125) (xy 174.151309 -289.976518) (xy 174.113188 -289.945393) (xy 174.080553 -289.908556)
			(xy 174.05425 -289.86696) (xy 174.034959 -289.821684) (xy 174.023182 -289.7739) (xy 174.019222 -289.724846)
			(xy 173.680374 -289.724846) (xy 173.679879 -289.749453) (xy 173.671984 -289.79803) (xy 173.6564 -289.844711)
			(xy 173.633529 -289.888288) (xy 173.603964 -289.927632) (xy 173.568471 -289.961724) (xy 173.527968 -289.98968)
			(xy 173.483506 -290.010778) (xy 173.436235 -290.02447) (xy 173.38738 -290.030402) (xy 173.338205 -290.028421)
			(xy 173.289986 -290.018577) (xy 173.24397 -290.001125) (xy 173.201349 -289.976518) (xy 173.163228 -289.945393)
			(xy 173.130593 -289.908556) (xy 173.10429 -289.86696) (xy 173.084999 -289.821684) (xy 173.073222 -289.7739)
			(xy 173.069262 -289.724846) (xy 172.73016 -289.724846) (xy 172.729665 -289.749453) (xy 172.72177 -289.79803)
			(xy 172.706186 -289.844711) (xy 172.683315 -289.888288) (xy 172.65375 -289.927632) (xy 172.618257 -289.961724)
			(xy 172.577754 -289.98968) (xy 172.533292 -290.010778) (xy 172.486021 -290.02447) (xy 172.437166 -290.030402)
			(xy 172.387991 -290.028421) (xy 172.339772 -290.018577) (xy 172.293756 -290.001125) (xy 172.251135 -289.976518)
			(xy 172.213014 -289.945393) (xy 172.180379 -289.908556) (xy 172.154076 -289.86696) (xy 172.134785 -289.821684)
			(xy 172.123008 -289.7739) (xy 172.119048 -289.724846) (xy 171.7802 -289.724846) (xy 171.779705 -289.749453)
			(xy 171.77181 -289.79803) (xy 171.756226 -289.844711) (xy 171.733355 -289.888288) (xy 171.70379 -289.927632)
			(xy 171.668297 -289.961724) (xy 171.627794 -289.98968) (xy 171.583332 -290.010778) (xy 171.536061 -290.02447)
			(xy 171.487206 -290.030402) (xy 171.438031 -290.028421) (xy 171.389812 -290.018577) (xy 171.343796 -290.001125)
			(xy 171.301175 -289.976518) (xy 171.263054 -289.945393) (xy 171.230419 -289.908556) (xy 171.204116 -289.86696)
			(xy 171.184825 -289.821684) (xy 171.173048 -289.7739) (xy 171.169088 -289.724846) (xy 170.83024 -289.724846)
			(xy 170.829745 -289.749453) (xy 170.82185 -289.79803) (xy 170.806266 -289.844711) (xy 170.783395 -289.888288)
			(xy 170.75383 -289.927632) (xy 170.718337 -289.961724) (xy 170.677834 -289.98968) (xy 170.633372 -290.010778)
			(xy 170.586101 -290.02447) (xy 170.537246 -290.030402) (xy 170.488071 -290.028421) (xy 170.439852 -290.018577)
			(xy 170.393836 -290.001125) (xy 170.351215 -289.976518) (xy 170.313094 -289.945393) (xy 170.280459 -289.908556)
			(xy 170.254156 -289.86696) (xy 170.234865 -289.821684) (xy 170.223088 -289.7739) (xy 170.219128 -289.724846)
			(xy 169.88028 -289.724846) (xy 169.879785 -289.749453) (xy 169.87189 -289.79803) (xy 169.856306 -289.844711)
			(xy 169.833435 -289.888288) (xy 169.80387 -289.927632) (xy 169.768377 -289.961724) (xy 169.727874 -289.98968)
			(xy 169.683412 -290.010778) (xy 169.636141 -290.02447) (xy 169.587286 -290.030402) (xy 169.538111 -290.028421)
			(xy 169.489892 -290.018577) (xy 169.443876 -290.001125) (xy 169.401255 -289.976518) (xy 169.363134 -289.945393)
			(xy 169.330499 -289.908556) (xy 169.304196 -289.86696) (xy 169.284905 -289.821684) (xy 169.273128 -289.7739)
			(xy 169.269168 -289.724846) (xy 168.93032 -289.724846) (xy 168.929825 -289.749453) (xy 168.92193 -289.79803)
			(xy 168.906346 -289.844711) (xy 168.883475 -289.888288) (xy 168.85391 -289.927632) (xy 168.818417 -289.961724)
			(xy 168.777914 -289.98968) (xy 168.733452 -290.010778) (xy 168.686181 -290.02447) (xy 168.637326 -290.030402)
			(xy 168.588151 -290.028421) (xy 168.539932 -290.018577) (xy 168.493916 -290.001125) (xy 168.451295 -289.976518)
			(xy 168.413174 -289.945393) (xy 168.380539 -289.908556) (xy 168.354236 -289.86696) (xy 168.334945 -289.821684)
			(xy 168.323168 -289.7739) (xy 168.319208 -289.724846) (xy 167.98036 -289.724846) (xy 167.979865 -289.749453)
			(xy 167.97197 -289.79803) (xy 167.956386 -289.844711) (xy 167.933515 -289.888288) (xy 167.90395 -289.927632)
			(xy 167.868457 -289.961724) (xy 167.827954 -289.98968) (xy 167.783492 -290.010778) (xy 167.736221 -290.02447)
			(xy 167.687366 -290.030402) (xy 167.638191 -290.028421) (xy 167.589972 -290.018577) (xy 167.543956 -290.001125)
			(xy 167.501335 -289.976518) (xy 167.463214 -289.945393) (xy 167.430579 -289.908556) (xy 167.404276 -289.86696)
			(xy 167.384985 -289.821684) (xy 167.373208 -289.7739) (xy 167.369248 -289.724846) (xy 167.0304 -289.724846)
			(xy 167.029905 -289.749453) (xy 167.02201 -289.79803) (xy 167.006426 -289.844711) (xy 166.983555 -289.888288)
			(xy 166.95399 -289.927632) (xy 166.918497 -289.961724) (xy 166.877994 -289.98968) (xy 166.833532 -290.010778)
			(xy 166.786261 -290.02447) (xy 166.737406 -290.030402) (xy 166.688231 -290.028421) (xy 166.640012 -290.018577)
			(xy 166.593996 -290.001125) (xy 166.551375 -289.976518) (xy 166.513254 -289.945393) (xy 166.480619 -289.908556)
			(xy 166.454316 -289.86696) (xy 166.435025 -289.821684) (xy 166.423248 -289.7739) (xy 166.419288 -289.724846)
			(xy 166.080186 -289.724846) (xy 166.079691 -289.749453) (xy 166.071796 -289.79803) (xy 166.056212 -289.844711)
			(xy 166.033341 -289.888288) (xy 166.003776 -289.927632) (xy 165.968283 -289.961724) (xy 165.92778 -289.98968)
			(xy 165.883318 -290.010778) (xy 165.836047 -290.02447) (xy 165.787192 -290.030402) (xy 165.738017 -290.028421)
			(xy 165.689798 -290.018577) (xy 165.643782 -290.001125) (xy 165.601161 -289.976518) (xy 165.56304 -289.945393)
			(xy 165.530405 -289.908556) (xy 165.504102 -289.86696) (xy 165.484811 -289.821684) (xy 165.473034 -289.7739)
			(xy 165.469074 -289.724846) (xy 165.130774 -289.724846) (xy 165.126606 -289.775144) (xy 165.114205 -289.824115)
			(xy 165.093914 -289.870377) (xy 165.066285 -289.912668) (xy 165.032072 -289.949835) (xy 164.992209 -289.980864)
			(xy 164.947782 -290.004909) (xy 164.900003 -290.021314) (xy 164.850176 -290.029631) (xy 164.824918 -290.030154)
			(xy 164.796081 -290.029476) (xy 164.73944 -290.0186) (xy 164.712396 -290.008564) (xy 164.712142 -290.008564)
			(xy 164.700398 -290.004562) (xy 164.675762 -290.007215) (xy 164.665152 -290.013644) (xy 164.595556 -290.060888)
			(xy 164.585552 -290.068426) (xy 164.573843 -290.090541) (xy 164.573204 -290.103052) (xy 164.573204 -290.2966)
			(xy 164.57382 -290.309117) (xy 164.585538 -290.331235) (xy 164.595556 -290.338764) (xy 164.665152 -290.386008)
			(xy 164.675819 -290.392269) (xy 164.700376 -290.394907) (xy 164.712142 -290.391088) (xy 164.712396 -290.391088)
			(xy 164.739443 -290.381066) (xy 164.796082 -290.370192) (xy 164.824918 -290.369498) (xy 164.850173 -290.370009)
			(xy 164.899993 -290.378325) (xy 164.947765 -290.394728) (xy 164.992187 -290.41877) (xy 165.032045 -290.449795)
			(xy 165.066253 -290.486957) (xy 165.093878 -290.529243) (xy 165.114167 -290.575498) (xy 165.126566 -290.624463)
			(xy 165.130737 -290.6748) (xy 165.130737 -290.674806) (xy 165.469074 -290.674806) (xy 165.473034 -290.625752)
			(xy 165.484811 -290.577968) (xy 165.504102 -290.532692) (xy 165.530405 -290.491096) (xy 165.56304 -290.454259)
			(xy 165.601161 -290.423134) (xy 165.643782 -290.398527) (xy 165.689798 -290.381075) (xy 165.738017 -290.371231)
			(xy 165.787192 -290.36925) (xy 165.836047 -290.375182) (xy 165.883318 -290.388874) (xy 165.92778 -290.409972)
			(xy 165.968283 -290.437928) (xy 166.003776 -290.47202) (xy 166.033341 -290.511364) (xy 166.056212 -290.554941)
			(xy 166.071796 -290.601622) (xy 166.079691 -290.650199) (xy 166.080186 -290.674806) (xy 184.469036 -290.674806)
			(xy 184.472996 -290.625752) (xy 184.484773 -290.577968) (xy 184.504064 -290.532692) (xy 184.530367 -290.491096)
			(xy 184.563002 -290.454259) (xy 184.601123 -290.423134) (xy 184.643744 -290.398527) (xy 184.68976 -290.381075)
			(xy 184.737979 -290.371231) (xy 184.787154 -290.36925) (xy 184.836009 -290.375182) (xy 184.88328 -290.388874)
			(xy 184.927742 -290.409972) (xy 184.968245 -290.437928) (xy 185.003738 -290.47202) (xy 185.033303 -290.511364)
			(xy 185.056174 -290.554941) (xy 185.071758 -290.601622) (xy 185.079653 -290.650199) (xy 185.080148 -290.674806)
			(xy 185.079653 -290.699413) (xy 185.071758 -290.74799) (xy 185.056174 -290.794671) (xy 185.033303 -290.838248)
			(xy 185.003738 -290.877592) (xy 184.968245 -290.911684) (xy 184.927742 -290.93964) (xy 184.88328 -290.960738)
			(xy 184.836009 -290.97443) (xy 184.787154 -290.980362) (xy 184.737979 -290.978381) (xy 184.68976 -290.968537)
			(xy 184.643744 -290.951085) (xy 184.601123 -290.926478) (xy 184.563002 -290.895353) (xy 184.530367 -290.858516)
			(xy 184.504064 -290.81692) (xy 184.484773 -290.771644) (xy 184.472996 -290.72386) (xy 184.469036 -290.674806)
			(xy 166.080186 -290.674806) (xy 166.079691 -290.699413) (xy 166.071796 -290.74799) (xy 166.056212 -290.794671)
			(xy 166.033341 -290.838248) (xy 166.003776 -290.877592) (xy 165.968283 -290.911684) (xy 165.92778 -290.93964)
			(xy 165.883318 -290.960738) (xy 165.836047 -290.97443) (xy 165.787192 -290.980362) (xy 165.738017 -290.978381)
			(xy 165.689798 -290.968537) (xy 165.643782 -290.951085) (xy 165.601161 -290.926478) (xy 165.56304 -290.895353)
			(xy 165.530405 -290.858516) (xy 165.504102 -290.81692) (xy 165.484811 -290.771644) (xy 165.473034 -290.72386)
			(xy 165.469074 -290.674806) (xy 165.130737 -290.674806) (xy 165.126566 -290.725137) (xy 165.114167 -290.774102)
			(xy 165.093878 -290.820357) (xy 165.066253 -290.862643) (xy 165.032045 -290.899805) (xy 164.992187 -290.93083)
			(xy 164.947765 -290.954872) (xy 164.899993 -290.971275) (xy 164.850173 -290.979591) (xy 164.824918 -290.980114)
			(xy 164.796081 -290.979438) (xy 164.739439 -290.968561) (xy 164.712396 -290.958524) (xy 164.712142 -290.958524)
			(xy 164.700397 -290.954528) (xy 164.675762 -290.957178) (xy 164.665152 -290.963604) (xy 164.595556 -291.010848)
			(xy 164.58557 -291.018406) (xy 164.573851 -291.040506) (xy 164.573204 -291.053012) (xy 164.573204 -291.24656)
			(xy 164.573784 -291.259082) (xy 164.585528 -291.281199) (xy 164.595556 -291.288724) (xy 164.665152 -291.335968)
			(xy 164.675819 -291.342229) (xy 164.700376 -291.344869) (xy 164.712142 -291.341048) (xy 164.712396 -291.341048)
			(xy 164.739443 -291.331024) (xy 164.796082 -291.320152) (xy 164.824918 -291.319458) (xy 164.85017 -291.320049)
			(xy 164.899983 -291.328364) (xy 164.947749 -291.344765) (xy 164.992165 -291.368803) (xy 165.032018 -291.399824)
			(xy 165.066221 -291.436982) (xy 165.093843 -291.479262) (xy 165.114129 -291.525511) (xy 165.126527 -291.574469)
			(xy 165.130694 -291.624766) (xy 165.469074 -291.624766) (xy 165.473034 -291.575712) (xy 165.484811 -291.527928)
			(xy 165.504102 -291.482652) (xy 165.530405 -291.441056) (xy 165.56304 -291.404219) (xy 165.601161 -291.373094)
			(xy 165.643782 -291.348487) (xy 165.689798 -291.331035) (xy 165.738017 -291.321191) (xy 165.787192 -291.31921)
			(xy 165.836047 -291.325142) (xy 165.883318 -291.338834) (xy 165.92778 -291.359932) (xy 165.968283 -291.387888)
			(xy 166.003776 -291.42198) (xy 166.033341 -291.461324) (xy 166.056212 -291.504901) (xy 166.071796 -291.551582)
			(xy 166.079691 -291.600159) (xy 166.080186 -291.624766) (xy 166.419288 -291.624766) (xy 166.423248 -291.575712)
			(xy 166.435025 -291.527928) (xy 166.454316 -291.482652) (xy 166.480619 -291.441056) (xy 166.513254 -291.404219)
			(xy 166.551375 -291.373094) (xy 166.593996 -291.348487) (xy 166.640012 -291.331035) (xy 166.688231 -291.321191)
			(xy 166.737406 -291.31921) (xy 166.786261 -291.325142) (xy 166.833532 -291.338834) (xy 166.877994 -291.359932)
			(xy 166.918497 -291.387888) (xy 166.95399 -291.42198) (xy 166.983555 -291.461324) (xy 167.006426 -291.504901)
			(xy 167.02201 -291.551582) (xy 167.029905 -291.600159) (xy 167.0304 -291.624766) (xy 167.369248 -291.624766)
			(xy 167.373208 -291.575712) (xy 167.384985 -291.527928) (xy 167.404276 -291.482652) (xy 167.430579 -291.441056)
			(xy 167.463214 -291.404219) (xy 167.501335 -291.373094) (xy 167.543956 -291.348487) (xy 167.589972 -291.331035)
			(xy 167.638191 -291.321191) (xy 167.687366 -291.31921) (xy 167.736221 -291.325142) (xy 167.783492 -291.338834)
			(xy 167.827954 -291.359932) (xy 167.868457 -291.387888) (xy 167.90395 -291.42198) (xy 167.933515 -291.461324)
			(xy 167.956386 -291.504901) (xy 167.97197 -291.551582) (xy 167.979865 -291.600159) (xy 167.98036 -291.624766)
			(xy 168.319208 -291.624766) (xy 168.323168 -291.575712) (xy 168.334945 -291.527928) (xy 168.354236 -291.482652)
			(xy 168.380539 -291.441056) (xy 168.413174 -291.404219) (xy 168.451295 -291.373094) (xy 168.493916 -291.348487)
			(xy 168.539932 -291.331035) (xy 168.588151 -291.321191) (xy 168.637326 -291.31921) (xy 168.686181 -291.325142)
			(xy 168.733452 -291.338834) (xy 168.777914 -291.359932) (xy 168.818417 -291.387888) (xy 168.85391 -291.42198)
			(xy 168.883475 -291.461324) (xy 168.906346 -291.504901) (xy 168.92193 -291.551582) (xy 168.929825 -291.600159)
			(xy 168.93032 -291.624766) (xy 169.269168 -291.624766) (xy 169.273128 -291.575712) (xy 169.284905 -291.527928)
			(xy 169.304196 -291.482652) (xy 169.330499 -291.441056) (xy 169.363134 -291.404219) (xy 169.401255 -291.373094)
			(xy 169.443876 -291.348487) (xy 169.489892 -291.331035) (xy 169.538111 -291.321191) (xy 169.587286 -291.31921)
			(xy 169.636141 -291.325142) (xy 169.683412 -291.338834) (xy 169.727874 -291.359932) (xy 169.768377 -291.387888)
			(xy 169.80387 -291.42198) (xy 169.833435 -291.461324) (xy 169.856306 -291.504901) (xy 169.87189 -291.551582)
			(xy 169.879785 -291.600159) (xy 169.88028 -291.624766) (xy 170.219128 -291.624766) (xy 170.223088 -291.575712)
			(xy 170.234865 -291.527928) (xy 170.254156 -291.482652) (xy 170.280459 -291.441056) (xy 170.313094 -291.404219)
			(xy 170.351215 -291.373094) (xy 170.393836 -291.348487) (xy 170.439852 -291.331035) (xy 170.488071 -291.321191)
			(xy 170.537246 -291.31921) (xy 170.586101 -291.325142) (xy 170.633372 -291.338834) (xy 170.677834 -291.359932)
			(xy 170.718337 -291.387888) (xy 170.75383 -291.42198) (xy 170.783395 -291.461324) (xy 170.806266 -291.504901)
			(xy 170.82185 -291.551582) (xy 170.829745 -291.600159) (xy 170.83024 -291.624766) (xy 171.169088 -291.624766)
			(xy 171.173048 -291.575712) (xy 171.184825 -291.527928) (xy 171.204116 -291.482652) (xy 171.230419 -291.441056)
			(xy 171.263054 -291.404219) (xy 171.301175 -291.373094) (xy 171.343796 -291.348487) (xy 171.389812 -291.331035)
			(xy 171.438031 -291.321191) (xy 171.487206 -291.31921) (xy 171.536061 -291.325142) (xy 171.583332 -291.338834)
			(xy 171.627794 -291.359932) (xy 171.668297 -291.387888) (xy 171.70379 -291.42198) (xy 171.733355 -291.461324)
			(xy 171.756226 -291.504901) (xy 171.77181 -291.551582) (xy 171.779705 -291.600159) (xy 171.7802 -291.624766)
			(xy 172.119048 -291.624766) (xy 172.123008 -291.575712) (xy 172.134785 -291.527928) (xy 172.154076 -291.482652)
			(xy 172.180379 -291.441056) (xy 172.213014 -291.404219) (xy 172.251135 -291.373094) (xy 172.293756 -291.348487)
			(xy 172.339772 -291.331035) (xy 172.387991 -291.321191) (xy 172.437166 -291.31921) (xy 172.486021 -291.325142)
			(xy 172.533292 -291.338834) (xy 172.577754 -291.359932) (xy 172.618257 -291.387888) (xy 172.65375 -291.42198)
			(xy 172.683315 -291.461324) (xy 172.706186 -291.504901) (xy 172.72177 -291.551582) (xy 172.729665 -291.600159)
			(xy 172.73016 -291.624766) (xy 173.069262 -291.624766) (xy 173.073222 -291.575712) (xy 173.084999 -291.527928)
			(xy 173.10429 -291.482652) (xy 173.130593 -291.441056) (xy 173.163228 -291.404219) (xy 173.201349 -291.373094)
			(xy 173.24397 -291.348487) (xy 173.289986 -291.331035) (xy 173.338205 -291.321191) (xy 173.38738 -291.31921)
			(xy 173.436235 -291.325142) (xy 173.483506 -291.338834) (xy 173.527968 -291.359932) (xy 173.568471 -291.387888)
			(xy 173.603964 -291.42198) (xy 173.633529 -291.461324) (xy 173.6564 -291.504901) (xy 173.671984 -291.551582)
			(xy 173.679879 -291.600159) (xy 173.680374 -291.624766) (xy 174.019222 -291.624766) (xy 174.023182 -291.575712)
			(xy 174.034959 -291.527928) (xy 174.05425 -291.482652) (xy 174.080553 -291.441056) (xy 174.113188 -291.404219)
			(xy 174.151309 -291.373094) (xy 174.19393 -291.348487) (xy 174.239946 -291.331035) (xy 174.288165 -291.321191)
			(xy 174.33734 -291.31921) (xy 174.386195 -291.325142) (xy 174.433466 -291.338834) (xy 174.477928 -291.359932)
			(xy 174.518431 -291.387888) (xy 174.553924 -291.42198) (xy 174.583489 -291.461324) (xy 174.60636 -291.504901)
			(xy 174.621944 -291.551582) (xy 174.629839 -291.600159) (xy 174.630334 -291.624766) (xy 175.919142 -291.624766)
			(xy 175.923102 -291.575712) (xy 175.934879 -291.527928) (xy 175.95417 -291.482652) (xy 175.980473 -291.441056)
			(xy 176.013108 -291.404219) (xy 176.051229 -291.373094) (xy 176.09385 -291.348487) (xy 176.139866 -291.331035)
			(xy 176.188085 -291.321191) (xy 176.23726 -291.31921) (xy 176.286115 -291.325142) (xy 176.333386 -291.338834)
			(xy 176.377848 -291.359932) (xy 176.418351 -291.387888) (xy 176.453844 -291.42198) (xy 176.483409 -291.461324)
			(xy 176.50628 -291.504901) (xy 176.521864 -291.551582) (xy 176.529759 -291.600159) (xy 176.530254 -291.624766)
			(xy 176.869102 -291.624766) (xy 176.873062 -291.575712) (xy 176.884839 -291.527928) (xy 176.90413 -291.482652)
			(xy 176.930433 -291.441056) (xy 176.963068 -291.404219) (xy 177.001189 -291.373094) (xy 177.04381 -291.348487)
			(xy 177.089826 -291.331035) (xy 177.138045 -291.321191) (xy 177.18722 -291.31921) (xy 177.236075 -291.325142)
			(xy 177.283346 -291.338834) (xy 177.327808 -291.359932) (xy 177.368311 -291.387888) (xy 177.403804 -291.42198)
			(xy 177.433369 -291.461324) (xy 177.45624 -291.504901) (xy 177.471824 -291.551582) (xy 177.479719 -291.600159)
			(xy 177.480214 -291.624766) (xy 177.819062 -291.624766) (xy 177.823022 -291.575712) (xy 177.834799 -291.527928)
			(xy 177.85409 -291.482652) (xy 177.880393 -291.441056) (xy 177.913028 -291.404219) (xy 177.951149 -291.373094)
			(xy 177.99377 -291.348487) (xy 178.039786 -291.331035) (xy 178.088005 -291.321191) (xy 178.13718 -291.31921)
			(xy 178.186035 -291.325142) (xy 178.233306 -291.338834) (xy 178.277768 -291.359932) (xy 178.318271 -291.387888)
			(xy 178.353764 -291.42198) (xy 178.383329 -291.461324) (xy 178.4062 -291.504901) (xy 178.421784 -291.551582)
			(xy 178.429679 -291.600159) (xy 178.430174 -291.624766) (xy 178.769276 -291.624766) (xy 178.773236 -291.575712)
			(xy 178.785013 -291.527928) (xy 178.804304 -291.482652) (xy 178.830607 -291.441056) (xy 178.863242 -291.404219)
			(xy 178.901363 -291.373094) (xy 178.943984 -291.348487) (xy 178.99 -291.331035) (xy 179.038219 -291.321191)
			(xy 179.087394 -291.31921) (xy 179.136249 -291.325142) (xy 179.18352 -291.338834) (xy 179.227982 -291.359932)
			(xy 179.268485 -291.387888) (xy 179.303978 -291.42198) (xy 179.333543 -291.461324) (xy 179.356414 -291.504901)
			(xy 179.371998 -291.551582) (xy 179.379893 -291.600159) (xy 179.380388 -291.624766) (xy 179.719236 -291.624766)
			(xy 179.723196 -291.575712) (xy 179.734973 -291.527928) (xy 179.754264 -291.482652) (xy 179.780567 -291.441056)
			(xy 179.813202 -291.404219) (xy 179.851323 -291.373094) (xy 179.893944 -291.348487) (xy 179.93996 -291.331035)
			(xy 179.988179 -291.321191) (xy 180.037354 -291.31921) (xy 180.086209 -291.325142) (xy 180.13348 -291.338834)
			(xy 180.177942 -291.359932) (xy 180.218445 -291.387888) (xy 180.253938 -291.42198) (xy 180.283503 -291.461324)
			(xy 180.306374 -291.504901) (xy 180.321958 -291.551582) (xy 180.329853 -291.600159) (xy 180.330348 -291.624766)
			(xy 180.669196 -291.624766) (xy 180.673156 -291.575712) (xy 180.684933 -291.527928) (xy 180.704224 -291.482652)
			(xy 180.730527 -291.441056) (xy 180.763162 -291.404219) (xy 180.801283 -291.373094) (xy 180.843904 -291.348487)
			(xy 180.88992 -291.331035) (xy 180.938139 -291.321191) (xy 180.987314 -291.31921) (xy 181.036169 -291.325142)
			(xy 181.08344 -291.338834) (xy 181.127902 -291.359932) (xy 181.168405 -291.387888) (xy 181.203898 -291.42198)
			(xy 181.233463 -291.461324) (xy 181.256334 -291.504901) (xy 181.271918 -291.551582) (xy 181.279813 -291.600159)
			(xy 181.280308 -291.624766) (xy 181.619156 -291.624766) (xy 181.623116 -291.575712) (xy 181.634893 -291.527928)
			(xy 181.654184 -291.482652) (xy 181.680487 -291.441056) (xy 181.713122 -291.404219) (xy 181.751243 -291.373094)
			(xy 181.793864 -291.348487) (xy 181.83988 -291.331035) (xy 181.888099 -291.321191) (xy 181.937274 -291.31921)
			(xy 181.986129 -291.325142) (xy 182.0334 -291.338834) (xy 182.077862 -291.359932) (xy 182.118365 -291.387888)
			(xy 182.153858 -291.42198) (xy 182.183423 -291.461324) (xy 182.206294 -291.504901) (xy 182.221878 -291.551582)
			(xy 182.229773 -291.600159) (xy 182.230268 -291.624766) (xy 182.569116 -291.624766) (xy 182.573076 -291.575712)
			(xy 182.584853 -291.527928) (xy 182.604144 -291.482652) (xy 182.630447 -291.441056) (xy 182.663082 -291.404219)
			(xy 182.701203 -291.373094) (xy 182.743824 -291.348487) (xy 182.78984 -291.331035) (xy 182.838059 -291.321191)
			(xy 182.887234 -291.31921) (xy 182.936089 -291.325142) (xy 182.98336 -291.338834) (xy 183.027822 -291.359932)
			(xy 183.068325 -291.387888) (xy 183.103818 -291.42198) (xy 183.133383 -291.461324) (xy 183.156254 -291.504901)
			(xy 183.171838 -291.551582) (xy 183.179733 -291.600159) (xy 183.180228 -291.624766) (xy 183.519076 -291.624766)
			(xy 183.523036 -291.575712) (xy 183.534813 -291.527928) (xy 183.554104 -291.482652) (xy 183.580407 -291.441056)
			(xy 183.613042 -291.404219) (xy 183.651163 -291.373094) (xy 183.693784 -291.348487) (xy 183.7398 -291.331035)
			(xy 183.788019 -291.321191) (xy 183.837194 -291.31921) (xy 183.886049 -291.325142) (xy 183.93332 -291.338834)
			(xy 183.977782 -291.359932) (xy 184.018285 -291.387888) (xy 184.053778 -291.42198) (xy 184.083343 -291.461324)
			(xy 184.106214 -291.504901) (xy 184.121798 -291.551582) (xy 184.129693 -291.600159) (xy 184.130188 -291.624766)
			(xy 184.469036 -291.624766) (xy 184.472996 -291.575712) (xy 184.484773 -291.527928) (xy 184.504064 -291.482652)
			(xy 184.530367 -291.441056) (xy 184.563002 -291.404219) (xy 184.601123 -291.373094) (xy 184.643744 -291.348487)
			(xy 184.68976 -291.331035) (xy 184.737979 -291.321191) (xy 184.787154 -291.31921) (xy 184.836009 -291.325142)
			(xy 184.88328 -291.338834) (xy 184.927742 -291.359932) (xy 184.968245 -291.387888) (xy 185.003738 -291.42198)
			(xy 185.033303 -291.461324) (xy 185.056174 -291.504901) (xy 185.071758 -291.551582) (xy 185.079653 -291.600159)
			(xy 185.080148 -291.624766) (xy 185.079653 -291.649373) (xy 185.071758 -291.69795) (xy 185.056174 -291.744631)
			(xy 185.033303 -291.788208) (xy 185.003738 -291.827552) (xy 184.968245 -291.861644) (xy 184.927742 -291.8896)
			(xy 184.88328 -291.910698) (xy 184.836009 -291.92439) (xy 184.787154 -291.930322) (xy 184.737979 -291.928341)
			(xy 184.68976 -291.918497) (xy 184.643744 -291.901045) (xy 184.601123 -291.876438) (xy 184.563002 -291.845313)
			(xy 184.530367 -291.808476) (xy 184.504064 -291.76688) (xy 184.484773 -291.721604) (xy 184.472996 -291.67382)
			(xy 184.469036 -291.624766) (xy 184.130188 -291.624766) (xy 184.129693 -291.649373) (xy 184.121798 -291.69795)
			(xy 184.106214 -291.744631) (xy 184.083343 -291.788208) (xy 184.053778 -291.827552) (xy 184.018285 -291.861644)
			(xy 183.977782 -291.8896) (xy 183.93332 -291.910698) (xy 183.886049 -291.92439) (xy 183.837194 -291.930322)
			(xy 183.788019 -291.928341) (xy 183.7398 -291.918497) (xy 183.693784 -291.901045) (xy 183.651163 -291.876438)
			(xy 183.613042 -291.845313) (xy 183.580407 -291.808476) (xy 183.554104 -291.76688) (xy 183.534813 -291.721604)
			(xy 183.523036 -291.67382) (xy 183.519076 -291.624766) (xy 183.180228 -291.624766) (xy 183.179733 -291.649373)
			(xy 183.171838 -291.69795) (xy 183.156254 -291.744631) (xy 183.133383 -291.788208) (xy 183.103818 -291.827552)
			(xy 183.068325 -291.861644) (xy 183.027822 -291.8896) (xy 182.98336 -291.910698) (xy 182.936089 -291.92439)
			(xy 182.887234 -291.930322) (xy 182.838059 -291.928341) (xy 182.78984 -291.918497) (xy 182.743824 -291.901045)
			(xy 182.701203 -291.876438) (xy 182.663082 -291.845313) (xy 182.630447 -291.808476) (xy 182.604144 -291.76688)
			(xy 182.584853 -291.721604) (xy 182.573076 -291.67382) (xy 182.569116 -291.624766) (xy 182.230268 -291.624766)
			(xy 182.229773 -291.649373) (xy 182.221878 -291.69795) (xy 182.206294 -291.744631) (xy 182.183423 -291.788208)
			(xy 182.153858 -291.827552) (xy 182.118365 -291.861644) (xy 182.077862 -291.8896) (xy 182.0334 -291.910698)
			(xy 181.986129 -291.92439) (xy 181.937274 -291.930322) (xy 181.888099 -291.928341) (xy 181.83988 -291.918497)
			(xy 181.793864 -291.901045) (xy 181.751243 -291.876438) (xy 181.713122 -291.845313) (xy 181.680487 -291.808476)
			(xy 181.654184 -291.76688) (xy 181.634893 -291.721604) (xy 181.623116 -291.67382) (xy 181.619156 -291.624766)
			(xy 181.280308 -291.624766) (xy 181.279813 -291.649373) (xy 181.271918 -291.69795) (xy 181.256334 -291.744631)
			(xy 181.233463 -291.788208) (xy 181.203898 -291.827552) (xy 181.168405 -291.861644) (xy 181.127902 -291.8896)
			(xy 181.08344 -291.910698) (xy 181.036169 -291.92439) (xy 180.987314 -291.930322) (xy 180.938139 -291.928341)
			(xy 180.88992 -291.918497) (xy 180.843904 -291.901045) (xy 180.801283 -291.876438) (xy 180.763162 -291.845313)
			(xy 180.730527 -291.808476) (xy 180.704224 -291.76688) (xy 180.684933 -291.721604) (xy 180.673156 -291.67382)
			(xy 180.669196 -291.624766) (xy 180.330348 -291.624766) (xy 180.329853 -291.649373) (xy 180.321958 -291.69795)
			(xy 180.306374 -291.744631) (xy 180.283503 -291.788208) (xy 180.253938 -291.827552) (xy 180.218445 -291.861644)
			(xy 180.177942 -291.8896) (xy 180.13348 -291.910698) (xy 180.086209 -291.92439) (xy 180.037354 -291.930322)
			(xy 179.988179 -291.928341) (xy 179.93996 -291.918497) (xy 179.893944 -291.901045) (xy 179.851323 -291.876438)
			(xy 179.813202 -291.845313) (xy 179.780567 -291.808476) (xy 179.754264 -291.76688) (xy 179.734973 -291.721604)
			(xy 179.723196 -291.67382) (xy 179.719236 -291.624766) (xy 179.380388 -291.624766) (xy 179.379893 -291.649373)
			(xy 179.371998 -291.69795) (xy 179.356414 -291.744631) (xy 179.333543 -291.788208) (xy 179.303978 -291.827552)
			(xy 179.268485 -291.861644) (xy 179.227982 -291.8896) (xy 179.18352 -291.910698) (xy 179.136249 -291.92439)
			(xy 179.087394 -291.930322) (xy 179.038219 -291.928341) (xy 178.99 -291.918497) (xy 178.943984 -291.901045)
			(xy 178.901363 -291.876438) (xy 178.863242 -291.845313) (xy 178.830607 -291.808476) (xy 178.804304 -291.76688)
			(xy 178.785013 -291.721604) (xy 178.773236 -291.67382) (xy 178.769276 -291.624766) (xy 178.430174 -291.624766)
			(xy 178.429679 -291.649373) (xy 178.421784 -291.69795) (xy 178.4062 -291.744631) (xy 178.383329 -291.788208)
			(xy 178.353764 -291.827552) (xy 178.318271 -291.861644) (xy 178.277768 -291.8896) (xy 178.233306 -291.910698)
			(xy 178.186035 -291.92439) (xy 178.13718 -291.930322) (xy 178.088005 -291.928341) (xy 178.039786 -291.918497)
			(xy 177.99377 -291.901045) (xy 177.951149 -291.876438) (xy 177.913028 -291.845313) (xy 177.880393 -291.808476)
			(xy 177.85409 -291.76688) (xy 177.834799 -291.721604) (xy 177.823022 -291.67382) (xy 177.819062 -291.624766)
			(xy 177.480214 -291.624766) (xy 177.479719 -291.649373) (xy 177.471824 -291.69795) (xy 177.45624 -291.744631)
			(xy 177.433369 -291.788208) (xy 177.403804 -291.827552) (xy 177.368311 -291.861644) (xy 177.327808 -291.8896)
			(xy 177.283346 -291.910698) (xy 177.236075 -291.92439) (xy 177.18722 -291.930322) (xy 177.138045 -291.928341)
			(xy 177.089826 -291.918497) (xy 177.04381 -291.901045) (xy 177.001189 -291.876438) (xy 176.963068 -291.845313)
			(xy 176.930433 -291.808476) (xy 176.90413 -291.76688) (xy 176.884839 -291.721604) (xy 176.873062 -291.67382)
			(xy 176.869102 -291.624766) (xy 176.530254 -291.624766) (xy 176.529759 -291.649373) (xy 176.521864 -291.69795)
			(xy 176.50628 -291.744631) (xy 176.483409 -291.788208) (xy 176.453844 -291.827552) (xy 176.418351 -291.861644)
			(xy 176.377848 -291.8896) (xy 176.333386 -291.910698) (xy 176.286115 -291.92439) (xy 176.23726 -291.930322)
			(xy 176.188085 -291.928341) (xy 176.139866 -291.918497) (xy 176.09385 -291.901045) (xy 176.051229 -291.876438)
			(xy 176.013108 -291.845313) (xy 175.980473 -291.808476) (xy 175.95417 -291.76688) (xy 175.934879 -291.721604)
			(xy 175.923102 -291.67382) (xy 175.919142 -291.624766) (xy 174.630334 -291.624766) (xy 174.629839 -291.649373)
			(xy 174.621944 -291.69795) (xy 174.60636 -291.744631) (xy 174.583489 -291.788208) (xy 174.553924 -291.827552)
			(xy 174.518431 -291.861644) (xy 174.477928 -291.8896) (xy 174.433466 -291.910698) (xy 174.386195 -291.92439)
			(xy 174.33734 -291.930322) (xy 174.288165 -291.928341) (xy 174.239946 -291.918497) (xy 174.19393 -291.901045)
			(xy 174.151309 -291.876438) (xy 174.113188 -291.845313) (xy 174.080553 -291.808476) (xy 174.05425 -291.76688)
			(xy 174.034959 -291.721604) (xy 174.023182 -291.67382) (xy 174.019222 -291.624766) (xy 173.680374 -291.624766)
			(xy 173.679879 -291.649373) (xy 173.671984 -291.69795) (xy 173.6564 -291.744631) (xy 173.633529 -291.788208)
			(xy 173.603964 -291.827552) (xy 173.568471 -291.861644) (xy 173.527968 -291.8896) (xy 173.483506 -291.910698)
			(xy 173.436235 -291.92439) (xy 173.38738 -291.930322) (xy 173.338205 -291.928341) (xy 173.289986 -291.918497)
			(xy 173.24397 -291.901045) (xy 173.201349 -291.876438) (xy 173.163228 -291.845313) (xy 173.130593 -291.808476)
			(xy 173.10429 -291.76688) (xy 173.084999 -291.721604) (xy 173.073222 -291.67382) (xy 173.069262 -291.624766)
			(xy 172.73016 -291.624766) (xy 172.729665 -291.649373) (xy 172.72177 -291.69795) (xy 172.706186 -291.744631)
			(xy 172.683315 -291.788208) (xy 172.65375 -291.827552) (xy 172.618257 -291.861644) (xy 172.577754 -291.8896)
			(xy 172.533292 -291.910698) (xy 172.486021 -291.92439) (xy 172.437166 -291.930322) (xy 172.387991 -291.928341)
			(xy 172.339772 -291.918497) (xy 172.293756 -291.901045) (xy 172.251135 -291.876438) (xy 172.213014 -291.845313)
			(xy 172.180379 -291.808476) (xy 172.154076 -291.76688) (xy 172.134785 -291.721604) (xy 172.123008 -291.67382)
			(xy 172.119048 -291.624766) (xy 171.7802 -291.624766) (xy 171.779705 -291.649373) (xy 171.77181 -291.69795)
			(xy 171.756226 -291.744631) (xy 171.733355 -291.788208) (xy 171.70379 -291.827552) (xy 171.668297 -291.861644)
			(xy 171.627794 -291.8896) (xy 171.583332 -291.910698) (xy 171.536061 -291.92439) (xy 171.487206 -291.930322)
			(xy 171.438031 -291.928341) (xy 171.389812 -291.918497) (xy 171.343796 -291.901045) (xy 171.301175 -291.876438)
			(xy 171.263054 -291.845313) (xy 171.230419 -291.808476) (xy 171.204116 -291.76688) (xy 171.184825 -291.721604)
			(xy 171.173048 -291.67382) (xy 171.169088 -291.624766) (xy 170.83024 -291.624766) (xy 170.829745 -291.649373)
			(xy 170.82185 -291.69795) (xy 170.806266 -291.744631) (xy 170.783395 -291.788208) (xy 170.75383 -291.827552)
			(xy 170.718337 -291.861644) (xy 170.677834 -291.8896) (xy 170.633372 -291.910698) (xy 170.586101 -291.92439)
			(xy 170.537246 -291.930322) (xy 170.488071 -291.928341) (xy 170.439852 -291.918497) (xy 170.393836 -291.901045)
			(xy 170.351215 -291.876438) (xy 170.313094 -291.845313) (xy 170.280459 -291.808476) (xy 170.254156 -291.76688)
			(xy 170.234865 -291.721604) (xy 170.223088 -291.67382) (xy 170.219128 -291.624766) (xy 169.88028 -291.624766)
			(xy 169.879785 -291.649373) (xy 169.87189 -291.69795) (xy 169.856306 -291.744631) (xy 169.833435 -291.788208)
			(xy 169.80387 -291.827552) (xy 169.768377 -291.861644) (xy 169.727874 -291.8896) (xy 169.683412 -291.910698)
			(xy 169.636141 -291.92439) (xy 169.587286 -291.930322) (xy 169.538111 -291.928341) (xy 169.489892 -291.918497)
			(xy 169.443876 -291.901045) (xy 169.401255 -291.876438) (xy 169.363134 -291.845313) (xy 169.330499 -291.808476)
			(xy 169.304196 -291.76688) (xy 169.284905 -291.721604) (xy 169.273128 -291.67382) (xy 169.269168 -291.624766)
			(xy 168.93032 -291.624766) (xy 168.929825 -291.649373) (xy 168.92193 -291.69795) (xy 168.906346 -291.744631)
			(xy 168.883475 -291.788208) (xy 168.85391 -291.827552) (xy 168.818417 -291.861644) (xy 168.777914 -291.8896)
			(xy 168.733452 -291.910698) (xy 168.686181 -291.92439) (xy 168.637326 -291.930322) (xy 168.588151 -291.928341)
			(xy 168.539932 -291.918497) (xy 168.493916 -291.901045) (xy 168.451295 -291.876438) (xy 168.413174 -291.845313)
			(xy 168.380539 -291.808476) (xy 168.354236 -291.76688) (xy 168.334945 -291.721604) (xy 168.323168 -291.67382)
			(xy 168.319208 -291.624766) (xy 167.98036 -291.624766) (xy 167.979865 -291.649373) (xy 167.97197 -291.69795)
			(xy 167.956386 -291.744631) (xy 167.933515 -291.788208) (xy 167.90395 -291.827552) (xy 167.868457 -291.861644)
			(xy 167.827954 -291.8896) (xy 167.783492 -291.910698) (xy 167.736221 -291.92439) (xy 167.687366 -291.930322)
			(xy 167.638191 -291.928341) (xy 167.589972 -291.918497) (xy 167.543956 -291.901045) (xy 167.501335 -291.876438)
			(xy 167.463214 -291.845313) (xy 167.430579 -291.808476) (xy 167.404276 -291.76688) (xy 167.384985 -291.721604)
			(xy 167.373208 -291.67382) (xy 167.369248 -291.624766) (xy 167.0304 -291.624766) (xy 167.029905 -291.649373)
			(xy 167.02201 -291.69795) (xy 167.006426 -291.744631) (xy 166.983555 -291.788208) (xy 166.95399 -291.827552)
			(xy 166.918497 -291.861644) (xy 166.877994 -291.8896) (xy 166.833532 -291.910698) (xy 166.786261 -291.92439)
			(xy 166.737406 -291.930322) (xy 166.688231 -291.928341) (xy 166.640012 -291.918497) (xy 166.593996 -291.901045)
			(xy 166.551375 -291.876438) (xy 166.513254 -291.845313) (xy 166.480619 -291.808476) (xy 166.454316 -291.76688)
			(xy 166.435025 -291.721604) (xy 166.423248 -291.67382) (xy 166.419288 -291.624766) (xy 166.080186 -291.624766)
			(xy 166.079691 -291.649373) (xy 166.071796 -291.69795) (xy 166.056212 -291.744631) (xy 166.033341 -291.788208)
			(xy 166.003776 -291.827552) (xy 165.968283 -291.861644) (xy 165.92778 -291.8896) (xy 165.883318 -291.910698)
			(xy 165.836047 -291.92439) (xy 165.787192 -291.930322) (xy 165.738017 -291.928341) (xy 165.689798 -291.918497)
			(xy 165.643782 -291.901045) (xy 165.601161 -291.876438) (xy 165.56304 -291.845313) (xy 165.530405 -291.808476)
			(xy 165.504102 -291.76688) (xy 165.484811 -291.721604) (xy 165.473034 -291.67382) (xy 165.469074 -291.624766)
			(xy 165.130694 -291.624766) (xy 165.130697 -291.6248) (xy 165.126527 -291.675131) (xy 165.114129 -291.724089)
			(xy 165.093843 -291.770338) (xy 165.066221 -291.812618) (xy 165.032018 -291.849776) (xy 164.992165 -291.880797)
			(xy 164.947749 -291.904835) (xy 164.899983 -291.921236) (xy 164.85017 -291.929551) (xy 164.824918 -291.930074)
			(xy 164.801523 -291.92965) (xy 164.755284 -291.922486) (xy 164.710683 -291.90834) (xy 164.689536 -291.898324)
			(xy 164.689282 -291.898324) (xy 164.679768 -291.894152) (xy 164.65904 -291.893111) (xy 164.64915 -291.896292)
			(xy 164.569648 -291.926264) (xy 164.554408 -291.94125) (xy 164.553138 -291.944044) (xy 164.553138 -291.944552)
			(xy 164.548685 -291.955695) (xy 164.538261 -291.977311) (xy 164.53231 -291.987732) (xy 164.522052 -292.004895)
			(xy 164.497713 -292.036621) (xy 164.483796 -292.050978) (xy 164.394896 -292.139878) (xy 164.377599 -292.156525)
			(xy 164.338791 -292.184778) (xy 164.296041 -292.206612) (xy 164.250402 -292.22149) (xy 164.202997 -292.229046)
			(xy 164.178996 -292.22954) (xy 164.074856 -292.22954) (xy 164.064841 -292.229953) (xy 164.04634 -292.237635)
			(xy 164.032187 -292.251811) (xy 164.024537 -292.270324) (xy 164.024056 -292.28034) (xy 164.024056 -292.29304)
			(xy 164.03574 -292.315138) (xy 164.046154 -292.32225) (xy 164.066454 -292.336559) (xy 164.102535 -292.370686)
			(xy 164.132611 -292.410206) (xy 164.155889 -292.454077) (xy 164.171753 -292.501138) (xy 164.179785 -292.550148)
			(xy 164.180261 -292.574726) (xy 164.519114 -292.574726) (xy 164.523074 -292.525672) (xy 164.534851 -292.477888)
			(xy 164.554142 -292.432612) (xy 164.580445 -292.391016) (xy 164.61308 -292.354179) (xy 164.651201 -292.323054)
			(xy 164.693822 -292.298447) (xy 164.739838 -292.280995) (xy 164.788057 -292.271151) (xy 164.837232 -292.26917)
			(xy 164.886087 -292.275102) (xy 164.933358 -292.288794) (xy 164.97782 -292.309892) (xy 165.018323 -292.337848)
			(xy 165.053816 -292.37194) (xy 165.083381 -292.411284) (xy 165.106252 -292.454861) (xy 165.121836 -292.501542)
			(xy 165.129731 -292.550119) (xy 165.130226 -292.574726) (xy 165.469074 -292.574726) (xy 165.473034 -292.525672)
			(xy 165.484811 -292.477888) (xy 165.504102 -292.432612) (xy 165.530405 -292.391016) (xy 165.56304 -292.354179)
			(xy 165.601161 -292.323054) (xy 165.643782 -292.298447) (xy 165.689798 -292.280995) (xy 165.738017 -292.271151)
			(xy 165.787192 -292.26917) (xy 165.836047 -292.275102) (xy 165.883318 -292.288794) (xy 165.92778 -292.309892)
			(xy 165.968283 -292.337848) (xy 166.003776 -292.37194) (xy 166.033341 -292.411284) (xy 166.056212 -292.454861)
			(xy 166.071796 -292.501542) (xy 166.079691 -292.550119) (xy 166.080186 -292.574726) (xy 184.469036 -292.574726)
			(xy 184.472996 -292.525672) (xy 184.484773 -292.477888) (xy 184.504064 -292.432612) (xy 184.530367 -292.391016)
			(xy 184.563002 -292.354179) (xy 184.601123 -292.323054) (xy 184.643744 -292.298447) (xy 184.68976 -292.280995)
			(xy 184.737979 -292.271151) (xy 184.787154 -292.26917) (xy 184.836009 -292.275102) (xy 184.88328 -292.288794)
			(xy 184.927742 -292.309892) (xy 184.968245 -292.337848) (xy 185.003738 -292.37194) (xy 185.033303 -292.411284)
			(xy 185.056174 -292.454861) (xy 185.071758 -292.501542) (xy 185.079653 -292.550119) (xy 185.080148 -292.574726)
			(xy 185.079653 -292.599333) (xy 185.071758 -292.64791) (xy 185.056174 -292.694591) (xy 185.033303 -292.738168)
			(xy 185.003738 -292.777512) (xy 184.968245 -292.811604) (xy 184.927742 -292.83956) (xy 184.88328 -292.860658)
			(xy 184.836009 -292.87435) (xy 184.787154 -292.880282) (xy 184.737979 -292.878301) (xy 184.68976 -292.868457)
			(xy 184.643744 -292.851005) (xy 184.601123 -292.826398) (xy 184.563002 -292.795273) (xy 184.530367 -292.758436)
			(xy 184.504064 -292.71684) (xy 184.484773 -292.671564) (xy 184.472996 -292.62378) (xy 184.469036 -292.574726)
			(xy 166.080186 -292.574726) (xy 166.079691 -292.599333) (xy 166.071796 -292.64791) (xy 166.056212 -292.694591)
			(xy 166.033341 -292.738168) (xy 166.003776 -292.777512) (xy 165.968283 -292.811604) (xy 165.92778 -292.83956)
			(xy 165.883318 -292.860658) (xy 165.836047 -292.87435) (xy 165.787192 -292.880282) (xy 165.738017 -292.878301)
			(xy 165.689798 -292.868457) (xy 165.643782 -292.851005) (xy 165.601161 -292.826398) (xy 165.56304 -292.795273)
			(xy 165.530405 -292.758436) (xy 165.504102 -292.71684) (xy 165.484811 -292.671564) (xy 165.473034 -292.62378)
			(xy 165.469074 -292.574726) (xy 165.130226 -292.574726) (xy 165.129731 -292.599333) (xy 165.121836 -292.64791)
			(xy 165.106252 -292.694591) (xy 165.083381 -292.738168) (xy 165.053816 -292.777512) (xy 165.018323 -292.811604)
			(xy 164.97782 -292.83956) (xy 164.933358 -292.860658) (xy 164.886087 -292.87435) (xy 164.837232 -292.880282)
			(xy 164.788057 -292.878301) (xy 164.739838 -292.868457) (xy 164.693822 -292.851005) (xy 164.651201 -292.826398)
			(xy 164.61308 -292.795273) (xy 164.580445 -292.758436) (xy 164.554142 -292.71684) (xy 164.534851 -292.671564)
			(xy 164.523074 -292.62378) (xy 164.519114 -292.574726) (xy 164.180261 -292.574726) (xy 164.180266 -292.57498)
			(xy 164.179843 -292.598975) (xy 164.172338 -292.646374) (xy 164.15751 -292.692014) (xy 164.135723 -292.734773)
			(xy 164.107515 -292.773597) (xy 164.07358 -292.80753) (xy 164.034755 -292.835735) (xy 163.991994 -292.857518)
			(xy 163.946352 -292.872343) (xy 163.898953 -292.879845) (xy 163.874958 -292.880288) (xy 163.85344 -292.879929)
			(xy 163.810832 -292.873874) (xy 163.769503 -292.861875) (xy 163.749736 -292.853364) (xy 163.741898 -292.850227)
			(xy 163.72509 -292.848756) (xy 163.708719 -292.852839) (xy 163.701476 -292.857174) (xy 163.629848 -292.903402)
			(xy 163.622863 -292.908231) (xy 163.612345 -292.921551) (xy 163.60679 -292.937588) (xy 163.60648 -292.946074)
			(xy 163.60648 -293.153846) (xy 163.606797 -293.162326) (xy 163.61239 -293.178339) (xy 163.622886 -293.191664)
			(xy 163.629848 -293.196518) (xy 163.712398 -293.249858) (xy 163.737798 -293.25189) (xy 163.749736 -293.246556)
			(xy 163.769507 -293.23806) (xy 163.81084 -293.226089) (xy 163.853442 -293.22002) (xy 163.874958 -293.219632)
			(xy 163.900221 -293.220042) (xy 163.95006 -293.228352) (xy 163.99785 -293.244752) (xy 164.042289 -293.268796)
			(xy 164.082164 -293.299827) (xy 164.116387 -293.336998) (xy 164.144025 -293.379296) (xy 164.164323 -293.425566)
			(xy 164.176727 -293.474546) (xy 164.1809 -293.5249) (xy 164.180897 -293.52494) (xy 164.519114 -293.52494)
			(xy 164.523074 -293.475886) (xy 164.534851 -293.428102) (xy 164.554142 -293.382826) (xy 164.580445 -293.34123)
			(xy 164.61308 -293.304393) (xy 164.651201 -293.273268) (xy 164.693822 -293.248661) (xy 164.739838 -293.231209)
			(xy 164.788057 -293.221365) (xy 164.837232 -293.219384) (xy 164.886087 -293.225316) (xy 164.933358 -293.239008)
			(xy 164.97782 -293.260106) (xy 165.018323 -293.288062) (xy 165.053816 -293.322154) (xy 165.083381 -293.361498)
			(xy 165.106252 -293.405075) (xy 165.121836 -293.451756) (xy 165.129731 -293.500333) (xy 165.130226 -293.52494)
			(xy 165.469074 -293.52494) (xy 165.473034 -293.475886) (xy 165.484811 -293.428102) (xy 165.504102 -293.382826)
			(xy 165.530405 -293.34123) (xy 165.56304 -293.304393) (xy 165.601161 -293.273268) (xy 165.643782 -293.248661)
			(xy 165.689798 -293.231209) (xy 165.738017 -293.221365) (xy 165.787192 -293.219384) (xy 165.836047 -293.225316)
			(xy 165.883318 -293.239008) (xy 165.92778 -293.260106) (xy 165.968283 -293.288062) (xy 166.003776 -293.322154)
			(xy 166.033341 -293.361498) (xy 166.056212 -293.405075) (xy 166.071796 -293.451756) (xy 166.079691 -293.500333)
			(xy 166.080186 -293.52494) (xy 166.419288 -293.52494) (xy 166.423248 -293.475886) (xy 166.435025 -293.428102)
			(xy 166.454316 -293.382826) (xy 166.480619 -293.34123) (xy 166.513254 -293.304393) (xy 166.551375 -293.273268)
			(xy 166.593996 -293.248661) (xy 166.640012 -293.231209) (xy 166.688231 -293.221365) (xy 166.737406 -293.219384)
			(xy 166.786261 -293.225316) (xy 166.833532 -293.239008) (xy 166.877994 -293.260106) (xy 166.918497 -293.288062)
			(xy 166.95399 -293.322154) (xy 166.983555 -293.361498) (xy 167.006426 -293.405075) (xy 167.02201 -293.451756)
			(xy 167.029905 -293.500333) (xy 167.0304 -293.52494) (xy 167.369248 -293.52494) (xy 167.373208 -293.475886)
			(xy 167.384985 -293.428102) (xy 167.404276 -293.382826) (xy 167.430579 -293.34123) (xy 167.463214 -293.304393)
			(xy 167.501335 -293.273268) (xy 167.543956 -293.248661) (xy 167.589972 -293.231209) (xy 167.638191 -293.221365)
			(xy 167.687366 -293.219384) (xy 167.736221 -293.225316) (xy 167.783492 -293.239008) (xy 167.827954 -293.260106)
			(xy 167.868457 -293.288062) (xy 167.90395 -293.322154) (xy 167.933515 -293.361498) (xy 167.956386 -293.405075)
			(xy 167.97197 -293.451756) (xy 167.979865 -293.500333) (xy 167.98036 -293.52494) (xy 168.319208 -293.52494)
			(xy 168.323168 -293.475886) (xy 168.334945 -293.428102) (xy 168.354236 -293.382826) (xy 168.380539 -293.34123)
			(xy 168.413174 -293.304393) (xy 168.451295 -293.273268) (xy 168.493916 -293.248661) (xy 168.539932 -293.231209)
			(xy 168.588151 -293.221365) (xy 168.637326 -293.219384) (xy 168.686181 -293.225316) (xy 168.733452 -293.239008)
			(xy 168.777914 -293.260106) (xy 168.818417 -293.288062) (xy 168.85391 -293.322154) (xy 168.883475 -293.361498)
			(xy 168.906346 -293.405075) (xy 168.92193 -293.451756) (xy 168.929825 -293.500333) (xy 168.93032 -293.52494)
			(xy 169.269168 -293.52494) (xy 169.273128 -293.475886) (xy 169.284905 -293.428102) (xy 169.304196 -293.382826)
			(xy 169.330499 -293.34123) (xy 169.363134 -293.304393) (xy 169.401255 -293.273268) (xy 169.443876 -293.248661)
			(xy 169.489892 -293.231209) (xy 169.538111 -293.221365) (xy 169.587286 -293.219384) (xy 169.636141 -293.225316)
			(xy 169.683412 -293.239008) (xy 169.727874 -293.260106) (xy 169.768377 -293.288062) (xy 169.80387 -293.322154)
			(xy 169.833435 -293.361498) (xy 169.856306 -293.405075) (xy 169.87189 -293.451756) (xy 169.879785 -293.500333)
			(xy 169.88028 -293.52494) (xy 170.219128 -293.52494) (xy 170.223088 -293.475886) (xy 170.234865 -293.428102)
			(xy 170.254156 -293.382826) (xy 170.280459 -293.34123) (xy 170.313094 -293.304393) (xy 170.351215 -293.273268)
			(xy 170.393836 -293.248661) (xy 170.439852 -293.231209) (xy 170.488071 -293.221365) (xy 170.537246 -293.219384)
			(xy 170.586101 -293.225316) (xy 170.633372 -293.239008) (xy 170.677834 -293.260106) (xy 170.718337 -293.288062)
			(xy 170.75383 -293.322154) (xy 170.783395 -293.361498) (xy 170.806266 -293.405075) (xy 170.82185 -293.451756)
			(xy 170.829745 -293.500333) (xy 170.83024 -293.52494) (xy 171.169088 -293.52494) (xy 171.173048 -293.475886)
			(xy 171.184825 -293.428102) (xy 171.204116 -293.382826) (xy 171.230419 -293.34123) (xy 171.263054 -293.304393)
			(xy 171.301175 -293.273268) (xy 171.343796 -293.248661) (xy 171.389812 -293.231209) (xy 171.438031 -293.221365)
			(xy 171.487206 -293.219384) (xy 171.536061 -293.225316) (xy 171.583332 -293.239008) (xy 171.627794 -293.260106)
			(xy 171.668297 -293.288062) (xy 171.70379 -293.322154) (xy 171.733355 -293.361498) (xy 171.756226 -293.405075)
			(xy 171.77181 -293.451756) (xy 171.779705 -293.500333) (xy 171.7802 -293.52494) (xy 172.119048 -293.52494)
			(xy 172.123008 -293.475886) (xy 172.134785 -293.428102) (xy 172.154076 -293.382826) (xy 172.180379 -293.34123)
			(xy 172.213014 -293.304393) (xy 172.251135 -293.273268) (xy 172.293756 -293.248661) (xy 172.339772 -293.231209)
			(xy 172.387991 -293.221365) (xy 172.437166 -293.219384) (xy 172.486021 -293.225316) (xy 172.533292 -293.239008)
			(xy 172.577754 -293.260106) (xy 172.618257 -293.288062) (xy 172.65375 -293.322154) (xy 172.683315 -293.361498)
			(xy 172.706186 -293.405075) (xy 172.72177 -293.451756) (xy 172.729665 -293.500333) (xy 172.73016 -293.52494)
			(xy 173.069262 -293.52494) (xy 173.073222 -293.475886) (xy 173.084999 -293.428102) (xy 173.10429 -293.382826)
			(xy 173.130593 -293.34123) (xy 173.163228 -293.304393) (xy 173.201349 -293.273268) (xy 173.24397 -293.248661)
			(xy 173.289986 -293.231209) (xy 173.338205 -293.221365) (xy 173.38738 -293.219384) (xy 173.436235 -293.225316)
			(xy 173.483506 -293.239008) (xy 173.527968 -293.260106) (xy 173.568471 -293.288062) (xy 173.603964 -293.322154)
			(xy 173.633529 -293.361498) (xy 173.6564 -293.405075) (xy 173.671984 -293.451756) (xy 173.679879 -293.500333)
			(xy 173.680374 -293.52494) (xy 174.019222 -293.52494) (xy 174.023182 -293.475886) (xy 174.034959 -293.428102)
			(xy 174.05425 -293.382826) (xy 174.080553 -293.34123) (xy 174.113188 -293.304393) (xy 174.151309 -293.273268)
			(xy 174.19393 -293.248661) (xy 174.239946 -293.231209) (xy 174.288165 -293.221365) (xy 174.33734 -293.219384)
			(xy 174.386195 -293.225316) (xy 174.433466 -293.239008) (xy 174.477928 -293.260106) (xy 174.518431 -293.288062)
			(xy 174.553924 -293.322154) (xy 174.583489 -293.361498) (xy 174.60636 -293.405075) (xy 174.621944 -293.451756)
			(xy 174.629839 -293.500333) (xy 174.630334 -293.52494) (xy 175.919142 -293.52494) (xy 175.923102 -293.475886)
			(xy 175.934879 -293.428102) (xy 175.95417 -293.382826) (xy 175.980473 -293.34123) (xy 176.013108 -293.304393)
			(xy 176.051229 -293.273268) (xy 176.09385 -293.248661) (xy 176.139866 -293.231209) (xy 176.188085 -293.221365)
			(xy 176.23726 -293.219384) (xy 176.286115 -293.225316) (xy 176.333386 -293.239008) (xy 176.377848 -293.260106)
			(xy 176.418351 -293.288062) (xy 176.453844 -293.322154) (xy 176.483409 -293.361498) (xy 176.50628 -293.405075)
			(xy 176.521864 -293.451756) (xy 176.529759 -293.500333) (xy 176.530254 -293.52494) (xy 176.869102 -293.52494)
			(xy 176.873062 -293.475886) (xy 176.884839 -293.428102) (xy 176.90413 -293.382826) (xy 176.930433 -293.34123)
			(xy 176.963068 -293.304393) (xy 177.001189 -293.273268) (xy 177.04381 -293.248661) (xy 177.089826 -293.231209)
			(xy 177.138045 -293.221365) (xy 177.18722 -293.219384) (xy 177.236075 -293.225316) (xy 177.283346 -293.239008)
			(xy 177.327808 -293.260106) (xy 177.368311 -293.288062) (xy 177.403804 -293.322154) (xy 177.433369 -293.361498)
			(xy 177.45624 -293.405075) (xy 177.471824 -293.451756) (xy 177.479719 -293.500333) (xy 177.480214 -293.52494)
			(xy 177.819062 -293.52494) (xy 177.823022 -293.475886) (xy 177.834799 -293.428102) (xy 177.85409 -293.382826)
			(xy 177.880393 -293.34123) (xy 177.913028 -293.304393) (xy 177.951149 -293.273268) (xy 177.99377 -293.248661)
			(xy 178.039786 -293.231209) (xy 178.088005 -293.221365) (xy 178.13718 -293.219384) (xy 178.186035 -293.225316)
			(xy 178.233306 -293.239008) (xy 178.277768 -293.260106) (xy 178.318271 -293.288062) (xy 178.353764 -293.322154)
			(xy 178.383329 -293.361498) (xy 178.4062 -293.405075) (xy 178.421784 -293.451756) (xy 178.429679 -293.500333)
			(xy 178.430174 -293.52494) (xy 178.769276 -293.52494) (xy 178.773236 -293.475886) (xy 178.785013 -293.428102)
			(xy 178.804304 -293.382826) (xy 178.830607 -293.34123) (xy 178.863242 -293.304393) (xy 178.901363 -293.273268)
			(xy 178.943984 -293.248661) (xy 178.99 -293.231209) (xy 179.038219 -293.221365) (xy 179.087394 -293.219384)
			(xy 179.136249 -293.225316) (xy 179.18352 -293.239008) (xy 179.227982 -293.260106) (xy 179.268485 -293.288062)
			(xy 179.303978 -293.322154) (xy 179.333543 -293.361498) (xy 179.356414 -293.405075) (xy 179.371998 -293.451756)
			(xy 179.379893 -293.500333) (xy 179.380388 -293.52494) (xy 179.719236 -293.52494) (xy 179.723196 -293.475886)
			(xy 179.734973 -293.428102) (xy 179.754264 -293.382826) (xy 179.780567 -293.34123) (xy 179.813202 -293.304393)
			(xy 179.851323 -293.273268) (xy 179.893944 -293.248661) (xy 179.93996 -293.231209) (xy 179.988179 -293.221365)
			(xy 180.037354 -293.219384) (xy 180.086209 -293.225316) (xy 180.13348 -293.239008) (xy 180.177942 -293.260106)
			(xy 180.218445 -293.288062) (xy 180.253938 -293.322154) (xy 180.283503 -293.361498) (xy 180.306374 -293.405075)
			(xy 180.321958 -293.451756) (xy 180.329853 -293.500333) (xy 180.330348 -293.52494) (xy 180.669196 -293.52494)
			(xy 180.673156 -293.475886) (xy 180.684933 -293.428102) (xy 180.704224 -293.382826) (xy 180.730527 -293.34123)
			(xy 180.763162 -293.304393) (xy 180.801283 -293.273268) (xy 180.843904 -293.248661) (xy 180.88992 -293.231209)
			(xy 180.938139 -293.221365) (xy 180.987314 -293.219384) (xy 181.036169 -293.225316) (xy 181.08344 -293.239008)
			(xy 181.127902 -293.260106) (xy 181.168405 -293.288062) (xy 181.203898 -293.322154) (xy 181.233463 -293.361498)
			(xy 181.256334 -293.405075) (xy 181.271918 -293.451756) (xy 181.279813 -293.500333) (xy 181.280308 -293.52494)
			(xy 181.619156 -293.52494) (xy 181.623116 -293.475886) (xy 181.634893 -293.428102) (xy 181.654184 -293.382826)
			(xy 181.680487 -293.34123) (xy 181.713122 -293.304393) (xy 181.751243 -293.273268) (xy 181.793864 -293.248661)
			(xy 181.83988 -293.231209) (xy 181.888099 -293.221365) (xy 181.937274 -293.219384) (xy 181.986129 -293.225316)
			(xy 182.0334 -293.239008) (xy 182.077862 -293.260106) (xy 182.118365 -293.288062) (xy 182.153858 -293.322154)
			(xy 182.183423 -293.361498) (xy 182.206294 -293.405075) (xy 182.221878 -293.451756) (xy 182.229773 -293.500333)
			(xy 182.230268 -293.52494) (xy 182.569116 -293.52494) (xy 182.573076 -293.475886) (xy 182.584853 -293.428102)
			(xy 182.604144 -293.382826) (xy 182.630447 -293.34123) (xy 182.663082 -293.304393) (xy 182.701203 -293.273268)
			(xy 182.743824 -293.248661) (xy 182.78984 -293.231209) (xy 182.838059 -293.221365) (xy 182.887234 -293.219384)
			(xy 182.936089 -293.225316) (xy 182.98336 -293.239008) (xy 183.027822 -293.260106) (xy 183.068325 -293.288062)
			(xy 183.103818 -293.322154) (xy 183.133383 -293.361498) (xy 183.156254 -293.405075) (xy 183.171838 -293.451756)
			(xy 183.179733 -293.500333) (xy 183.180228 -293.52494) (xy 183.519076 -293.52494) (xy 183.523036 -293.475886)
			(xy 183.534813 -293.428102) (xy 183.554104 -293.382826) (xy 183.580407 -293.34123) (xy 183.613042 -293.304393)
			(xy 183.651163 -293.273268) (xy 183.693784 -293.248661) (xy 183.7398 -293.231209) (xy 183.788019 -293.221365)
			(xy 183.837194 -293.219384) (xy 183.886049 -293.225316) (xy 183.93332 -293.239008) (xy 183.977782 -293.260106)
			(xy 184.018285 -293.288062) (xy 184.053778 -293.322154) (xy 184.083343 -293.361498) (xy 184.106214 -293.405075)
			(xy 184.121798 -293.451756) (xy 184.129693 -293.500333) (xy 184.130188 -293.52494) (xy 184.469036 -293.52494)
			(xy 184.472996 -293.475886) (xy 184.484773 -293.428102) (xy 184.504064 -293.382826) (xy 184.530367 -293.34123)
			(xy 184.563002 -293.304393) (xy 184.601123 -293.273268) (xy 184.643744 -293.248661) (xy 184.68976 -293.231209)
			(xy 184.737979 -293.221365) (xy 184.787154 -293.219384) (xy 184.836009 -293.225316) (xy 184.88328 -293.239008)
			(xy 184.927742 -293.260106) (xy 184.968245 -293.288062) (xy 185.003738 -293.322154) (xy 185.033303 -293.361498)
			(xy 185.056174 -293.405075) (xy 185.071758 -293.451756) (xy 185.079653 -293.500333) (xy 185.080148 -293.52494)
			(xy 185.079653 -293.549547) (xy 185.071758 -293.598124) (xy 185.056174 -293.644805) (xy 185.033303 -293.688382)
			(xy 185.003738 -293.727726) (xy 184.968245 -293.761818) (xy 184.927742 -293.789774) (xy 184.88328 -293.810872)
			(xy 184.836009 -293.824564) (xy 184.787154 -293.830496) (xy 184.737979 -293.828515) (xy 184.68976 -293.818671)
			(xy 184.643744 -293.801219) (xy 184.601123 -293.776612) (xy 184.563002 -293.745487) (xy 184.530367 -293.70865)
			(xy 184.504064 -293.667054) (xy 184.484773 -293.621778) (xy 184.472996 -293.573994) (xy 184.469036 -293.52494)
			(xy 184.130188 -293.52494) (xy 184.129693 -293.549547) (xy 184.121798 -293.598124) (xy 184.106214 -293.644805)
			(xy 184.083343 -293.688382) (xy 184.053778 -293.727726) (xy 184.018285 -293.761818) (xy 183.977782 -293.789774)
			(xy 183.93332 -293.810872) (xy 183.886049 -293.824564) (xy 183.837194 -293.830496) (xy 183.788019 -293.828515)
			(xy 183.7398 -293.818671) (xy 183.693784 -293.801219) (xy 183.651163 -293.776612) (xy 183.613042 -293.745487)
			(xy 183.580407 -293.70865) (xy 183.554104 -293.667054) (xy 183.534813 -293.621778) (xy 183.523036 -293.573994)
			(xy 183.519076 -293.52494) (xy 183.180228 -293.52494) (xy 183.179733 -293.549547) (xy 183.171838 -293.598124)
			(xy 183.156254 -293.644805) (xy 183.133383 -293.688382) (xy 183.103818 -293.727726) (xy 183.068325 -293.761818)
			(xy 183.027822 -293.789774) (xy 182.98336 -293.810872) (xy 182.936089 -293.824564) (xy 182.887234 -293.830496)
			(xy 182.838059 -293.828515) (xy 182.78984 -293.818671) (xy 182.743824 -293.801219) (xy 182.701203 -293.776612)
			(xy 182.663082 -293.745487) (xy 182.630447 -293.70865) (xy 182.604144 -293.667054) (xy 182.584853 -293.621778)
			(xy 182.573076 -293.573994) (xy 182.569116 -293.52494) (xy 182.230268 -293.52494) (xy 182.229773 -293.549547)
			(xy 182.221878 -293.598124) (xy 182.206294 -293.644805) (xy 182.183423 -293.688382) (xy 182.153858 -293.727726)
			(xy 182.118365 -293.761818) (xy 182.077862 -293.789774) (xy 182.0334 -293.810872) (xy 181.986129 -293.824564)
			(xy 181.937274 -293.830496) (xy 181.888099 -293.828515) (xy 181.83988 -293.818671) (xy 181.793864 -293.801219)
			(xy 181.751243 -293.776612) (xy 181.713122 -293.745487) (xy 181.680487 -293.70865) (xy 181.654184 -293.667054)
			(xy 181.634893 -293.621778) (xy 181.623116 -293.573994) (xy 181.619156 -293.52494) (xy 181.280308 -293.52494)
			(xy 181.279813 -293.549547) (xy 181.271918 -293.598124) (xy 181.256334 -293.644805) (xy 181.233463 -293.688382)
			(xy 181.203898 -293.727726) (xy 181.168405 -293.761818) (xy 181.127902 -293.789774) (xy 181.08344 -293.810872)
			(xy 181.036169 -293.824564) (xy 180.987314 -293.830496) (xy 180.938139 -293.828515) (xy 180.88992 -293.818671)
			(xy 180.843904 -293.801219) (xy 180.801283 -293.776612) (xy 180.763162 -293.745487) (xy 180.730527 -293.70865)
			(xy 180.704224 -293.667054) (xy 180.684933 -293.621778) (xy 180.673156 -293.573994) (xy 180.669196 -293.52494)
			(xy 180.330348 -293.52494) (xy 180.329853 -293.549547) (xy 180.321958 -293.598124) (xy 180.306374 -293.644805)
			(xy 180.283503 -293.688382) (xy 180.253938 -293.727726) (xy 180.218445 -293.761818) (xy 180.177942 -293.789774)
			(xy 180.13348 -293.810872) (xy 180.086209 -293.824564) (xy 180.037354 -293.830496) (xy 179.988179 -293.828515)
			(xy 179.93996 -293.818671) (xy 179.893944 -293.801219) (xy 179.851323 -293.776612) (xy 179.813202 -293.745487)
			(xy 179.780567 -293.70865) (xy 179.754264 -293.667054) (xy 179.734973 -293.621778) (xy 179.723196 -293.573994)
			(xy 179.719236 -293.52494) (xy 179.380388 -293.52494) (xy 179.379893 -293.549547) (xy 179.371998 -293.598124)
			(xy 179.356414 -293.644805) (xy 179.333543 -293.688382) (xy 179.303978 -293.727726) (xy 179.268485 -293.761818)
			(xy 179.227982 -293.789774) (xy 179.18352 -293.810872) (xy 179.136249 -293.824564) (xy 179.087394 -293.830496)
			(xy 179.038219 -293.828515) (xy 178.99 -293.818671) (xy 178.943984 -293.801219) (xy 178.901363 -293.776612)
			(xy 178.863242 -293.745487) (xy 178.830607 -293.70865) (xy 178.804304 -293.667054) (xy 178.785013 -293.621778)
			(xy 178.773236 -293.573994) (xy 178.769276 -293.52494) (xy 178.430174 -293.52494) (xy 178.429679 -293.549547)
			(xy 178.421784 -293.598124) (xy 178.4062 -293.644805) (xy 178.383329 -293.688382) (xy 178.353764 -293.727726)
			(xy 178.318271 -293.761818) (xy 178.277768 -293.789774) (xy 178.233306 -293.810872) (xy 178.186035 -293.824564)
			(xy 178.13718 -293.830496) (xy 178.088005 -293.828515) (xy 178.039786 -293.818671) (xy 177.99377 -293.801219)
			(xy 177.951149 -293.776612) (xy 177.913028 -293.745487) (xy 177.880393 -293.70865) (xy 177.85409 -293.667054)
			(xy 177.834799 -293.621778) (xy 177.823022 -293.573994) (xy 177.819062 -293.52494) (xy 177.480214 -293.52494)
			(xy 177.479719 -293.549547) (xy 177.471824 -293.598124) (xy 177.45624 -293.644805) (xy 177.433369 -293.688382)
			(xy 177.403804 -293.727726) (xy 177.368311 -293.761818) (xy 177.327808 -293.789774) (xy 177.283346 -293.810872)
			(xy 177.236075 -293.824564) (xy 177.18722 -293.830496) (xy 177.138045 -293.828515) (xy 177.089826 -293.818671)
			(xy 177.04381 -293.801219) (xy 177.001189 -293.776612) (xy 176.963068 -293.745487) (xy 176.930433 -293.70865)
			(xy 176.90413 -293.667054) (xy 176.884839 -293.621778) (xy 176.873062 -293.573994) (xy 176.869102 -293.52494)
			(xy 176.530254 -293.52494) (xy 176.529759 -293.549547) (xy 176.521864 -293.598124) (xy 176.50628 -293.644805)
			(xy 176.483409 -293.688382) (xy 176.453844 -293.727726) (xy 176.418351 -293.761818) (xy 176.377848 -293.789774)
			(xy 176.333386 -293.810872) (xy 176.286115 -293.824564) (xy 176.23726 -293.830496) (xy 176.188085 -293.828515)
			(xy 176.139866 -293.818671) (xy 176.09385 -293.801219) (xy 176.051229 -293.776612) (xy 176.013108 -293.745487)
			(xy 175.980473 -293.70865) (xy 175.95417 -293.667054) (xy 175.934879 -293.621778) (xy 175.923102 -293.573994)
			(xy 175.919142 -293.52494) (xy 174.630334 -293.52494) (xy 174.629839 -293.549547) (xy 174.621944 -293.598124)
			(xy 174.60636 -293.644805) (xy 174.583489 -293.688382) (xy 174.553924 -293.727726) (xy 174.518431 -293.761818)
			(xy 174.477928 -293.789774) (xy 174.433466 -293.810872) (xy 174.386195 -293.824564) (xy 174.33734 -293.830496)
			(xy 174.288165 -293.828515) (xy 174.239946 -293.818671) (xy 174.19393 -293.801219) (xy 174.151309 -293.776612)
			(xy 174.113188 -293.745487) (xy 174.080553 -293.70865) (xy 174.05425 -293.667054) (xy 174.034959 -293.621778)
			(xy 174.023182 -293.573994) (xy 174.019222 -293.52494) (xy 173.680374 -293.52494) (xy 173.679879 -293.549547)
			(xy 173.671984 -293.598124) (xy 173.6564 -293.644805) (xy 173.633529 -293.688382) (xy 173.603964 -293.727726)
			(xy 173.568471 -293.761818) (xy 173.527968 -293.789774) (xy 173.483506 -293.810872) (xy 173.436235 -293.824564)
			(xy 173.38738 -293.830496) (xy 173.338205 -293.828515) (xy 173.289986 -293.818671) (xy 173.24397 -293.801219)
			(xy 173.201349 -293.776612) (xy 173.163228 -293.745487) (xy 173.130593 -293.70865) (xy 173.10429 -293.667054)
			(xy 173.084999 -293.621778) (xy 173.073222 -293.573994) (xy 173.069262 -293.52494) (xy 172.73016 -293.52494)
			(xy 172.729665 -293.549547) (xy 172.72177 -293.598124) (xy 172.706186 -293.644805) (xy 172.683315 -293.688382)
			(xy 172.65375 -293.727726) (xy 172.618257 -293.761818) (xy 172.577754 -293.789774) (xy 172.533292 -293.810872)
			(xy 172.486021 -293.824564) (xy 172.437166 -293.830496) (xy 172.387991 -293.828515) (xy 172.339772 -293.818671)
			(xy 172.293756 -293.801219) (xy 172.251135 -293.776612) (xy 172.213014 -293.745487) (xy 172.180379 -293.70865)
			(xy 172.154076 -293.667054) (xy 172.134785 -293.621778) (xy 172.123008 -293.573994) (xy 172.119048 -293.52494)
			(xy 171.7802 -293.52494) (xy 171.779705 -293.549547) (xy 171.77181 -293.598124) (xy 171.756226 -293.644805)
			(xy 171.733355 -293.688382) (xy 171.70379 -293.727726) (xy 171.668297 -293.761818) (xy 171.627794 -293.789774)
			(xy 171.583332 -293.810872) (xy 171.536061 -293.824564) (xy 171.487206 -293.830496) (xy 171.438031 -293.828515)
			(xy 171.389812 -293.818671) (xy 171.343796 -293.801219) (xy 171.301175 -293.776612) (xy 171.263054 -293.745487)
			(xy 171.230419 -293.70865) (xy 171.204116 -293.667054) (xy 171.184825 -293.621778) (xy 171.173048 -293.573994)
			(xy 171.169088 -293.52494) (xy 170.83024 -293.52494) (xy 170.829745 -293.549547) (xy 170.82185 -293.598124)
			(xy 170.806266 -293.644805) (xy 170.783395 -293.688382) (xy 170.75383 -293.727726) (xy 170.718337 -293.761818)
			(xy 170.677834 -293.789774) (xy 170.633372 -293.810872) (xy 170.586101 -293.824564) (xy 170.537246 -293.830496)
			(xy 170.488071 -293.828515) (xy 170.439852 -293.818671) (xy 170.393836 -293.801219) (xy 170.351215 -293.776612)
			(xy 170.313094 -293.745487) (xy 170.280459 -293.70865) (xy 170.254156 -293.667054) (xy 170.234865 -293.621778)
			(xy 170.223088 -293.573994) (xy 170.219128 -293.52494) (xy 169.88028 -293.52494) (xy 169.879785 -293.549547)
			(xy 169.87189 -293.598124) (xy 169.856306 -293.644805) (xy 169.833435 -293.688382) (xy 169.80387 -293.727726)
			(xy 169.768377 -293.761818) (xy 169.727874 -293.789774) (xy 169.683412 -293.810872) (xy 169.636141 -293.824564)
			(xy 169.587286 -293.830496) (xy 169.538111 -293.828515) (xy 169.489892 -293.818671) (xy 169.443876 -293.801219)
			(xy 169.401255 -293.776612) (xy 169.363134 -293.745487) (xy 169.330499 -293.70865) (xy 169.304196 -293.667054)
			(xy 169.284905 -293.621778) (xy 169.273128 -293.573994) (xy 169.269168 -293.52494) (xy 168.93032 -293.52494)
			(xy 168.929825 -293.549547) (xy 168.92193 -293.598124) (xy 168.906346 -293.644805) (xy 168.883475 -293.688382)
			(xy 168.85391 -293.727726) (xy 168.818417 -293.761818) (xy 168.777914 -293.789774) (xy 168.733452 -293.810872)
			(xy 168.686181 -293.824564) (xy 168.637326 -293.830496) (xy 168.588151 -293.828515) (xy 168.539932 -293.818671)
			(xy 168.493916 -293.801219) (xy 168.451295 -293.776612) (xy 168.413174 -293.745487) (xy 168.380539 -293.70865)
			(xy 168.354236 -293.667054) (xy 168.334945 -293.621778) (xy 168.323168 -293.573994) (xy 168.319208 -293.52494)
			(xy 167.98036 -293.52494) (xy 167.979865 -293.549547) (xy 167.97197 -293.598124) (xy 167.956386 -293.644805)
			(xy 167.933515 -293.688382) (xy 167.90395 -293.727726) (xy 167.868457 -293.761818) (xy 167.827954 -293.789774)
			(xy 167.783492 -293.810872) (xy 167.736221 -293.824564) (xy 167.687366 -293.830496) (xy 167.638191 -293.828515)
			(xy 167.589972 -293.818671) (xy 167.543956 -293.801219) (xy 167.501335 -293.776612) (xy 167.463214 -293.745487)
			(xy 167.430579 -293.70865) (xy 167.404276 -293.667054) (xy 167.384985 -293.621778) (xy 167.373208 -293.573994)
			(xy 167.369248 -293.52494) (xy 167.0304 -293.52494) (xy 167.029905 -293.549547) (xy 167.02201 -293.598124)
			(xy 167.006426 -293.644805) (xy 166.983555 -293.688382) (xy 166.95399 -293.727726) (xy 166.918497 -293.761818)
			(xy 166.877994 -293.789774) (xy 166.833532 -293.810872) (xy 166.786261 -293.824564) (xy 166.737406 -293.830496)
			(xy 166.688231 -293.828515) (xy 166.640012 -293.818671) (xy 166.593996 -293.801219) (xy 166.551375 -293.776612)
			(xy 166.513254 -293.745487) (xy 166.480619 -293.70865) (xy 166.454316 -293.667054) (xy 166.435025 -293.621778)
			(xy 166.423248 -293.573994) (xy 166.419288 -293.52494) (xy 166.080186 -293.52494) (xy 166.079691 -293.549547)
			(xy 166.071796 -293.598124) (xy 166.056212 -293.644805) (xy 166.033341 -293.688382) (xy 166.003776 -293.727726)
			(xy 165.968283 -293.761818) (xy 165.92778 -293.789774) (xy 165.883318 -293.810872) (xy 165.836047 -293.824564)
			(xy 165.787192 -293.830496) (xy 165.738017 -293.828515) (xy 165.689798 -293.818671) (xy 165.643782 -293.801219)
			(xy 165.601161 -293.776612) (xy 165.56304 -293.745487) (xy 165.530405 -293.70865) (xy 165.504102 -293.667054)
			(xy 165.484811 -293.621778) (xy 165.473034 -293.573994) (xy 165.469074 -293.52494) (xy 165.130226 -293.52494)
			(xy 165.129731 -293.549547) (xy 165.121836 -293.598124) (xy 165.106252 -293.644805) (xy 165.083381 -293.688382)
			(xy 165.053816 -293.727726) (xy 165.018323 -293.761818) (xy 164.97782 -293.789774) (xy 164.933358 -293.810872)
			(xy 164.886087 -293.824564) (xy 164.837232 -293.830496) (xy 164.788057 -293.828515) (xy 164.739838 -293.818671)
			(xy 164.693822 -293.801219) (xy 164.651201 -293.776612) (xy 164.61308 -293.745487) (xy 164.580445 -293.70865)
			(xy 164.554142 -293.667054) (xy 164.534851 -293.621778) (xy 164.523074 -293.573994) (xy 164.519114 -293.52494)
			(xy 164.180897 -293.52494) (xy 164.176727 -293.575254) (xy 164.164323 -293.624234) (xy 164.144025 -293.670504)
			(xy 164.116387 -293.712802) (xy 164.082164 -293.749973) (xy 164.042289 -293.781004) (xy 163.99785 -293.805048)
			(xy 163.95006 -293.821448) (xy 163.900221 -293.829758) (xy 163.874958 -293.830248) (xy 163.850606 -293.829786)
			(xy 163.802519 -293.822061) (xy 163.756268 -293.8068) (xy 163.713028 -293.784388) (xy 163.673895 -293.755394)
			(xy 163.639862 -293.720554) (xy 163.611793 -293.680753) (xy 163.590399 -293.636999) (xy 163.582858 -293.61384)
			(xy 163.579556 -293.602918) (xy 163.56457 -293.586154) (xy 163.47059 -293.547292) (xy 163.44773 -293.548562)
			(xy 163.437824 -293.553896) (xy 163.423092 -293.561262) (xy 163.411916 -293.566596) (xy 163.39693 -293.586154)
			(xy 163.38042 -293.680388) (xy 163.378991 -293.692495) (xy 163.386302 -293.715714) (xy 163.39439 -293.724838)
			(xy 163.448492 -293.77894) (xy 163.465085 -293.796238) (xy 163.49325 -293.835017) (xy 163.515019 -293.877717)
			(xy 163.529857 -293.923291) (xy 163.537401 -293.970622) (xy 163.5379 -293.994586) (xy 163.5379 -294.142922)
			(xy 163.538311 -294.152223) (xy 163.544885 -294.169619) (xy 163.557258 -294.183502) (xy 163.565332 -294.188134)
			(xy 163.645596 -294.229536) (xy 163.654039 -294.233379) (xy 163.672456 -294.235428) (xy 163.690391 -294.230769)
			(xy 163.698174 -294.225726) (xy 163.698428 -294.225726) (xy 163.7179 -294.212496) (xy 163.760043 -294.191519)
			(xy 163.804903 -294.177251) (xy 163.851421 -294.170029) (xy 163.874958 -294.169592) (xy 163.900218 -294.170081)
			(xy 163.95005 -294.178391) (xy 163.997834 -294.194789) (xy 164.042267 -294.21883) (xy 164.082137 -294.249856)
			(xy 164.116356 -294.287023) (xy 164.14399 -294.329315) (xy 164.164285 -294.375579) (xy 164.176688 -294.424553)
			(xy 164.18086 -294.4749) (xy 164.519114 -294.4749) (xy 164.523074 -294.425846) (xy 164.534851 -294.378062)
			(xy 164.554142 -294.332786) (xy 164.580445 -294.29119) (xy 164.61308 -294.254353) (xy 164.651201 -294.223228)
			(xy 164.693822 -294.198621) (xy 164.739838 -294.181169) (xy 164.788057 -294.171325) (xy 164.837232 -294.169344)
			(xy 164.886087 -294.175276) (xy 164.933358 -294.188968) (xy 164.97782 -294.210066) (xy 165.018323 -294.238022)
			(xy 165.053816 -294.272114) (xy 165.083381 -294.311458) (xy 165.106252 -294.355035) (xy 165.121836 -294.401716)
			(xy 165.129731 -294.450293) (xy 165.130226 -294.4749) (xy 165.469074 -294.4749) (xy 165.473034 -294.425846)
			(xy 165.484811 -294.378062) (xy 165.504102 -294.332786) (xy 165.530405 -294.29119) (xy 165.56304 -294.254353)
			(xy 165.601161 -294.223228) (xy 165.643782 -294.198621) (xy 165.689798 -294.181169) (xy 165.738017 -294.171325)
			(xy 165.787192 -294.169344) (xy 165.836047 -294.175276) (xy 165.883318 -294.188968) (xy 165.92778 -294.210066)
			(xy 165.968283 -294.238022) (xy 166.003776 -294.272114) (xy 166.033341 -294.311458) (xy 166.056212 -294.355035)
			(xy 166.071796 -294.401716) (xy 166.079691 -294.450293) (xy 166.080186 -294.4749) (xy 166.419288 -294.4749)
			(xy 166.423248 -294.425846) (xy 166.435025 -294.378062) (xy 166.454316 -294.332786) (xy 166.480619 -294.29119)
			(xy 166.513254 -294.254353) (xy 166.551375 -294.223228) (xy 166.593996 -294.198621) (xy 166.640012 -294.181169)
			(xy 166.688231 -294.171325) (xy 166.737406 -294.169344) (xy 166.786261 -294.175276) (xy 166.833532 -294.188968)
			(xy 166.877994 -294.210066) (xy 166.918497 -294.238022) (xy 166.95399 -294.272114) (xy 166.983555 -294.311458)
			(xy 167.006426 -294.355035) (xy 167.02201 -294.401716) (xy 167.029905 -294.450293) (xy 167.0304 -294.4749)
			(xy 167.369248 -294.4749) (xy 167.373208 -294.425846) (xy 167.384985 -294.378062) (xy 167.404276 -294.332786)
			(xy 167.430579 -294.29119) (xy 167.463214 -294.254353) (xy 167.501335 -294.223228) (xy 167.543956 -294.198621)
			(xy 167.589972 -294.181169) (xy 167.638191 -294.171325) (xy 167.687366 -294.169344) (xy 167.736221 -294.175276)
			(xy 167.783492 -294.188968) (xy 167.827954 -294.210066) (xy 167.868457 -294.238022) (xy 167.90395 -294.272114)
			(xy 167.933515 -294.311458) (xy 167.956386 -294.355035) (xy 167.97197 -294.401716) (xy 167.979865 -294.450293)
			(xy 167.98036 -294.4749) (xy 168.319208 -294.4749) (xy 168.323168 -294.425846) (xy 168.334945 -294.378062)
			(xy 168.354236 -294.332786) (xy 168.380539 -294.29119) (xy 168.413174 -294.254353) (xy 168.451295 -294.223228)
			(xy 168.493916 -294.198621) (xy 168.539932 -294.181169) (xy 168.588151 -294.171325) (xy 168.637326 -294.169344)
			(xy 168.686181 -294.175276) (xy 168.733452 -294.188968) (xy 168.777914 -294.210066) (xy 168.818417 -294.238022)
			(xy 168.85391 -294.272114) (xy 168.883475 -294.311458) (xy 168.906346 -294.355035) (xy 168.92193 -294.401716)
			(xy 168.929825 -294.450293) (xy 168.93032 -294.4749) (xy 169.269168 -294.4749) (xy 169.273128 -294.425846)
			(xy 169.284905 -294.378062) (xy 169.304196 -294.332786) (xy 169.330499 -294.29119) (xy 169.363134 -294.254353)
			(xy 169.401255 -294.223228) (xy 169.443876 -294.198621) (xy 169.489892 -294.181169) (xy 169.538111 -294.171325)
			(xy 169.587286 -294.169344) (xy 169.636141 -294.175276) (xy 169.683412 -294.188968) (xy 169.727874 -294.210066)
			(xy 169.768377 -294.238022) (xy 169.80387 -294.272114) (xy 169.833435 -294.311458) (xy 169.856306 -294.355035)
			(xy 169.87189 -294.401716) (xy 169.879785 -294.450293) (xy 169.88028 -294.4749) (xy 170.219128 -294.4749)
			(xy 170.223088 -294.425846) (xy 170.234865 -294.378062) (xy 170.254156 -294.332786) (xy 170.280459 -294.29119)
			(xy 170.313094 -294.254353) (xy 170.351215 -294.223228) (xy 170.393836 -294.198621) (xy 170.439852 -294.181169)
			(xy 170.488071 -294.171325) (xy 170.537246 -294.169344) (xy 170.586101 -294.175276) (xy 170.633372 -294.188968)
			(xy 170.677834 -294.210066) (xy 170.718337 -294.238022) (xy 170.75383 -294.272114) (xy 170.783395 -294.311458)
			(xy 170.806266 -294.355035) (xy 170.82185 -294.401716) (xy 170.829745 -294.450293) (xy 170.83024 -294.4749)
			(xy 171.169088 -294.4749) (xy 171.173048 -294.425846) (xy 171.184825 -294.378062) (xy 171.204116 -294.332786)
			(xy 171.230419 -294.29119) (xy 171.263054 -294.254353) (xy 171.301175 -294.223228) (xy 171.343796 -294.198621)
			(xy 171.389812 -294.181169) (xy 171.438031 -294.171325) (xy 171.487206 -294.169344) (xy 171.536061 -294.175276)
			(xy 171.583332 -294.188968) (xy 171.627794 -294.210066) (xy 171.668297 -294.238022) (xy 171.70379 -294.272114)
			(xy 171.733355 -294.311458) (xy 171.756226 -294.355035) (xy 171.77181 -294.401716) (xy 171.779705 -294.450293)
			(xy 171.7802 -294.4749) (xy 172.119048 -294.4749) (xy 172.123008 -294.425846) (xy 172.134785 -294.378062)
			(xy 172.154076 -294.332786) (xy 172.180379 -294.29119) (xy 172.213014 -294.254353) (xy 172.251135 -294.223228)
			(xy 172.293756 -294.198621) (xy 172.339772 -294.181169) (xy 172.387991 -294.171325) (xy 172.437166 -294.169344)
			(xy 172.486021 -294.175276) (xy 172.533292 -294.188968) (xy 172.577754 -294.210066) (xy 172.618257 -294.238022)
			(xy 172.65375 -294.272114) (xy 172.683315 -294.311458) (xy 172.706186 -294.355035) (xy 172.72177 -294.401716)
			(xy 172.729665 -294.450293) (xy 172.73016 -294.4749) (xy 173.069262 -294.4749) (xy 173.073222 -294.425846)
			(xy 173.084999 -294.378062) (xy 173.10429 -294.332786) (xy 173.130593 -294.29119) (xy 173.163228 -294.254353)
			(xy 173.201349 -294.223228) (xy 173.24397 -294.198621) (xy 173.289986 -294.181169) (xy 173.338205 -294.171325)
			(xy 173.38738 -294.169344) (xy 173.436235 -294.175276) (xy 173.483506 -294.188968) (xy 173.527968 -294.210066)
			(xy 173.568471 -294.238022) (xy 173.603964 -294.272114) (xy 173.633529 -294.311458) (xy 173.6564 -294.355035)
			(xy 173.671984 -294.401716) (xy 173.679879 -294.450293) (xy 173.680374 -294.4749) (xy 174.019222 -294.4749)
			(xy 174.023182 -294.425846) (xy 174.034959 -294.378062) (xy 174.05425 -294.332786) (xy 174.080553 -294.29119)
			(xy 174.113188 -294.254353) (xy 174.151309 -294.223228) (xy 174.19393 -294.198621) (xy 174.239946 -294.181169)
			(xy 174.288165 -294.171325) (xy 174.33734 -294.169344) (xy 174.386195 -294.175276) (xy 174.433466 -294.188968)
			(xy 174.477928 -294.210066) (xy 174.518431 -294.238022) (xy 174.553924 -294.272114) (xy 174.583489 -294.311458)
			(xy 174.60636 -294.355035) (xy 174.621944 -294.401716) (xy 174.629839 -294.450293) (xy 174.630334 -294.4749)
			(xy 175.919142 -294.4749) (xy 175.923102 -294.425846) (xy 175.934879 -294.378062) (xy 175.95417 -294.332786)
			(xy 175.980473 -294.29119) (xy 176.013108 -294.254353) (xy 176.051229 -294.223228) (xy 176.09385 -294.198621)
			(xy 176.139866 -294.181169) (xy 176.188085 -294.171325) (xy 176.23726 -294.169344) (xy 176.286115 -294.175276)
			(xy 176.333386 -294.188968) (xy 176.377848 -294.210066) (xy 176.418351 -294.238022) (xy 176.453844 -294.272114)
			(xy 176.483409 -294.311458) (xy 176.50628 -294.355035) (xy 176.521864 -294.401716) (xy 176.529759 -294.450293)
			(xy 176.530254 -294.4749) (xy 176.869102 -294.4749) (xy 176.873062 -294.425846) (xy 176.884839 -294.378062)
			(xy 176.90413 -294.332786) (xy 176.930433 -294.29119) (xy 176.963068 -294.254353) (xy 177.001189 -294.223228)
			(xy 177.04381 -294.198621) (xy 177.089826 -294.181169) (xy 177.138045 -294.171325) (xy 177.18722 -294.169344)
			(xy 177.236075 -294.175276) (xy 177.283346 -294.188968) (xy 177.327808 -294.210066) (xy 177.368311 -294.238022)
			(xy 177.403804 -294.272114) (xy 177.433369 -294.311458) (xy 177.45624 -294.355035) (xy 177.471824 -294.401716)
			(xy 177.479719 -294.450293) (xy 177.480214 -294.4749) (xy 177.819062 -294.4749) (xy 177.823022 -294.425846)
			(xy 177.834799 -294.378062) (xy 177.85409 -294.332786) (xy 177.880393 -294.29119) (xy 177.913028 -294.254353)
			(xy 177.951149 -294.223228) (xy 177.99377 -294.198621) (xy 178.039786 -294.181169) (xy 178.088005 -294.171325)
			(xy 178.13718 -294.169344) (xy 178.186035 -294.175276) (xy 178.233306 -294.188968) (xy 178.277768 -294.210066)
			(xy 178.318271 -294.238022) (xy 178.353764 -294.272114) (xy 178.383329 -294.311458) (xy 178.4062 -294.355035)
			(xy 178.421784 -294.401716) (xy 178.429679 -294.450293) (xy 178.430174 -294.4749) (xy 178.769276 -294.4749)
			(xy 178.773236 -294.425846) (xy 178.785013 -294.378062) (xy 178.804304 -294.332786) (xy 178.830607 -294.29119)
			(xy 178.863242 -294.254353) (xy 178.901363 -294.223228) (xy 178.943984 -294.198621) (xy 178.99 -294.181169)
			(xy 179.038219 -294.171325) (xy 179.087394 -294.169344) (xy 179.136249 -294.175276) (xy 179.18352 -294.188968)
			(xy 179.227982 -294.210066) (xy 179.268485 -294.238022) (xy 179.303978 -294.272114) (xy 179.333543 -294.311458)
			(xy 179.356414 -294.355035) (xy 179.371998 -294.401716) (xy 179.379893 -294.450293) (xy 179.380388 -294.4749)
			(xy 179.719236 -294.4749) (xy 179.723196 -294.425846) (xy 179.734973 -294.378062) (xy 179.754264 -294.332786)
			(xy 179.780567 -294.29119) (xy 179.813202 -294.254353) (xy 179.851323 -294.223228) (xy 179.893944 -294.198621)
			(xy 179.93996 -294.181169) (xy 179.988179 -294.171325) (xy 180.037354 -294.169344) (xy 180.086209 -294.175276)
			(xy 180.13348 -294.188968) (xy 180.177942 -294.210066) (xy 180.218445 -294.238022) (xy 180.253938 -294.272114)
			(xy 180.283503 -294.311458) (xy 180.306374 -294.355035) (xy 180.321958 -294.401716) (xy 180.329853 -294.450293)
			(xy 180.330348 -294.4749) (xy 180.669196 -294.4749) (xy 180.673156 -294.425846) (xy 180.684933 -294.378062)
			(xy 180.704224 -294.332786) (xy 180.730527 -294.29119) (xy 180.763162 -294.254353) (xy 180.801283 -294.223228)
			(xy 180.843904 -294.198621) (xy 180.88992 -294.181169) (xy 180.938139 -294.171325) (xy 180.987314 -294.169344)
			(xy 181.036169 -294.175276) (xy 181.08344 -294.188968) (xy 181.127902 -294.210066) (xy 181.168405 -294.238022)
			(xy 181.203898 -294.272114) (xy 181.233463 -294.311458) (xy 181.256334 -294.355035) (xy 181.271918 -294.401716)
			(xy 181.279813 -294.450293) (xy 181.280308 -294.4749) (xy 181.619156 -294.4749) (xy 181.623116 -294.425846)
			(xy 181.634893 -294.378062) (xy 181.654184 -294.332786) (xy 181.680487 -294.29119) (xy 181.713122 -294.254353)
			(xy 181.751243 -294.223228) (xy 181.793864 -294.198621) (xy 181.83988 -294.181169) (xy 181.888099 -294.171325)
			(xy 181.937274 -294.169344) (xy 181.986129 -294.175276) (xy 182.0334 -294.188968) (xy 182.077862 -294.210066)
			(xy 182.118365 -294.238022) (xy 182.153858 -294.272114) (xy 182.183423 -294.311458) (xy 182.206294 -294.355035)
			(xy 182.221878 -294.401716) (xy 182.229773 -294.450293) (xy 182.230268 -294.4749) (xy 182.229773 -294.499507)
			(xy 182.221878 -294.548084) (xy 182.206294 -294.594765) (xy 182.183423 -294.638342) (xy 182.153858 -294.677686)
			(xy 182.118365 -294.711778) (xy 182.077862 -294.739734) (xy 182.0334 -294.760832) (xy 181.986129 -294.774524)
			(xy 181.937274 -294.780456) (xy 181.888099 -294.778475) (xy 181.83988 -294.768631) (xy 181.793864 -294.751179)
			(xy 181.751243 -294.726572) (xy 181.713122 -294.695447) (xy 181.680487 -294.65861) (xy 181.654184 -294.617014)
			(xy 181.634893 -294.571738) (xy 181.623116 -294.523954) (xy 181.619156 -294.4749) (xy 181.280308 -294.4749)
			(xy 181.279813 -294.499507) (xy 181.271918 -294.548084) (xy 181.256334 -294.594765) (xy 181.233463 -294.638342)
			(xy 181.203898 -294.677686) (xy 181.168405 -294.711778) (xy 181.127902 -294.739734) (xy 181.08344 -294.760832)
			(xy 181.036169 -294.774524) (xy 180.987314 -294.780456) (xy 180.938139 -294.778475) (xy 180.88992 -294.768631)
			(xy 180.843904 -294.751179) (xy 180.801283 -294.726572) (xy 180.763162 -294.695447) (xy 180.730527 -294.65861)
			(xy 180.704224 -294.617014) (xy 180.684933 -294.571738) (xy 180.673156 -294.523954) (xy 180.669196 -294.4749)
			(xy 180.330348 -294.4749) (xy 180.329853 -294.499507) (xy 180.321958 -294.548084) (xy 180.306374 -294.594765)
			(xy 180.283503 -294.638342) (xy 180.253938 -294.677686) (xy 180.218445 -294.711778) (xy 180.177942 -294.739734)
			(xy 180.13348 -294.760832) (xy 180.086209 -294.774524) (xy 180.037354 -294.780456) (xy 179.988179 -294.778475)
			(xy 179.93996 -294.768631) (xy 179.893944 -294.751179) (xy 179.851323 -294.726572) (xy 179.813202 -294.695447)
			(xy 179.780567 -294.65861) (xy 179.754264 -294.617014) (xy 179.734973 -294.571738) (xy 179.723196 -294.523954)
			(xy 179.719236 -294.4749) (xy 179.380388 -294.4749) (xy 179.379893 -294.499507) (xy 179.371998 -294.548084)
			(xy 179.356414 -294.594765) (xy 179.333543 -294.638342) (xy 179.303978 -294.677686) (xy 179.268485 -294.711778)
			(xy 179.227982 -294.739734) (xy 179.18352 -294.760832) (xy 179.136249 -294.774524) (xy 179.087394 -294.780456)
			(xy 179.038219 -294.778475) (xy 178.99 -294.768631) (xy 178.943984 -294.751179) (xy 178.901363 -294.726572)
			(xy 178.863242 -294.695447) (xy 178.830607 -294.65861) (xy 178.804304 -294.617014) (xy 178.785013 -294.571738)
			(xy 178.773236 -294.523954) (xy 178.769276 -294.4749) (xy 178.430174 -294.4749) (xy 178.429679 -294.499507)
			(xy 178.421784 -294.548084) (xy 178.4062 -294.594765) (xy 178.383329 -294.638342) (xy 178.353764 -294.677686)
			(xy 178.318271 -294.711778) (xy 178.277768 -294.739734) (xy 178.233306 -294.760832) (xy 178.186035 -294.774524)
			(xy 178.13718 -294.780456) (xy 178.088005 -294.778475) (xy 178.039786 -294.768631) (xy 177.99377 -294.751179)
			(xy 177.951149 -294.726572) (xy 177.913028 -294.695447) (xy 177.880393 -294.65861) (xy 177.85409 -294.617014)
			(xy 177.834799 -294.571738) (xy 177.823022 -294.523954) (xy 177.819062 -294.4749) (xy 177.480214 -294.4749)
			(xy 177.479719 -294.499507) (xy 177.471824 -294.548084) (xy 177.45624 -294.594765) (xy 177.433369 -294.638342)
			(xy 177.403804 -294.677686) (xy 177.368311 -294.711778) (xy 177.327808 -294.739734) (xy 177.283346 -294.760832)
			(xy 177.236075 -294.774524) (xy 177.18722 -294.780456) (xy 177.138045 -294.778475) (xy 177.089826 -294.768631)
			(xy 177.04381 -294.751179) (xy 177.001189 -294.726572) (xy 176.963068 -294.695447) (xy 176.930433 -294.65861)
			(xy 176.90413 -294.617014) (xy 176.884839 -294.571738) (xy 176.873062 -294.523954) (xy 176.869102 -294.4749)
			(xy 176.530254 -294.4749) (xy 176.529759 -294.499507) (xy 176.521864 -294.548084) (xy 176.50628 -294.594765)
			(xy 176.483409 -294.638342) (xy 176.453844 -294.677686) (xy 176.418351 -294.711778) (xy 176.377848 -294.739734)
			(xy 176.333386 -294.760832) (xy 176.286115 -294.774524) (xy 176.23726 -294.780456) (xy 176.188085 -294.778475)
			(xy 176.139866 -294.768631) (xy 176.09385 -294.751179) (xy 176.051229 -294.726572) (xy 176.013108 -294.695447)
			(xy 175.980473 -294.65861) (xy 175.95417 -294.617014) (xy 175.934879 -294.571738) (xy 175.923102 -294.523954)
			(xy 175.919142 -294.4749) (xy 174.630334 -294.4749) (xy 174.629839 -294.499507) (xy 174.621944 -294.548084)
			(xy 174.60636 -294.594765) (xy 174.583489 -294.638342) (xy 174.553924 -294.677686) (xy 174.518431 -294.711778)
			(xy 174.477928 -294.739734) (xy 174.433466 -294.760832) (xy 174.386195 -294.774524) (xy 174.33734 -294.780456)
			(xy 174.288165 -294.778475) (xy 174.239946 -294.768631) (xy 174.19393 -294.751179) (xy 174.151309 -294.726572)
			(xy 174.113188 -294.695447) (xy 174.080553 -294.65861) (xy 174.05425 -294.617014) (xy 174.034959 -294.571738)
			(xy 174.023182 -294.523954) (xy 174.019222 -294.4749) (xy 173.680374 -294.4749) (xy 173.679879 -294.499507)
			(xy 173.671984 -294.548084) (xy 173.6564 -294.594765) (xy 173.633529 -294.638342) (xy 173.603964 -294.677686)
			(xy 173.568471 -294.711778) (xy 173.527968 -294.739734) (xy 173.483506 -294.760832) (xy 173.436235 -294.774524)
			(xy 173.38738 -294.780456) (xy 173.338205 -294.778475) (xy 173.289986 -294.768631) (xy 173.24397 -294.751179)
			(xy 173.201349 -294.726572) (xy 173.163228 -294.695447) (xy 173.130593 -294.65861) (xy 173.10429 -294.617014)
			(xy 173.084999 -294.571738) (xy 173.073222 -294.523954) (xy 173.069262 -294.4749) (xy 172.73016 -294.4749)
			(xy 172.729665 -294.499507) (xy 172.72177 -294.548084) (xy 172.706186 -294.594765) (xy 172.683315 -294.638342)
			(xy 172.65375 -294.677686) (xy 172.618257 -294.711778) (xy 172.577754 -294.739734) (xy 172.533292 -294.760832)
			(xy 172.486021 -294.774524) (xy 172.437166 -294.780456) (xy 172.387991 -294.778475) (xy 172.339772 -294.768631)
			(xy 172.293756 -294.751179) (xy 172.251135 -294.726572) (xy 172.213014 -294.695447) (xy 172.180379 -294.65861)
			(xy 172.154076 -294.617014) (xy 172.134785 -294.571738) (xy 172.123008 -294.523954) (xy 172.119048 -294.4749)
			(xy 171.7802 -294.4749) (xy 171.779705 -294.499507) (xy 171.77181 -294.548084) (xy 171.756226 -294.594765)
			(xy 171.733355 -294.638342) (xy 171.70379 -294.677686) (xy 171.668297 -294.711778) (xy 171.627794 -294.739734)
			(xy 171.583332 -294.760832) (xy 171.536061 -294.774524) (xy 171.487206 -294.780456) (xy 171.438031 -294.778475)
			(xy 171.389812 -294.768631) (xy 171.343796 -294.751179) (xy 171.301175 -294.726572) (xy 171.263054 -294.695447)
			(xy 171.230419 -294.65861) (xy 171.204116 -294.617014) (xy 171.184825 -294.571738) (xy 171.173048 -294.523954)
			(xy 171.169088 -294.4749) (xy 170.83024 -294.4749) (xy 170.829745 -294.499507) (xy 170.82185 -294.548084)
			(xy 170.806266 -294.594765) (xy 170.783395 -294.638342) (xy 170.75383 -294.677686) (xy 170.718337 -294.711778)
			(xy 170.677834 -294.739734) (xy 170.633372 -294.760832) (xy 170.586101 -294.774524) (xy 170.537246 -294.780456)
			(xy 170.488071 -294.778475) (xy 170.439852 -294.768631) (xy 170.393836 -294.751179) (xy 170.351215 -294.726572)
			(xy 170.313094 -294.695447) (xy 170.280459 -294.65861) (xy 170.254156 -294.617014) (xy 170.234865 -294.571738)
			(xy 170.223088 -294.523954) (xy 170.219128 -294.4749) (xy 169.88028 -294.4749) (xy 169.879785 -294.499507)
			(xy 169.87189 -294.548084) (xy 169.856306 -294.594765) (xy 169.833435 -294.638342) (xy 169.80387 -294.677686)
			(xy 169.768377 -294.711778) (xy 169.727874 -294.739734) (xy 169.683412 -294.760832) (xy 169.636141 -294.774524)
			(xy 169.587286 -294.780456) (xy 169.538111 -294.778475) (xy 169.489892 -294.768631) (xy 169.443876 -294.751179)
			(xy 169.401255 -294.726572) (xy 169.363134 -294.695447) (xy 169.330499 -294.65861) (xy 169.304196 -294.617014)
			(xy 169.284905 -294.571738) (xy 169.273128 -294.523954) (xy 169.269168 -294.4749) (xy 168.93032 -294.4749)
			(xy 168.929825 -294.499507) (xy 168.92193 -294.548084) (xy 168.906346 -294.594765) (xy 168.883475 -294.638342)
			(xy 168.85391 -294.677686) (xy 168.818417 -294.711778) (xy 168.777914 -294.739734) (xy 168.733452 -294.760832)
			(xy 168.686181 -294.774524) (xy 168.637326 -294.780456) (xy 168.588151 -294.778475) (xy 168.539932 -294.768631)
			(xy 168.493916 -294.751179) (xy 168.451295 -294.726572) (xy 168.413174 -294.695447) (xy 168.380539 -294.65861)
			(xy 168.354236 -294.617014) (xy 168.334945 -294.571738) (xy 168.323168 -294.523954) (xy 168.319208 -294.4749)
			(xy 167.98036 -294.4749) (xy 167.979865 -294.499507) (xy 167.97197 -294.548084) (xy 167.956386 -294.594765)
			(xy 167.933515 -294.638342) (xy 167.90395 -294.677686) (xy 167.868457 -294.711778) (xy 167.827954 -294.739734)
			(xy 167.783492 -294.760832) (xy 167.736221 -294.774524) (xy 167.687366 -294.780456) (xy 167.638191 -294.778475)
			(xy 167.589972 -294.768631) (xy 167.543956 -294.751179) (xy 167.501335 -294.726572) (xy 167.463214 -294.695447)
			(xy 167.430579 -294.65861) (xy 167.404276 -294.617014) (xy 167.384985 -294.571738) (xy 167.373208 -294.523954)
			(xy 167.369248 -294.4749) (xy 167.0304 -294.4749) (xy 167.029905 -294.499507) (xy 167.02201 -294.548084)
			(xy 167.006426 -294.594765) (xy 166.983555 -294.638342) (xy 166.95399 -294.677686) (xy 166.918497 -294.711778)
			(xy 166.877994 -294.739734) (xy 166.833532 -294.760832) (xy 166.786261 -294.774524) (xy 166.737406 -294.780456)
			(xy 166.688231 -294.778475) (xy 166.640012 -294.768631) (xy 166.593996 -294.751179) (xy 166.551375 -294.726572)
			(xy 166.513254 -294.695447) (xy 166.480619 -294.65861) (xy 166.454316 -294.617014) (xy 166.435025 -294.571738)
			(xy 166.423248 -294.523954) (xy 166.419288 -294.4749) (xy 166.080186 -294.4749) (xy 166.079691 -294.499507)
			(xy 166.071796 -294.548084) (xy 166.056212 -294.594765) (xy 166.033341 -294.638342) (xy 166.003776 -294.677686)
			(xy 165.968283 -294.711778) (xy 165.92778 -294.739734) (xy 165.883318 -294.760832) (xy 165.836047 -294.774524)
			(xy 165.787192 -294.780456) (xy 165.738017 -294.778475) (xy 165.689798 -294.768631) (xy 165.643782 -294.751179)
			(xy 165.601161 -294.726572) (xy 165.56304 -294.695447) (xy 165.530405 -294.65861) (xy 165.504102 -294.617014)
			(xy 165.484811 -294.571738) (xy 165.473034 -294.523954) (xy 165.469074 -294.4749) (xy 165.130226 -294.4749)
			(xy 165.129731 -294.499507) (xy 165.121836 -294.548084) (xy 165.106252 -294.594765) (xy 165.083381 -294.638342)
			(xy 165.053816 -294.677686) (xy 165.018323 -294.711778) (xy 164.97782 -294.739734) (xy 164.933358 -294.760832)
			(xy 164.886087 -294.774524) (xy 164.837232 -294.780456) (xy 164.788057 -294.778475) (xy 164.739838 -294.768631)
			(xy 164.693822 -294.751179) (xy 164.651201 -294.726572) (xy 164.61308 -294.695447) (xy 164.580445 -294.65861)
			(xy 164.554142 -294.617014) (xy 164.534851 -294.571738) (xy 164.523074 -294.523954) (xy 164.519114 -294.4749)
			(xy 164.18086 -294.4749) (xy 164.176688 -294.525247) (xy 164.164285 -294.574221) (xy 164.14399 -294.620485)
			(xy 164.116356 -294.662777) (xy 164.082137 -294.699944) (xy 164.042267 -294.73097) (xy 163.997834 -294.755011)
			(xy 163.95005 -294.771409) (xy 163.900218 -294.779719) (xy 163.874958 -294.780208) (xy 163.851419 -294.779787)
			(xy 163.804897 -294.772572) (xy 163.760034 -294.758303) (xy 163.717891 -294.73732) (xy 163.698428 -294.724074)
			(xy 163.698174 -294.724074) (xy 163.690367 -294.719074) (xy 163.672442 -294.714412) (xy 163.654029 -294.716417)
			(xy 163.645596 -294.720264) (xy 163.565332 -294.761666) (xy 163.557302 -294.766357) (xy 163.544952 -294.780235)
			(xy 163.538324 -294.79759) (xy 163.5379 -294.806878) (xy 163.5379 -295.598342) (xy 163.537493 -295.622315)
			(xy 163.529989 -295.669671) (xy 163.515157 -295.715266) (xy 163.493363 -295.757974) (xy 163.465147 -295.796739)
			(xy 163.448492 -295.813988) (xy 163.21024 -296.05224) (xy 163.192943 -296.068833) (xy 163.154164 -296.097001)
			(xy 163.111464 -296.11877) (xy 163.06589 -296.133608) (xy 163.018558 -296.14115) (xy 162.994594 -296.141648)
			(xy 162.91179 -296.141648) (xy 162.900675 -296.142179) (xy 162.880516 -296.151542) (xy 162.872928 -296.159682)
			(xy 162.866226 -296.168351) (xy 162.86031 -296.189428) (xy 162.861498 -296.200322) (xy 162.872674 -296.271188)
			(xy 162.873476 -296.277186) (xy 162.872577 -296.289251) (xy 162.870896 -296.295064) (xy 162.852354 -296.351706)
			(xy 162.851846 -296.353484) (xy 162.8504 -296.358763) (xy 162.848873 -296.369601) (xy 162.848801 -296.37482)
			(xy 163.569154 -296.37482) (xy 163.573114 -296.325766) (xy 163.584891 -296.277982) (xy 163.604182 -296.232706)
			(xy 163.630485 -296.19111) (xy 163.66312 -296.154273) (xy 163.701241 -296.123148) (xy 163.743862 -296.098541)
			(xy 163.789878 -296.081089) (xy 163.838097 -296.071245) (xy 163.887272 -296.069264) (xy 163.936127 -296.075196)
			(xy 163.983398 -296.088888) (xy 164.02786 -296.109986) (xy 164.068363 -296.137942) (xy 164.103856 -296.172034)
			(xy 164.133421 -296.211378) (xy 164.156292 -296.254955) (xy 164.171876 -296.301636) (xy 164.179771 -296.350213)
			(xy 164.180266 -296.37482) (xy 164.519114 -296.37482) (xy 164.523074 -296.325766) (xy 164.534851 -296.277982)
			(xy 164.554142 -296.232706) (xy 164.580445 -296.19111) (xy 164.61308 -296.154273) (xy 164.651201 -296.123148)
			(xy 164.693822 -296.098541) (xy 164.739838 -296.081089) (xy 164.788057 -296.071245) (xy 164.837232 -296.069264)
			(xy 164.886087 -296.075196) (xy 164.933358 -296.088888) (xy 164.97782 -296.109986) (xy 165.018323 -296.137942)
			(xy 165.053816 -296.172034) (xy 165.083381 -296.211378) (xy 165.106252 -296.254955) (xy 165.121836 -296.301636)
			(xy 165.129731 -296.350213) (xy 165.130226 -296.37482) (xy 165.469074 -296.37482) (xy 165.473034 -296.325766)
			(xy 165.484811 -296.277982) (xy 165.504102 -296.232706) (xy 165.530405 -296.19111) (xy 165.56304 -296.154273)
			(xy 165.601161 -296.123148) (xy 165.643782 -296.098541) (xy 165.689798 -296.081089) (xy 165.738017 -296.071245)
			(xy 165.787192 -296.069264) (xy 165.836047 -296.075196) (xy 165.883318 -296.088888) (xy 165.92778 -296.109986)
			(xy 165.968283 -296.137942) (xy 166.003776 -296.172034) (xy 166.033341 -296.211378) (xy 166.056212 -296.254955)
			(xy 166.071796 -296.301636) (xy 166.079691 -296.350213) (xy 166.080186 -296.37482) (xy 166.419288 -296.37482)
			(xy 166.423248 -296.325766) (xy 166.435025 -296.277982) (xy 166.454316 -296.232706) (xy 166.480619 -296.19111)
			(xy 166.513254 -296.154273) (xy 166.551375 -296.123148) (xy 166.593996 -296.098541) (xy 166.640012 -296.081089)
			(xy 166.688231 -296.071245) (xy 166.737406 -296.069264) (xy 166.786261 -296.075196) (xy 166.833532 -296.088888)
			(xy 166.877994 -296.109986) (xy 166.918497 -296.137942) (xy 166.95399 -296.172034) (xy 166.983555 -296.211378)
			(xy 167.006426 -296.254955) (xy 167.02201 -296.301636) (xy 167.029905 -296.350213) (xy 167.0304 -296.37482)
			(xy 167.369248 -296.37482) (xy 167.373208 -296.325766) (xy 167.384985 -296.277982) (xy 167.404276 -296.232706)
			(xy 167.430579 -296.19111) (xy 167.463214 -296.154273) (xy 167.501335 -296.123148) (xy 167.543956 -296.098541)
			(xy 167.589972 -296.081089) (xy 167.638191 -296.071245) (xy 167.687366 -296.069264) (xy 167.736221 -296.075196)
			(xy 167.783492 -296.088888) (xy 167.827954 -296.109986) (xy 167.868457 -296.137942) (xy 167.90395 -296.172034)
			(xy 167.933515 -296.211378) (xy 167.956386 -296.254955) (xy 167.97197 -296.301636) (xy 167.979865 -296.350213)
			(xy 167.98036 -296.37482) (xy 168.319208 -296.37482) (xy 168.323168 -296.325766) (xy 168.334945 -296.277982)
			(xy 168.354236 -296.232706) (xy 168.380539 -296.19111) (xy 168.413174 -296.154273) (xy 168.451295 -296.123148)
			(xy 168.493916 -296.098541) (xy 168.539932 -296.081089) (xy 168.588151 -296.071245) (xy 168.637326 -296.069264)
			(xy 168.686181 -296.075196) (xy 168.733452 -296.088888) (xy 168.777914 -296.109986) (xy 168.818417 -296.137942)
			(xy 168.85391 -296.172034) (xy 168.883475 -296.211378) (xy 168.906346 -296.254955) (xy 168.92193 -296.301636)
			(xy 168.929825 -296.350213) (xy 168.93032 -296.37482) (xy 169.269168 -296.37482) (xy 169.273128 -296.325766)
			(xy 169.284905 -296.277982) (xy 169.304196 -296.232706) (xy 169.330499 -296.19111) (xy 169.363134 -296.154273)
			(xy 169.401255 -296.123148) (xy 169.443876 -296.098541) (xy 169.489892 -296.081089) (xy 169.538111 -296.071245)
			(xy 169.587286 -296.069264) (xy 169.636141 -296.075196) (xy 169.683412 -296.088888) (xy 169.727874 -296.109986)
			(xy 169.768377 -296.137942) (xy 169.80387 -296.172034) (xy 169.833435 -296.211378) (xy 169.856306 -296.254955)
			(xy 169.87189 -296.301636) (xy 169.879785 -296.350213) (xy 169.88028 -296.37482) (xy 170.219128 -296.37482)
			(xy 170.223088 -296.325766) (xy 170.234865 -296.277982) (xy 170.254156 -296.232706) (xy 170.280459 -296.19111)
			(xy 170.313094 -296.154273) (xy 170.351215 -296.123148) (xy 170.393836 -296.098541) (xy 170.439852 -296.081089)
			(xy 170.488071 -296.071245) (xy 170.537246 -296.069264) (xy 170.586101 -296.075196) (xy 170.633372 -296.088888)
			(xy 170.677834 -296.109986) (xy 170.718337 -296.137942) (xy 170.75383 -296.172034) (xy 170.783395 -296.211378)
			(xy 170.806266 -296.254955) (xy 170.82185 -296.301636) (xy 170.829745 -296.350213) (xy 170.83024 -296.37482)
			(xy 171.169088 -296.37482) (xy 171.173048 -296.325766) (xy 171.184825 -296.277982) (xy 171.204116 -296.232706)
			(xy 171.230419 -296.19111) (xy 171.263054 -296.154273) (xy 171.301175 -296.123148) (xy 171.343796 -296.098541)
			(xy 171.389812 -296.081089) (xy 171.438031 -296.071245) (xy 171.487206 -296.069264) (xy 171.536061 -296.075196)
			(xy 171.583332 -296.088888) (xy 171.627794 -296.109986) (xy 171.668297 -296.137942) (xy 171.70379 -296.172034)
			(xy 171.733355 -296.211378) (xy 171.756226 -296.254955) (xy 171.77181 -296.301636) (xy 171.779705 -296.350213)
			(xy 171.7802 -296.37482) (xy 172.119302 -296.37482) (xy 172.123262 -296.325766) (xy 172.135039 -296.277982)
			(xy 172.15433 -296.232706) (xy 172.180633 -296.19111) (xy 172.213268 -296.154273) (xy 172.251389 -296.123148)
			(xy 172.29401 -296.098541) (xy 172.340026 -296.081089) (xy 172.388245 -296.071245) (xy 172.43742 -296.069264)
			(xy 172.486275 -296.075196) (xy 172.533546 -296.088888) (xy 172.578008 -296.109986) (xy 172.618511 -296.137942)
			(xy 172.654004 -296.172034) (xy 172.683569 -296.211378) (xy 172.70644 -296.254955) (xy 172.722024 -296.301636)
			(xy 172.729919 -296.350213) (xy 172.730414 -296.37482) (xy 173.069262 -296.37482) (xy 173.073222 -296.325766)
			(xy 173.084999 -296.277982) (xy 173.10429 -296.232706) (xy 173.130593 -296.19111) (xy 173.163228 -296.154273)
			(xy 173.201349 -296.123148) (xy 173.24397 -296.098541) (xy 173.289986 -296.081089) (xy 173.338205 -296.071245)
			(xy 173.38738 -296.069264) (xy 173.436235 -296.075196) (xy 173.483506 -296.088888) (xy 173.527968 -296.109986)
			(xy 173.568471 -296.137942) (xy 173.603964 -296.172034) (xy 173.633529 -296.211378) (xy 173.6564 -296.254955)
			(xy 173.671984 -296.301636) (xy 173.679879 -296.350213) (xy 173.680374 -296.37482) (xy 174.019222 -296.37482)
			(xy 174.023182 -296.325766) (xy 174.034959 -296.277982) (xy 174.05425 -296.232706) (xy 174.080553 -296.19111)
			(xy 174.113188 -296.154273) (xy 174.151309 -296.123148) (xy 174.19393 -296.098541) (xy 174.239946 -296.081089)
			(xy 174.288165 -296.071245) (xy 174.33734 -296.069264) (xy 174.386195 -296.075196) (xy 174.433466 -296.088888)
			(xy 174.477928 -296.109986) (xy 174.518431 -296.137942) (xy 174.553924 -296.172034) (xy 174.583489 -296.211378)
			(xy 174.60636 -296.254955) (xy 174.621944 -296.301636) (xy 174.629839 -296.350213) (xy 174.630334 -296.37482)
			(xy 175.919142 -296.37482) (xy 175.923102 -296.325766) (xy 175.934879 -296.277982) (xy 175.95417 -296.232706)
			(xy 175.980473 -296.19111) (xy 176.013108 -296.154273) (xy 176.051229 -296.123148) (xy 176.09385 -296.098541)
			(xy 176.139866 -296.081089) (xy 176.188085 -296.071245) (xy 176.23726 -296.069264) (xy 176.286115 -296.075196)
			(xy 176.333386 -296.088888) (xy 176.377848 -296.109986) (xy 176.418351 -296.137942) (xy 176.453844 -296.172034)
			(xy 176.483409 -296.211378) (xy 176.50628 -296.254955) (xy 176.521864 -296.301636) (xy 176.529759 -296.350213)
			(xy 176.530254 -296.37482) (xy 176.869102 -296.37482) (xy 176.873062 -296.325766) (xy 176.884839 -296.277982)
			(xy 176.90413 -296.232706) (xy 176.930433 -296.19111) (xy 176.963068 -296.154273) (xy 177.001189 -296.123148)
			(xy 177.04381 -296.098541) (xy 177.089826 -296.081089) (xy 177.138045 -296.071245) (xy 177.18722 -296.069264)
			(xy 177.236075 -296.075196) (xy 177.283346 -296.088888) (xy 177.327808 -296.109986) (xy 177.368311 -296.137942)
			(xy 177.403804 -296.172034) (xy 177.433369 -296.211378) (xy 177.45624 -296.254955) (xy 177.471824 -296.301636)
			(xy 177.479719 -296.350213) (xy 177.480214 -296.37482) (xy 177.819062 -296.37482) (xy 177.823022 -296.325766)
			(xy 177.834799 -296.277982) (xy 177.85409 -296.232706) (xy 177.880393 -296.19111) (xy 177.913028 -296.154273)
			(xy 177.951149 -296.123148) (xy 177.99377 -296.098541) (xy 178.039786 -296.081089) (xy 178.088005 -296.071245)
			(xy 178.13718 -296.069264) (xy 178.186035 -296.075196) (xy 178.233306 -296.088888) (xy 178.277768 -296.109986)
			(xy 178.318271 -296.137942) (xy 178.353764 -296.172034) (xy 178.383329 -296.211378) (xy 178.4062 -296.254955)
			(xy 178.421784 -296.301636) (xy 178.429679 -296.350213) (xy 178.430174 -296.37482) (xy 178.769276 -296.37482)
			(xy 178.773236 -296.325766) (xy 178.785013 -296.277982) (xy 178.804304 -296.232706) (xy 178.830607 -296.19111)
			(xy 178.863242 -296.154273) (xy 178.901363 -296.123148) (xy 178.943984 -296.098541) (xy 178.99 -296.081089)
			(xy 179.038219 -296.071245) (xy 179.087394 -296.069264) (xy 179.136249 -296.075196) (xy 179.18352 -296.088888)
			(xy 179.227982 -296.109986) (xy 179.268485 -296.137942) (xy 179.303978 -296.172034) (xy 179.333543 -296.211378)
			(xy 179.356414 -296.254955) (xy 179.371998 -296.301636) (xy 179.379893 -296.350213) (xy 179.380388 -296.37482)
			(xy 179.719236 -296.37482) (xy 179.723196 -296.325766) (xy 179.734973 -296.277982) (xy 179.754264 -296.232706)
			(xy 179.780567 -296.19111) (xy 179.813202 -296.154273) (xy 179.851323 -296.123148) (xy 179.893944 -296.098541)
			(xy 179.93996 -296.081089) (xy 179.988179 -296.071245) (xy 180.037354 -296.069264) (xy 180.086209 -296.075196)
			(xy 180.13348 -296.088888) (xy 180.177942 -296.109986) (xy 180.218445 -296.137942) (xy 180.253938 -296.172034)
			(xy 180.283503 -296.211378) (xy 180.306374 -296.254955) (xy 180.321958 -296.301636) (xy 180.329853 -296.350213)
			(xy 180.330348 -296.37482) (xy 180.669196 -296.37482) (xy 180.673156 -296.325766) (xy 180.684933 -296.277982)
			(xy 180.704224 -296.232706) (xy 180.730527 -296.19111) (xy 180.763162 -296.154273) (xy 180.801283 -296.123148)
			(xy 180.843904 -296.098541) (xy 180.88992 -296.081089) (xy 180.938139 -296.071245) (xy 180.987314 -296.069264)
			(xy 181.036169 -296.075196) (xy 181.08344 -296.088888) (xy 181.127902 -296.109986) (xy 181.168405 -296.137942)
			(xy 181.203898 -296.172034) (xy 181.233463 -296.211378) (xy 181.256334 -296.254955) (xy 181.271918 -296.301636)
			(xy 181.279813 -296.350213) (xy 181.280308 -296.37482) (xy 181.619156 -296.37482) (xy 181.623116 -296.325766)
			(xy 181.634893 -296.277982) (xy 181.654184 -296.232706) (xy 181.680487 -296.19111) (xy 181.713122 -296.154273)
			(xy 181.751243 -296.123148) (xy 181.793864 -296.098541) (xy 181.83988 -296.081089) (xy 181.888099 -296.071245)
			(xy 181.937274 -296.069264) (xy 181.986129 -296.075196) (xy 182.0334 -296.088888) (xy 182.077862 -296.109986)
			(xy 182.118365 -296.137942) (xy 182.153858 -296.172034) (xy 182.183423 -296.211378) (xy 182.206294 -296.254955)
			(xy 182.221878 -296.301636) (xy 182.229773 -296.350213) (xy 182.230268 -296.37482) (xy 182.569116 -296.37482)
			(xy 182.573076 -296.325766) (xy 182.584853 -296.277982) (xy 182.604144 -296.232706) (xy 182.630447 -296.19111)
			(xy 182.663082 -296.154273) (xy 182.701203 -296.123148) (xy 182.743824 -296.098541) (xy 182.78984 -296.081089)
			(xy 182.838059 -296.071245) (xy 182.887234 -296.069264) (xy 182.936089 -296.075196) (xy 182.98336 -296.088888)
			(xy 183.027822 -296.109986) (xy 183.068325 -296.137942) (xy 183.103818 -296.172034) (xy 183.133383 -296.211378)
			(xy 183.156254 -296.254955) (xy 183.171838 -296.301636) (xy 183.179733 -296.350213) (xy 183.180228 -296.37482)
			(xy 183.179733 -296.399427) (xy 183.171838 -296.448004) (xy 183.156254 -296.494685) (xy 183.133383 -296.538262)
			(xy 183.103818 -296.577606) (xy 183.068325 -296.611698) (xy 183.027822 -296.639654) (xy 182.98336 -296.660752)
			(xy 182.936089 -296.674444) (xy 182.887234 -296.680376) (xy 182.838059 -296.678395) (xy 182.78984 -296.668551)
			(xy 182.743824 -296.651099) (xy 182.701203 -296.626492) (xy 182.663082 -296.595367) (xy 182.630447 -296.55853)
			(xy 182.604144 -296.516934) (xy 182.584853 -296.471658) (xy 182.573076 -296.423874) (xy 182.569116 -296.37482)
			(xy 182.230268 -296.37482) (xy 182.229773 -296.399427) (xy 182.221878 -296.448004) (xy 182.206294 -296.494685)
			(xy 182.183423 -296.538262) (xy 182.153858 -296.577606) (xy 182.118365 -296.611698) (xy 182.077862 -296.639654)
			(xy 182.0334 -296.660752) (xy 181.986129 -296.674444) (xy 181.937274 -296.680376) (xy 181.888099 -296.678395)
			(xy 181.83988 -296.668551) (xy 181.793864 -296.651099) (xy 181.751243 -296.626492) (xy 181.713122 -296.595367)
			(xy 181.680487 -296.55853) (xy 181.654184 -296.516934) (xy 181.634893 -296.471658) (xy 181.623116 -296.423874)
			(xy 181.619156 -296.37482) (xy 181.280308 -296.37482) (xy 181.279813 -296.399427) (xy 181.271918 -296.448004)
			(xy 181.256334 -296.494685) (xy 181.233463 -296.538262) (xy 181.203898 -296.577606) (xy 181.168405 -296.611698)
			(xy 181.127902 -296.639654) (xy 181.08344 -296.660752) (xy 181.036169 -296.674444) (xy 180.987314 -296.680376)
			(xy 180.938139 -296.678395) (xy 180.88992 -296.668551) (xy 180.843904 -296.651099) (xy 180.801283 -296.626492)
			(xy 180.763162 -296.595367) (xy 180.730527 -296.55853) (xy 180.704224 -296.516934) (xy 180.684933 -296.471658)
			(xy 180.673156 -296.423874) (xy 180.669196 -296.37482) (xy 180.330348 -296.37482) (xy 180.329853 -296.399427)
			(xy 180.321958 -296.448004) (xy 180.306374 -296.494685) (xy 180.283503 -296.538262) (xy 180.253938 -296.577606)
			(xy 180.218445 -296.611698) (xy 180.177942 -296.639654) (xy 180.13348 -296.660752) (xy 180.086209 -296.674444)
			(xy 180.037354 -296.680376) (xy 179.988179 -296.678395) (xy 179.93996 -296.668551) (xy 179.893944 -296.651099)
			(xy 179.851323 -296.626492) (xy 179.813202 -296.595367) (xy 179.780567 -296.55853) (xy 179.754264 -296.516934)
			(xy 179.734973 -296.471658) (xy 179.723196 -296.423874) (xy 179.719236 -296.37482) (xy 179.380388 -296.37482)
			(xy 179.379893 -296.399427) (xy 179.371998 -296.448004) (xy 179.356414 -296.494685) (xy 179.333543 -296.538262)
			(xy 179.303978 -296.577606) (xy 179.268485 -296.611698) (xy 179.227982 -296.639654) (xy 179.18352 -296.660752)
			(xy 179.136249 -296.674444) (xy 179.087394 -296.680376) (xy 179.038219 -296.678395) (xy 178.99 -296.668551)
			(xy 178.943984 -296.651099) (xy 178.901363 -296.626492) (xy 178.863242 -296.595367) (xy 178.830607 -296.55853)
			(xy 178.804304 -296.516934) (xy 178.785013 -296.471658) (xy 178.773236 -296.423874) (xy 178.769276 -296.37482)
			(xy 178.430174 -296.37482) (xy 178.429679 -296.399427) (xy 178.421784 -296.448004) (xy 178.4062 -296.494685)
			(xy 178.383329 -296.538262) (xy 178.353764 -296.577606) (xy 178.318271 -296.611698) (xy 178.277768 -296.639654)
			(xy 178.233306 -296.660752) (xy 178.186035 -296.674444) (xy 178.13718 -296.680376) (xy 178.088005 -296.678395)
			(xy 178.039786 -296.668551) (xy 177.99377 -296.651099) (xy 177.951149 -296.626492) (xy 177.913028 -296.595367)
			(xy 177.880393 -296.55853) (xy 177.85409 -296.516934) (xy 177.834799 -296.471658) (xy 177.823022 -296.423874)
			(xy 177.819062 -296.37482) (xy 177.480214 -296.37482) (xy 177.479719 -296.399427) (xy 177.471824 -296.448004)
			(xy 177.45624 -296.494685) (xy 177.433369 -296.538262) (xy 177.403804 -296.577606) (xy 177.368311 -296.611698)
			(xy 177.327808 -296.639654) (xy 177.283346 -296.660752) (xy 177.236075 -296.674444) (xy 177.18722 -296.680376)
			(xy 177.138045 -296.678395) (xy 177.089826 -296.668551) (xy 177.04381 -296.651099) (xy 177.001189 -296.626492)
			(xy 176.963068 -296.595367) (xy 176.930433 -296.55853) (xy 176.90413 -296.516934) (xy 176.884839 -296.471658)
			(xy 176.873062 -296.423874) (xy 176.869102 -296.37482) (xy 176.530254 -296.37482) (xy 176.529759 -296.399427)
			(xy 176.521864 -296.448004) (xy 176.50628 -296.494685) (xy 176.483409 -296.538262) (xy 176.453844 -296.577606)
			(xy 176.418351 -296.611698) (xy 176.377848 -296.639654) (xy 176.333386 -296.660752) (xy 176.286115 -296.674444)
			(xy 176.23726 -296.680376) (xy 176.188085 -296.678395) (xy 176.139866 -296.668551) (xy 176.09385 -296.651099)
			(xy 176.051229 -296.626492) (xy 176.013108 -296.595367) (xy 175.980473 -296.55853) (xy 175.95417 -296.516934)
			(xy 175.934879 -296.471658) (xy 175.923102 -296.423874) (xy 175.919142 -296.37482) (xy 174.630334 -296.37482)
			(xy 174.629839 -296.399427) (xy 174.621944 -296.448004) (xy 174.60636 -296.494685) (xy 174.583489 -296.538262)
			(xy 174.553924 -296.577606) (xy 174.518431 -296.611698) (xy 174.477928 -296.639654) (xy 174.433466 -296.660752)
			(xy 174.386195 -296.674444) (xy 174.33734 -296.680376) (xy 174.288165 -296.678395) (xy 174.239946 -296.668551)
			(xy 174.19393 -296.651099) (xy 174.151309 -296.626492) (xy 174.113188 -296.595367) (xy 174.080553 -296.55853)
			(xy 174.05425 -296.516934) (xy 174.034959 -296.471658) (xy 174.023182 -296.423874) (xy 174.019222 -296.37482)
			(xy 173.680374 -296.37482) (xy 173.679879 -296.399427) (xy 173.671984 -296.448004) (xy 173.6564 -296.494685)
			(xy 173.633529 -296.538262) (xy 173.603964 -296.577606) (xy 173.568471 -296.611698) (xy 173.527968 -296.639654)
			(xy 173.483506 -296.660752) (xy 173.436235 -296.674444) (xy 173.38738 -296.680376) (xy 173.338205 -296.678395)
			(xy 173.289986 -296.668551) (xy 173.24397 -296.651099) (xy 173.201349 -296.626492) (xy 173.163228 -296.595367)
			(xy 173.130593 -296.55853) (xy 173.10429 -296.516934) (xy 173.084999 -296.471658) (xy 173.073222 -296.423874)
			(xy 173.069262 -296.37482) (xy 172.730414 -296.37482) (xy 172.729919 -296.399427) (xy 172.722024 -296.448004)
			(xy 172.70644 -296.494685) (xy 172.683569 -296.538262) (xy 172.654004 -296.577606) (xy 172.618511 -296.611698)
			(xy 172.578008 -296.639654) (xy 172.533546 -296.660752) (xy 172.486275 -296.674444) (xy 172.43742 -296.680376)
			(xy 172.388245 -296.678395) (xy 172.340026 -296.668551) (xy 172.29401 -296.651099) (xy 172.251389 -296.626492)
			(xy 172.213268 -296.595367) (xy 172.180633 -296.55853) (xy 172.15433 -296.516934) (xy 172.135039 -296.471658)
			(xy 172.123262 -296.423874) (xy 172.119302 -296.37482) (xy 171.7802 -296.37482) (xy 171.779705 -296.399427)
			(xy 171.77181 -296.448004) (xy 171.756226 -296.494685) (xy 171.733355 -296.538262) (xy 171.70379 -296.577606)
			(xy 171.668297 -296.611698) (xy 171.627794 -296.639654) (xy 171.583332 -296.660752) (xy 171.536061 -296.674444)
			(xy 171.487206 -296.680376) (xy 171.438031 -296.678395) (xy 171.389812 -296.668551) (xy 171.343796 -296.651099)
			(xy 171.301175 -296.626492) (xy 171.263054 -296.595367) (xy 171.230419 -296.55853) (xy 171.204116 -296.516934)
			(xy 171.184825 -296.471658) (xy 171.173048 -296.423874) (xy 171.169088 -296.37482) (xy 170.83024 -296.37482)
			(xy 170.829745 -296.399427) (xy 170.82185 -296.448004) (xy 170.806266 -296.494685) (xy 170.783395 -296.538262)
			(xy 170.75383 -296.577606) (xy 170.718337 -296.611698) (xy 170.677834 -296.639654) (xy 170.633372 -296.660752)
			(xy 170.586101 -296.674444) (xy 170.537246 -296.680376) (xy 170.488071 -296.678395) (xy 170.439852 -296.668551)
			(xy 170.393836 -296.651099) (xy 170.351215 -296.626492) (xy 170.313094 -296.595367) (xy 170.280459 -296.55853)
			(xy 170.254156 -296.516934) (xy 170.234865 -296.471658) (xy 170.223088 -296.423874) (xy 170.219128 -296.37482)
			(xy 169.88028 -296.37482) (xy 169.879785 -296.399427) (xy 169.87189 -296.448004) (xy 169.856306 -296.494685)
			(xy 169.833435 -296.538262) (xy 169.80387 -296.577606) (xy 169.768377 -296.611698) (xy 169.727874 -296.639654)
			(xy 169.683412 -296.660752) (xy 169.636141 -296.674444) (xy 169.587286 -296.680376) (xy 169.538111 -296.678395)
			(xy 169.489892 -296.668551) (xy 169.443876 -296.651099) (xy 169.401255 -296.626492) (xy 169.363134 -296.595367)
			(xy 169.330499 -296.55853) (xy 169.304196 -296.516934) (xy 169.284905 -296.471658) (xy 169.273128 -296.423874)
			(xy 169.269168 -296.37482) (xy 168.93032 -296.37482) (xy 168.929825 -296.399427) (xy 168.92193 -296.448004)
			(xy 168.906346 -296.494685) (xy 168.883475 -296.538262) (xy 168.85391 -296.577606) (xy 168.818417 -296.611698)
			(xy 168.777914 -296.639654) (xy 168.733452 -296.660752) (xy 168.686181 -296.674444) (xy 168.637326 -296.680376)
			(xy 168.588151 -296.678395) (xy 168.539932 -296.668551) (xy 168.493916 -296.651099) (xy 168.451295 -296.626492)
			(xy 168.413174 -296.595367) (xy 168.380539 -296.55853) (xy 168.354236 -296.516934) (xy 168.334945 -296.471658)
			(xy 168.323168 -296.423874) (xy 168.319208 -296.37482) (xy 167.98036 -296.37482) (xy 167.979865 -296.399427)
			(xy 167.97197 -296.448004) (xy 167.956386 -296.494685) (xy 167.933515 -296.538262) (xy 167.90395 -296.577606)
			(xy 167.868457 -296.611698) (xy 167.827954 -296.639654) (xy 167.783492 -296.660752) (xy 167.736221 -296.674444)
			(xy 167.687366 -296.680376) (xy 167.638191 -296.678395) (xy 167.589972 -296.668551) (xy 167.543956 -296.651099)
			(xy 167.501335 -296.626492) (xy 167.463214 -296.595367) (xy 167.430579 -296.55853) (xy 167.404276 -296.516934)
			(xy 167.384985 -296.471658) (xy 167.373208 -296.423874) (xy 167.369248 -296.37482) (xy 167.0304 -296.37482)
			(xy 167.029905 -296.399427) (xy 167.02201 -296.448004) (xy 167.006426 -296.494685) (xy 166.983555 -296.538262)
			(xy 166.95399 -296.577606) (xy 166.918497 -296.611698) (xy 166.877994 -296.639654) (xy 166.833532 -296.660752)
			(xy 166.786261 -296.674444) (xy 166.737406 -296.680376) (xy 166.688231 -296.678395) (xy 166.640012 -296.668551)
			(xy 166.593996 -296.651099) (xy 166.551375 -296.626492) (xy 166.513254 -296.595367) (xy 166.480619 -296.55853)
			(xy 166.454316 -296.516934) (xy 166.435025 -296.471658) (xy 166.423248 -296.423874) (xy 166.419288 -296.37482)
			(xy 166.080186 -296.37482) (xy 166.079691 -296.399427) (xy 166.071796 -296.448004) (xy 166.056212 -296.494685)
			(xy 166.033341 -296.538262) (xy 166.003776 -296.577606) (xy 165.968283 -296.611698) (xy 165.92778 -296.639654)
			(xy 165.883318 -296.660752) (xy 165.836047 -296.674444) (xy 165.787192 -296.680376) (xy 165.738017 -296.678395)
			(xy 165.689798 -296.668551) (xy 165.643782 -296.651099) (xy 165.601161 -296.626492) (xy 165.56304 -296.595367)
			(xy 165.530405 -296.55853) (xy 165.504102 -296.516934) (xy 165.484811 -296.471658) (xy 165.473034 -296.423874)
			(xy 165.469074 -296.37482) (xy 165.130226 -296.37482) (xy 165.129731 -296.399427) (xy 165.121836 -296.448004)
			(xy 165.106252 -296.494685) (xy 165.083381 -296.538262) (xy 165.053816 -296.577606) (xy 165.018323 -296.611698)
			(xy 164.97782 -296.639654) (xy 164.933358 -296.660752) (xy 164.886087 -296.674444) (xy 164.837232 -296.680376)
			(xy 164.788057 -296.678395) (xy 164.739838 -296.668551) (xy 164.693822 -296.651099) (xy 164.651201 -296.626492)
			(xy 164.61308 -296.595367) (xy 164.580445 -296.55853) (xy 164.554142 -296.516934) (xy 164.534851 -296.471658)
			(xy 164.523074 -296.423874) (xy 164.519114 -296.37482) (xy 164.180266 -296.37482) (xy 164.179771 -296.399427)
			(xy 164.171876 -296.448004) (xy 164.156292 -296.494685) (xy 164.133421 -296.538262) (xy 164.103856 -296.577606)
			(xy 164.068363 -296.611698) (xy 164.02786 -296.639654) (xy 163.983398 -296.660752) (xy 163.936127 -296.674444)
			(xy 163.887272 -296.680376) (xy 163.838097 -296.678395) (xy 163.789878 -296.668551) (xy 163.743862 -296.651099)
			(xy 163.701241 -296.626492) (xy 163.66312 -296.595367) (xy 163.630485 -296.55853) (xy 163.604182 -296.516934)
			(xy 163.584891 -296.471658) (xy 163.573114 -296.423874) (xy 163.569154 -296.37482) (xy 162.848801 -296.37482)
			(xy 162.848798 -296.375074) (xy 162.849288 -296.387043) (xy 162.856752 -296.40979) (xy 162.870865 -296.429128)
			(xy 162.890254 -296.443173) (xy 162.913028 -296.450555) (xy 162.924998 -296.45102) (xy 162.925252 -296.45102)
			(xy 162.935314 -296.450639) (xy 162.954739 -296.445376) (xy 162.963606 -296.440606) (xy 162.964114 -296.440098)
			(xy 163.023296 -296.405554) (xy 163.029097 -296.402392) (xy 163.041839 -296.398916) (xy 163.048442 -296.398696)
			(xy 163.185094 -296.397426) (xy 163.191809 -296.397554) (xy 163.204812 -296.40089) (xy 163.210748 -296.40403)
			(xy 163.347146 -296.481754) (xy 163.366919 -296.493417) (xy 163.402964 -296.521847) (xy 163.434341 -296.555358)
			(xy 163.460342 -296.593192) (xy 163.48038 -296.634496) (xy 163.494002 -296.678336) (xy 163.5009 -296.723722)
			(xy 163.501324 -296.746676) (xy 163.501324 -297.022266) (xy 163.501752 -297.032078) (xy 163.509109 -297.05027)
			(xy 163.522759 -297.064367) (xy 163.53155 -297.068748) (xy 163.616132 -297.10634) (xy 163.625243 -297.10993)
			(xy 163.644796 -297.110624) (xy 163.66318 -297.103926) (xy 163.670742 -297.097704) (xy 163.687658 -297.083053)
			(xy 163.724959 -297.05833) (xy 163.765465 -297.039308) (xy 163.808312 -297.026395) (xy 163.852583 -297.019865)
			(xy 163.874958 -297.019472) (xy 163.900216 -297.020001) (xy 163.950045 -297.02831) (xy 163.997826 -297.044707)
			(xy 164.042256 -297.068746) (xy 164.082124 -297.099771) (xy 164.11634 -297.136935) (xy 164.143972 -297.179225)
			(xy 164.164266 -297.225486) (xy 164.176668 -297.274456) (xy 164.180838 -297.32478) (xy 164.519114 -297.32478)
			(xy 164.523074 -297.275726) (xy 164.534851 -297.227942) (xy 164.554142 -297.182666) (xy 164.580445 -297.14107)
			(xy 164.61308 -297.104233) (xy 164.651201 -297.073108) (xy 164.693822 -297.048501) (xy 164.739838 -297.031049)
			(xy 164.788057 -297.021205) (xy 164.837232 -297.019224) (xy 164.886087 -297.025156) (xy 164.933358 -297.038848)
			(xy 164.97782 -297.059946) (xy 165.018323 -297.087902) (xy 165.053816 -297.121994) (xy 165.083381 -297.161338)
			(xy 165.106252 -297.204915) (xy 165.121836 -297.251596) (xy 165.129731 -297.300173) (xy 165.130226 -297.32478)
			(xy 165.469074 -297.32478) (xy 165.473034 -297.275726) (xy 165.484811 -297.227942) (xy 165.504102 -297.182666)
			(xy 165.530405 -297.14107) (xy 165.56304 -297.104233) (xy 165.601161 -297.073108) (xy 165.643782 -297.048501)
			(xy 165.689798 -297.031049) (xy 165.738017 -297.021205) (xy 165.787192 -297.019224) (xy 165.836047 -297.025156)
			(xy 165.883318 -297.038848) (xy 165.92778 -297.059946) (xy 165.968283 -297.087902) (xy 166.003776 -297.121994)
			(xy 166.033341 -297.161338) (xy 166.056212 -297.204915) (xy 166.071796 -297.251596) (xy 166.079691 -297.300173)
			(xy 166.080186 -297.32478) (xy 166.419288 -297.32478) (xy 166.423248 -297.275726) (xy 166.435025 -297.227942)
			(xy 166.454316 -297.182666) (xy 166.480619 -297.14107) (xy 166.513254 -297.104233) (xy 166.551375 -297.073108)
			(xy 166.593996 -297.048501) (xy 166.640012 -297.031049) (xy 166.688231 -297.021205) (xy 166.737406 -297.019224)
			(xy 166.786261 -297.025156) (xy 166.833532 -297.038848) (xy 166.877994 -297.059946) (xy 166.918497 -297.087902)
			(xy 166.95399 -297.121994) (xy 166.983555 -297.161338) (xy 167.006426 -297.204915) (xy 167.02201 -297.251596)
			(xy 167.029905 -297.300173) (xy 167.0304 -297.32478) (xy 167.369248 -297.32478) (xy 167.373208 -297.275726)
			(xy 167.384985 -297.227942) (xy 167.404276 -297.182666) (xy 167.430579 -297.14107) (xy 167.463214 -297.104233)
			(xy 167.501335 -297.073108) (xy 167.543956 -297.048501) (xy 167.589972 -297.031049) (xy 167.638191 -297.021205)
			(xy 167.687366 -297.019224) (xy 167.736221 -297.025156) (xy 167.783492 -297.038848) (xy 167.827954 -297.059946)
			(xy 167.868457 -297.087902) (xy 167.90395 -297.121994) (xy 167.933515 -297.161338) (xy 167.956386 -297.204915)
			(xy 167.97197 -297.251596) (xy 167.979865 -297.300173) (xy 167.98036 -297.32478) (xy 168.319208 -297.32478)
			(xy 168.323168 -297.275726) (xy 168.334945 -297.227942) (xy 168.354236 -297.182666) (xy 168.380539 -297.14107)
			(xy 168.413174 -297.104233) (xy 168.451295 -297.073108) (xy 168.493916 -297.048501) (xy 168.539932 -297.031049)
			(xy 168.588151 -297.021205) (xy 168.637326 -297.019224) (xy 168.686181 -297.025156) (xy 168.733452 -297.038848)
			(xy 168.777914 -297.059946) (xy 168.818417 -297.087902) (xy 168.85391 -297.121994) (xy 168.883475 -297.161338)
			(xy 168.906346 -297.204915) (xy 168.92193 -297.251596) (xy 168.929825 -297.300173) (xy 168.93032 -297.32478)
			(xy 169.269168 -297.32478) (xy 169.273128 -297.275726) (xy 169.284905 -297.227942) (xy 169.304196 -297.182666)
			(xy 169.330499 -297.14107) (xy 169.363134 -297.104233) (xy 169.401255 -297.073108) (xy 169.443876 -297.048501)
			(xy 169.489892 -297.031049) (xy 169.538111 -297.021205) (xy 169.587286 -297.019224) (xy 169.636141 -297.025156)
			(xy 169.683412 -297.038848) (xy 169.727874 -297.059946) (xy 169.768377 -297.087902) (xy 169.80387 -297.121994)
			(xy 169.833435 -297.161338) (xy 169.856306 -297.204915) (xy 169.87189 -297.251596) (xy 169.879785 -297.300173)
			(xy 169.88028 -297.32478) (xy 170.219128 -297.32478) (xy 170.223088 -297.275726) (xy 170.234865 -297.227942)
			(xy 170.254156 -297.182666) (xy 170.280459 -297.14107) (xy 170.313094 -297.104233) (xy 170.351215 -297.073108)
			(xy 170.393836 -297.048501) (xy 170.439852 -297.031049) (xy 170.488071 -297.021205) (xy 170.537246 -297.019224)
			(xy 170.586101 -297.025156) (xy 170.633372 -297.038848) (xy 170.677834 -297.059946) (xy 170.718337 -297.087902)
			(xy 170.75383 -297.121994) (xy 170.783395 -297.161338) (xy 170.806266 -297.204915) (xy 170.82185 -297.251596)
			(xy 170.829745 -297.300173) (xy 170.83024 -297.32478) (xy 171.169088 -297.32478) (xy 171.173048 -297.275726)
			(xy 171.184825 -297.227942) (xy 171.204116 -297.182666) (xy 171.230419 -297.14107) (xy 171.263054 -297.104233)
			(xy 171.301175 -297.073108) (xy 171.343796 -297.048501) (xy 171.389812 -297.031049) (xy 171.438031 -297.021205)
			(xy 171.487206 -297.019224) (xy 171.536061 -297.025156) (xy 171.583332 -297.038848) (xy 171.627794 -297.059946)
			(xy 171.668297 -297.087902) (xy 171.70379 -297.121994) (xy 171.733355 -297.161338) (xy 171.756226 -297.204915)
			(xy 171.77181 -297.251596) (xy 171.779705 -297.300173) (xy 171.7802 -297.32478) (xy 172.119048 -297.32478)
			(xy 172.123008 -297.275726) (xy 172.134785 -297.227942) (xy 172.154076 -297.182666) (xy 172.180379 -297.14107)
			(xy 172.213014 -297.104233) (xy 172.251135 -297.073108) (xy 172.293756 -297.048501) (xy 172.339772 -297.031049)
			(xy 172.387991 -297.021205) (xy 172.437166 -297.019224) (xy 172.486021 -297.025156) (xy 172.533292 -297.038848)
			(xy 172.577754 -297.059946) (xy 172.618257 -297.087902) (xy 172.65375 -297.121994) (xy 172.683315 -297.161338)
			(xy 172.706186 -297.204915) (xy 172.72177 -297.251596) (xy 172.729665 -297.300173) (xy 172.73016 -297.32478)
			(xy 173.069262 -297.32478) (xy 173.073222 -297.275726) (xy 173.084999 -297.227942) (xy 173.10429 -297.182666)
			(xy 173.130593 -297.14107) (xy 173.163228 -297.104233) (xy 173.201349 -297.073108) (xy 173.24397 -297.048501)
			(xy 173.289986 -297.031049) (xy 173.338205 -297.021205) (xy 173.38738 -297.019224) (xy 173.436235 -297.025156)
			(xy 173.483506 -297.038848) (xy 173.527968 -297.059946) (xy 173.568471 -297.087902) (xy 173.603964 -297.121994)
			(xy 173.633529 -297.161338) (xy 173.6564 -297.204915) (xy 173.671984 -297.251596) (xy 173.679879 -297.300173)
			(xy 173.680374 -297.32478) (xy 174.019222 -297.32478) (xy 174.023182 -297.275726) (xy 174.034959 -297.227942)
			(xy 174.05425 -297.182666) (xy 174.080553 -297.14107) (xy 174.113188 -297.104233) (xy 174.151309 -297.073108)
			(xy 174.19393 -297.048501) (xy 174.239946 -297.031049) (xy 174.288165 -297.021205) (xy 174.33734 -297.019224)
			(xy 174.386195 -297.025156) (xy 174.433466 -297.038848) (xy 174.477928 -297.059946) (xy 174.518431 -297.087902)
			(xy 174.553924 -297.121994) (xy 174.583489 -297.161338) (xy 174.60636 -297.204915) (xy 174.621944 -297.251596)
			(xy 174.629839 -297.300173) (xy 174.630334 -297.32478) (xy 175.919142 -297.32478) (xy 175.923102 -297.275726)
			(xy 175.934879 -297.227942) (xy 175.95417 -297.182666) (xy 175.980473 -297.14107) (xy 176.013108 -297.104233)
			(xy 176.051229 -297.073108) (xy 176.09385 -297.048501) (xy 176.139866 -297.031049) (xy 176.188085 -297.021205)
			(xy 176.23726 -297.019224) (xy 176.286115 -297.025156) (xy 176.333386 -297.038848) (xy 176.377848 -297.059946)
			(xy 176.418351 -297.087902) (xy 176.453844 -297.121994) (xy 176.483409 -297.161338) (xy 176.50628 -297.204915)
			(xy 176.521864 -297.251596) (xy 176.529759 -297.300173) (xy 176.530254 -297.32478) (xy 176.869102 -297.32478)
			(xy 176.873062 -297.275726) (xy 176.884839 -297.227942) (xy 176.90413 -297.182666) (xy 176.930433 -297.14107)
			(xy 176.963068 -297.104233) (xy 177.001189 -297.073108) (xy 177.04381 -297.048501) (xy 177.089826 -297.031049)
			(xy 177.138045 -297.021205) (xy 177.18722 -297.019224) (xy 177.236075 -297.025156) (xy 177.283346 -297.038848)
			(xy 177.327808 -297.059946) (xy 177.368311 -297.087902) (xy 177.403804 -297.121994) (xy 177.433369 -297.161338)
			(xy 177.45624 -297.204915) (xy 177.471824 -297.251596) (xy 177.479719 -297.300173) (xy 177.480214 -297.32478)
			(xy 177.819062 -297.32478) (xy 177.823022 -297.275726) (xy 177.834799 -297.227942) (xy 177.85409 -297.182666)
			(xy 177.880393 -297.14107) (xy 177.913028 -297.104233) (xy 177.951149 -297.073108) (xy 177.99377 -297.048501)
			(xy 178.039786 -297.031049) (xy 178.088005 -297.021205) (xy 178.13718 -297.019224) (xy 178.186035 -297.025156)
			(xy 178.233306 -297.038848) (xy 178.277768 -297.059946) (xy 178.318271 -297.087902) (xy 178.353764 -297.121994)
			(xy 178.383329 -297.161338) (xy 178.4062 -297.204915) (xy 178.421784 -297.251596) (xy 178.429679 -297.300173)
			(xy 178.430174 -297.32478) (xy 178.769276 -297.32478) (xy 178.773236 -297.275726) (xy 178.785013 -297.227942)
			(xy 178.804304 -297.182666) (xy 178.830607 -297.14107) (xy 178.863242 -297.104233) (xy 178.901363 -297.073108)
			(xy 178.943984 -297.048501) (xy 178.99 -297.031049) (xy 179.038219 -297.021205) (xy 179.087394 -297.019224)
			(xy 179.136249 -297.025156) (xy 179.18352 -297.038848) (xy 179.227982 -297.059946) (xy 179.268485 -297.087902)
			(xy 179.303978 -297.121994) (xy 179.333543 -297.161338) (xy 179.356414 -297.204915) (xy 179.371998 -297.251596)
			(xy 179.379893 -297.300173) (xy 179.380388 -297.32478) (xy 179.719236 -297.32478) (xy 179.723196 -297.275726)
			(xy 179.734973 -297.227942) (xy 179.754264 -297.182666) (xy 179.780567 -297.14107) (xy 179.813202 -297.104233)
			(xy 179.851323 -297.073108) (xy 179.893944 -297.048501) (xy 179.93996 -297.031049) (xy 179.988179 -297.021205)
			(xy 180.037354 -297.019224) (xy 180.086209 -297.025156) (xy 180.13348 -297.038848) (xy 180.177942 -297.059946)
			(xy 180.218445 -297.087902) (xy 180.253938 -297.121994) (xy 180.283503 -297.161338) (xy 180.306374 -297.204915)
			(xy 180.321958 -297.251596) (xy 180.329853 -297.300173) (xy 180.330348 -297.32478) (xy 180.669196 -297.32478)
			(xy 180.673156 -297.275726) (xy 180.684933 -297.227942) (xy 180.704224 -297.182666) (xy 180.730527 -297.14107)
			(xy 180.763162 -297.104233) (xy 180.801283 -297.073108) (xy 180.843904 -297.048501) (xy 180.88992 -297.031049)
			(xy 180.938139 -297.021205) (xy 180.987314 -297.019224) (xy 181.036169 -297.025156) (xy 181.08344 -297.038848)
			(xy 181.127902 -297.059946) (xy 181.168405 -297.087902) (xy 181.203898 -297.121994) (xy 181.233463 -297.161338)
			(xy 181.256334 -297.204915) (xy 181.271918 -297.251596) (xy 181.279813 -297.300173) (xy 181.280308 -297.32478)
			(xy 181.619156 -297.32478) (xy 181.623116 -297.275726) (xy 181.634893 -297.227942) (xy 181.654184 -297.182666)
			(xy 181.680487 -297.14107) (xy 181.713122 -297.104233) (xy 181.751243 -297.073108) (xy 181.793864 -297.048501)
			(xy 181.83988 -297.031049) (xy 181.888099 -297.021205) (xy 181.937274 -297.019224) (xy 181.986129 -297.025156)
			(xy 182.0334 -297.038848) (xy 182.077862 -297.059946) (xy 182.118365 -297.087902) (xy 182.153858 -297.121994)
			(xy 182.183423 -297.161338) (xy 182.206294 -297.204915) (xy 182.221878 -297.251596) (xy 182.229773 -297.300173)
			(xy 182.230268 -297.32478) (xy 182.229773 -297.349387) (xy 182.221878 -297.397964) (xy 182.206294 -297.444645)
			(xy 182.183423 -297.488222) (xy 182.153858 -297.527566) (xy 182.118365 -297.561658) (xy 182.077862 -297.589614)
			(xy 182.0334 -297.610712) (xy 181.986129 -297.624404) (xy 181.937274 -297.630336) (xy 181.888099 -297.628355)
			(xy 181.83988 -297.618511) (xy 181.793864 -297.601059) (xy 181.751243 -297.576452) (xy 181.713122 -297.545327)
			(xy 181.680487 -297.50849) (xy 181.654184 -297.466894) (xy 181.634893 -297.421618) (xy 181.623116 -297.373834)
			(xy 181.619156 -297.32478) (xy 181.280308 -297.32478) (xy 181.279813 -297.349387) (xy 181.271918 -297.397964)
			(xy 181.256334 -297.444645) (xy 181.233463 -297.488222) (xy 181.203898 -297.527566) (xy 181.168405 -297.561658)
			(xy 181.127902 -297.589614) (xy 181.08344 -297.610712) (xy 181.036169 -297.624404) (xy 180.987314 -297.630336)
			(xy 180.938139 -297.628355) (xy 180.88992 -297.618511) (xy 180.843904 -297.601059) (xy 180.801283 -297.576452)
			(xy 180.763162 -297.545327) (xy 180.730527 -297.50849) (xy 180.704224 -297.466894) (xy 180.684933 -297.421618)
			(xy 180.673156 -297.373834) (xy 180.669196 -297.32478) (xy 180.330348 -297.32478) (xy 180.329853 -297.349387)
			(xy 180.321958 -297.397964) (xy 180.306374 -297.444645) (xy 180.283503 -297.488222) (xy 180.253938 -297.527566)
			(xy 180.218445 -297.561658) (xy 180.177942 -297.589614) (xy 180.13348 -297.610712) (xy 180.086209 -297.624404)
			(xy 180.037354 -297.630336) (xy 179.988179 -297.628355) (xy 179.93996 -297.618511) (xy 179.893944 -297.601059)
			(xy 179.851323 -297.576452) (xy 179.813202 -297.545327) (xy 179.780567 -297.50849) (xy 179.754264 -297.466894)
			(xy 179.734973 -297.421618) (xy 179.723196 -297.373834) (xy 179.719236 -297.32478) (xy 179.380388 -297.32478)
			(xy 179.379893 -297.349387) (xy 179.371998 -297.397964) (xy 179.356414 -297.444645) (xy 179.333543 -297.488222)
			(xy 179.303978 -297.527566) (xy 179.268485 -297.561658) (xy 179.227982 -297.589614) (xy 179.18352 -297.610712)
			(xy 179.136249 -297.624404) (xy 179.087394 -297.630336) (xy 179.038219 -297.628355) (xy 178.99 -297.618511)
			(xy 178.943984 -297.601059) (xy 178.901363 -297.576452) (xy 178.863242 -297.545327) (xy 178.830607 -297.50849)
			(xy 178.804304 -297.466894) (xy 178.785013 -297.421618) (xy 178.773236 -297.373834) (xy 178.769276 -297.32478)
			(xy 178.430174 -297.32478) (xy 178.429679 -297.349387) (xy 178.421784 -297.397964) (xy 178.4062 -297.444645)
			(xy 178.383329 -297.488222) (xy 178.353764 -297.527566) (xy 178.318271 -297.561658) (xy 178.277768 -297.589614)
			(xy 178.233306 -297.610712) (xy 178.186035 -297.624404) (xy 178.13718 -297.630336) (xy 178.088005 -297.628355)
			(xy 178.039786 -297.618511) (xy 177.99377 -297.601059) (xy 177.951149 -297.576452) (xy 177.913028 -297.545327)
			(xy 177.880393 -297.50849) (xy 177.85409 -297.466894) (xy 177.834799 -297.421618) (xy 177.823022 -297.373834)
			(xy 177.819062 -297.32478) (xy 177.480214 -297.32478) (xy 177.479719 -297.349387) (xy 177.471824 -297.397964)
			(xy 177.45624 -297.444645) (xy 177.433369 -297.488222) (xy 177.403804 -297.527566) (xy 177.368311 -297.561658)
			(xy 177.327808 -297.589614) (xy 177.283346 -297.610712) (xy 177.236075 -297.624404) (xy 177.18722 -297.630336)
			(xy 177.138045 -297.628355) (xy 177.089826 -297.618511) (xy 177.04381 -297.601059) (xy 177.001189 -297.576452)
			(xy 176.963068 -297.545327) (xy 176.930433 -297.50849) (xy 176.90413 -297.466894) (xy 176.884839 -297.421618)
			(xy 176.873062 -297.373834) (xy 176.869102 -297.32478) (xy 176.530254 -297.32478) (xy 176.529759 -297.349387)
			(xy 176.521864 -297.397964) (xy 176.50628 -297.444645) (xy 176.483409 -297.488222) (xy 176.453844 -297.527566)
			(xy 176.418351 -297.561658) (xy 176.377848 -297.589614) (xy 176.333386 -297.610712) (xy 176.286115 -297.624404)
			(xy 176.23726 -297.630336) (xy 176.188085 -297.628355) (xy 176.139866 -297.618511) (xy 176.09385 -297.601059)
			(xy 176.051229 -297.576452) (xy 176.013108 -297.545327) (xy 175.980473 -297.50849) (xy 175.95417 -297.466894)
			(xy 175.934879 -297.421618) (xy 175.923102 -297.373834) (xy 175.919142 -297.32478) (xy 174.630334 -297.32478)
			(xy 174.629839 -297.349387) (xy 174.621944 -297.397964) (xy 174.60636 -297.444645) (xy 174.583489 -297.488222)
			(xy 174.553924 -297.527566) (xy 174.518431 -297.561658) (xy 174.477928 -297.589614) (xy 174.433466 -297.610712)
			(xy 174.386195 -297.624404) (xy 174.33734 -297.630336) (xy 174.288165 -297.628355) (xy 174.239946 -297.618511)
			(xy 174.19393 -297.601059) (xy 174.151309 -297.576452) (xy 174.113188 -297.545327) (xy 174.080553 -297.50849)
			(xy 174.05425 -297.466894) (xy 174.034959 -297.421618) (xy 174.023182 -297.373834) (xy 174.019222 -297.32478)
			(xy 173.680374 -297.32478) (xy 173.679879 -297.349387) (xy 173.671984 -297.397964) (xy 173.6564 -297.444645)
			(xy 173.633529 -297.488222) (xy 173.603964 -297.527566) (xy 173.568471 -297.561658) (xy 173.527968 -297.589614)
			(xy 173.483506 -297.610712) (xy 173.436235 -297.624404) (xy 173.38738 -297.630336) (xy 173.338205 -297.628355)
			(xy 173.289986 -297.618511) (xy 173.24397 -297.601059) (xy 173.201349 -297.576452) (xy 173.163228 -297.545327)
			(xy 173.130593 -297.50849) (xy 173.10429 -297.466894) (xy 173.084999 -297.421618) (xy 173.073222 -297.373834)
			(xy 173.069262 -297.32478) (xy 172.73016 -297.32478) (xy 172.729665 -297.349387) (xy 172.72177 -297.397964)
			(xy 172.706186 -297.444645) (xy 172.683315 -297.488222) (xy 172.65375 -297.527566) (xy 172.618257 -297.561658)
			(xy 172.577754 -297.589614) (xy 172.533292 -297.610712) (xy 172.486021 -297.624404) (xy 172.437166 -297.630336)
			(xy 172.387991 -297.628355) (xy 172.339772 -297.618511) (xy 172.293756 -297.601059) (xy 172.251135 -297.576452)
			(xy 172.213014 -297.545327) (xy 172.180379 -297.50849) (xy 172.154076 -297.466894) (xy 172.134785 -297.421618)
			(xy 172.123008 -297.373834) (xy 172.119048 -297.32478) (xy 171.7802 -297.32478) (xy 171.779705 -297.349387)
			(xy 171.77181 -297.397964) (xy 171.756226 -297.444645) (xy 171.733355 -297.488222) (xy 171.70379 -297.527566)
			(xy 171.668297 -297.561658) (xy 171.627794 -297.589614) (xy 171.583332 -297.610712) (xy 171.536061 -297.624404)
			(xy 171.487206 -297.630336) (xy 171.438031 -297.628355) (xy 171.389812 -297.618511) (xy 171.343796 -297.601059)
			(xy 171.301175 -297.576452) (xy 171.263054 -297.545327) (xy 171.230419 -297.50849) (xy 171.204116 -297.466894)
			(xy 171.184825 -297.421618) (xy 171.173048 -297.373834) (xy 171.169088 -297.32478) (xy 170.83024 -297.32478)
			(xy 170.829745 -297.349387) (xy 170.82185 -297.397964) (xy 170.806266 -297.444645) (xy 170.783395 -297.488222)
			(xy 170.75383 -297.527566) (xy 170.718337 -297.561658) (xy 170.677834 -297.589614) (xy 170.633372 -297.610712)
			(xy 170.586101 -297.624404) (xy 170.537246 -297.630336) (xy 170.488071 -297.628355) (xy 170.439852 -297.618511)
			(xy 170.393836 -297.601059) (xy 170.351215 -297.576452) (xy 170.313094 -297.545327) (xy 170.280459 -297.50849)
			(xy 170.254156 -297.466894) (xy 170.234865 -297.421618) (xy 170.223088 -297.373834) (xy 170.219128 -297.32478)
			(xy 169.88028 -297.32478) (xy 169.879785 -297.349387) (xy 169.87189 -297.397964) (xy 169.856306 -297.444645)
			(xy 169.833435 -297.488222) (xy 169.80387 -297.527566) (xy 169.768377 -297.561658) (xy 169.727874 -297.589614)
			(xy 169.683412 -297.610712) (xy 169.636141 -297.624404) (xy 169.587286 -297.630336) (xy 169.538111 -297.628355)
			(xy 169.489892 -297.618511) (xy 169.443876 -297.601059) (xy 169.401255 -297.576452) (xy 169.363134 -297.545327)
			(xy 169.330499 -297.50849) (xy 169.304196 -297.466894) (xy 169.284905 -297.421618) (xy 169.273128 -297.373834)
			(xy 169.269168 -297.32478) (xy 168.93032 -297.32478) (xy 168.929825 -297.349387) (xy 168.92193 -297.397964)
			(xy 168.906346 -297.444645) (xy 168.883475 -297.488222) (xy 168.85391 -297.527566) (xy 168.818417 -297.561658)
			(xy 168.777914 -297.589614) (xy 168.733452 -297.610712) (xy 168.686181 -297.624404) (xy 168.637326 -297.630336)
			(xy 168.588151 -297.628355) (xy 168.539932 -297.618511) (xy 168.493916 -297.601059) (xy 168.451295 -297.576452)
			(xy 168.413174 -297.545327) (xy 168.380539 -297.50849) (xy 168.354236 -297.466894) (xy 168.334945 -297.421618)
			(xy 168.323168 -297.373834) (xy 168.319208 -297.32478) (xy 167.98036 -297.32478) (xy 167.979865 -297.349387)
			(xy 167.97197 -297.397964) (xy 167.956386 -297.444645) (xy 167.933515 -297.488222) (xy 167.90395 -297.527566)
			(xy 167.868457 -297.561658) (xy 167.827954 -297.589614) (xy 167.783492 -297.610712) (xy 167.736221 -297.624404)
			(xy 167.687366 -297.630336) (xy 167.638191 -297.628355) (xy 167.589972 -297.618511) (xy 167.543956 -297.601059)
			(xy 167.501335 -297.576452) (xy 167.463214 -297.545327) (xy 167.430579 -297.50849) (xy 167.404276 -297.466894)
			(xy 167.384985 -297.421618) (xy 167.373208 -297.373834) (xy 167.369248 -297.32478) (xy 167.0304 -297.32478)
			(xy 167.029905 -297.349387) (xy 167.02201 -297.397964) (xy 167.006426 -297.444645) (xy 166.983555 -297.488222)
			(xy 166.95399 -297.527566) (xy 166.918497 -297.561658) (xy 166.877994 -297.589614) (xy 166.833532 -297.610712)
			(xy 166.786261 -297.624404) (xy 166.737406 -297.630336) (xy 166.688231 -297.628355) (xy 166.640012 -297.618511)
			(xy 166.593996 -297.601059) (xy 166.551375 -297.576452) (xy 166.513254 -297.545327) (xy 166.480619 -297.50849)
			(xy 166.454316 -297.466894) (xy 166.435025 -297.421618) (xy 166.423248 -297.373834) (xy 166.419288 -297.32478)
			(xy 166.080186 -297.32478) (xy 166.079691 -297.349387) (xy 166.071796 -297.397964) (xy 166.056212 -297.444645)
			(xy 166.033341 -297.488222) (xy 166.003776 -297.527566) (xy 165.968283 -297.561658) (xy 165.92778 -297.589614)
			(xy 165.883318 -297.610712) (xy 165.836047 -297.624404) (xy 165.787192 -297.630336) (xy 165.738017 -297.628355)
			(xy 165.689798 -297.618511) (xy 165.643782 -297.601059) (xy 165.601161 -297.576452) (xy 165.56304 -297.545327)
			(xy 165.530405 -297.50849) (xy 165.504102 -297.466894) (xy 165.484811 -297.421618) (xy 165.473034 -297.373834)
			(xy 165.469074 -297.32478) (xy 165.130226 -297.32478) (xy 165.129731 -297.349387) (xy 165.121836 -297.397964)
			(xy 165.106252 -297.444645) (xy 165.083381 -297.488222) (xy 165.053816 -297.527566) (xy 165.018323 -297.561658)
			(xy 164.97782 -297.589614) (xy 164.933358 -297.610712) (xy 164.886087 -297.624404) (xy 164.837232 -297.630336)
			(xy 164.788057 -297.628355) (xy 164.739838 -297.618511) (xy 164.693822 -297.601059) (xy 164.651201 -297.576452)
			(xy 164.61308 -297.545327) (xy 164.580445 -297.50849) (xy 164.554142 -297.466894) (xy 164.534851 -297.421618)
			(xy 164.523074 -297.373834) (xy 164.519114 -297.32478) (xy 164.180838 -297.32478) (xy 164.18084 -297.3248)
			(xy 164.176668 -297.375144) (xy 164.164266 -297.424114) (xy 164.143972 -297.470375) (xy 164.11634 -297.512665)
			(xy 164.082124 -297.549829) (xy 164.042256 -297.580854) (xy 163.997826 -297.604893) (xy 163.950045 -297.62129)
			(xy 163.900216 -297.629599) (xy 163.874958 -297.630088) (xy 163.85258 -297.629731) (xy 163.808303 -297.623208)
			(xy 163.765452 -297.610292) (xy 163.724944 -297.591262) (xy 163.687647 -297.566523) (xy 163.670742 -297.551856)
			(xy 163.663144 -297.545696) (xy 163.644777 -297.539027) (xy 163.625248 -297.539679) (xy 163.616132 -297.54322)
			(xy 163.53155 -297.580812) (xy 163.522764 -297.585195) (xy 163.509127 -297.599298) (xy 163.501772 -297.617485)
			(xy 163.501324 -297.627294) (xy 163.501324 -297.902884) (xy 163.500727 -297.929661) (xy 163.491311 -297.982382)
			(xy 163.472851 -298.032656) (xy 163.445912 -298.078943) (xy 163.41132 -298.119828) (xy 163.370132 -298.154058)
			(xy 163.347146 -298.167806) (xy 163.210748 -298.24553) (xy 163.204791 -298.24862) (xy 163.191802 -298.251972)
			(xy 163.185094 -298.252134) (xy 163.117022 -298.251626) (xy 163.08832 -298.276518) (xy 163.085526 -298.295822)
			(xy 163.084602 -298.305008) (xy 163.088726 -298.322991) (xy 163.098985 -298.338327) (xy 163.114033 -298.349002)
			(xy 163.122864 -298.351702) (xy 163.172394 -298.36491) (xy 163.178809 -298.366821) (xy 163.190397 -298.373512)
			(xy 163.195254 -298.378118) (xy 163.205668 -298.388532) (xy 163.213102 -298.395248) (xy 163.231602 -298.402884)
			(xy 163.251616 -298.402884) (xy 163.270116 -298.395248) (xy 163.27755 -298.388532) (xy 163.303204 -298.362878)
			(xy 163.310606 -298.35604) (xy 163.329204 -298.34832) (xy 163.339272 -298.347892) (xy 163.469066 -298.347892)
			(xy 163.478681 -298.347493) (xy 163.496571 -298.340453) (xy 163.503864 -298.334176) (xy 163.55441 -298.286932)
			(xy 163.561107 -298.2802) (xy 163.569317 -298.263091) (xy 163.570412 -298.253658) (xy 163.570412 -298.25315)
			(xy 163.572481 -298.229111) (xy 163.583429 -298.18212) (xy 163.601631 -298.137435) (xy 163.626634 -298.096169)
			(xy 163.657816 -298.059348) (xy 163.6944 -298.02789) (xy 163.735476 -298.002576) (xy 163.780023 -297.984037)
			(xy 163.82693 -297.972734) (xy 163.875031 -297.968949) (xy 163.923129 -297.972775) (xy 163.970027 -297.984118)
			(xy 164.014557 -298.002696) (xy 164.055611 -298.028044) (xy 164.092169 -298.059534) (xy 164.123319 -298.096382)
			(xy 164.148286 -298.137669) (xy 164.16645 -298.18237) (xy 164.177358 -298.22937) (xy 164.179504 -298.253404)
			(xy 164.179504 -298.253658) (xy 164.180606 -298.263087) (xy 164.188831 -298.280182) (xy 164.195506 -298.286932)
			(xy 164.246052 -298.334176) (xy 164.253351 -298.340441) (xy 164.271239 -298.347483) (xy 164.28085 -298.347892)
			(xy 164.419026 -298.347892) (xy 164.428644 -298.347523) (xy 164.446534 -298.340462) (xy 164.453824 -298.334176)
			(xy 164.50437 -298.286932) (xy 164.511061 -298.280195) (xy 164.519276 -298.26309) (xy 164.520372 -298.253658)
			(xy 164.520372 -298.25315) (xy 164.522699 -298.227792) (xy 164.534671 -298.178301) (xy 164.554688 -298.131483)
			(xy 164.582195 -298.088635) (xy 164.616431 -298.050944) (xy 164.656446 -298.019457) (xy 164.701131 -297.995045)
			(xy 164.749246 -297.978385) (xy 164.799459 -297.96994) (xy 164.824918 -297.969432) (xy 164.848914 -297.969822)
			(xy 164.896314 -297.977332) (xy 164.941955 -297.992166) (xy 164.984714 -298.013957) (xy 165.023537 -298.042169)
			(xy 165.057469 -298.076107) (xy 165.085673 -298.114936) (xy 165.107456 -298.157699) (xy 165.122281 -298.203343)
			(xy 165.129783 -298.250744) (xy 165.130226 -298.27474) (xy 165.469074 -298.27474) (xy 165.473034 -298.225686)
			(xy 165.484811 -298.177902) (xy 165.504102 -298.132626) (xy 165.530405 -298.09103) (xy 165.56304 -298.054193)
			(xy 165.601161 -298.023068) (xy 165.643782 -297.998461) (xy 165.689798 -297.981009) (xy 165.738017 -297.971165)
			(xy 165.787192 -297.969184) (xy 165.836047 -297.975116) (xy 165.883318 -297.988808) (xy 165.92778 -298.009906)
			(xy 165.968283 -298.037862) (xy 166.003776 -298.071954) (xy 166.033341 -298.111298) (xy 166.056212 -298.154875)
			(xy 166.071796 -298.201556) (xy 166.079691 -298.250133) (xy 166.080186 -298.27474) (xy 166.419288 -298.27474)
			(xy 166.423248 -298.225686) (xy 166.435025 -298.177902) (xy 166.454316 -298.132626) (xy 166.480619 -298.09103)
			(xy 166.513254 -298.054193) (xy 166.551375 -298.023068) (xy 166.593996 -297.998461) (xy 166.640012 -297.981009)
			(xy 166.688231 -297.971165) (xy 166.737406 -297.969184) (xy 166.786261 -297.975116) (xy 166.833532 -297.988808)
			(xy 166.877994 -298.009906) (xy 166.918497 -298.037862) (xy 166.95399 -298.071954) (xy 166.983555 -298.111298)
			(xy 167.006426 -298.154875) (xy 167.02201 -298.201556) (xy 167.029905 -298.250133) (xy 167.0304 -298.27474)
			(xy 167.369248 -298.27474) (xy 167.373208 -298.225686) (xy 167.384985 -298.177902) (xy 167.404276 -298.132626)
			(xy 167.430579 -298.09103) (xy 167.463214 -298.054193) (xy 167.501335 -298.023068) (xy 167.543956 -297.998461)
			(xy 167.589972 -297.981009) (xy 167.638191 -297.971165) (xy 167.687366 -297.969184) (xy 167.736221 -297.975116)
			(xy 167.783492 -297.988808) (xy 167.827954 -298.009906) (xy 167.868457 -298.037862) (xy 167.90395 -298.071954)
			(xy 167.933515 -298.111298) (xy 167.956386 -298.154875) (xy 167.97197 -298.201556) (xy 167.979865 -298.250133)
			(xy 167.98036 -298.27474) (xy 168.319208 -298.27474) (xy 168.323168 -298.225686) (xy 168.334945 -298.177902)
			(xy 168.354236 -298.132626) (xy 168.380539 -298.09103) (xy 168.413174 -298.054193) (xy 168.451295 -298.023068)
			(xy 168.493916 -297.998461) (xy 168.539932 -297.981009) (xy 168.588151 -297.971165) (xy 168.637326 -297.969184)
			(xy 168.686181 -297.975116) (xy 168.733452 -297.988808) (xy 168.777914 -298.009906) (xy 168.818417 -298.037862)
			(xy 168.85391 -298.071954) (xy 168.883475 -298.111298) (xy 168.906346 -298.154875) (xy 168.92193 -298.201556)
			(xy 168.929825 -298.250133) (xy 168.93032 -298.27474) (xy 169.269168 -298.27474) (xy 169.273128 -298.225686)
			(xy 169.284905 -298.177902) (xy 169.304196 -298.132626) (xy 169.330499 -298.09103) (xy 169.363134 -298.054193)
			(xy 169.401255 -298.023068) (xy 169.443876 -297.998461) (xy 169.489892 -297.981009) (xy 169.538111 -297.971165)
			(xy 169.587286 -297.969184) (xy 169.636141 -297.975116) (xy 169.683412 -297.988808) (xy 169.727874 -298.009906)
			(xy 169.768377 -298.037862) (xy 169.80387 -298.071954) (xy 169.833435 -298.111298) (xy 169.856306 -298.154875)
			(xy 169.87189 -298.201556) (xy 169.879785 -298.250133) (xy 169.88028 -298.27474) (xy 170.219128 -298.27474)
			(xy 170.223088 -298.225686) (xy 170.234865 -298.177902) (xy 170.254156 -298.132626) (xy 170.280459 -298.09103)
			(xy 170.313094 -298.054193) (xy 170.351215 -298.023068) (xy 170.393836 -297.998461) (xy 170.439852 -297.981009)
			(xy 170.488071 -297.971165) (xy 170.537246 -297.969184) (xy 170.586101 -297.975116) (xy 170.633372 -297.988808)
			(xy 170.677834 -298.009906) (xy 170.718337 -298.037862) (xy 170.75383 -298.071954) (xy 170.783395 -298.111298)
			(xy 170.806266 -298.154875) (xy 170.82185 -298.201556) (xy 170.829745 -298.250133) (xy 170.83024 -298.27474)
			(xy 171.169088 -298.27474) (xy 171.173048 -298.225686) (xy 171.184825 -298.177902) (xy 171.204116 -298.132626)
			(xy 171.230419 -298.09103) (xy 171.263054 -298.054193) (xy 171.301175 -298.023068) (xy 171.343796 -297.998461)
			(xy 171.389812 -297.981009) (xy 171.438031 -297.971165) (xy 171.487206 -297.969184) (xy 171.536061 -297.975116)
			(xy 171.583332 -297.988808) (xy 171.627794 -298.009906) (xy 171.668297 -298.037862) (xy 171.70379 -298.071954)
			(xy 171.733355 -298.111298) (xy 171.756226 -298.154875) (xy 171.77181 -298.201556) (xy 171.779705 -298.250133)
			(xy 171.7802 -298.27474) (xy 172.119048 -298.27474) (xy 172.123008 -298.225686) (xy 172.134785 -298.177902)
			(xy 172.154076 -298.132626) (xy 172.180379 -298.09103) (xy 172.213014 -298.054193) (xy 172.251135 -298.023068)
			(xy 172.293756 -297.998461) (xy 172.339772 -297.981009) (xy 172.387991 -297.971165) (xy 172.437166 -297.969184)
			(xy 172.486021 -297.975116) (xy 172.533292 -297.988808) (xy 172.577754 -298.009906) (xy 172.618257 -298.037862)
			(xy 172.65375 -298.071954) (xy 172.683315 -298.111298) (xy 172.706186 -298.154875) (xy 172.72177 -298.201556)
			(xy 172.729665 -298.250133) (xy 172.73016 -298.27474) (xy 173.069262 -298.27474) (xy 173.073222 -298.225686)
			(xy 173.084999 -298.177902) (xy 173.10429 -298.132626) (xy 173.130593 -298.09103) (xy 173.163228 -298.054193)
			(xy 173.201349 -298.023068) (xy 173.24397 -297.998461) (xy 173.289986 -297.981009) (xy 173.338205 -297.971165)
			(xy 173.38738 -297.969184) (xy 173.436235 -297.975116) (xy 173.483506 -297.988808) (xy 173.527968 -298.009906)
			(xy 173.568471 -298.037862) (xy 173.603964 -298.071954) (xy 173.633529 -298.111298) (xy 173.6564 -298.154875)
			(xy 173.671984 -298.201556) (xy 173.679879 -298.250133) (xy 173.680374 -298.27474) (xy 174.019222 -298.27474)
			(xy 174.023182 -298.225686) (xy 174.034959 -298.177902) (xy 174.05425 -298.132626) (xy 174.080553 -298.09103)
			(xy 174.113188 -298.054193) (xy 174.151309 -298.023068) (xy 174.19393 -297.998461) (xy 174.239946 -297.981009)
			(xy 174.288165 -297.971165) (xy 174.33734 -297.969184) (xy 174.386195 -297.975116) (xy 174.433466 -297.988808)
			(xy 174.477928 -298.009906) (xy 174.518431 -298.037862) (xy 174.553924 -298.071954) (xy 174.583489 -298.111298)
			(xy 174.60636 -298.154875) (xy 174.621944 -298.201556) (xy 174.629839 -298.250133) (xy 174.630334 -298.27474)
			(xy 175.919142 -298.27474) (xy 175.923102 -298.225686) (xy 175.934879 -298.177902) (xy 175.95417 -298.132626)
			(xy 175.980473 -298.09103) (xy 176.013108 -298.054193) (xy 176.051229 -298.023068) (xy 176.09385 -297.998461)
			(xy 176.139866 -297.981009) (xy 176.188085 -297.971165) (xy 176.23726 -297.969184) (xy 176.286115 -297.975116)
			(xy 176.333386 -297.988808) (xy 176.377848 -298.009906) (xy 176.418351 -298.037862) (xy 176.453844 -298.071954)
			(xy 176.483409 -298.111298) (xy 176.50628 -298.154875) (xy 176.521864 -298.201556) (xy 176.529759 -298.250133)
			(xy 176.530254 -298.27474) (xy 176.869102 -298.27474) (xy 176.873062 -298.225686) (xy 176.884839 -298.177902)
			(xy 176.90413 -298.132626) (xy 176.930433 -298.09103) (xy 176.963068 -298.054193) (xy 177.001189 -298.023068)
			(xy 177.04381 -297.998461) (xy 177.089826 -297.981009) (xy 177.138045 -297.971165) (xy 177.18722 -297.969184)
			(xy 177.236075 -297.975116) (xy 177.283346 -297.988808) (xy 177.327808 -298.009906) (xy 177.368311 -298.037862)
			(xy 177.403804 -298.071954) (xy 177.433369 -298.111298) (xy 177.45624 -298.154875) (xy 177.471824 -298.201556)
			(xy 177.479719 -298.250133) (xy 177.480214 -298.27474) (xy 177.819062 -298.27474) (xy 177.823022 -298.225686)
			(xy 177.834799 -298.177902) (xy 177.85409 -298.132626) (xy 177.880393 -298.09103) (xy 177.913028 -298.054193)
			(xy 177.951149 -298.023068) (xy 177.99377 -297.998461) (xy 178.039786 -297.981009) (xy 178.088005 -297.971165)
			(xy 178.13718 -297.969184) (xy 178.186035 -297.975116) (xy 178.233306 -297.988808) (xy 178.277768 -298.009906)
			(xy 178.318271 -298.037862) (xy 178.353764 -298.071954) (xy 178.383329 -298.111298) (xy 178.4062 -298.154875)
			(xy 178.421784 -298.201556) (xy 178.429679 -298.250133) (xy 178.430174 -298.27474) (xy 178.769276 -298.27474)
			(xy 178.773236 -298.225686) (xy 178.785013 -298.177902) (xy 178.804304 -298.132626) (xy 178.830607 -298.09103)
			(xy 178.863242 -298.054193) (xy 178.901363 -298.023068) (xy 178.943984 -297.998461) (xy 178.99 -297.981009)
			(xy 179.038219 -297.971165) (xy 179.087394 -297.969184) (xy 179.136249 -297.975116) (xy 179.18352 -297.988808)
			(xy 179.227982 -298.009906) (xy 179.268485 -298.037862) (xy 179.303978 -298.071954) (xy 179.333543 -298.111298)
			(xy 179.356414 -298.154875) (xy 179.371998 -298.201556) (xy 179.379893 -298.250133) (xy 179.380388 -298.27474)
			(xy 179.719236 -298.27474) (xy 179.723196 -298.225686) (xy 179.734973 -298.177902) (xy 179.754264 -298.132626)
			(xy 179.780567 -298.09103) (xy 179.813202 -298.054193) (xy 179.851323 -298.023068) (xy 179.893944 -297.998461)
			(xy 179.93996 -297.981009) (xy 179.988179 -297.971165) (xy 180.037354 -297.969184) (xy 180.086209 -297.975116)
			(xy 180.13348 -297.988808) (xy 180.177942 -298.009906) (xy 180.218445 -298.037862) (xy 180.253938 -298.071954)
			(xy 180.283503 -298.111298) (xy 180.306374 -298.154875) (xy 180.321958 -298.201556) (xy 180.329853 -298.250133)
			(xy 180.330348 -298.27474) (xy 180.669196 -298.27474) (xy 180.673156 -298.225686) (xy 180.684933 -298.177902)
			(xy 180.704224 -298.132626) (xy 180.730527 -298.09103) (xy 180.763162 -298.054193) (xy 180.801283 -298.023068)
			(xy 180.843904 -297.998461) (xy 180.88992 -297.981009) (xy 180.938139 -297.971165) (xy 180.987314 -297.969184)
			(xy 181.036169 -297.975116) (xy 181.08344 -297.988808) (xy 181.127902 -298.009906) (xy 181.168405 -298.037862)
			(xy 181.203898 -298.071954) (xy 181.233463 -298.111298) (xy 181.256334 -298.154875) (xy 181.271918 -298.201556)
			(xy 181.279813 -298.250133) (xy 181.280308 -298.27474) (xy 181.619156 -298.27474) (xy 181.623116 -298.225686)
			(xy 181.634893 -298.177902) (xy 181.654184 -298.132626) (xy 181.680487 -298.09103) (xy 181.713122 -298.054193)
			(xy 181.751243 -298.023068) (xy 181.793864 -297.998461) (xy 181.83988 -297.981009) (xy 181.888099 -297.971165)
			(xy 181.937274 -297.969184) (xy 181.986129 -297.975116) (xy 182.0334 -297.988808) (xy 182.077862 -298.009906)
			(xy 182.118365 -298.037862) (xy 182.153858 -298.071954) (xy 182.183423 -298.111298) (xy 182.206294 -298.154875)
			(xy 182.221878 -298.201556) (xy 182.229773 -298.250133) (xy 182.230268 -298.27474) (xy 182.569116 -298.27474)
			(xy 182.573076 -298.225686) (xy 182.584853 -298.177902) (xy 182.604144 -298.132626) (xy 182.630447 -298.09103)
			(xy 182.663082 -298.054193) (xy 182.701203 -298.023068) (xy 182.743824 -297.998461) (xy 182.78984 -297.981009)
			(xy 182.838059 -297.971165) (xy 182.887234 -297.969184) (xy 182.936089 -297.975116) (xy 182.98336 -297.988808)
			(xy 183.027822 -298.009906) (xy 183.068325 -298.037862) (xy 183.103818 -298.071954) (xy 183.133383 -298.111298)
			(xy 183.156254 -298.154875) (xy 183.171838 -298.201556) (xy 183.179733 -298.250133) (xy 183.180228 -298.27474)
			(xy 183.519076 -298.27474) (xy 183.523036 -298.225686) (xy 183.534813 -298.177902) (xy 183.554104 -298.132626)
			(xy 183.580407 -298.09103) (xy 183.613042 -298.054193) (xy 183.651163 -298.023068) (xy 183.693784 -297.998461)
			(xy 183.7398 -297.981009) (xy 183.788019 -297.971165) (xy 183.837194 -297.969184) (xy 183.886049 -297.975116)
			(xy 183.93332 -297.988808) (xy 183.977782 -298.009906) (xy 184.018285 -298.037862) (xy 184.053778 -298.071954)
			(xy 184.083343 -298.111298) (xy 184.106214 -298.154875) (xy 184.121798 -298.201556) (xy 184.129693 -298.250133)
			(xy 184.130188 -298.27474) (xy 184.469036 -298.27474) (xy 184.472996 -298.225686) (xy 184.484773 -298.177902)
			(xy 184.504064 -298.132626) (xy 184.530367 -298.09103) (xy 184.563002 -298.054193) (xy 184.601123 -298.023068)
			(xy 184.643744 -297.998461) (xy 184.68976 -297.981009) (xy 184.737979 -297.971165) (xy 184.787154 -297.969184)
			(xy 184.836009 -297.975116) (xy 184.88328 -297.988808) (xy 184.927742 -298.009906) (xy 184.968245 -298.037862)
			(xy 185.003738 -298.071954) (xy 185.033303 -298.111298) (xy 185.056174 -298.154875) (xy 185.071758 -298.201556)
			(xy 185.079653 -298.250133) (xy 185.080148 -298.27474) (xy 185.079653 -298.299347) (xy 185.071758 -298.347924)
			(xy 185.056174 -298.394605) (xy 185.033303 -298.438182) (xy 185.003738 -298.477526) (xy 184.968245 -298.511618)
			(xy 184.927742 -298.539574) (xy 184.88328 -298.560672) (xy 184.836009 -298.574364) (xy 184.787154 -298.580296)
			(xy 184.737979 -298.578315) (xy 184.68976 -298.568471) (xy 184.643744 -298.551019) (xy 184.601123 -298.526412)
			(xy 184.563002 -298.495287) (xy 184.530367 -298.45845) (xy 184.504064 -298.416854) (xy 184.484773 -298.371578)
			(xy 184.472996 -298.323794) (xy 184.469036 -298.27474) (xy 184.130188 -298.27474) (xy 184.129693 -298.299347)
			(xy 184.121798 -298.347924) (xy 184.106214 -298.394605) (xy 184.083343 -298.438182) (xy 184.053778 -298.477526)
			(xy 184.018285 -298.511618) (xy 183.977782 -298.539574) (xy 183.93332 -298.560672) (xy 183.886049 -298.574364)
			(xy 183.837194 -298.580296) (xy 183.788019 -298.578315) (xy 183.7398 -298.568471) (xy 183.693784 -298.551019)
			(xy 183.651163 -298.526412) (xy 183.613042 -298.495287) (xy 183.580407 -298.45845) (xy 183.554104 -298.416854)
			(xy 183.534813 -298.371578) (xy 183.523036 -298.323794) (xy 183.519076 -298.27474) (xy 183.180228 -298.27474)
			(xy 183.179733 -298.299347) (xy 183.171838 -298.347924) (xy 183.156254 -298.394605) (xy 183.133383 -298.438182)
			(xy 183.103818 -298.477526) (xy 183.068325 -298.511618) (xy 183.027822 -298.539574) (xy 182.98336 -298.560672)
			(xy 182.936089 -298.574364) (xy 182.887234 -298.580296) (xy 182.838059 -298.578315) (xy 182.78984 -298.568471)
			(xy 182.743824 -298.551019) (xy 182.701203 -298.526412) (xy 182.663082 -298.495287) (xy 182.630447 -298.45845)
			(xy 182.604144 -298.416854) (xy 182.584853 -298.371578) (xy 182.573076 -298.323794) (xy 182.569116 -298.27474)
			(xy 182.230268 -298.27474) (xy 182.229773 -298.299347) (xy 182.221878 -298.347924) (xy 182.206294 -298.394605)
			(xy 182.183423 -298.438182) (xy 182.153858 -298.477526) (xy 182.118365 -298.511618) (xy 182.077862 -298.539574)
			(xy 182.0334 -298.560672) (xy 181.986129 -298.574364) (xy 181.937274 -298.580296) (xy 181.888099 -298.578315)
			(xy 181.83988 -298.568471) (xy 181.793864 -298.551019) (xy 181.751243 -298.526412) (xy 181.713122 -298.495287)
			(xy 181.680487 -298.45845) (xy 181.654184 -298.416854) (xy 181.634893 -298.371578) (xy 181.623116 -298.323794)
			(xy 181.619156 -298.27474) (xy 181.280308 -298.27474) (xy 181.279813 -298.299347) (xy 181.271918 -298.347924)
			(xy 181.256334 -298.394605) (xy 181.233463 -298.438182) (xy 181.203898 -298.477526) (xy 181.168405 -298.511618)
			(xy 181.127902 -298.539574) (xy 181.08344 -298.560672) (xy 181.036169 -298.574364) (xy 180.987314 -298.580296)
			(xy 180.938139 -298.578315) (xy 180.88992 -298.568471) (xy 180.843904 -298.551019) (xy 180.801283 -298.526412)
			(xy 180.763162 -298.495287) (xy 180.730527 -298.45845) (xy 180.704224 -298.416854) (xy 180.684933 -298.371578)
			(xy 180.673156 -298.323794) (xy 180.669196 -298.27474) (xy 180.330348 -298.27474) (xy 180.329853 -298.299347)
			(xy 180.321958 -298.347924) (xy 180.306374 -298.394605) (xy 180.283503 -298.438182) (xy 180.253938 -298.477526)
			(xy 180.218445 -298.511618) (xy 180.177942 -298.539574) (xy 180.13348 -298.560672) (xy 180.086209 -298.574364)
			(xy 180.037354 -298.580296) (xy 179.988179 -298.578315) (xy 179.93996 -298.568471) (xy 179.893944 -298.551019)
			(xy 179.851323 -298.526412) (xy 179.813202 -298.495287) (xy 179.780567 -298.45845) (xy 179.754264 -298.416854)
			(xy 179.734973 -298.371578) (xy 179.723196 -298.323794) (xy 179.719236 -298.27474) (xy 179.380388 -298.27474)
			(xy 179.379893 -298.299347) (xy 179.371998 -298.347924) (xy 179.356414 -298.394605) (xy 179.333543 -298.438182)
			(xy 179.303978 -298.477526) (xy 179.268485 -298.511618) (xy 179.227982 -298.539574) (xy 179.18352 -298.560672)
			(xy 179.136249 -298.574364) (xy 179.087394 -298.580296) (xy 179.038219 -298.578315) (xy 178.99 -298.568471)
			(xy 178.943984 -298.551019) (xy 178.901363 -298.526412) (xy 178.863242 -298.495287) (xy 178.830607 -298.45845)
			(xy 178.804304 -298.416854) (xy 178.785013 -298.371578) (xy 178.773236 -298.323794) (xy 178.769276 -298.27474)
			(xy 178.430174 -298.27474) (xy 178.429679 -298.299347) (xy 178.421784 -298.347924) (xy 178.4062 -298.394605)
			(xy 178.383329 -298.438182) (xy 178.353764 -298.477526) (xy 178.318271 -298.511618) (xy 178.277768 -298.539574)
			(xy 178.233306 -298.560672) (xy 178.186035 -298.574364) (xy 178.13718 -298.580296) (xy 178.088005 -298.578315)
			(xy 178.039786 -298.568471) (xy 177.99377 -298.551019) (xy 177.951149 -298.526412) (xy 177.913028 -298.495287)
			(xy 177.880393 -298.45845) (xy 177.85409 -298.416854) (xy 177.834799 -298.371578) (xy 177.823022 -298.323794)
			(xy 177.819062 -298.27474) (xy 177.480214 -298.27474) (xy 177.479719 -298.299347) (xy 177.471824 -298.347924)
			(xy 177.45624 -298.394605) (xy 177.433369 -298.438182) (xy 177.403804 -298.477526) (xy 177.368311 -298.511618)
			(xy 177.327808 -298.539574) (xy 177.283346 -298.560672) (xy 177.236075 -298.574364) (xy 177.18722 -298.580296)
			(xy 177.138045 -298.578315) (xy 177.089826 -298.568471) (xy 177.04381 -298.551019) (xy 177.001189 -298.526412)
			(xy 176.963068 -298.495287) (xy 176.930433 -298.45845) (xy 176.90413 -298.416854) (xy 176.884839 -298.371578)
			(xy 176.873062 -298.323794) (xy 176.869102 -298.27474) (xy 176.530254 -298.27474) (xy 176.529759 -298.299347)
			(xy 176.521864 -298.347924) (xy 176.50628 -298.394605) (xy 176.483409 -298.438182) (xy 176.453844 -298.477526)
			(xy 176.418351 -298.511618) (xy 176.377848 -298.539574) (xy 176.333386 -298.560672) (xy 176.286115 -298.574364)
			(xy 176.23726 -298.580296) (xy 176.188085 -298.578315) (xy 176.139866 -298.568471) (xy 176.09385 -298.551019)
			(xy 176.051229 -298.526412) (xy 176.013108 -298.495287) (xy 175.980473 -298.45845) (xy 175.95417 -298.416854)
			(xy 175.934879 -298.371578) (xy 175.923102 -298.323794) (xy 175.919142 -298.27474) (xy 174.630334 -298.27474)
			(xy 174.629839 -298.299347) (xy 174.621944 -298.347924) (xy 174.60636 -298.394605) (xy 174.583489 -298.438182)
			(xy 174.553924 -298.477526) (xy 174.518431 -298.511618) (xy 174.477928 -298.539574) (xy 174.433466 -298.560672)
			(xy 174.386195 -298.574364) (xy 174.33734 -298.580296) (xy 174.288165 -298.578315) (xy 174.239946 -298.568471)
			(xy 174.19393 -298.551019) (xy 174.151309 -298.526412) (xy 174.113188 -298.495287) (xy 174.080553 -298.45845)
			(xy 174.05425 -298.416854) (xy 174.034959 -298.371578) (xy 174.023182 -298.323794) (xy 174.019222 -298.27474)
			(xy 173.680374 -298.27474) (xy 173.679879 -298.299347) (xy 173.671984 -298.347924) (xy 173.6564 -298.394605)
			(xy 173.633529 -298.438182) (xy 173.603964 -298.477526) (xy 173.568471 -298.511618) (xy 173.527968 -298.539574)
			(xy 173.483506 -298.560672) (xy 173.436235 -298.574364) (xy 173.38738 -298.580296) (xy 173.338205 -298.578315)
			(xy 173.289986 -298.568471) (xy 173.24397 -298.551019) (xy 173.201349 -298.526412) (xy 173.163228 -298.495287)
			(xy 173.130593 -298.45845) (xy 173.10429 -298.416854) (xy 173.084999 -298.371578) (xy 173.073222 -298.323794)
			(xy 173.069262 -298.27474) (xy 172.73016 -298.27474) (xy 172.729665 -298.299347) (xy 172.72177 -298.347924)
			(xy 172.706186 -298.394605) (xy 172.683315 -298.438182) (xy 172.65375 -298.477526) (xy 172.618257 -298.511618)
			(xy 172.577754 -298.539574) (xy 172.533292 -298.560672) (xy 172.486021 -298.574364) (xy 172.437166 -298.580296)
			(xy 172.387991 -298.578315) (xy 172.339772 -298.568471) (xy 172.293756 -298.551019) (xy 172.251135 -298.526412)
			(xy 172.213014 -298.495287) (xy 172.180379 -298.45845) (xy 172.154076 -298.416854) (xy 172.134785 -298.371578)
			(xy 172.123008 -298.323794) (xy 172.119048 -298.27474) (xy 171.7802 -298.27474) (xy 171.779705 -298.299347)
			(xy 171.77181 -298.347924) (xy 171.756226 -298.394605) (xy 171.733355 -298.438182) (xy 171.70379 -298.477526)
			(xy 171.668297 -298.511618) (xy 171.627794 -298.539574) (xy 171.583332 -298.560672) (xy 171.536061 -298.574364)
			(xy 171.487206 -298.580296) (xy 171.438031 -298.578315) (xy 171.389812 -298.568471) (xy 171.343796 -298.551019)
			(xy 171.301175 -298.526412) (xy 171.263054 -298.495287) (xy 171.230419 -298.45845) (xy 171.204116 -298.416854)
			(xy 171.184825 -298.371578) (xy 171.173048 -298.323794) (xy 171.169088 -298.27474) (xy 170.83024 -298.27474)
			(xy 170.829745 -298.299347) (xy 170.82185 -298.347924) (xy 170.806266 -298.394605) (xy 170.783395 -298.438182)
			(xy 170.75383 -298.477526) (xy 170.718337 -298.511618) (xy 170.677834 -298.539574) (xy 170.633372 -298.560672)
			(xy 170.586101 -298.574364) (xy 170.537246 -298.580296) (xy 170.488071 -298.578315) (xy 170.439852 -298.568471)
			(xy 170.393836 -298.551019) (xy 170.351215 -298.526412) (xy 170.313094 -298.495287) (xy 170.280459 -298.45845)
			(xy 170.254156 -298.416854) (xy 170.234865 -298.371578) (xy 170.223088 -298.323794) (xy 170.219128 -298.27474)
			(xy 169.88028 -298.27474) (xy 169.879785 -298.299347) (xy 169.87189 -298.347924) (xy 169.856306 -298.394605)
			(xy 169.833435 -298.438182) (xy 169.80387 -298.477526) (xy 169.768377 -298.511618) (xy 169.727874 -298.539574)
			(xy 169.683412 -298.560672) (xy 169.636141 -298.574364) (xy 169.587286 -298.580296) (xy 169.538111 -298.578315)
			(xy 169.489892 -298.568471) (xy 169.443876 -298.551019) (xy 169.401255 -298.526412) (xy 169.363134 -298.495287)
			(xy 169.330499 -298.45845) (xy 169.304196 -298.416854) (xy 169.284905 -298.371578) (xy 169.273128 -298.323794)
			(xy 169.269168 -298.27474) (xy 168.93032 -298.27474) (xy 168.929825 -298.299347) (xy 168.92193 -298.347924)
			(xy 168.906346 -298.394605) (xy 168.883475 -298.438182) (xy 168.85391 -298.477526) (xy 168.818417 -298.511618)
			(xy 168.777914 -298.539574) (xy 168.733452 -298.560672) (xy 168.686181 -298.574364) (xy 168.637326 -298.580296)
			(xy 168.588151 -298.578315) (xy 168.539932 -298.568471) (xy 168.493916 -298.551019) (xy 168.451295 -298.526412)
			(xy 168.413174 -298.495287) (xy 168.380539 -298.45845) (xy 168.354236 -298.416854) (xy 168.334945 -298.371578)
			(xy 168.323168 -298.323794) (xy 168.319208 -298.27474) (xy 167.98036 -298.27474) (xy 167.979865 -298.299347)
			(xy 167.97197 -298.347924) (xy 167.956386 -298.394605) (xy 167.933515 -298.438182) (xy 167.90395 -298.477526)
			(xy 167.868457 -298.511618) (xy 167.827954 -298.539574) (xy 167.783492 -298.560672) (xy 167.736221 -298.574364)
			(xy 167.687366 -298.580296) (xy 167.638191 -298.578315) (xy 167.589972 -298.568471) (xy 167.543956 -298.551019)
			(xy 167.501335 -298.526412) (xy 167.463214 -298.495287) (xy 167.430579 -298.45845) (xy 167.404276 -298.416854)
			(xy 167.384985 -298.371578) (xy 167.373208 -298.323794) (xy 167.369248 -298.27474) (xy 167.0304 -298.27474)
			(xy 167.029905 -298.299347) (xy 167.02201 -298.347924) (xy 167.006426 -298.394605) (xy 166.983555 -298.438182)
			(xy 166.95399 -298.477526) (xy 166.918497 -298.511618) (xy 166.877994 -298.539574) (xy 166.833532 -298.560672)
			(xy 166.786261 -298.574364) (xy 166.737406 -298.580296) (xy 166.688231 -298.578315) (xy 166.640012 -298.568471)
			(xy 166.593996 -298.551019) (xy 166.551375 -298.526412) (xy 166.513254 -298.495287) (xy 166.480619 -298.45845)
			(xy 166.454316 -298.416854) (xy 166.435025 -298.371578) (xy 166.423248 -298.323794) (xy 166.419288 -298.27474)
			(xy 166.080186 -298.27474) (xy 166.079691 -298.299347) (xy 166.071796 -298.347924) (xy 166.056212 -298.394605)
			(xy 166.033341 -298.438182) (xy 166.003776 -298.477526) (xy 165.968283 -298.511618) (xy 165.92778 -298.539574)
			(xy 165.883318 -298.560672) (xy 165.836047 -298.574364) (xy 165.787192 -298.580296) (xy 165.738017 -298.578315)
			(xy 165.689798 -298.568471) (xy 165.643782 -298.551019) (xy 165.601161 -298.526412) (xy 165.56304 -298.495287)
			(xy 165.530405 -298.45845) (xy 165.504102 -298.416854) (xy 165.484811 -298.371578) (xy 165.473034 -298.323794)
			(xy 165.469074 -298.27474) (xy 165.130226 -298.27474) (xy 165.129736 -298.299108) (xy 165.121946 -298.347217)
			(xy 165.114732 -298.370498) (xy 165.112183 -298.379542) (xy 165.113124 -298.398293) (xy 165.120777 -298.415437)
			(xy 165.127178 -298.422314) (xy 165.364922 -298.659804) (xy 165.37176 -298.667206) (xy 165.37948 -298.685804)
			(xy 165.379908 -298.695872) (xy 165.379908 -298.943268) (xy 165.380351 -298.953338) (xy 165.388163 -298.971906)
			(xy 165.402489 -298.986068) (xy 165.411658 -298.990258) (xy 165.499034 -299.025564) (xy 165.508593 -299.028917)
			(xy 165.528834 -299.028551) (xy 165.547366 -299.020404) (xy 165.55466 -299.013372) (xy 165.572088 -298.995996)
			(xy 165.611442 -298.966455) (xy 165.655023 -298.943603) (xy 165.701702 -298.928031) (xy 165.750274 -298.920141)
			(xy 165.774878 -298.919646) (xy 165.800133 -298.920229) (xy 165.849955 -298.928539) (xy 165.897729 -298.944937)
			(xy 165.942153 -298.968975) (xy 165.982014 -298.999997) (xy 166.016225 -299.037158) (xy 166.043852 -299.079443)
			(xy 166.064143 -299.125698) (xy 166.076543 -299.174662) (xy 166.08071 -299.224954) (xy 184.469036 -299.224954)
			(xy 184.472996 -299.1759) (xy 184.484773 -299.128116) (xy 184.504064 -299.08284) (xy 184.530367 -299.041244)
			(xy 184.563002 -299.004407) (xy 184.601123 -298.973282) (xy 184.643744 -298.948675) (xy 184.68976 -298.931223)
			(xy 184.737979 -298.921379) (xy 184.787154 -298.919398) (xy 184.836009 -298.92533) (xy 184.88328 -298.939022)
			(xy 184.927742 -298.96012) (xy 184.968245 -298.988076) (xy 185.003738 -299.022168) (xy 185.033303 -299.061512)
			(xy 185.056174 -299.105089) (xy 185.071758 -299.15177) (xy 185.079653 -299.200347) (xy 185.080148 -299.224954)
			(xy 185.079653 -299.249561) (xy 185.071758 -299.298138) (xy 185.056174 -299.344819) (xy 185.033303 -299.388396)
			(xy 185.003738 -299.42774) (xy 184.968245 -299.461832) (xy 184.927742 -299.489788) (xy 184.88328 -299.510886)
			(xy 184.836009 -299.524578) (xy 184.787154 -299.53051) (xy 184.737979 -299.528529) (xy 184.68976 -299.518685)
			(xy 184.643744 -299.501233) (xy 184.601123 -299.476626) (xy 184.563002 -299.445501) (xy 184.530367 -299.408664)
			(xy 184.504064 -299.367068) (xy 184.484773 -299.321792) (xy 184.472996 -299.274008) (xy 184.469036 -299.224954)
			(xy 166.08071 -299.224954) (xy 166.080714 -299.225) (xy 166.076543 -299.275338) (xy 166.064143 -299.324302)
			(xy 166.043852 -299.370557) (xy 166.016225 -299.412842) (xy 165.982014 -299.450003) (xy 165.942153 -299.481025)
			(xy 165.897729 -299.505063) (xy 165.849955 -299.521461) (xy 165.800133 -299.529771) (xy 165.774878 -299.530262)
			(xy 165.750272 -299.529786) (xy 165.701697 -299.521896) (xy 165.655014 -299.506323) (xy 165.611431 -299.48347)
			(xy 165.572073 -299.453928) (xy 165.55466 -299.436536) (xy 165.54735 -299.429527) (xy 165.528828 -299.421383)
			(xy 165.508598 -299.421016) (xy 165.499034 -299.424344) (xy 165.411658 -299.45965) (xy 165.402487 -299.46385)
			(xy 165.388121 -299.477979) (xy 165.38034 -299.496565) (xy 165.379908 -299.50664) (xy 165.379908 -299.893228)
			(xy 165.380381 -299.903295) (xy 165.388178 -299.921862) (xy 165.402493 -299.936026) (xy 165.411658 -299.940218)
			(xy 165.499034 -299.975524) (xy 165.508591 -299.978888) (xy 165.528835 -299.978522) (xy 165.547368 -299.970368)
			(xy 165.55466 -299.963332) (xy 165.57208 -299.945949) (xy 165.611438 -299.916411) (xy 165.65502 -299.893561)
			(xy 165.701701 -299.87799) (xy 165.750274 -299.870101) (xy 165.774878 -299.869606) (xy 165.800138 -299.870069)
			(xy 165.84997 -299.878381) (xy 165.897753 -299.894782) (xy 165.942186 -299.918825) (xy 165.982054 -299.949853)
			(xy 166.016272 -299.987021) (xy 166.043905 -300.029314) (xy 166.064199 -300.075578) (xy 166.076602 -300.124553)
			(xy 166.080774 -300.1749) (xy 166.080773 -300.174914) (xy 166.419288 -300.174914) (xy 166.423248 -300.12586)
			(xy 166.435025 -300.078076) (xy 166.454316 -300.0328) (xy 166.480619 -299.991204) (xy 166.513254 -299.954367)
			(xy 166.551375 -299.923242) (xy 166.593996 -299.898635) (xy 166.640012 -299.881183) (xy 166.688231 -299.871339)
			(xy 166.737406 -299.869358) (xy 166.786261 -299.87529) (xy 166.833532 -299.888982) (xy 166.877994 -299.91008)
			(xy 166.918497 -299.938036) (xy 166.95399 -299.972128) (xy 166.983555 -300.011472) (xy 167.006426 -300.055049)
			(xy 167.02201 -300.10173) (xy 167.029905 -300.150307) (xy 167.0304 -300.174914) (xy 167.369248 -300.174914)
			(xy 167.373208 -300.12586) (xy 167.384985 -300.078076) (xy 167.404276 -300.0328) (xy 167.430579 -299.991204)
			(xy 167.463214 -299.954367) (xy 167.501335 -299.923242) (xy 167.543956 -299.898635) (xy 167.589972 -299.881183)
			(xy 167.638191 -299.871339) (xy 167.687366 -299.869358) (xy 167.736221 -299.87529) (xy 167.783492 -299.888982)
			(xy 167.827954 -299.91008) (xy 167.868457 -299.938036) (xy 167.90395 -299.972128) (xy 167.933515 -300.011472)
			(xy 167.956386 -300.055049) (xy 167.97197 -300.10173) (xy 167.979865 -300.150307) (xy 167.98036 -300.174914)
			(xy 168.319208 -300.174914) (xy 168.323168 -300.12586) (xy 168.334945 -300.078076) (xy 168.354236 -300.0328)
			(xy 168.380539 -299.991204) (xy 168.413174 -299.954367) (xy 168.451295 -299.923242) (xy 168.493916 -299.898635)
			(xy 168.539932 -299.881183) (xy 168.588151 -299.871339) (xy 168.637326 -299.869358) (xy 168.686181 -299.87529)
			(xy 168.733452 -299.888982) (xy 168.777914 -299.91008) (xy 168.818417 -299.938036) (xy 168.85391 -299.972128)
			(xy 168.883475 -300.011472) (xy 168.906346 -300.055049) (xy 168.92193 -300.10173) (xy 168.929825 -300.150307)
			(xy 168.93032 -300.174914) (xy 169.269168 -300.174914) (xy 169.273128 -300.12586) (xy 169.284905 -300.078076)
			(xy 169.304196 -300.0328) (xy 169.330499 -299.991204) (xy 169.363134 -299.954367) (xy 169.401255 -299.923242)
			(xy 169.443876 -299.898635) (xy 169.489892 -299.881183) (xy 169.538111 -299.871339) (xy 169.587286 -299.869358)
			(xy 169.636141 -299.87529) (xy 169.683412 -299.888982) (xy 169.727874 -299.91008) (xy 169.768377 -299.938036)
			(xy 169.80387 -299.972128) (xy 169.833435 -300.011472) (xy 169.856306 -300.055049) (xy 169.87189 -300.10173)
			(xy 169.879785 -300.150307) (xy 169.88028 -300.174914) (xy 170.219128 -300.174914) (xy 170.223088 -300.12586)
			(xy 170.234865 -300.078076) (xy 170.254156 -300.0328) (xy 170.280459 -299.991204) (xy 170.313094 -299.954367)
			(xy 170.351215 -299.923242) (xy 170.393836 -299.898635) (xy 170.439852 -299.881183) (xy 170.488071 -299.871339)
			(xy 170.537246 -299.869358) (xy 170.586101 -299.87529) (xy 170.633372 -299.888982) (xy 170.677834 -299.91008)
			(xy 170.718337 -299.938036) (xy 170.75383 -299.972128) (xy 170.783395 -300.011472) (xy 170.806266 -300.055049)
			(xy 170.82185 -300.10173) (xy 170.829745 -300.150307) (xy 170.83024 -300.174914) (xy 171.169088 -300.174914)
			(xy 171.173048 -300.12586) (xy 171.184825 -300.078076) (xy 171.204116 -300.0328) (xy 171.230419 -299.991204)
			(xy 171.263054 -299.954367) (xy 171.301175 -299.923242) (xy 171.343796 -299.898635) (xy 171.389812 -299.881183)
			(xy 171.438031 -299.871339) (xy 171.487206 -299.869358) (xy 171.536061 -299.87529) (xy 171.583332 -299.888982)
			(xy 171.627794 -299.91008) (xy 171.668297 -299.938036) (xy 171.70379 -299.972128) (xy 171.733355 -300.011472)
			(xy 171.756226 -300.055049) (xy 171.77181 -300.10173) (xy 171.779705 -300.150307) (xy 171.7802 -300.174914)
			(xy 172.119048 -300.174914) (xy 172.123008 -300.12586) (xy 172.134785 -300.078076) (xy 172.154076 -300.0328)
			(xy 172.180379 -299.991204) (xy 172.213014 -299.954367) (xy 172.251135 -299.923242) (xy 172.293756 -299.898635)
			(xy 172.339772 -299.881183) (xy 172.387991 -299.871339) (xy 172.437166 -299.869358) (xy 172.486021 -299.87529)
			(xy 172.533292 -299.888982) (xy 172.577754 -299.91008) (xy 172.618257 -299.938036) (xy 172.65375 -299.972128)
			(xy 172.683315 -300.011472) (xy 172.706186 -300.055049) (xy 172.72177 -300.10173) (xy 172.729665 -300.150307)
			(xy 172.73016 -300.174914) (xy 173.069262 -300.174914) (xy 173.073222 -300.12586) (xy 173.084999 -300.078076)
			(xy 173.10429 -300.0328) (xy 173.130593 -299.991204) (xy 173.163228 -299.954367) (xy 173.201349 -299.923242)
			(xy 173.24397 -299.898635) (xy 173.289986 -299.881183) (xy 173.338205 -299.871339) (xy 173.38738 -299.869358)
			(xy 173.436235 -299.87529) (xy 173.483506 -299.888982) (xy 173.527968 -299.91008) (xy 173.568471 -299.938036)
			(xy 173.603964 -299.972128) (xy 173.633529 -300.011472) (xy 173.6564 -300.055049) (xy 173.671984 -300.10173)
			(xy 173.679879 -300.150307) (xy 173.680374 -300.174914) (xy 174.019222 -300.174914) (xy 174.023182 -300.12586)
			(xy 174.034959 -300.078076) (xy 174.05425 -300.0328) (xy 174.080553 -299.991204) (xy 174.113188 -299.954367)
			(xy 174.151309 -299.923242) (xy 174.19393 -299.898635) (xy 174.239946 -299.881183) (xy 174.288165 -299.871339)
			(xy 174.33734 -299.869358) (xy 174.386195 -299.87529) (xy 174.433466 -299.888982) (xy 174.477928 -299.91008)
			(xy 174.518431 -299.938036) (xy 174.553924 -299.972128) (xy 174.583489 -300.011472) (xy 174.60636 -300.055049)
			(xy 174.621944 -300.10173) (xy 174.629839 -300.150307) (xy 174.630334 -300.174914) (xy 175.919142 -300.174914)
			(xy 175.923102 -300.12586) (xy 175.934879 -300.078076) (xy 175.95417 -300.0328) (xy 175.980473 -299.991204)
			(xy 176.013108 -299.954367) (xy 176.051229 -299.923242) (xy 176.09385 -299.898635) (xy 176.139866 -299.881183)
			(xy 176.188085 -299.871339) (xy 176.23726 -299.869358) (xy 176.286115 -299.87529) (xy 176.333386 -299.888982)
			(xy 176.377848 -299.91008) (xy 176.418351 -299.938036) (xy 176.453844 -299.972128) (xy 176.483409 -300.011472)
			(xy 176.50628 -300.055049) (xy 176.521864 -300.10173) (xy 176.529759 -300.150307) (xy 176.530254 -300.174914)
			(xy 176.869102 -300.174914) (xy 176.873062 -300.12586) (xy 176.884839 -300.078076) (xy 176.90413 -300.0328)
			(xy 176.930433 -299.991204) (xy 176.963068 -299.954367) (xy 177.001189 -299.923242) (xy 177.04381 -299.898635)
			(xy 177.089826 -299.881183) (xy 177.138045 -299.871339) (xy 177.18722 -299.869358) (xy 177.236075 -299.87529)
			(xy 177.283346 -299.888982) (xy 177.327808 -299.91008) (xy 177.368311 -299.938036) (xy 177.403804 -299.972128)
			(xy 177.433369 -300.011472) (xy 177.45624 -300.055049) (xy 177.471824 -300.10173) (xy 177.479719 -300.150307)
			(xy 177.480214 -300.174914) (xy 177.819062 -300.174914) (xy 177.823022 -300.12586) (xy 177.834799 -300.078076)
			(xy 177.85409 -300.0328) (xy 177.880393 -299.991204) (xy 177.913028 -299.954367) (xy 177.951149 -299.923242)
			(xy 177.99377 -299.898635) (xy 178.039786 -299.881183) (xy 178.088005 -299.871339) (xy 178.13718 -299.869358)
			(xy 178.186035 -299.87529) (xy 178.233306 -299.888982) (xy 178.277768 -299.91008) (xy 178.318271 -299.938036)
			(xy 178.353764 -299.972128) (xy 178.383329 -300.011472) (xy 178.4062 -300.055049) (xy 178.421784 -300.10173)
			(xy 178.429679 -300.150307) (xy 178.430174 -300.174914) (xy 178.769276 -300.174914) (xy 178.773236 -300.12586)
			(xy 178.785013 -300.078076) (xy 178.804304 -300.0328) (xy 178.830607 -299.991204) (xy 178.863242 -299.954367)
			(xy 178.901363 -299.923242) (xy 178.943984 -299.898635) (xy 178.99 -299.881183) (xy 179.038219 -299.871339)
			(xy 179.087394 -299.869358) (xy 179.136249 -299.87529) (xy 179.18352 -299.888982) (xy 179.227982 -299.91008)
			(xy 179.268485 -299.938036) (xy 179.303978 -299.972128) (xy 179.333543 -300.011472) (xy 179.356414 -300.055049)
			(xy 179.371998 -300.10173) (xy 179.379893 -300.150307) (xy 179.380388 -300.174914) (xy 179.719236 -300.174914)
			(xy 179.723196 -300.12586) (xy 179.734973 -300.078076) (xy 179.754264 -300.0328) (xy 179.780567 -299.991204)
			(xy 179.813202 -299.954367) (xy 179.851323 -299.923242) (xy 179.893944 -299.898635) (xy 179.93996 -299.881183)
			(xy 179.988179 -299.871339) (xy 180.037354 -299.869358) (xy 180.086209 -299.87529) (xy 180.13348 -299.888982)
			(xy 180.177942 -299.91008) (xy 180.218445 -299.938036) (xy 180.253938 -299.972128) (xy 180.283503 -300.011472)
			(xy 180.306374 -300.055049) (xy 180.321958 -300.10173) (xy 180.329853 -300.150307) (xy 180.330348 -300.174914)
			(xy 180.669196 -300.174914) (xy 180.673156 -300.12586) (xy 180.684933 -300.078076) (xy 180.704224 -300.0328)
			(xy 180.730527 -299.991204) (xy 180.763162 -299.954367) (xy 180.801283 -299.923242) (xy 180.843904 -299.898635)
			(xy 180.88992 -299.881183) (xy 180.938139 -299.871339) (xy 180.987314 -299.869358) (xy 181.036169 -299.87529)
			(xy 181.08344 -299.888982) (xy 181.127902 -299.91008) (xy 181.168405 -299.938036) (xy 181.203898 -299.972128)
			(xy 181.233463 -300.011472) (xy 181.256334 -300.055049) (xy 181.271918 -300.10173) (xy 181.279813 -300.150307)
			(xy 181.280308 -300.174914) (xy 181.619156 -300.174914) (xy 181.623116 -300.12586) (xy 181.634893 -300.078076)
			(xy 181.654184 -300.0328) (xy 181.680487 -299.991204) (xy 181.713122 -299.954367) (xy 181.751243 -299.923242)
			(xy 181.793864 -299.898635) (xy 181.83988 -299.881183) (xy 181.888099 -299.871339) (xy 181.937274 -299.869358)
			(xy 181.986129 -299.87529) (xy 182.0334 -299.888982) (xy 182.077862 -299.91008) (xy 182.118365 -299.938036)
			(xy 182.153858 -299.972128) (xy 182.183423 -300.011472) (xy 182.206294 -300.055049) (xy 182.221878 -300.10173)
			(xy 182.229773 -300.150307) (xy 182.230268 -300.174914) (xy 182.569116 -300.174914) (xy 182.573076 -300.12586)
			(xy 182.584853 -300.078076) (xy 182.604144 -300.0328) (xy 182.630447 -299.991204) (xy 182.663082 -299.954367)
			(xy 182.701203 -299.923242) (xy 182.743824 -299.898635) (xy 182.78984 -299.881183) (xy 182.838059 -299.871339)
			(xy 182.887234 -299.869358) (xy 182.936089 -299.87529) (xy 182.98336 -299.888982) (xy 183.027822 -299.91008)
			(xy 183.068325 -299.938036) (xy 183.103818 -299.972128) (xy 183.133383 -300.011472) (xy 183.156254 -300.055049)
			(xy 183.171838 -300.10173) (xy 183.179733 -300.150307) (xy 183.180228 -300.174914) (xy 183.519076 -300.174914)
			(xy 183.523036 -300.12586) (xy 183.534813 -300.078076) (xy 183.554104 -300.0328) (xy 183.580407 -299.991204)
			(xy 183.613042 -299.954367) (xy 183.651163 -299.923242) (xy 183.693784 -299.898635) (xy 183.7398 -299.881183)
			(xy 183.788019 -299.871339) (xy 183.837194 -299.869358) (xy 183.886049 -299.87529) (xy 183.93332 -299.888982)
			(xy 183.977782 -299.91008) (xy 184.018285 -299.938036) (xy 184.053778 -299.972128) (xy 184.083343 -300.011472)
			(xy 184.106214 -300.055049) (xy 184.121798 -300.10173) (xy 184.129693 -300.150307) (xy 184.130188 -300.174914)
			(xy 184.469036 -300.174914) (xy 184.472996 -300.12586) (xy 184.484773 -300.078076) (xy 184.504064 -300.0328)
			(xy 184.530367 -299.991204) (xy 184.563002 -299.954367) (xy 184.601123 -299.923242) (xy 184.643744 -299.898635)
			(xy 184.68976 -299.881183) (xy 184.737979 -299.871339) (xy 184.787154 -299.869358) (xy 184.836009 -299.87529)
			(xy 184.88328 -299.888982) (xy 184.927742 -299.91008) (xy 184.968245 -299.938036) (xy 185.003738 -299.972128)
			(xy 185.033303 -300.011472) (xy 185.056174 -300.055049) (xy 185.071758 -300.10173) (xy 185.079653 -300.150307)
			(xy 185.080148 -300.174914) (xy 185.079653 -300.199521) (xy 185.071758 -300.248098) (xy 185.056174 -300.294779)
			(xy 185.033303 -300.338356) (xy 185.003738 -300.3777) (xy 184.968245 -300.411792) (xy 184.927742 -300.439748)
			(xy 184.88328 -300.460846) (xy 184.836009 -300.474538) (xy 184.787154 -300.48047) (xy 184.737979 -300.478489)
			(xy 184.68976 -300.468645) (xy 184.643744 -300.451193) (xy 184.601123 -300.426586) (xy 184.563002 -300.395461)
			(xy 184.530367 -300.358624) (xy 184.504064 -300.317028) (xy 184.484773 -300.271752) (xy 184.472996 -300.223968)
			(xy 184.469036 -300.174914) (xy 184.130188 -300.174914) (xy 184.129693 -300.199521) (xy 184.121798 -300.248098)
			(xy 184.106214 -300.294779) (xy 184.083343 -300.338356) (xy 184.053778 -300.3777) (xy 184.018285 -300.411792)
			(xy 183.977782 -300.439748) (xy 183.93332 -300.460846) (xy 183.886049 -300.474538) (xy 183.837194 -300.48047)
			(xy 183.788019 -300.478489) (xy 183.7398 -300.468645) (xy 183.693784 -300.451193) (xy 183.651163 -300.426586)
			(xy 183.613042 -300.395461) (xy 183.580407 -300.358624) (xy 183.554104 -300.317028) (xy 183.534813 -300.271752)
			(xy 183.523036 -300.223968) (xy 183.519076 -300.174914) (xy 183.180228 -300.174914) (xy 183.179733 -300.199521)
			(xy 183.171838 -300.248098) (xy 183.156254 -300.294779) (xy 183.133383 -300.338356) (xy 183.103818 -300.3777)
			(xy 183.068325 -300.411792) (xy 183.027822 -300.439748) (xy 182.98336 -300.460846) (xy 182.936089 -300.474538)
			(xy 182.887234 -300.48047) (xy 182.838059 -300.478489) (xy 182.78984 -300.468645) (xy 182.743824 -300.451193)
			(xy 182.701203 -300.426586) (xy 182.663082 -300.395461) (xy 182.630447 -300.358624) (xy 182.604144 -300.317028)
			(xy 182.584853 -300.271752) (xy 182.573076 -300.223968) (xy 182.569116 -300.174914) (xy 182.230268 -300.174914)
			(xy 182.229773 -300.199521) (xy 182.221878 -300.248098) (xy 182.206294 -300.294779) (xy 182.183423 -300.338356)
			(xy 182.153858 -300.3777) (xy 182.118365 -300.411792) (xy 182.077862 -300.439748) (xy 182.0334 -300.460846)
			(xy 181.986129 -300.474538) (xy 181.937274 -300.48047) (xy 181.888099 -300.478489) (xy 181.83988 -300.468645)
			(xy 181.793864 -300.451193) (xy 181.751243 -300.426586) (xy 181.713122 -300.395461) (xy 181.680487 -300.358624)
			(xy 181.654184 -300.317028) (xy 181.634893 -300.271752) (xy 181.623116 -300.223968) (xy 181.619156 -300.174914)
			(xy 181.280308 -300.174914) (xy 181.279813 -300.199521) (xy 181.271918 -300.248098) (xy 181.256334 -300.294779)
			(xy 181.233463 -300.338356) (xy 181.203898 -300.3777) (xy 181.168405 -300.411792) (xy 181.127902 -300.439748)
			(xy 181.08344 -300.460846) (xy 181.036169 -300.474538) (xy 180.987314 -300.48047) (xy 180.938139 -300.478489)
			(xy 180.88992 -300.468645) (xy 180.843904 -300.451193) (xy 180.801283 -300.426586) (xy 180.763162 -300.395461)
			(xy 180.730527 -300.358624) (xy 180.704224 -300.317028) (xy 180.684933 -300.271752) (xy 180.673156 -300.223968)
			(xy 180.669196 -300.174914) (xy 180.330348 -300.174914) (xy 180.329853 -300.199521) (xy 180.321958 -300.248098)
			(xy 180.306374 -300.294779) (xy 180.283503 -300.338356) (xy 180.253938 -300.3777) (xy 180.218445 -300.411792)
			(xy 180.177942 -300.439748) (xy 180.13348 -300.460846) (xy 180.086209 -300.474538) (xy 180.037354 -300.48047)
			(xy 179.988179 -300.478489) (xy 179.93996 -300.468645) (xy 179.893944 -300.451193) (xy 179.851323 -300.426586)
			(xy 179.813202 -300.395461) (xy 179.780567 -300.358624) (xy 179.754264 -300.317028) (xy 179.734973 -300.271752)
			(xy 179.723196 -300.223968) (xy 179.719236 -300.174914) (xy 179.380388 -300.174914) (xy 179.379893 -300.199521)
			(xy 179.371998 -300.248098) (xy 179.356414 -300.294779) (xy 179.333543 -300.338356) (xy 179.303978 -300.3777)
			(xy 179.268485 -300.411792) (xy 179.227982 -300.439748) (xy 179.18352 -300.460846) (xy 179.136249 -300.474538)
			(xy 179.087394 -300.48047) (xy 179.038219 -300.478489) (xy 178.99 -300.468645) (xy 178.943984 -300.451193)
			(xy 178.901363 -300.426586) (xy 178.863242 -300.395461) (xy 178.830607 -300.358624) (xy 178.804304 -300.317028)
			(xy 178.785013 -300.271752) (xy 178.773236 -300.223968) (xy 178.769276 -300.174914) (xy 178.430174 -300.174914)
			(xy 178.429679 -300.199521) (xy 178.421784 -300.248098) (xy 178.4062 -300.294779) (xy 178.383329 -300.338356)
			(xy 178.353764 -300.3777) (xy 178.318271 -300.411792) (xy 178.277768 -300.439748) (xy 178.233306 -300.460846)
			(xy 178.186035 -300.474538) (xy 178.13718 -300.48047) (xy 178.088005 -300.478489) (xy 178.039786 -300.468645)
			(xy 177.99377 -300.451193) (xy 177.951149 -300.426586) (xy 177.913028 -300.395461) (xy 177.880393 -300.358624)
			(xy 177.85409 -300.317028) (xy 177.834799 -300.271752) (xy 177.823022 -300.223968) (xy 177.819062 -300.174914)
			(xy 177.480214 -300.174914) (xy 177.479719 -300.199521) (xy 177.471824 -300.248098) (xy 177.45624 -300.294779)
			(xy 177.433369 -300.338356) (xy 177.403804 -300.3777) (xy 177.368311 -300.411792) (xy 177.327808 -300.439748)
			(xy 177.283346 -300.460846) (xy 177.236075 -300.474538) (xy 177.18722 -300.48047) (xy 177.138045 -300.478489)
			(xy 177.089826 -300.468645) (xy 177.04381 -300.451193) (xy 177.001189 -300.426586) (xy 176.963068 -300.395461)
			(xy 176.930433 -300.358624) (xy 176.90413 -300.317028) (xy 176.884839 -300.271752) (xy 176.873062 -300.223968)
			(xy 176.869102 -300.174914) (xy 176.530254 -300.174914) (xy 176.529759 -300.199521) (xy 176.521864 -300.248098)
			(xy 176.50628 -300.294779) (xy 176.483409 -300.338356) (xy 176.453844 -300.3777) (xy 176.418351 -300.411792)
			(xy 176.377848 -300.439748) (xy 176.333386 -300.460846) (xy 176.286115 -300.474538) (xy 176.23726 -300.48047)
			(xy 176.188085 -300.478489) (xy 176.139866 -300.468645) (xy 176.09385 -300.451193) (xy 176.051229 -300.426586)
			(xy 176.013108 -300.395461) (xy 175.980473 -300.358624) (xy 175.95417 -300.317028) (xy 175.934879 -300.271752)
			(xy 175.923102 -300.223968) (xy 175.919142 -300.174914) (xy 174.630334 -300.174914) (xy 174.629839 -300.199521)
			(xy 174.621944 -300.248098) (xy 174.60636 -300.294779) (xy 174.583489 -300.338356) (xy 174.553924 -300.3777)
			(xy 174.518431 -300.411792) (xy 174.477928 -300.439748) (xy 174.433466 -300.460846) (xy 174.386195 -300.474538)
			(xy 174.33734 -300.48047) (xy 174.288165 -300.478489) (xy 174.239946 -300.468645) (xy 174.19393 -300.451193)
			(xy 174.151309 -300.426586) (xy 174.113188 -300.395461) (xy 174.080553 -300.358624) (xy 174.05425 -300.317028)
			(xy 174.034959 -300.271752) (xy 174.023182 -300.223968) (xy 174.019222 -300.174914) (xy 173.680374 -300.174914)
			(xy 173.679879 -300.199521) (xy 173.671984 -300.248098) (xy 173.6564 -300.294779) (xy 173.633529 -300.338356)
			(xy 173.603964 -300.3777) (xy 173.568471 -300.411792) (xy 173.527968 -300.439748) (xy 173.483506 -300.460846)
			(xy 173.436235 -300.474538) (xy 173.38738 -300.48047) (xy 173.338205 -300.478489) (xy 173.289986 -300.468645)
			(xy 173.24397 -300.451193) (xy 173.201349 -300.426586) (xy 173.163228 -300.395461) (xy 173.130593 -300.358624)
			(xy 173.10429 -300.317028) (xy 173.084999 -300.271752) (xy 173.073222 -300.223968) (xy 173.069262 -300.174914)
			(xy 172.73016 -300.174914) (xy 172.729665 -300.199521) (xy 172.72177 -300.248098) (xy 172.706186 -300.294779)
			(xy 172.683315 -300.338356) (xy 172.65375 -300.3777) (xy 172.618257 -300.411792) (xy 172.577754 -300.439748)
			(xy 172.533292 -300.460846) (xy 172.486021 -300.474538) (xy 172.437166 -300.48047) (xy 172.387991 -300.478489)
			(xy 172.339772 -300.468645) (xy 172.293756 -300.451193) (xy 172.251135 -300.426586) (xy 172.213014 -300.395461)
			(xy 172.180379 -300.358624) (xy 172.154076 -300.317028) (xy 172.134785 -300.271752) (xy 172.123008 -300.223968)
			(xy 172.119048 -300.174914) (xy 171.7802 -300.174914) (xy 171.779705 -300.199521) (xy 171.77181 -300.248098)
			(xy 171.756226 -300.294779) (xy 171.733355 -300.338356) (xy 171.70379 -300.3777) (xy 171.668297 -300.411792)
			(xy 171.627794 -300.439748) (xy 171.583332 -300.460846) (xy 171.536061 -300.474538) (xy 171.487206 -300.48047)
			(xy 171.438031 -300.478489) (xy 171.389812 -300.468645) (xy 171.343796 -300.451193) (xy 171.301175 -300.426586)
			(xy 171.263054 -300.395461) (xy 171.230419 -300.358624) (xy 171.204116 -300.317028) (xy 171.184825 -300.271752)
			(xy 171.173048 -300.223968) (xy 171.169088 -300.174914) (xy 170.83024 -300.174914) (xy 170.829745 -300.199521)
			(xy 170.82185 -300.248098) (xy 170.806266 -300.294779) (xy 170.783395 -300.338356) (xy 170.75383 -300.3777)
			(xy 170.718337 -300.411792) (xy 170.677834 -300.439748) (xy 170.633372 -300.460846) (xy 170.586101 -300.474538)
			(xy 170.537246 -300.48047) (xy 170.488071 -300.478489) (xy 170.439852 -300.468645) (xy 170.393836 -300.451193)
			(xy 170.351215 -300.426586) (xy 170.313094 -300.395461) (xy 170.280459 -300.358624) (xy 170.254156 -300.317028)
			(xy 170.234865 -300.271752) (xy 170.223088 -300.223968) (xy 170.219128 -300.174914) (xy 169.88028 -300.174914)
			(xy 169.879785 -300.199521) (xy 169.87189 -300.248098) (xy 169.856306 -300.294779) (xy 169.833435 -300.338356)
			(xy 169.80387 -300.3777) (xy 169.768377 -300.411792) (xy 169.727874 -300.439748) (xy 169.683412 -300.460846)
			(xy 169.636141 -300.474538) (xy 169.587286 -300.48047) (xy 169.538111 -300.478489) (xy 169.489892 -300.468645)
			(xy 169.443876 -300.451193) (xy 169.401255 -300.426586) (xy 169.363134 -300.395461) (xy 169.330499 -300.358624)
			(xy 169.304196 -300.317028) (xy 169.284905 -300.271752) (xy 169.273128 -300.223968) (xy 169.269168 -300.174914)
			(xy 168.93032 -300.174914) (xy 168.929825 -300.199521) (xy 168.92193 -300.248098) (xy 168.906346 -300.294779)
			(xy 168.883475 -300.338356) (xy 168.85391 -300.3777) (xy 168.818417 -300.411792) (xy 168.777914 -300.439748)
			(xy 168.733452 -300.460846) (xy 168.686181 -300.474538) (xy 168.637326 -300.48047) (xy 168.588151 -300.478489)
			(xy 168.539932 -300.468645) (xy 168.493916 -300.451193) (xy 168.451295 -300.426586) (xy 168.413174 -300.395461)
			(xy 168.380539 -300.358624) (xy 168.354236 -300.317028) (xy 168.334945 -300.271752) (xy 168.323168 -300.223968)
			(xy 168.319208 -300.174914) (xy 167.98036 -300.174914) (xy 167.979865 -300.199521) (xy 167.97197 -300.248098)
			(xy 167.956386 -300.294779) (xy 167.933515 -300.338356) (xy 167.90395 -300.3777) (xy 167.868457 -300.411792)
			(xy 167.827954 -300.439748) (xy 167.783492 -300.460846) (xy 167.736221 -300.474538) (xy 167.687366 -300.48047)
			(xy 167.638191 -300.478489) (xy 167.589972 -300.468645) (xy 167.543956 -300.451193) (xy 167.501335 -300.426586)
			(xy 167.463214 -300.395461) (xy 167.430579 -300.358624) (xy 167.404276 -300.317028) (xy 167.384985 -300.271752)
			(xy 167.373208 -300.223968) (xy 167.369248 -300.174914) (xy 167.0304 -300.174914) (xy 167.029905 -300.199521)
			(xy 167.02201 -300.248098) (xy 167.006426 -300.294779) (xy 166.983555 -300.338356) (xy 166.95399 -300.3777)
			(xy 166.918497 -300.411792) (xy 166.877994 -300.439748) (xy 166.833532 -300.460846) (xy 166.786261 -300.474538)
			(xy 166.737406 -300.48047) (xy 166.688231 -300.478489) (xy 166.640012 -300.468645) (xy 166.593996 -300.451193)
			(xy 166.551375 -300.426586) (xy 166.513254 -300.395461) (xy 166.480619 -300.358624) (xy 166.454316 -300.317028)
			(xy 166.435025 -300.271752) (xy 166.423248 -300.223968) (xy 166.419288 -300.174914) (xy 166.080773 -300.174914)
			(xy 166.076602 -300.225247) (xy 166.064199 -300.274222) (xy 166.043905 -300.320486) (xy 166.016272 -300.362779)
			(xy 165.982054 -300.399947) (xy 165.942186 -300.430975) (xy 165.897753 -300.455018) (xy 165.84997 -300.471419)
			(xy 165.800138 -300.479731) (xy 165.774878 -300.480222) (xy 165.750272 -300.479758) (xy 165.701695 -300.471867)
			(xy 165.655012 -300.456292) (xy 165.611429 -300.433436) (xy 165.572072 -300.40389) (xy 165.55466 -300.386496)
			(xy 165.547345 -300.379492) (xy 165.528826 -300.37134) (xy 165.508597 -300.370974) (xy 165.499034 -300.374304)
			(xy 165.411658 -300.40961) (xy 165.402463 -300.413766) (xy 165.388097 -300.427913) (xy 165.380329 -300.446518)
			(xy 165.379908 -300.4566) (xy 165.379908 -300.843188) (xy 165.38041 -300.853252) (xy 165.388194 -300.871818)
			(xy 165.402498 -300.885984) (xy 165.411658 -300.890178) (xy 165.499034 -300.925484) (xy 165.508594 -300.928832)
			(xy 165.528833 -300.928465) (xy 165.547365 -300.920321) (xy 165.55466 -300.913292) (xy 165.572073 -300.895902)
			(xy 165.611434 -300.866366) (xy 165.655018 -300.843518) (xy 165.7017 -300.827949) (xy 165.750273 -300.820061)
			(xy 165.774878 -300.819566) (xy 165.800135 -300.820109) (xy 165.84996 -300.82842) (xy 165.897737 -300.844819)
			(xy 165.942164 -300.868858) (xy 165.982027 -300.899883) (xy 166.01624 -300.937046) (xy 166.04387 -300.979333)
			(xy 166.064162 -301.025591) (xy 166.076562 -301.074559) (xy 166.080732 -301.124874) (xy 184.469036 -301.124874)
			(xy 184.472996 -301.07582) (xy 184.484773 -301.028036) (xy 184.504064 -300.98276) (xy 184.530367 -300.941164)
			(xy 184.563002 -300.904327) (xy 184.601123 -300.873202) (xy 184.643744 -300.848595) (xy 184.68976 -300.831143)
			(xy 184.737979 -300.821299) (xy 184.787154 -300.819318) (xy 184.836009 -300.82525) (xy 184.88328 -300.838942)
			(xy 184.927742 -300.86004) (xy 184.968245 -300.887996) (xy 185.003738 -300.922088) (xy 185.033303 -300.961432)
			(xy 185.056174 -301.005009) (xy 185.071758 -301.05169) (xy 185.079653 -301.100267) (xy 185.080148 -301.124874)
			(xy 185.079653 -301.149481) (xy 185.071758 -301.198058) (xy 185.056174 -301.244739) (xy 185.033303 -301.288316)
			(xy 185.003738 -301.32766) (xy 184.968245 -301.361752) (xy 184.927742 -301.389708) (xy 184.88328 -301.410806)
			(xy 184.836009 -301.424498) (xy 184.787154 -301.43043) (xy 184.737979 -301.428449) (xy 184.68976 -301.418605)
			(xy 184.643744 -301.401153) (xy 184.601123 -301.376546) (xy 184.563002 -301.345421) (xy 184.530367 -301.308584)
			(xy 184.504064 -301.266988) (xy 184.484773 -301.221712) (xy 184.472996 -301.173928) (xy 184.469036 -301.124874)
			(xy 166.080732 -301.124874) (xy 166.080734 -301.1249) (xy 166.076562 -301.175241) (xy 166.064162 -301.224209)
			(xy 166.04387 -301.270467) (xy 166.01624 -301.312754) (xy 165.982027 -301.349917) (xy 165.942164 -301.380942)
			(xy 165.897737 -301.404981) (xy 165.84996 -301.42138) (xy 165.800135 -301.429691) (xy 165.774878 -301.430182)
			(xy 165.750273 -301.4297) (xy 165.701698 -301.421811) (xy 165.655016 -301.406239) (xy 165.611432 -301.383387)
			(xy 165.572074 -301.353847) (xy 165.55466 -301.336456) (xy 165.547348 -301.329448) (xy 165.528827 -301.321302)
			(xy 165.508597 -301.320935) (xy 165.499034 -301.324264) (xy 165.411658 -301.35957) (xy 165.402479 -301.363755)
			(xy 165.388113 -301.37789) (xy 165.380336 -301.396483) (xy 165.379908 -301.40656) (xy 165.379908 -301.793148)
			(xy 165.380366 -301.803217) (xy 165.38817 -301.821784) (xy 165.402491 -301.835947) (xy 165.411658 -301.840138)
			(xy 165.499034 -301.875444) (xy 165.508592 -301.878803) (xy 165.528834 -301.878436) (xy 165.547367 -301.870286)
			(xy 165.55466 -301.863252) (xy 165.572084 -301.845873) (xy 165.61144 -301.816333) (xy 165.655021 -301.793482)
			(xy 165.701702 -301.777911) (xy 165.750274 -301.770021) (xy 165.774878 -301.769526) (xy 165.80014 -301.769949)
			(xy 165.849975 -301.778262) (xy 165.897761 -301.794664) (xy 165.942197 -301.818708) (xy 165.982068 -301.849739)
			(xy 166.016288 -301.886909) (xy 166.043922 -301.929204) (xy 166.064218 -301.975472) (xy 166.076622 -302.024449)
			(xy 166.080794 -302.0748) (xy 166.080791 -302.074834) (xy 166.419288 -302.074834) (xy 166.423248 -302.02578)
			(xy 166.435025 -301.977996) (xy 166.454316 -301.93272) (xy 166.480619 -301.891124) (xy 166.513254 -301.854287)
			(xy 166.551375 -301.823162) (xy 166.593996 -301.798555) (xy 166.640012 -301.781103) (xy 166.688231 -301.771259)
			(xy 166.737406 -301.769278) (xy 166.786261 -301.77521) (xy 166.833532 -301.788902) (xy 166.877994 -301.81)
			(xy 166.918497 -301.837956) (xy 166.95399 -301.872048) (xy 166.983555 -301.911392) (xy 167.006426 -301.954969)
			(xy 167.02201 -302.00165) (xy 167.029905 -302.050227) (xy 167.0304 -302.074834) (xy 167.369248 -302.074834)
			(xy 167.373208 -302.02578) (xy 167.384985 -301.977996) (xy 167.404276 -301.93272) (xy 167.430579 -301.891124)
			(xy 167.463214 -301.854287) (xy 167.501335 -301.823162) (xy 167.543956 -301.798555) (xy 167.589972 -301.781103)
			(xy 167.638191 -301.771259) (xy 167.687366 -301.769278) (xy 167.736221 -301.77521) (xy 167.783492 -301.788902)
			(xy 167.827954 -301.81) (xy 167.868457 -301.837956) (xy 167.90395 -301.872048) (xy 167.933515 -301.911392)
			(xy 167.956386 -301.954969) (xy 167.97197 -302.00165) (xy 167.979865 -302.050227) (xy 167.98036 -302.074834)
			(xy 168.319208 -302.074834) (xy 168.323168 -302.02578) (xy 168.334945 -301.977996) (xy 168.354236 -301.93272)
			(xy 168.380539 -301.891124) (xy 168.413174 -301.854287) (xy 168.451295 -301.823162) (xy 168.493916 -301.798555)
			(xy 168.539932 -301.781103) (xy 168.588151 -301.771259) (xy 168.637326 -301.769278) (xy 168.686181 -301.77521)
			(xy 168.733452 -301.788902) (xy 168.777914 -301.81) (xy 168.818417 -301.837956) (xy 168.85391 -301.872048)
			(xy 168.883475 -301.911392) (xy 168.906346 -301.954969) (xy 168.92193 -302.00165) (xy 168.929825 -302.050227)
			(xy 168.93032 -302.074834) (xy 169.269168 -302.074834) (xy 169.273128 -302.02578) (xy 169.284905 -301.977996)
			(xy 169.304196 -301.93272) (xy 169.330499 -301.891124) (xy 169.363134 -301.854287) (xy 169.401255 -301.823162)
			(xy 169.443876 -301.798555) (xy 169.489892 -301.781103) (xy 169.538111 -301.771259) (xy 169.587286 -301.769278)
			(xy 169.636141 -301.77521) (xy 169.683412 -301.788902) (xy 169.727874 -301.81) (xy 169.768377 -301.837956)
			(xy 169.80387 -301.872048) (xy 169.833435 -301.911392) (xy 169.856306 -301.954969) (xy 169.87189 -302.00165)
			(xy 169.879785 -302.050227) (xy 169.88028 -302.074834) (xy 170.219128 -302.074834) (xy 170.223088 -302.02578)
			(xy 170.234865 -301.977996) (xy 170.254156 -301.93272) (xy 170.280459 -301.891124) (xy 170.313094 -301.854287)
			(xy 170.351215 -301.823162) (xy 170.393836 -301.798555) (xy 170.439852 -301.781103) (xy 170.488071 -301.771259)
			(xy 170.537246 -301.769278) (xy 170.586101 -301.77521) (xy 170.633372 -301.788902) (xy 170.677834 -301.81)
			(xy 170.718337 -301.837956) (xy 170.75383 -301.872048) (xy 170.783395 -301.911392) (xy 170.806266 -301.954969)
			(xy 170.82185 -302.00165) (xy 170.829745 -302.050227) (xy 170.83024 -302.074834) (xy 171.169088 -302.074834)
			(xy 171.173048 -302.02578) (xy 171.184825 -301.977996) (xy 171.204116 -301.93272) (xy 171.230419 -301.891124)
			(xy 171.263054 -301.854287) (xy 171.301175 -301.823162) (xy 171.343796 -301.798555) (xy 171.389812 -301.781103)
			(xy 171.438031 -301.771259) (xy 171.487206 -301.769278) (xy 171.536061 -301.77521) (xy 171.583332 -301.788902)
			(xy 171.627794 -301.81) (xy 171.668297 -301.837956) (xy 171.70379 -301.872048) (xy 171.733355 -301.911392)
			(xy 171.756226 -301.954969) (xy 171.77181 -302.00165) (xy 171.779705 -302.050227) (xy 171.7802 -302.074834)
			(xy 172.119048 -302.074834) (xy 172.123008 -302.02578) (xy 172.134785 -301.977996) (xy 172.154076 -301.93272)
			(xy 172.180379 -301.891124) (xy 172.213014 -301.854287) (xy 172.251135 -301.823162) (xy 172.293756 -301.798555)
			(xy 172.339772 -301.781103) (xy 172.387991 -301.771259) (xy 172.437166 -301.769278) (xy 172.486021 -301.77521)
			(xy 172.533292 -301.788902) (xy 172.577754 -301.81) (xy 172.618257 -301.837956) (xy 172.65375 -301.872048)
			(xy 172.683315 -301.911392) (xy 172.706186 -301.954969) (xy 172.72177 -302.00165) (xy 172.729665 -302.050227)
			(xy 172.73016 -302.074834) (xy 173.069262 -302.074834) (xy 173.073222 -302.02578) (xy 173.084999 -301.977996)
			(xy 173.10429 -301.93272) (xy 173.130593 -301.891124) (xy 173.163228 -301.854287) (xy 173.201349 -301.823162)
			(xy 173.24397 -301.798555) (xy 173.289986 -301.781103) (xy 173.338205 -301.771259) (xy 173.38738 -301.769278)
			(xy 173.436235 -301.77521) (xy 173.483506 -301.788902) (xy 173.527968 -301.81) (xy 173.568471 -301.837956)
			(xy 173.603964 -301.872048) (xy 173.633529 -301.911392) (xy 173.6564 -301.954969) (xy 173.671984 -302.00165)
			(xy 173.679879 -302.050227) (xy 173.680374 -302.074834) (xy 174.019222 -302.074834) (xy 174.023182 -302.02578)
			(xy 174.034959 -301.977996) (xy 174.05425 -301.93272) (xy 174.080553 -301.891124) (xy 174.113188 -301.854287)
			(xy 174.151309 -301.823162) (xy 174.19393 -301.798555) (xy 174.239946 -301.781103) (xy 174.288165 -301.771259)
			(xy 174.33734 -301.769278) (xy 174.386195 -301.77521) (xy 174.433466 -301.788902) (xy 174.477928 -301.81)
			(xy 174.518431 -301.837956) (xy 174.553924 -301.872048) (xy 174.583489 -301.911392) (xy 174.60636 -301.954969)
			(xy 174.621944 -302.00165) (xy 174.629839 -302.050227) (xy 174.630334 -302.074834) (xy 175.919142 -302.074834)
			(xy 175.923102 -302.02578) (xy 175.934879 -301.977996) (xy 175.95417 -301.93272) (xy 175.980473 -301.891124)
			(xy 176.013108 -301.854287) (xy 176.051229 -301.823162) (xy 176.09385 -301.798555) (xy 176.139866 -301.781103)
			(xy 176.188085 -301.771259) (xy 176.23726 -301.769278) (xy 176.286115 -301.77521) (xy 176.333386 -301.788902)
			(xy 176.377848 -301.81) (xy 176.418351 -301.837956) (xy 176.453844 -301.872048) (xy 176.483409 -301.911392)
			(xy 176.50628 -301.954969) (xy 176.521864 -302.00165) (xy 176.529759 -302.050227) (xy 176.530254 -302.074834)
			(xy 176.869102 -302.074834) (xy 176.873062 -302.02578) (xy 176.884839 -301.977996) (xy 176.90413 -301.93272)
			(xy 176.930433 -301.891124) (xy 176.963068 -301.854287) (xy 177.001189 -301.823162) (xy 177.04381 -301.798555)
			(xy 177.089826 -301.781103) (xy 177.138045 -301.771259) (xy 177.18722 -301.769278) (xy 177.236075 -301.77521)
			(xy 177.283346 -301.788902) (xy 177.327808 -301.81) (xy 177.368311 -301.837956) (xy 177.403804 -301.872048)
			(xy 177.433369 -301.911392) (xy 177.45624 -301.954969) (xy 177.471824 -302.00165) (xy 177.479719 -302.050227)
			(xy 177.480214 -302.074834) (xy 177.819062 -302.074834) (xy 177.823022 -302.02578) (xy 177.834799 -301.977996)
			(xy 177.85409 -301.93272) (xy 177.880393 -301.891124) (xy 177.913028 -301.854287) (xy 177.951149 -301.823162)
			(xy 177.99377 -301.798555) (xy 178.039786 -301.781103) (xy 178.088005 -301.771259) (xy 178.13718 -301.769278)
			(xy 178.186035 -301.77521) (xy 178.233306 -301.788902) (xy 178.277768 -301.81) (xy 178.318271 -301.837956)
			(xy 178.353764 -301.872048) (xy 178.383329 -301.911392) (xy 178.4062 -301.954969) (xy 178.421784 -302.00165)
			(xy 178.429679 -302.050227) (xy 178.430174 -302.074834) (xy 178.769276 -302.074834) (xy 178.773236 -302.02578)
			(xy 178.785013 -301.977996) (xy 178.804304 -301.93272) (xy 178.830607 -301.891124) (xy 178.863242 -301.854287)
			(xy 178.901363 -301.823162) (xy 178.943984 -301.798555) (xy 178.99 -301.781103) (xy 179.038219 -301.771259)
			(xy 179.087394 -301.769278) (xy 179.136249 -301.77521) (xy 179.18352 -301.788902) (xy 179.227982 -301.81)
			(xy 179.268485 -301.837956) (xy 179.303978 -301.872048) (xy 179.333543 -301.911392) (xy 179.356414 -301.954969)
			(xy 179.371998 -302.00165) (xy 179.379893 -302.050227) (xy 179.380388 -302.074834) (xy 179.719236 -302.074834)
			(xy 179.723196 -302.02578) (xy 179.734973 -301.977996) (xy 179.754264 -301.93272) (xy 179.780567 -301.891124)
			(xy 179.813202 -301.854287) (xy 179.851323 -301.823162) (xy 179.893944 -301.798555) (xy 179.93996 -301.781103)
			(xy 179.988179 -301.771259) (xy 180.037354 -301.769278) (xy 180.086209 -301.77521) (xy 180.13348 -301.788902)
			(xy 180.177942 -301.81) (xy 180.218445 -301.837956) (xy 180.253938 -301.872048) (xy 180.283503 -301.911392)
			(xy 180.306374 -301.954969) (xy 180.321958 -302.00165) (xy 180.329853 -302.050227) (xy 180.330348 -302.074834)
			(xy 180.669196 -302.074834) (xy 180.673156 -302.02578) (xy 180.684933 -301.977996) (xy 180.704224 -301.93272)
			(xy 180.730527 -301.891124) (xy 180.763162 -301.854287) (xy 180.801283 -301.823162) (xy 180.843904 -301.798555)
			(xy 180.88992 -301.781103) (xy 180.938139 -301.771259) (xy 180.987314 -301.769278) (xy 181.036169 -301.77521)
			(xy 181.08344 -301.788902) (xy 181.127902 -301.81) (xy 181.168405 -301.837956) (xy 181.203898 -301.872048)
			(xy 181.233463 -301.911392) (xy 181.256334 -301.954969) (xy 181.271918 -302.00165) (xy 181.279813 -302.050227)
			(xy 181.280308 -302.074834) (xy 181.619156 -302.074834) (xy 181.623116 -302.02578) (xy 181.634893 -301.977996)
			(xy 181.654184 -301.93272) (xy 181.680487 -301.891124) (xy 181.713122 -301.854287) (xy 181.751243 -301.823162)
			(xy 181.793864 -301.798555) (xy 181.83988 -301.781103) (xy 181.888099 -301.771259) (xy 181.937274 -301.769278)
			(xy 181.986129 -301.77521) (xy 182.0334 -301.788902) (xy 182.077862 -301.81) (xy 182.118365 -301.837956)
			(xy 182.153858 -301.872048) (xy 182.183423 -301.911392) (xy 182.206294 -301.954969) (xy 182.221878 -302.00165)
			(xy 182.229773 -302.050227) (xy 182.230268 -302.074834) (xy 182.569116 -302.074834) (xy 182.573076 -302.02578)
			(xy 182.584853 -301.977996) (xy 182.604144 -301.93272) (xy 182.630447 -301.891124) (xy 182.663082 -301.854287)
			(xy 182.701203 -301.823162) (xy 182.743824 -301.798555) (xy 182.78984 -301.781103) (xy 182.838059 -301.771259)
			(xy 182.887234 -301.769278) (xy 182.936089 -301.77521) (xy 182.98336 -301.788902) (xy 183.027822 -301.81)
			(xy 183.068325 -301.837956) (xy 183.103818 -301.872048) (xy 183.133383 -301.911392) (xy 183.156254 -301.954969)
			(xy 183.171838 -302.00165) (xy 183.179733 -302.050227) (xy 183.180228 -302.074834) (xy 183.519076 -302.074834)
			(xy 183.523036 -302.02578) (xy 183.534813 -301.977996) (xy 183.554104 -301.93272) (xy 183.580407 -301.891124)
			(xy 183.613042 -301.854287) (xy 183.651163 -301.823162) (xy 183.693784 -301.798555) (xy 183.7398 -301.781103)
			(xy 183.788019 -301.771259) (xy 183.837194 -301.769278) (xy 183.886049 -301.77521) (xy 183.93332 -301.788902)
			(xy 183.977782 -301.81) (xy 184.018285 -301.837956) (xy 184.053778 -301.872048) (xy 184.083343 -301.911392)
			(xy 184.106214 -301.954969) (xy 184.121798 -302.00165) (xy 184.129693 -302.050227) (xy 184.130188 -302.074834)
			(xy 184.469036 -302.074834) (xy 184.472996 -302.02578) (xy 184.484773 -301.977996) (xy 184.504064 -301.93272)
			(xy 184.530367 -301.891124) (xy 184.563002 -301.854287) (xy 184.601123 -301.823162) (xy 184.643744 -301.798555)
			(xy 184.68976 -301.781103) (xy 184.737979 -301.771259) (xy 184.787154 -301.769278) (xy 184.836009 -301.77521)
			(xy 184.88328 -301.788902) (xy 184.927742 -301.81) (xy 184.968245 -301.837956) (xy 185.003738 -301.872048)
			(xy 185.033303 -301.911392) (xy 185.056174 -301.954969) (xy 185.071758 -302.00165) (xy 185.079653 -302.050227)
			(xy 185.080148 -302.074834) (xy 185.079653 -302.099441) (xy 185.071758 -302.148018) (xy 185.056174 -302.194699)
			(xy 185.033303 -302.238276) (xy 185.003738 -302.27762) (xy 184.968245 -302.311712) (xy 184.927742 -302.339668)
			(xy 184.88328 -302.360766) (xy 184.836009 -302.374458) (xy 184.787154 -302.38039) (xy 184.737979 -302.378409)
			(xy 184.68976 -302.368565) (xy 184.643744 -302.351113) (xy 184.601123 -302.326506) (xy 184.563002 -302.295381)
			(xy 184.530367 -302.258544) (xy 184.504064 -302.216948) (xy 184.484773 -302.171672) (xy 184.472996 -302.123888)
			(xy 184.469036 -302.074834) (xy 184.130188 -302.074834) (xy 184.129693 -302.099441) (xy 184.121798 -302.148018)
			(xy 184.106214 -302.194699) (xy 184.083343 -302.238276) (xy 184.053778 -302.27762) (xy 184.018285 -302.311712)
			(xy 183.977782 -302.339668) (xy 183.93332 -302.360766) (xy 183.886049 -302.374458) (xy 183.837194 -302.38039)
			(xy 183.788019 -302.378409) (xy 183.7398 -302.368565) (xy 183.693784 -302.351113) (xy 183.651163 -302.326506)
			(xy 183.613042 -302.295381) (xy 183.580407 -302.258544) (xy 183.554104 -302.216948) (xy 183.534813 -302.171672)
			(xy 183.523036 -302.123888) (xy 183.519076 -302.074834) (xy 183.180228 -302.074834) (xy 183.179733 -302.099441)
			(xy 183.171838 -302.148018) (xy 183.156254 -302.194699) (xy 183.133383 -302.238276) (xy 183.103818 -302.27762)
			(xy 183.068325 -302.311712) (xy 183.027822 -302.339668) (xy 182.98336 -302.360766) (xy 182.936089 -302.374458)
			(xy 182.887234 -302.38039) (xy 182.838059 -302.378409) (xy 182.78984 -302.368565) (xy 182.743824 -302.351113)
			(xy 182.701203 -302.326506) (xy 182.663082 -302.295381) (xy 182.630447 -302.258544) (xy 182.604144 -302.216948)
			(xy 182.584853 -302.171672) (xy 182.573076 -302.123888) (xy 182.569116 -302.074834) (xy 182.230268 -302.074834)
			(xy 182.229773 -302.099441) (xy 182.221878 -302.148018) (xy 182.206294 -302.194699) (xy 182.183423 -302.238276)
			(xy 182.153858 -302.27762) (xy 182.118365 -302.311712) (xy 182.077862 -302.339668) (xy 182.0334 -302.360766)
			(xy 181.986129 -302.374458) (xy 181.937274 -302.38039) (xy 181.888099 -302.378409) (xy 181.83988 -302.368565)
			(xy 181.793864 -302.351113) (xy 181.751243 -302.326506) (xy 181.713122 -302.295381) (xy 181.680487 -302.258544)
			(xy 181.654184 -302.216948) (xy 181.634893 -302.171672) (xy 181.623116 -302.123888) (xy 181.619156 -302.074834)
			(xy 181.280308 -302.074834) (xy 181.279813 -302.099441) (xy 181.271918 -302.148018) (xy 181.256334 -302.194699)
			(xy 181.233463 -302.238276) (xy 181.203898 -302.27762) (xy 181.168405 -302.311712) (xy 181.127902 -302.339668)
			(xy 181.08344 -302.360766) (xy 181.036169 -302.374458) (xy 180.987314 -302.38039) (xy 180.938139 -302.378409)
			(xy 180.88992 -302.368565) (xy 180.843904 -302.351113) (xy 180.801283 -302.326506) (xy 180.763162 -302.295381)
			(xy 180.730527 -302.258544) (xy 180.704224 -302.216948) (xy 180.684933 -302.171672) (xy 180.673156 -302.123888)
			(xy 180.669196 -302.074834) (xy 180.330348 -302.074834) (xy 180.329853 -302.099441) (xy 180.321958 -302.148018)
			(xy 180.306374 -302.194699) (xy 180.283503 -302.238276) (xy 180.253938 -302.27762) (xy 180.218445 -302.311712)
			(xy 180.177942 -302.339668) (xy 180.13348 -302.360766) (xy 180.086209 -302.374458) (xy 180.037354 -302.38039)
			(xy 179.988179 -302.378409) (xy 179.93996 -302.368565) (xy 179.893944 -302.351113) (xy 179.851323 -302.326506)
			(xy 179.813202 -302.295381) (xy 179.780567 -302.258544) (xy 179.754264 -302.216948) (xy 179.734973 -302.171672)
			(xy 179.723196 -302.123888) (xy 179.719236 -302.074834) (xy 179.380388 -302.074834) (xy 179.379893 -302.099441)
			(xy 179.371998 -302.148018) (xy 179.356414 -302.194699) (xy 179.333543 -302.238276) (xy 179.303978 -302.27762)
			(xy 179.268485 -302.311712) (xy 179.227982 -302.339668) (xy 179.18352 -302.360766) (xy 179.136249 -302.374458)
			(xy 179.087394 -302.38039) (xy 179.038219 -302.378409) (xy 178.99 -302.368565) (xy 178.943984 -302.351113)
			(xy 178.901363 -302.326506) (xy 178.863242 -302.295381) (xy 178.830607 -302.258544) (xy 178.804304 -302.216948)
			(xy 178.785013 -302.171672) (xy 178.773236 -302.123888) (xy 178.769276 -302.074834) (xy 178.430174 -302.074834)
			(xy 178.429679 -302.099441) (xy 178.421784 -302.148018) (xy 178.4062 -302.194699) (xy 178.383329 -302.238276)
			(xy 178.353764 -302.27762) (xy 178.318271 -302.311712) (xy 178.277768 -302.339668) (xy 178.233306 -302.360766)
			(xy 178.186035 -302.374458) (xy 178.13718 -302.38039) (xy 178.088005 -302.378409) (xy 178.039786 -302.368565)
			(xy 177.99377 -302.351113) (xy 177.951149 -302.326506) (xy 177.913028 -302.295381) (xy 177.880393 -302.258544)
			(xy 177.85409 -302.216948) (xy 177.834799 -302.171672) (xy 177.823022 -302.123888) (xy 177.819062 -302.074834)
			(xy 177.480214 -302.074834) (xy 177.479719 -302.099441) (xy 177.471824 -302.148018) (xy 177.45624 -302.194699)
			(xy 177.433369 -302.238276) (xy 177.403804 -302.27762) (xy 177.368311 -302.311712) (xy 177.327808 -302.339668)
			(xy 177.283346 -302.360766) (xy 177.236075 -302.374458) (xy 177.18722 -302.38039) (xy 177.138045 -302.378409)
			(xy 177.089826 -302.368565) (xy 177.04381 -302.351113) (xy 177.001189 -302.326506) (xy 176.963068 -302.295381)
			(xy 176.930433 -302.258544) (xy 176.90413 -302.216948) (xy 176.884839 -302.171672) (xy 176.873062 -302.123888)
			(xy 176.869102 -302.074834) (xy 176.530254 -302.074834) (xy 176.529759 -302.099441) (xy 176.521864 -302.148018)
			(xy 176.50628 -302.194699) (xy 176.483409 -302.238276) (xy 176.453844 -302.27762) (xy 176.418351 -302.311712)
			(xy 176.377848 -302.339668) (xy 176.333386 -302.360766) (xy 176.286115 -302.374458) (xy 176.23726 -302.38039)
			(xy 176.188085 -302.378409) (xy 176.139866 -302.368565) (xy 176.09385 -302.351113) (xy 176.051229 -302.326506)
			(xy 176.013108 -302.295381) (xy 175.980473 -302.258544) (xy 175.95417 -302.216948) (xy 175.934879 -302.171672)
			(xy 175.923102 -302.123888) (xy 175.919142 -302.074834) (xy 174.630334 -302.074834) (xy 174.629839 -302.099441)
			(xy 174.621944 -302.148018) (xy 174.60636 -302.194699) (xy 174.583489 -302.238276) (xy 174.553924 -302.27762)
			(xy 174.518431 -302.311712) (xy 174.477928 -302.339668) (xy 174.433466 -302.360766) (xy 174.386195 -302.374458)
			(xy 174.33734 -302.38039) (xy 174.288165 -302.378409) (xy 174.239946 -302.368565) (xy 174.19393 -302.351113)
			(xy 174.151309 -302.326506) (xy 174.113188 -302.295381) (xy 174.080553 -302.258544) (xy 174.05425 -302.216948)
			(xy 174.034959 -302.171672) (xy 174.023182 -302.123888) (xy 174.019222 -302.074834) (xy 173.680374 -302.074834)
			(xy 173.679879 -302.099441) (xy 173.671984 -302.148018) (xy 173.6564 -302.194699) (xy 173.633529 -302.238276)
			(xy 173.603964 -302.27762) (xy 173.568471 -302.311712) (xy 173.527968 -302.339668) (xy 173.483506 -302.360766)
			(xy 173.436235 -302.374458) (xy 173.38738 -302.38039) (xy 173.338205 -302.378409) (xy 173.289986 -302.368565)
			(xy 173.24397 -302.351113) (xy 173.201349 -302.326506) (xy 173.163228 -302.295381) (xy 173.130593 -302.258544)
			(xy 173.10429 -302.216948) (xy 173.084999 -302.171672) (xy 173.073222 -302.123888) (xy 173.069262 -302.074834)
			(xy 172.73016 -302.074834) (xy 172.729665 -302.099441) (xy 172.72177 -302.148018) (xy 172.706186 -302.194699)
			(xy 172.683315 -302.238276) (xy 172.65375 -302.27762) (xy 172.618257 -302.311712) (xy 172.577754 -302.339668)
			(xy 172.533292 -302.360766) (xy 172.486021 -302.374458) (xy 172.437166 -302.38039) (xy 172.387991 -302.378409)
			(xy 172.339772 -302.368565) (xy 172.293756 -302.351113) (xy 172.251135 -302.326506) (xy 172.213014 -302.295381)
			(xy 172.180379 -302.258544) (xy 172.154076 -302.216948) (xy 172.134785 -302.171672) (xy 172.123008 -302.123888)
			(xy 172.119048 -302.074834) (xy 171.7802 -302.074834) (xy 171.779705 -302.099441) (xy 171.77181 -302.148018)
			(xy 171.756226 -302.194699) (xy 171.733355 -302.238276) (xy 171.70379 -302.27762) (xy 171.668297 -302.311712)
			(xy 171.627794 -302.339668) (xy 171.583332 -302.360766) (xy 171.536061 -302.374458) (xy 171.487206 -302.38039)
			(xy 171.438031 -302.378409) (xy 171.389812 -302.368565) (xy 171.343796 -302.351113) (xy 171.301175 -302.326506)
			(xy 171.263054 -302.295381) (xy 171.230419 -302.258544) (xy 171.204116 -302.216948) (xy 171.184825 -302.171672)
			(xy 171.173048 -302.123888) (xy 171.169088 -302.074834) (xy 170.83024 -302.074834) (xy 170.829745 -302.099441)
			(xy 170.82185 -302.148018) (xy 170.806266 -302.194699) (xy 170.783395 -302.238276) (xy 170.75383 -302.27762)
			(xy 170.718337 -302.311712) (xy 170.677834 -302.339668) (xy 170.633372 -302.360766) (xy 170.586101 -302.374458)
			(xy 170.537246 -302.38039) (xy 170.488071 -302.378409) (xy 170.439852 -302.368565) (xy 170.393836 -302.351113)
			(xy 170.351215 -302.326506) (xy 170.313094 -302.295381) (xy 170.280459 -302.258544) (xy 170.254156 -302.216948)
			(xy 170.234865 -302.171672) (xy 170.223088 -302.123888) (xy 170.219128 -302.074834) (xy 169.88028 -302.074834)
			(xy 169.879785 -302.099441) (xy 169.87189 -302.148018) (xy 169.856306 -302.194699) (xy 169.833435 -302.238276)
			(xy 169.80387 -302.27762) (xy 169.768377 -302.311712) (xy 169.727874 -302.339668) (xy 169.683412 -302.360766)
			(xy 169.636141 -302.374458) (xy 169.587286 -302.38039) (xy 169.538111 -302.378409) (xy 169.489892 -302.368565)
			(xy 169.443876 -302.351113) (xy 169.401255 -302.326506) (xy 169.363134 -302.295381) (xy 169.330499 -302.258544)
			(xy 169.304196 -302.216948) (xy 169.284905 -302.171672) (xy 169.273128 -302.123888) (xy 169.269168 -302.074834)
			(xy 168.93032 -302.074834) (xy 168.929825 -302.099441) (xy 168.92193 -302.148018) (xy 168.906346 -302.194699)
			(xy 168.883475 -302.238276) (xy 168.85391 -302.27762) (xy 168.818417 -302.311712) (xy 168.777914 -302.339668)
			(xy 168.733452 -302.360766) (xy 168.686181 -302.374458) (xy 168.637326 -302.38039) (xy 168.588151 -302.378409)
			(xy 168.539932 -302.368565) (xy 168.493916 -302.351113) (xy 168.451295 -302.326506) (xy 168.413174 -302.295381)
			(xy 168.380539 -302.258544) (xy 168.354236 -302.216948) (xy 168.334945 -302.171672) (xy 168.323168 -302.123888)
			(xy 168.319208 -302.074834) (xy 167.98036 -302.074834) (xy 167.979865 -302.099441) (xy 167.97197 -302.148018)
			(xy 167.956386 -302.194699) (xy 167.933515 -302.238276) (xy 167.90395 -302.27762) (xy 167.868457 -302.311712)
			(xy 167.827954 -302.339668) (xy 167.783492 -302.360766) (xy 167.736221 -302.374458) (xy 167.687366 -302.38039)
			(xy 167.638191 -302.378409) (xy 167.589972 -302.368565) (xy 167.543956 -302.351113) (xy 167.501335 -302.326506)
			(xy 167.463214 -302.295381) (xy 167.430579 -302.258544) (xy 167.404276 -302.216948) (xy 167.384985 -302.171672)
			(xy 167.373208 -302.123888) (xy 167.369248 -302.074834) (xy 167.0304 -302.074834) (xy 167.029905 -302.099441)
			(xy 167.02201 -302.148018) (xy 167.006426 -302.194699) (xy 166.983555 -302.238276) (xy 166.95399 -302.27762)
			(xy 166.918497 -302.311712) (xy 166.877994 -302.339668) (xy 166.833532 -302.360766) (xy 166.786261 -302.374458)
			(xy 166.737406 -302.38039) (xy 166.688231 -302.378409) (xy 166.640012 -302.368565) (xy 166.593996 -302.351113)
			(xy 166.551375 -302.326506) (xy 166.513254 -302.295381) (xy 166.480619 -302.258544) (xy 166.454316 -302.216948)
			(xy 166.435025 -302.171672) (xy 166.423248 -302.123888) (xy 166.419288 -302.074834) (xy 166.080791 -302.074834)
			(xy 166.076622 -302.125151) (xy 166.064218 -302.174128) (xy 166.043922 -302.220396) (xy 166.016288 -302.262691)
			(xy 165.982068 -302.299861) (xy 165.942197 -302.330892) (xy 165.897761 -302.354936) (xy 165.849975 -302.371338)
			(xy 165.80014 -302.379651) (xy 165.774878 -302.380142) (xy 165.750272 -302.379672) (xy 165.701696 -302.371782)
			(xy 165.655013 -302.356208) (xy 165.61143 -302.333353) (xy 165.572073 -302.303809) (xy 165.55466 -302.286416)
			(xy 165.547352 -302.279405) (xy 165.528828 -302.271264) (xy 165.508598 -302.270897) (xy 165.499034 -302.274224)
			(xy 165.411658 -302.30953) (xy 165.402455 -302.313671) (xy 165.38809 -302.327824) (xy 165.380326 -302.346436)
			(xy 165.379908 -302.35652) (xy 165.379908 -302.743108) (xy 165.380395 -302.753174) (xy 165.388186 -302.77174)
			(xy 165.402495 -302.785905) (xy 165.411658 -302.790098) (xy 165.499034 -302.825404) (xy 165.50859 -302.828774)
			(xy 165.528835 -302.828408) (xy 165.547369 -302.820251) (xy 165.55466 -302.813212) (xy 165.572077 -302.795826)
			(xy 165.611436 -302.766288) (xy 165.655019 -302.74344) (xy 165.7017 -302.72787) (xy 165.750273 -302.719981)
			(xy 165.774878 -302.719486) (xy 165.800136 -302.719989) (xy 165.849965 -302.7283) (xy 165.897745 -302.744701)
			(xy 165.942175 -302.768742) (xy 165.982041 -302.799768) (xy 166.016256 -302.836933) (xy 166.043887 -302.879223)
			(xy 166.06418 -302.925485) (xy 166.076582 -302.974456) (xy 166.080754 -303.024794) (xy 166.419288 -303.024794)
			(xy 166.423248 -302.97574) (xy 166.435025 -302.927956) (xy 166.454316 -302.88268) (xy 166.480619 -302.841084)
			(xy 166.513254 -302.804247) (xy 166.551375 -302.773122) (xy 166.593996 -302.748515) (xy 166.640012 -302.731063)
			(xy 166.688231 -302.721219) (xy 166.737406 -302.719238) (xy 166.786261 -302.72517) (xy 166.833532 -302.738862)
			(xy 166.877994 -302.75996) (xy 166.918497 -302.787916) (xy 166.95399 -302.822008) (xy 166.983555 -302.861352)
			(xy 167.006426 -302.904929) (xy 167.02201 -302.95161) (xy 167.029905 -303.000187) (xy 167.0304 -303.024794)
			(xy 167.369248 -303.024794) (xy 167.373208 -302.97574) (xy 167.384985 -302.927956) (xy 167.404276 -302.88268)
			(xy 167.430579 -302.841084) (xy 167.463214 -302.804247) (xy 167.501335 -302.773122) (xy 167.543956 -302.748515)
			(xy 167.589972 -302.731063) (xy 167.638191 -302.721219) (xy 167.687366 -302.719238) (xy 167.736221 -302.72517)
			(xy 167.783492 -302.738862) (xy 167.827954 -302.75996) (xy 167.868457 -302.787916) (xy 167.90395 -302.822008)
			(xy 167.933515 -302.861352) (xy 167.956386 -302.904929) (xy 167.97197 -302.95161) (xy 167.979865 -303.000187)
			(xy 167.98036 -303.024794) (xy 168.319208 -303.024794) (xy 168.323168 -302.97574) (xy 168.334945 -302.927956)
			(xy 168.354236 -302.88268) (xy 168.380539 -302.841084) (xy 168.413174 -302.804247) (xy 168.451295 -302.773122)
			(xy 168.493916 -302.748515) (xy 168.539932 -302.731063) (xy 168.588151 -302.721219) (xy 168.637326 -302.719238)
			(xy 168.686181 -302.72517) (xy 168.733452 -302.738862) (xy 168.777914 -302.75996) (xy 168.818417 -302.787916)
			(xy 168.85391 -302.822008) (xy 168.883475 -302.861352) (xy 168.906346 -302.904929) (xy 168.92193 -302.95161)
			(xy 168.929825 -303.000187) (xy 168.93032 -303.024794) (xy 169.269168 -303.024794) (xy 169.273128 -302.97574)
			(xy 169.284905 -302.927956) (xy 169.304196 -302.88268) (xy 169.330499 -302.841084) (xy 169.363134 -302.804247)
			(xy 169.401255 -302.773122) (xy 169.443876 -302.748515) (xy 169.489892 -302.731063) (xy 169.538111 -302.721219)
			(xy 169.587286 -302.719238) (xy 169.636141 -302.72517) (xy 169.683412 -302.738862) (xy 169.727874 -302.75996)
			(xy 169.768377 -302.787916) (xy 169.80387 -302.822008) (xy 169.833435 -302.861352) (xy 169.856306 -302.904929)
			(xy 169.87189 -302.95161) (xy 169.879785 -303.000187) (xy 169.88028 -303.024794) (xy 170.219128 -303.024794)
			(xy 170.223088 -302.97574) (xy 170.234865 -302.927956) (xy 170.254156 -302.88268) (xy 170.280459 -302.841084)
			(xy 170.313094 -302.804247) (xy 170.351215 -302.773122) (xy 170.393836 -302.748515) (xy 170.439852 -302.731063)
			(xy 170.488071 -302.721219) (xy 170.537246 -302.719238) (xy 170.586101 -302.72517) (xy 170.633372 -302.738862)
			(xy 170.677834 -302.75996) (xy 170.718337 -302.787916) (xy 170.75383 -302.822008) (xy 170.783395 -302.861352)
			(xy 170.806266 -302.904929) (xy 170.82185 -302.95161) (xy 170.829745 -303.000187) (xy 170.83024 -303.024794)
			(xy 171.169088 -303.024794) (xy 171.173048 -302.97574) (xy 171.184825 -302.927956) (xy 171.204116 -302.88268)
			(xy 171.230419 -302.841084) (xy 171.263054 -302.804247) (xy 171.301175 -302.773122) (xy 171.343796 -302.748515)
			(xy 171.389812 -302.731063) (xy 171.438031 -302.721219) (xy 171.487206 -302.719238) (xy 171.536061 -302.72517)
			(xy 171.583332 -302.738862) (xy 171.627794 -302.75996) (xy 171.668297 -302.787916) (xy 171.70379 -302.822008)
			(xy 171.733355 -302.861352) (xy 171.756226 -302.904929) (xy 171.77181 -302.95161) (xy 171.779705 -303.000187)
			(xy 171.7802 -303.024794) (xy 172.119048 -303.024794) (xy 172.123008 -302.97574) (xy 172.134785 -302.927956)
			(xy 172.154076 -302.88268) (xy 172.180379 -302.841084) (xy 172.213014 -302.804247) (xy 172.251135 -302.773122)
			(xy 172.293756 -302.748515) (xy 172.339772 -302.731063) (xy 172.387991 -302.721219) (xy 172.437166 -302.719238)
			(xy 172.486021 -302.72517) (xy 172.533292 -302.738862) (xy 172.577754 -302.75996) (xy 172.618257 -302.787916)
			(xy 172.65375 -302.822008) (xy 172.683315 -302.861352) (xy 172.706186 -302.904929) (xy 172.72177 -302.95161)
			(xy 172.729665 -303.000187) (xy 172.73016 -303.024794) (xy 173.069262 -303.024794) (xy 173.073222 -302.97574)
			(xy 173.084999 -302.927956) (xy 173.10429 -302.88268) (xy 173.130593 -302.841084) (xy 173.163228 -302.804247)
			(xy 173.201349 -302.773122) (xy 173.24397 -302.748515) (xy 173.289986 -302.731063) (xy 173.338205 -302.721219)
			(xy 173.38738 -302.719238) (xy 173.436235 -302.72517) (xy 173.483506 -302.738862) (xy 173.527968 -302.75996)
			(xy 173.568471 -302.787916) (xy 173.603964 -302.822008) (xy 173.633529 -302.861352) (xy 173.6564 -302.904929)
			(xy 173.671984 -302.95161) (xy 173.679879 -303.000187) (xy 173.680374 -303.024794) (xy 174.019222 -303.024794)
			(xy 174.023182 -302.97574) (xy 174.034959 -302.927956) (xy 174.05425 -302.88268) (xy 174.080553 -302.841084)
			(xy 174.113188 -302.804247) (xy 174.151309 -302.773122) (xy 174.19393 -302.748515) (xy 174.239946 -302.731063)
			(xy 174.288165 -302.721219) (xy 174.33734 -302.719238) (xy 174.386195 -302.72517) (xy 174.433466 -302.738862)
			(xy 174.477928 -302.75996) (xy 174.518431 -302.787916) (xy 174.553924 -302.822008) (xy 174.583489 -302.861352)
			(xy 174.60636 -302.904929) (xy 174.621944 -302.95161) (xy 174.629839 -303.000187) (xy 174.630334 -303.024794)
			(xy 175.919142 -303.024794) (xy 175.923102 -302.97574) (xy 175.934879 -302.927956) (xy 175.95417 -302.88268)
			(xy 175.980473 -302.841084) (xy 176.013108 -302.804247) (xy 176.051229 -302.773122) (xy 176.09385 -302.748515)
			(xy 176.139866 -302.731063) (xy 176.188085 -302.721219) (xy 176.23726 -302.719238) (xy 176.286115 -302.72517)
			(xy 176.333386 -302.738862) (xy 176.377848 -302.75996) (xy 176.418351 -302.787916) (xy 176.453844 -302.822008)
			(xy 176.483409 -302.861352) (xy 176.50628 -302.904929) (xy 176.521864 -302.95161) (xy 176.529759 -303.000187)
			(xy 176.530254 -303.024794) (xy 176.869102 -303.024794) (xy 176.873062 -302.97574) (xy 176.884839 -302.927956)
			(xy 176.90413 -302.88268) (xy 176.930433 -302.841084) (xy 176.963068 -302.804247) (xy 177.001189 -302.773122)
			(xy 177.04381 -302.748515) (xy 177.089826 -302.731063) (xy 177.138045 -302.721219) (xy 177.18722 -302.719238)
			(xy 177.236075 -302.72517) (xy 177.283346 -302.738862) (xy 177.327808 -302.75996) (xy 177.368311 -302.787916)
			(xy 177.403804 -302.822008) (xy 177.433369 -302.861352) (xy 177.45624 -302.904929) (xy 177.471824 -302.95161)
			(xy 177.479719 -303.000187) (xy 177.480214 -303.024794) (xy 177.819062 -303.024794) (xy 177.823022 -302.97574)
			(xy 177.834799 -302.927956) (xy 177.85409 -302.88268) (xy 177.880393 -302.841084) (xy 177.913028 -302.804247)
			(xy 177.951149 -302.773122) (xy 177.99377 -302.748515) (xy 178.039786 -302.731063) (xy 178.088005 -302.721219)
			(xy 178.13718 -302.719238) (xy 178.186035 -302.72517) (xy 178.233306 -302.738862) (xy 178.277768 -302.75996)
			(xy 178.318271 -302.787916) (xy 178.353764 -302.822008) (xy 178.383329 -302.861352) (xy 178.4062 -302.904929)
			(xy 178.421784 -302.95161) (xy 178.429679 -303.000187) (xy 178.430174 -303.024794) (xy 178.769276 -303.024794)
			(xy 178.773236 -302.97574) (xy 178.785013 -302.927956) (xy 178.804304 -302.88268) (xy 178.830607 -302.841084)
			(xy 178.863242 -302.804247) (xy 178.901363 -302.773122) (xy 178.943984 -302.748515) (xy 178.99 -302.731063)
			(xy 179.038219 -302.721219) (xy 179.087394 -302.719238) (xy 179.136249 -302.72517) (xy 179.18352 -302.738862)
			(xy 179.227982 -302.75996) (xy 179.268485 -302.787916) (xy 179.303978 -302.822008) (xy 179.333543 -302.861352)
			(xy 179.356414 -302.904929) (xy 179.371998 -302.95161) (xy 179.379893 -303.000187) (xy 179.380388 -303.024794)
			(xy 179.719236 -303.024794) (xy 179.723196 -302.97574) (xy 179.734973 -302.927956) (xy 179.754264 -302.88268)
			(xy 179.780567 -302.841084) (xy 179.813202 -302.804247) (xy 179.851323 -302.773122) (xy 179.893944 -302.748515)
			(xy 179.93996 -302.731063) (xy 179.988179 -302.721219) (xy 180.037354 -302.719238) (xy 180.086209 -302.72517)
			(xy 180.13348 -302.738862) (xy 180.177942 -302.75996) (xy 180.218445 -302.787916) (xy 180.253938 -302.822008)
			(xy 180.283503 -302.861352) (xy 180.306374 -302.904929) (xy 180.321958 -302.95161) (xy 180.329853 -303.000187)
			(xy 180.330348 -303.024794) (xy 180.669196 -303.024794) (xy 180.673156 -302.97574) (xy 180.684933 -302.927956)
			(xy 180.704224 -302.88268) (xy 180.730527 -302.841084) (xy 180.763162 -302.804247) (xy 180.801283 -302.773122)
			(xy 180.843904 -302.748515) (xy 180.88992 -302.731063) (xy 180.938139 -302.721219) (xy 180.987314 -302.719238)
			(xy 181.036169 -302.72517) (xy 181.08344 -302.738862) (xy 181.127902 -302.75996) (xy 181.168405 -302.787916)
			(xy 181.203898 -302.822008) (xy 181.233463 -302.861352) (xy 181.256334 -302.904929) (xy 181.271918 -302.95161)
			(xy 181.279813 -303.000187) (xy 181.280308 -303.024794) (xy 181.619156 -303.024794) (xy 181.623116 -302.97574)
			(xy 181.634893 -302.927956) (xy 181.654184 -302.88268) (xy 181.680487 -302.841084) (xy 181.713122 -302.804247)
			(xy 181.751243 -302.773122) (xy 181.793864 -302.748515) (xy 181.83988 -302.731063) (xy 181.888099 -302.721219)
			(xy 181.937274 -302.719238) (xy 181.986129 -302.72517) (xy 182.0334 -302.738862) (xy 182.077862 -302.75996)
			(xy 182.118365 -302.787916) (xy 182.153858 -302.822008) (xy 182.183423 -302.861352) (xy 182.206294 -302.904929)
			(xy 182.221878 -302.95161) (xy 182.229773 -303.000187) (xy 182.230268 -303.024794) (xy 182.569116 -303.024794)
			(xy 182.573076 -302.97574) (xy 182.584853 -302.927956) (xy 182.604144 -302.88268) (xy 182.630447 -302.841084)
			(xy 182.663082 -302.804247) (xy 182.701203 -302.773122) (xy 182.743824 -302.748515) (xy 182.78984 -302.731063)
			(xy 182.838059 -302.721219) (xy 182.887234 -302.719238) (xy 182.936089 -302.72517) (xy 182.98336 -302.738862)
			(xy 183.027822 -302.75996) (xy 183.068325 -302.787916) (xy 183.103818 -302.822008) (xy 183.133383 -302.861352)
			(xy 183.156254 -302.904929) (xy 183.171838 -302.95161) (xy 183.179733 -303.000187) (xy 183.180228 -303.024794)
			(xy 183.519076 -303.024794) (xy 183.523036 -302.97574) (xy 183.534813 -302.927956) (xy 183.554104 -302.88268)
			(xy 183.580407 -302.841084) (xy 183.613042 -302.804247) (xy 183.651163 -302.773122) (xy 183.693784 -302.748515)
			(xy 183.7398 -302.731063) (xy 183.788019 -302.721219) (xy 183.837194 -302.719238) (xy 183.886049 -302.72517)
			(xy 183.93332 -302.738862) (xy 183.977782 -302.75996) (xy 184.018285 -302.787916) (xy 184.053778 -302.822008)
			(xy 184.083343 -302.861352) (xy 184.106214 -302.904929) (xy 184.121798 -302.95161) (xy 184.129693 -303.000187)
			(xy 184.130188 -303.024794) (xy 184.129693 -303.049401) (xy 184.121798 -303.097978) (xy 184.106214 -303.144659)
			(xy 184.083343 -303.188236) (xy 184.053778 -303.22758) (xy 184.018285 -303.261672) (xy 183.977782 -303.289628)
			(xy 183.93332 -303.310726) (xy 183.886049 -303.324418) (xy 183.837194 -303.33035) (xy 183.788019 -303.328369)
			(xy 183.7398 -303.318525) (xy 183.693784 -303.301073) (xy 183.651163 -303.276466) (xy 183.613042 -303.245341)
			(xy 183.580407 -303.208504) (xy 183.554104 -303.166908) (xy 183.534813 -303.121632) (xy 183.523036 -303.073848)
			(xy 183.519076 -303.024794) (xy 183.180228 -303.024794) (xy 183.179733 -303.049401) (xy 183.171838 -303.097978)
			(xy 183.156254 -303.144659) (xy 183.133383 -303.188236) (xy 183.103818 -303.22758) (xy 183.068325 -303.261672)
			(xy 183.027822 -303.289628) (xy 182.98336 -303.310726) (xy 182.936089 -303.324418) (xy 182.887234 -303.33035)
			(xy 182.838059 -303.328369) (xy 182.78984 -303.318525) (xy 182.743824 -303.301073) (xy 182.701203 -303.276466)
			(xy 182.663082 -303.245341) (xy 182.630447 -303.208504) (xy 182.604144 -303.166908) (xy 182.584853 -303.121632)
			(xy 182.573076 -303.073848) (xy 182.569116 -303.024794) (xy 182.230268 -303.024794) (xy 182.229773 -303.049401)
			(xy 182.221878 -303.097978) (xy 182.206294 -303.144659) (xy 182.183423 -303.188236) (xy 182.153858 -303.22758)
			(xy 182.118365 -303.261672) (xy 182.077862 -303.289628) (xy 182.0334 -303.310726) (xy 181.986129 -303.324418)
			(xy 181.937274 -303.33035) (xy 181.888099 -303.328369) (xy 181.83988 -303.318525) (xy 181.793864 -303.301073)
			(xy 181.751243 -303.276466) (xy 181.713122 -303.245341) (xy 181.680487 -303.208504) (xy 181.654184 -303.166908)
			(xy 181.634893 -303.121632) (xy 181.623116 -303.073848) (xy 181.619156 -303.024794) (xy 181.280308 -303.024794)
			(xy 181.279813 -303.049401) (xy 181.271918 -303.097978) (xy 181.256334 -303.144659) (xy 181.233463 -303.188236)
			(xy 181.203898 -303.22758) (xy 181.168405 -303.261672) (xy 181.127902 -303.289628) (xy 181.08344 -303.310726)
			(xy 181.036169 -303.324418) (xy 180.987314 -303.33035) (xy 180.938139 -303.328369) (xy 180.88992 -303.318525)
			(xy 180.843904 -303.301073) (xy 180.801283 -303.276466) (xy 180.763162 -303.245341) (xy 180.730527 -303.208504)
			(xy 180.704224 -303.166908) (xy 180.684933 -303.121632) (xy 180.673156 -303.073848) (xy 180.669196 -303.024794)
			(xy 180.330348 -303.024794) (xy 180.329853 -303.049401) (xy 180.321958 -303.097978) (xy 180.306374 -303.144659)
			(xy 180.283503 -303.188236) (xy 180.253938 -303.22758) (xy 180.218445 -303.261672) (xy 180.177942 -303.289628)
			(xy 180.13348 -303.310726) (xy 180.086209 -303.324418) (xy 180.037354 -303.33035) (xy 179.988179 -303.328369)
			(xy 179.93996 -303.318525) (xy 179.893944 -303.301073) (xy 179.851323 -303.276466) (xy 179.813202 -303.245341)
			(xy 179.780567 -303.208504) (xy 179.754264 -303.166908) (xy 179.734973 -303.121632) (xy 179.723196 -303.073848)
			(xy 179.719236 -303.024794) (xy 179.380388 -303.024794) (xy 179.379893 -303.049401) (xy 179.371998 -303.097978)
			(xy 179.356414 -303.144659) (xy 179.333543 -303.188236) (xy 179.303978 -303.22758) (xy 179.268485 -303.261672)
			(xy 179.227982 -303.289628) (xy 179.18352 -303.310726) (xy 179.136249 -303.324418) (xy 179.087394 -303.33035)
			(xy 179.038219 -303.328369) (xy 178.99 -303.318525) (xy 178.943984 -303.301073) (xy 178.901363 -303.276466)
			(xy 178.863242 -303.245341) (xy 178.830607 -303.208504) (xy 178.804304 -303.166908) (xy 178.785013 -303.121632)
			(xy 178.773236 -303.073848) (xy 178.769276 -303.024794) (xy 178.430174 -303.024794) (xy 178.429679 -303.049401)
			(xy 178.421784 -303.097978) (xy 178.4062 -303.144659) (xy 178.383329 -303.188236) (xy 178.353764 -303.22758)
			(xy 178.318271 -303.261672) (xy 178.277768 -303.289628) (xy 178.233306 -303.310726) (xy 178.186035 -303.324418)
			(xy 178.13718 -303.33035) (xy 178.088005 -303.328369) (xy 178.039786 -303.318525) (xy 177.99377 -303.301073)
			(xy 177.951149 -303.276466) (xy 177.913028 -303.245341) (xy 177.880393 -303.208504) (xy 177.85409 -303.166908)
			(xy 177.834799 -303.121632) (xy 177.823022 -303.073848) (xy 177.819062 -303.024794) (xy 177.480214 -303.024794)
			(xy 177.479719 -303.049401) (xy 177.471824 -303.097978) (xy 177.45624 -303.144659) (xy 177.433369 -303.188236)
			(xy 177.403804 -303.22758) (xy 177.368311 -303.261672) (xy 177.327808 -303.289628) (xy 177.283346 -303.310726)
			(xy 177.236075 -303.324418) (xy 177.18722 -303.33035) (xy 177.138045 -303.328369) (xy 177.089826 -303.318525)
			(xy 177.04381 -303.301073) (xy 177.001189 -303.276466) (xy 176.963068 -303.245341) (xy 176.930433 -303.208504)
			(xy 176.90413 -303.166908) (xy 176.884839 -303.121632) (xy 176.873062 -303.073848) (xy 176.869102 -303.024794)
			(xy 176.530254 -303.024794) (xy 176.529759 -303.049401) (xy 176.521864 -303.097978) (xy 176.50628 -303.144659)
			(xy 176.483409 -303.188236) (xy 176.453844 -303.22758) (xy 176.418351 -303.261672) (xy 176.377848 -303.289628)
			(xy 176.333386 -303.310726) (xy 176.286115 -303.324418) (xy 176.23726 -303.33035) (xy 176.188085 -303.328369)
			(xy 176.139866 -303.318525) (xy 176.09385 -303.301073) (xy 176.051229 -303.276466) (xy 176.013108 -303.245341)
			(xy 175.980473 -303.208504) (xy 175.95417 -303.166908) (xy 175.934879 -303.121632) (xy 175.923102 -303.073848)
			(xy 175.919142 -303.024794) (xy 174.630334 -303.024794) (xy 174.629839 -303.049401) (xy 174.621944 -303.097978)
			(xy 174.60636 -303.144659) (xy 174.583489 -303.188236) (xy 174.553924 -303.22758) (xy 174.518431 -303.261672)
			(xy 174.477928 -303.289628) (xy 174.433466 -303.310726) (xy 174.386195 -303.324418) (xy 174.33734 -303.33035)
			(xy 174.288165 -303.328369) (xy 174.239946 -303.318525) (xy 174.19393 -303.301073) (xy 174.151309 -303.276466)
			(xy 174.113188 -303.245341) (xy 174.080553 -303.208504) (xy 174.05425 -303.166908) (xy 174.034959 -303.121632)
			(xy 174.023182 -303.073848) (xy 174.019222 -303.024794) (xy 173.680374 -303.024794) (xy 173.679879 -303.049401)
			(xy 173.671984 -303.097978) (xy 173.6564 -303.144659) (xy 173.633529 -303.188236) (xy 173.603964 -303.22758)
			(xy 173.568471 -303.261672) (xy 173.527968 -303.289628) (xy 173.483506 -303.310726) (xy 173.436235 -303.324418)
			(xy 173.38738 -303.33035) (xy 173.338205 -303.328369) (xy 173.289986 -303.318525) (xy 173.24397 -303.301073)
			(xy 173.201349 -303.276466) (xy 173.163228 -303.245341) (xy 173.130593 -303.208504) (xy 173.10429 -303.166908)
			(xy 173.084999 -303.121632) (xy 173.073222 -303.073848) (xy 173.069262 -303.024794) (xy 172.73016 -303.024794)
			(xy 172.729665 -303.049401) (xy 172.72177 -303.097978) (xy 172.706186 -303.144659) (xy 172.683315 -303.188236)
			(xy 172.65375 -303.22758) (xy 172.618257 -303.261672) (xy 172.577754 -303.289628) (xy 172.533292 -303.310726)
			(xy 172.486021 -303.324418) (xy 172.437166 -303.33035) (xy 172.387991 -303.328369) (xy 172.339772 -303.318525)
			(xy 172.293756 -303.301073) (xy 172.251135 -303.276466) (xy 172.213014 -303.245341) (xy 172.180379 -303.208504)
			(xy 172.154076 -303.166908) (xy 172.134785 -303.121632) (xy 172.123008 -303.073848) (xy 172.119048 -303.024794)
			(xy 171.7802 -303.024794) (xy 171.779705 -303.049401) (xy 171.77181 -303.097978) (xy 171.756226 -303.144659)
			(xy 171.733355 -303.188236) (xy 171.70379 -303.22758) (xy 171.668297 -303.261672) (xy 171.627794 -303.289628)
			(xy 171.583332 -303.310726) (xy 171.536061 -303.324418) (xy 171.487206 -303.33035) (xy 171.438031 -303.328369)
			(xy 171.389812 -303.318525) (xy 171.343796 -303.301073) (xy 171.301175 -303.276466) (xy 171.263054 -303.245341)
			(xy 171.230419 -303.208504) (xy 171.204116 -303.166908) (xy 171.184825 -303.121632) (xy 171.173048 -303.073848)
			(xy 171.169088 -303.024794) (xy 170.83024 -303.024794) (xy 170.829745 -303.049401) (xy 170.82185 -303.097978)
			(xy 170.806266 -303.144659) (xy 170.783395 -303.188236) (xy 170.75383 -303.22758) (xy 170.718337 -303.261672)
			(xy 170.677834 -303.289628) (xy 170.633372 -303.310726) (xy 170.586101 -303.324418) (xy 170.537246 -303.33035)
			(xy 170.488071 -303.328369) (xy 170.439852 -303.318525) (xy 170.393836 -303.301073) (xy 170.351215 -303.276466)
			(xy 170.313094 -303.245341) (xy 170.280459 -303.208504) (xy 170.254156 -303.166908) (xy 170.234865 -303.121632)
			(xy 170.223088 -303.073848) (xy 170.219128 -303.024794) (xy 169.88028 -303.024794) (xy 169.879785 -303.049401)
			(xy 169.87189 -303.097978) (xy 169.856306 -303.144659) (xy 169.833435 -303.188236) (xy 169.80387 -303.22758)
			(xy 169.768377 -303.261672) (xy 169.727874 -303.289628) (xy 169.683412 -303.310726) (xy 169.636141 -303.324418)
			(xy 169.587286 -303.33035) (xy 169.538111 -303.328369) (xy 169.489892 -303.318525) (xy 169.443876 -303.301073)
			(xy 169.401255 -303.276466) (xy 169.363134 -303.245341) (xy 169.330499 -303.208504) (xy 169.304196 -303.166908)
			(xy 169.284905 -303.121632) (xy 169.273128 -303.073848) (xy 169.269168 -303.024794) (xy 168.93032 -303.024794)
			(xy 168.929825 -303.049401) (xy 168.92193 -303.097978) (xy 168.906346 -303.144659) (xy 168.883475 -303.188236)
			(xy 168.85391 -303.22758) (xy 168.818417 -303.261672) (xy 168.777914 -303.289628) (xy 168.733452 -303.310726)
			(xy 168.686181 -303.324418) (xy 168.637326 -303.33035) (xy 168.588151 -303.328369) (xy 168.539932 -303.318525)
			(xy 168.493916 -303.301073) (xy 168.451295 -303.276466) (xy 168.413174 -303.245341) (xy 168.380539 -303.208504)
			(xy 168.354236 -303.166908) (xy 168.334945 -303.121632) (xy 168.323168 -303.073848) (xy 168.319208 -303.024794)
			(xy 167.98036 -303.024794) (xy 167.979865 -303.049401) (xy 167.97197 -303.097978) (xy 167.956386 -303.144659)
			(xy 167.933515 -303.188236) (xy 167.90395 -303.22758) (xy 167.868457 -303.261672) (xy 167.827954 -303.289628)
			(xy 167.783492 -303.310726) (xy 167.736221 -303.324418) (xy 167.687366 -303.33035) (xy 167.638191 -303.328369)
			(xy 167.589972 -303.318525) (xy 167.543956 -303.301073) (xy 167.501335 -303.276466) (xy 167.463214 -303.245341)
			(xy 167.430579 -303.208504) (xy 167.404276 -303.166908) (xy 167.384985 -303.121632) (xy 167.373208 -303.073848)
			(xy 167.369248 -303.024794) (xy 167.0304 -303.024794) (xy 167.029905 -303.049401) (xy 167.02201 -303.097978)
			(xy 167.006426 -303.144659) (xy 166.983555 -303.188236) (xy 166.95399 -303.22758) (xy 166.918497 -303.261672)
			(xy 166.877994 -303.289628) (xy 166.833532 -303.310726) (xy 166.786261 -303.324418) (xy 166.737406 -303.33035)
			(xy 166.688231 -303.328369) (xy 166.640012 -303.318525) (xy 166.593996 -303.301073) (xy 166.551375 -303.276466)
			(xy 166.513254 -303.245341) (xy 166.480619 -303.208504) (xy 166.454316 -303.166908) (xy 166.435025 -303.121632)
			(xy 166.423248 -303.073848) (xy 166.419288 -303.024794) (xy 166.080754 -303.024794) (xy 166.080754 -303.0248)
			(xy 166.076582 -303.075144) (xy 166.06418 -303.124115) (xy 166.043887 -303.170377) (xy 166.016256 -303.212667)
			(xy 165.982041 -303.249832) (xy 165.942175 -303.280858) (xy 165.897745 -303.304899) (xy 165.849965 -303.3213)
			(xy 165.800136 -303.329611) (xy 165.774878 -303.330102) (xy 165.750271 -303.329644) (xy 165.701695 -303.321753)
			(xy 165.655011 -303.306176) (xy 165.611427 -303.283319) (xy 165.572071 -303.253771) (xy 165.55466 -303.236376)
			(xy 165.547346 -303.22937) (xy 165.528827 -303.221221) (xy 165.508597 -303.220855) (xy 165.499034 -303.224184)
			(xy 165.411658 -303.25949) (xy 165.402471 -303.26366) (xy 165.388105 -303.277801) (xy 165.380333 -303.2964)
			(xy 165.379908 -303.30648) (xy 165.379908 -303.693068) (xy 165.380351 -303.703138) (xy 165.388163 -303.721706)
			(xy 165.402489 -303.735868) (xy 165.411658 -303.740058) (xy 165.499034 -303.775364) (xy 165.508593 -303.778717)
			(xy 165.528834 -303.778351) (xy 165.547366 -303.770204) (xy 165.55466 -303.763172) (xy 165.572088 -303.745796)
			(xy 165.611442 -303.716255) (xy 165.655023 -303.693403) (xy 165.701702 -303.677831) (xy 165.750274 -303.669941)
			(xy 165.774878 -303.669446) (xy 165.800133 -303.670029) (xy 165.849955 -303.678339) (xy 165.897729 -303.694737)
			(xy 165.942153 -303.718775) (xy 165.982014 -303.749797) (xy 166.016225 -303.786958) (xy 166.043852 -303.829243)
			(xy 166.064143 -303.875498) (xy 166.076543 -303.924462) (xy 166.08071 -303.974754) (xy 166.419288 -303.974754)
			(xy 166.423248 -303.9257) (xy 166.435025 -303.877916) (xy 166.454316 -303.83264) (xy 166.480619 -303.791044)
			(xy 166.513254 -303.754207) (xy 166.551375 -303.723082) (xy 166.593996 -303.698475) (xy 166.640012 -303.681023)
			(xy 166.688231 -303.671179) (xy 166.737406 -303.669198) (xy 166.786261 -303.67513) (xy 166.833532 -303.688822)
			(xy 166.877994 -303.70992) (xy 166.918497 -303.737876) (xy 166.95399 -303.771968) (xy 166.983555 -303.811312)
			(xy 167.006426 -303.854889) (xy 167.02201 -303.90157) (xy 167.029905 -303.950147) (xy 167.0304 -303.974754)
			(xy 167.369248 -303.974754) (xy 167.373208 -303.9257) (xy 167.384985 -303.877916) (xy 167.404276 -303.83264)
			(xy 167.430579 -303.791044) (xy 167.463214 -303.754207) (xy 167.501335 -303.723082) (xy 167.543956 -303.698475)
			(xy 167.589972 -303.681023) (xy 167.638191 -303.671179) (xy 167.687366 -303.669198) (xy 167.736221 -303.67513)
			(xy 167.783492 -303.688822) (xy 167.827954 -303.70992) (xy 167.868457 -303.737876) (xy 167.90395 -303.771968)
			(xy 167.933515 -303.811312) (xy 167.956386 -303.854889) (xy 167.97197 -303.90157) (xy 167.979865 -303.950147)
			(xy 167.98036 -303.974754) (xy 168.319208 -303.974754) (xy 168.323168 -303.9257) (xy 168.334945 -303.877916)
			(xy 168.354236 -303.83264) (xy 168.380539 -303.791044) (xy 168.413174 -303.754207) (xy 168.451295 -303.723082)
			(xy 168.493916 -303.698475) (xy 168.539932 -303.681023) (xy 168.588151 -303.671179) (xy 168.637326 -303.669198)
			(xy 168.686181 -303.67513) (xy 168.733452 -303.688822) (xy 168.777914 -303.70992) (xy 168.818417 -303.737876)
			(xy 168.85391 -303.771968) (xy 168.883475 -303.811312) (xy 168.906346 -303.854889) (xy 168.92193 -303.90157)
			(xy 168.929825 -303.950147) (xy 168.93032 -303.974754) (xy 169.269168 -303.974754) (xy 169.273128 -303.9257)
			(xy 169.284905 -303.877916) (xy 169.304196 -303.83264) (xy 169.330499 -303.791044) (xy 169.363134 -303.754207)
			(xy 169.401255 -303.723082) (xy 169.443876 -303.698475) (xy 169.489892 -303.681023) (xy 169.538111 -303.671179)
			(xy 169.587286 -303.669198) (xy 169.636141 -303.67513) (xy 169.683412 -303.688822) (xy 169.727874 -303.70992)
			(xy 169.768377 -303.737876) (xy 169.80387 -303.771968) (xy 169.833435 -303.811312) (xy 169.856306 -303.854889)
			(xy 169.87189 -303.90157) (xy 169.879785 -303.950147) (xy 169.88028 -303.974754) (xy 170.219128 -303.974754)
			(xy 170.223088 -303.9257) (xy 170.234865 -303.877916) (xy 170.254156 -303.83264) (xy 170.280459 -303.791044)
			(xy 170.313094 -303.754207) (xy 170.351215 -303.723082) (xy 170.393836 -303.698475) (xy 170.439852 -303.681023)
			(xy 170.488071 -303.671179) (xy 170.537246 -303.669198) (xy 170.586101 -303.67513) (xy 170.633372 -303.688822)
			(xy 170.677834 -303.70992) (xy 170.718337 -303.737876) (xy 170.75383 -303.771968) (xy 170.783395 -303.811312)
			(xy 170.806266 -303.854889) (xy 170.82185 -303.90157) (xy 170.829745 -303.950147) (xy 170.83024 -303.974754)
			(xy 171.169088 -303.974754) (xy 171.173048 -303.9257) (xy 171.184825 -303.877916) (xy 171.204116 -303.83264)
			(xy 171.230419 -303.791044) (xy 171.263054 -303.754207) (xy 171.301175 -303.723082) (xy 171.343796 -303.698475)
			(xy 171.389812 -303.681023) (xy 171.438031 -303.671179) (xy 171.487206 -303.669198) (xy 171.536061 -303.67513)
			(xy 171.583332 -303.688822) (xy 171.627794 -303.70992) (xy 171.668297 -303.737876) (xy 171.70379 -303.771968)
			(xy 171.733355 -303.811312) (xy 171.756226 -303.854889) (xy 171.77181 -303.90157) (xy 171.779705 -303.950147)
			(xy 171.7802 -303.974754) (xy 172.119048 -303.974754) (xy 172.123008 -303.9257) (xy 172.134785 -303.877916)
			(xy 172.154076 -303.83264) (xy 172.180379 -303.791044) (xy 172.213014 -303.754207) (xy 172.251135 -303.723082)
			(xy 172.293756 -303.698475) (xy 172.339772 -303.681023) (xy 172.387991 -303.671179) (xy 172.437166 -303.669198)
			(xy 172.486021 -303.67513) (xy 172.533292 -303.688822) (xy 172.577754 -303.70992) (xy 172.618257 -303.737876)
			(xy 172.65375 -303.771968) (xy 172.683315 -303.811312) (xy 172.706186 -303.854889) (xy 172.72177 -303.90157)
			(xy 172.729665 -303.950147) (xy 172.73016 -303.974754) (xy 173.069262 -303.974754) (xy 173.073222 -303.9257)
			(xy 173.084999 -303.877916) (xy 173.10429 -303.83264) (xy 173.130593 -303.791044) (xy 173.163228 -303.754207)
			(xy 173.201349 -303.723082) (xy 173.24397 -303.698475) (xy 173.289986 -303.681023) (xy 173.338205 -303.671179)
			(xy 173.38738 -303.669198) (xy 173.436235 -303.67513) (xy 173.483506 -303.688822) (xy 173.527968 -303.70992)
			(xy 173.568471 -303.737876) (xy 173.603964 -303.771968) (xy 173.633529 -303.811312) (xy 173.6564 -303.854889)
			(xy 173.671984 -303.90157) (xy 173.679879 -303.950147) (xy 173.680374 -303.974754) (xy 174.019222 -303.974754)
			(xy 174.023182 -303.9257) (xy 174.034959 -303.877916) (xy 174.05425 -303.83264) (xy 174.080553 -303.791044)
			(xy 174.113188 -303.754207) (xy 174.151309 -303.723082) (xy 174.19393 -303.698475) (xy 174.239946 -303.681023)
			(xy 174.288165 -303.671179) (xy 174.33734 -303.669198) (xy 174.386195 -303.67513) (xy 174.433466 -303.688822)
			(xy 174.477928 -303.70992) (xy 174.518431 -303.737876) (xy 174.553924 -303.771968) (xy 174.583489 -303.811312)
			(xy 174.60636 -303.854889) (xy 174.621944 -303.90157) (xy 174.629839 -303.950147) (xy 174.630334 -303.974754)
			(xy 175.919142 -303.974754) (xy 175.923102 -303.9257) (xy 175.934879 -303.877916) (xy 175.95417 -303.83264)
			(xy 175.980473 -303.791044) (xy 176.013108 -303.754207) (xy 176.051229 -303.723082) (xy 176.09385 -303.698475)
			(xy 176.139866 -303.681023) (xy 176.188085 -303.671179) (xy 176.23726 -303.669198) (xy 176.286115 -303.67513)
			(xy 176.333386 -303.688822) (xy 176.377848 -303.70992) (xy 176.418351 -303.737876) (xy 176.453844 -303.771968)
			(xy 176.483409 -303.811312) (xy 176.50628 -303.854889) (xy 176.521864 -303.90157) (xy 176.529759 -303.950147)
			(xy 176.530254 -303.974754) (xy 176.869102 -303.974754) (xy 176.873062 -303.9257) (xy 176.884839 -303.877916)
			(xy 176.90413 -303.83264) (xy 176.930433 -303.791044) (xy 176.963068 -303.754207) (xy 177.001189 -303.723082)
			(xy 177.04381 -303.698475) (xy 177.089826 -303.681023) (xy 177.138045 -303.671179) (xy 177.18722 -303.669198)
			(xy 177.236075 -303.67513) (xy 177.283346 -303.688822) (xy 177.327808 -303.70992) (xy 177.368311 -303.737876)
			(xy 177.403804 -303.771968) (xy 177.433369 -303.811312) (xy 177.45624 -303.854889) (xy 177.471824 -303.90157)
			(xy 177.479719 -303.950147) (xy 177.480214 -303.974754) (xy 177.819062 -303.974754) (xy 177.823022 -303.9257)
			(xy 177.834799 -303.877916) (xy 177.85409 -303.83264) (xy 177.880393 -303.791044) (xy 177.913028 -303.754207)
			(xy 177.951149 -303.723082) (xy 177.99377 -303.698475) (xy 178.039786 -303.681023) (xy 178.088005 -303.671179)
			(xy 178.13718 -303.669198) (xy 178.186035 -303.67513) (xy 178.233306 -303.688822) (xy 178.277768 -303.70992)
			(xy 178.318271 -303.737876) (xy 178.353764 -303.771968) (xy 178.383329 -303.811312) (xy 178.4062 -303.854889)
			(xy 178.421784 -303.90157) (xy 178.429679 -303.950147) (xy 178.430174 -303.974754) (xy 178.769276 -303.974754)
			(xy 178.773236 -303.9257) (xy 178.785013 -303.877916) (xy 178.804304 -303.83264) (xy 178.830607 -303.791044)
			(xy 178.863242 -303.754207) (xy 178.901363 -303.723082) (xy 178.943984 -303.698475) (xy 178.99 -303.681023)
			(xy 179.038219 -303.671179) (xy 179.087394 -303.669198) (xy 179.136249 -303.67513) (xy 179.18352 -303.688822)
			(xy 179.227982 -303.70992) (xy 179.268485 -303.737876) (xy 179.303978 -303.771968) (xy 179.333543 -303.811312)
			(xy 179.356414 -303.854889) (xy 179.371998 -303.90157) (xy 179.379893 -303.950147) (xy 179.380388 -303.974754)
			(xy 179.719236 -303.974754) (xy 179.723196 -303.9257) (xy 179.734973 -303.877916) (xy 179.754264 -303.83264)
			(xy 179.780567 -303.791044) (xy 179.813202 -303.754207) (xy 179.851323 -303.723082) (xy 179.893944 -303.698475)
			(xy 179.93996 -303.681023) (xy 179.988179 -303.671179) (xy 180.037354 -303.669198) (xy 180.086209 -303.67513)
			(xy 180.13348 -303.688822) (xy 180.177942 -303.70992) (xy 180.218445 -303.737876) (xy 180.253938 -303.771968)
			(xy 180.283503 -303.811312) (xy 180.306374 -303.854889) (xy 180.321958 -303.90157) (xy 180.329853 -303.950147)
			(xy 180.330348 -303.974754) (xy 180.669196 -303.974754) (xy 180.673156 -303.9257) (xy 180.684933 -303.877916)
			(xy 180.704224 -303.83264) (xy 180.730527 -303.791044) (xy 180.763162 -303.754207) (xy 180.801283 -303.723082)
			(xy 180.843904 -303.698475) (xy 180.88992 -303.681023) (xy 180.938139 -303.671179) (xy 180.987314 -303.669198)
			(xy 181.036169 -303.67513) (xy 181.08344 -303.688822) (xy 181.127902 -303.70992) (xy 181.168405 -303.737876)
			(xy 181.203898 -303.771968) (xy 181.233463 -303.811312) (xy 181.256334 -303.854889) (xy 181.271918 -303.90157)
			(xy 181.279813 -303.950147) (xy 181.280308 -303.974754) (xy 181.619156 -303.974754) (xy 181.623116 -303.9257)
			(xy 181.634893 -303.877916) (xy 181.654184 -303.83264) (xy 181.680487 -303.791044) (xy 181.713122 -303.754207)
			(xy 181.751243 -303.723082) (xy 181.793864 -303.698475) (xy 181.83988 -303.681023) (xy 181.888099 -303.671179)
			(xy 181.937274 -303.669198) (xy 181.986129 -303.67513) (xy 182.0334 -303.688822) (xy 182.077862 -303.70992)
			(xy 182.118365 -303.737876) (xy 182.153858 -303.771968) (xy 182.183423 -303.811312) (xy 182.206294 -303.854889)
			(xy 182.221878 -303.90157) (xy 182.229773 -303.950147) (xy 182.230268 -303.974754) (xy 182.569116 -303.974754)
			(xy 182.573076 -303.9257) (xy 182.584853 -303.877916) (xy 182.604144 -303.83264) (xy 182.630447 -303.791044)
			(xy 182.663082 -303.754207) (xy 182.701203 -303.723082) (xy 182.743824 -303.698475) (xy 182.78984 -303.681023)
			(xy 182.838059 -303.671179) (xy 182.887234 -303.669198) (xy 182.936089 -303.67513) (xy 182.98336 -303.688822)
			(xy 183.027822 -303.70992) (xy 183.068325 -303.737876) (xy 183.103818 -303.771968) (xy 183.133383 -303.811312)
			(xy 183.156254 -303.854889) (xy 183.171838 -303.90157) (xy 183.179733 -303.950147) (xy 183.180228 -303.974754)
			(xy 183.519076 -303.974754) (xy 183.523036 -303.9257) (xy 183.534813 -303.877916) (xy 183.554104 -303.83264)
			(xy 183.580407 -303.791044) (xy 183.613042 -303.754207) (xy 183.651163 -303.723082) (xy 183.693784 -303.698475)
			(xy 183.7398 -303.681023) (xy 183.788019 -303.671179) (xy 183.837194 -303.669198) (xy 183.886049 -303.67513)
			(xy 183.93332 -303.688822) (xy 183.977782 -303.70992) (xy 184.018285 -303.737876) (xy 184.053778 -303.771968)
			(xy 184.083343 -303.811312) (xy 184.106214 -303.854889) (xy 184.121798 -303.90157) (xy 184.129693 -303.950147)
			(xy 184.130188 -303.974754) (xy 184.129693 -303.999361) (xy 184.121798 -304.047938) (xy 184.106214 -304.094619)
			(xy 184.083343 -304.138196) (xy 184.053778 -304.17754) (xy 184.018285 -304.211632) (xy 183.977782 -304.239588)
			(xy 183.93332 -304.260686) (xy 183.886049 -304.274378) (xy 183.837194 -304.28031) (xy 183.788019 -304.278329)
			(xy 183.7398 -304.268485) (xy 183.693784 -304.251033) (xy 183.651163 -304.226426) (xy 183.613042 -304.195301)
			(xy 183.580407 -304.158464) (xy 183.554104 -304.116868) (xy 183.534813 -304.071592) (xy 183.523036 -304.023808)
			(xy 183.519076 -303.974754) (xy 183.180228 -303.974754) (xy 183.179733 -303.999361) (xy 183.171838 -304.047938)
			(xy 183.156254 -304.094619) (xy 183.133383 -304.138196) (xy 183.103818 -304.17754) (xy 183.068325 -304.211632)
			(xy 183.027822 -304.239588) (xy 182.98336 -304.260686) (xy 182.936089 -304.274378) (xy 182.887234 -304.28031)
			(xy 182.838059 -304.278329) (xy 182.78984 -304.268485) (xy 182.743824 -304.251033) (xy 182.701203 -304.226426)
			(xy 182.663082 -304.195301) (xy 182.630447 -304.158464) (xy 182.604144 -304.116868) (xy 182.584853 -304.071592)
			(xy 182.573076 -304.023808) (xy 182.569116 -303.974754) (xy 182.230268 -303.974754) (xy 182.229773 -303.999361)
			(xy 182.221878 -304.047938) (xy 182.206294 -304.094619) (xy 182.183423 -304.138196) (xy 182.153858 -304.17754)
			(xy 182.118365 -304.211632) (xy 182.077862 -304.239588) (xy 182.0334 -304.260686) (xy 181.986129 -304.274378)
			(xy 181.937274 -304.28031) (xy 181.888099 -304.278329) (xy 181.83988 -304.268485) (xy 181.793864 -304.251033)
			(xy 181.751243 -304.226426) (xy 181.713122 -304.195301) (xy 181.680487 -304.158464) (xy 181.654184 -304.116868)
			(xy 181.634893 -304.071592) (xy 181.623116 -304.023808) (xy 181.619156 -303.974754) (xy 181.280308 -303.974754)
			(xy 181.279813 -303.999361) (xy 181.271918 -304.047938) (xy 181.256334 -304.094619) (xy 181.233463 -304.138196)
			(xy 181.203898 -304.17754) (xy 181.168405 -304.211632) (xy 181.127902 -304.239588) (xy 181.08344 -304.260686)
			(xy 181.036169 -304.274378) (xy 180.987314 -304.28031) (xy 180.938139 -304.278329) (xy 180.88992 -304.268485)
			(xy 180.843904 -304.251033) (xy 180.801283 -304.226426) (xy 180.763162 -304.195301) (xy 180.730527 -304.158464)
			(xy 180.704224 -304.116868) (xy 180.684933 -304.071592) (xy 180.673156 -304.023808) (xy 180.669196 -303.974754)
			(xy 180.330348 -303.974754) (xy 180.329853 -303.999361) (xy 180.321958 -304.047938) (xy 180.306374 -304.094619)
			(xy 180.283503 -304.138196) (xy 180.253938 -304.17754) (xy 180.218445 -304.211632) (xy 180.177942 -304.239588)
			(xy 180.13348 -304.260686) (xy 180.086209 -304.274378) (xy 180.037354 -304.28031) (xy 179.988179 -304.278329)
			(xy 179.93996 -304.268485) (xy 179.893944 -304.251033) (xy 179.851323 -304.226426) (xy 179.813202 -304.195301)
			(xy 179.780567 -304.158464) (xy 179.754264 -304.116868) (xy 179.734973 -304.071592) (xy 179.723196 -304.023808)
			(xy 179.719236 -303.974754) (xy 179.380388 -303.974754) (xy 179.379893 -303.999361) (xy 179.371998 -304.047938)
			(xy 179.356414 -304.094619) (xy 179.333543 -304.138196) (xy 179.303978 -304.17754) (xy 179.268485 -304.211632)
			(xy 179.227982 -304.239588) (xy 179.18352 -304.260686) (xy 179.136249 -304.274378) (xy 179.087394 -304.28031)
			(xy 179.038219 -304.278329) (xy 178.99 -304.268485) (xy 178.943984 -304.251033) (xy 178.901363 -304.226426)
			(xy 178.863242 -304.195301) (xy 178.830607 -304.158464) (xy 178.804304 -304.116868) (xy 178.785013 -304.071592)
			(xy 178.773236 -304.023808) (xy 178.769276 -303.974754) (xy 178.430174 -303.974754) (xy 178.429679 -303.999361)
			(xy 178.421784 -304.047938) (xy 178.4062 -304.094619) (xy 178.383329 -304.138196) (xy 178.353764 -304.17754)
			(xy 178.318271 -304.211632) (xy 178.277768 -304.239588) (xy 178.233306 -304.260686) (xy 178.186035 -304.274378)
			(xy 178.13718 -304.28031) (xy 178.088005 -304.278329) (xy 178.039786 -304.268485) (xy 177.99377 -304.251033)
			(xy 177.951149 -304.226426) (xy 177.913028 -304.195301) (xy 177.880393 -304.158464) (xy 177.85409 -304.116868)
			(xy 177.834799 -304.071592) (xy 177.823022 -304.023808) (xy 177.819062 -303.974754) (xy 177.480214 -303.974754)
			(xy 177.479719 -303.999361) (xy 177.471824 -304.047938) (xy 177.45624 -304.094619) (xy 177.433369 -304.138196)
			(xy 177.403804 -304.17754) (xy 177.368311 -304.211632) (xy 177.327808 -304.239588) (xy 177.283346 -304.260686)
			(xy 177.236075 -304.274378) (xy 177.18722 -304.28031) (xy 177.138045 -304.278329) (xy 177.089826 -304.268485)
			(xy 177.04381 -304.251033) (xy 177.001189 -304.226426) (xy 176.963068 -304.195301) (xy 176.930433 -304.158464)
			(xy 176.90413 -304.116868) (xy 176.884839 -304.071592) (xy 176.873062 -304.023808) (xy 176.869102 -303.974754)
			(xy 176.530254 -303.974754) (xy 176.529759 -303.999361) (xy 176.521864 -304.047938) (xy 176.50628 -304.094619)
			(xy 176.483409 -304.138196) (xy 176.453844 -304.17754) (xy 176.418351 -304.211632) (xy 176.377848 -304.239588)
			(xy 176.333386 -304.260686) (xy 176.286115 -304.274378) (xy 176.23726 -304.28031) (xy 176.188085 -304.278329)
			(xy 176.139866 -304.268485) (xy 176.09385 -304.251033) (xy 176.051229 -304.226426) (xy 176.013108 -304.195301)
			(xy 175.980473 -304.158464) (xy 175.95417 -304.116868) (xy 175.934879 -304.071592) (xy 175.923102 -304.023808)
			(xy 175.919142 -303.974754) (xy 174.630334 -303.974754) (xy 174.629839 -303.999361) (xy 174.621944 -304.047938)
			(xy 174.60636 -304.094619) (xy 174.583489 -304.138196) (xy 174.553924 -304.17754) (xy 174.518431 -304.211632)
			(xy 174.477928 -304.239588) (xy 174.433466 -304.260686) (xy 174.386195 -304.274378) (xy 174.33734 -304.28031)
			(xy 174.288165 -304.278329) (xy 174.239946 -304.268485) (xy 174.19393 -304.251033) (xy 174.151309 -304.226426)
			(xy 174.113188 -304.195301) (xy 174.080553 -304.158464) (xy 174.05425 -304.116868) (xy 174.034959 -304.071592)
			(xy 174.023182 -304.023808) (xy 174.019222 -303.974754) (xy 173.680374 -303.974754) (xy 173.679879 -303.999361)
			(xy 173.671984 -304.047938) (xy 173.6564 -304.094619) (xy 173.633529 -304.138196) (xy 173.603964 -304.17754)
			(xy 173.568471 -304.211632) (xy 173.527968 -304.239588) (xy 173.483506 -304.260686) (xy 173.436235 -304.274378)
			(xy 173.38738 -304.28031) (xy 173.338205 -304.278329) (xy 173.289986 -304.268485) (xy 173.24397 -304.251033)
			(xy 173.201349 -304.226426) (xy 173.163228 -304.195301) (xy 173.130593 -304.158464) (xy 173.10429 -304.116868)
			(xy 173.084999 -304.071592) (xy 173.073222 -304.023808) (xy 173.069262 -303.974754) (xy 172.73016 -303.974754)
			(xy 172.729665 -303.999361) (xy 172.72177 -304.047938) (xy 172.706186 -304.094619) (xy 172.683315 -304.138196)
			(xy 172.65375 -304.17754) (xy 172.618257 -304.211632) (xy 172.577754 -304.239588) (xy 172.533292 -304.260686)
			(xy 172.486021 -304.274378) (xy 172.437166 -304.28031) (xy 172.387991 -304.278329) (xy 172.339772 -304.268485)
			(xy 172.293756 -304.251033) (xy 172.251135 -304.226426) (xy 172.213014 -304.195301) (xy 172.180379 -304.158464)
			(xy 172.154076 -304.116868) (xy 172.134785 -304.071592) (xy 172.123008 -304.023808) (xy 172.119048 -303.974754)
			(xy 171.7802 -303.974754) (xy 171.779705 -303.999361) (xy 171.77181 -304.047938) (xy 171.756226 -304.094619)
			(xy 171.733355 -304.138196) (xy 171.70379 -304.17754) (xy 171.668297 -304.211632) (xy 171.627794 -304.239588)
			(xy 171.583332 -304.260686) (xy 171.536061 -304.274378) (xy 171.487206 -304.28031) (xy 171.438031 -304.278329)
			(xy 171.389812 -304.268485) (xy 171.343796 -304.251033) (xy 171.301175 -304.226426) (xy 171.263054 -304.195301)
			(xy 171.230419 -304.158464) (xy 171.204116 -304.116868) (xy 171.184825 -304.071592) (xy 171.173048 -304.023808)
			(xy 171.169088 -303.974754) (xy 170.83024 -303.974754) (xy 170.829745 -303.999361) (xy 170.82185 -304.047938)
			(xy 170.806266 -304.094619) (xy 170.783395 -304.138196) (xy 170.75383 -304.17754) (xy 170.718337 -304.211632)
			(xy 170.677834 -304.239588) (xy 170.633372 -304.260686) (xy 170.586101 -304.274378) (xy 170.537246 -304.28031)
			(xy 170.488071 -304.278329) (xy 170.439852 -304.268485) (xy 170.393836 -304.251033) (xy 170.351215 -304.226426)
			(xy 170.313094 -304.195301) (xy 170.280459 -304.158464) (xy 170.254156 -304.116868) (xy 170.234865 -304.071592)
			(xy 170.223088 -304.023808) (xy 170.219128 -303.974754) (xy 169.88028 -303.974754) (xy 169.879785 -303.999361)
			(xy 169.87189 -304.047938) (xy 169.856306 -304.094619) (xy 169.833435 -304.138196) (xy 169.80387 -304.17754)
			(xy 169.768377 -304.211632) (xy 169.727874 -304.239588) (xy 169.683412 -304.260686) (xy 169.636141 -304.274378)
			(xy 169.587286 -304.28031) (xy 169.538111 -304.278329) (xy 169.489892 -304.268485) (xy 169.443876 -304.251033)
			(xy 169.401255 -304.226426) (xy 169.363134 -304.195301) (xy 169.330499 -304.158464) (xy 169.304196 -304.116868)
			(xy 169.284905 -304.071592) (xy 169.273128 -304.023808) (xy 169.269168 -303.974754) (xy 168.93032 -303.974754)
			(xy 168.929825 -303.999361) (xy 168.92193 -304.047938) (xy 168.906346 -304.094619) (xy 168.883475 -304.138196)
			(xy 168.85391 -304.17754) (xy 168.818417 -304.211632) (xy 168.777914 -304.239588) (xy 168.733452 -304.260686)
			(xy 168.686181 -304.274378) (xy 168.637326 -304.28031) (xy 168.588151 -304.278329) (xy 168.539932 -304.268485)
			(xy 168.493916 -304.251033) (xy 168.451295 -304.226426) (xy 168.413174 -304.195301) (xy 168.380539 -304.158464)
			(xy 168.354236 -304.116868) (xy 168.334945 -304.071592) (xy 168.323168 -304.023808) (xy 168.319208 -303.974754)
			(xy 167.98036 -303.974754) (xy 167.979865 -303.999361) (xy 167.97197 -304.047938) (xy 167.956386 -304.094619)
			(xy 167.933515 -304.138196) (xy 167.90395 -304.17754) (xy 167.868457 -304.211632) (xy 167.827954 -304.239588)
			(xy 167.783492 -304.260686) (xy 167.736221 -304.274378) (xy 167.687366 -304.28031) (xy 167.638191 -304.278329)
			(xy 167.589972 -304.268485) (xy 167.543956 -304.251033) (xy 167.501335 -304.226426) (xy 167.463214 -304.195301)
			(xy 167.430579 -304.158464) (xy 167.404276 -304.116868) (xy 167.384985 -304.071592) (xy 167.373208 -304.023808)
			(xy 167.369248 -303.974754) (xy 167.0304 -303.974754) (xy 167.029905 -303.999361) (xy 167.02201 -304.047938)
			(xy 167.006426 -304.094619) (xy 166.983555 -304.138196) (xy 166.95399 -304.17754) (xy 166.918497 -304.211632)
			(xy 166.877994 -304.239588) (xy 166.833532 -304.260686) (xy 166.786261 -304.274378) (xy 166.737406 -304.28031)
			(xy 166.688231 -304.278329) (xy 166.640012 -304.268485) (xy 166.593996 -304.251033) (xy 166.551375 -304.226426)
			(xy 166.513254 -304.195301) (xy 166.480619 -304.158464) (xy 166.454316 -304.116868) (xy 166.435025 -304.071592)
			(xy 166.423248 -304.023808) (xy 166.419288 -303.974754) (xy 166.08071 -303.974754) (xy 166.080714 -303.9748)
			(xy 166.076543 -304.025138) (xy 166.064143 -304.074102) (xy 166.043852 -304.120357) (xy 166.016225 -304.162642)
			(xy 165.982014 -304.199803) (xy 165.942153 -304.230825) (xy 165.897729 -304.254863) (xy 165.849955 -304.271261)
			(xy 165.800133 -304.279571) (xy 165.774878 -304.280062) (xy 165.750272 -304.279586) (xy 165.701697 -304.271696)
			(xy 165.655014 -304.256123) (xy 165.611431 -304.23327) (xy 165.572073 -304.203728) (xy 165.55466 -304.186336)
			(xy 165.54735 -304.179327) (xy 165.528828 -304.171183) (xy 165.508598 -304.170816) (xy 165.499034 -304.174144)
			(xy 165.411658 -304.20945) (xy 165.402487 -304.21365) (xy 165.388121 -304.227779) (xy 165.38034 -304.246365)
			(xy 165.379908 -304.25644) (xy 165.379908 -304.274728) (xy 165.379521 -304.284802) (xy 165.371776 -304.303401)
			(xy 165.364922 -304.310796) (xy 165.039802 -304.635916) (xy 165.03315 -304.643345) (xy 165.025505 -304.661734)
			(xy 165.025423 -304.681649) (xy 165.032916 -304.700101) (xy 165.039548 -304.707544) (xy 165.039802 -304.707798)
			(xy 165.056638 -304.725101) (xy 165.085151 -304.764057) (xy 165.107181 -304.807013) (xy 165.122178 -304.852901)
			(xy 165.12977 -304.900576) (xy 165.130226 -304.924714) (xy 165.469074 -304.924714) (xy 165.473034 -304.87566)
			(xy 165.484811 -304.827876) (xy 165.504102 -304.7826) (xy 165.530405 -304.741004) (xy 165.56304 -304.704167)
			(xy 165.601161 -304.673042) (xy 165.643782 -304.648435) (xy 165.689798 -304.630983) (xy 165.738017 -304.621139)
			(xy 165.787192 -304.619158) (xy 165.836047 -304.62509) (xy 165.883318 -304.638782) (xy 165.92778 -304.65988)
			(xy 165.968283 -304.687836) (xy 166.003776 -304.721928) (xy 166.033341 -304.761272) (xy 166.056212 -304.804849)
			(xy 166.071796 -304.85153) (xy 166.079691 -304.900107) (xy 166.080186 -304.924714) (xy 166.419288 -304.924714)
			(xy 166.423248 -304.87566) (xy 166.435025 -304.827876) (xy 166.454316 -304.7826) (xy 166.480619 -304.741004)
			(xy 166.513254 -304.704167) (xy 166.551375 -304.673042) (xy 166.593996 -304.648435) (xy 166.640012 -304.630983)
			(xy 166.688231 -304.621139) (xy 166.737406 -304.619158) (xy 166.786261 -304.62509) (xy 166.833532 -304.638782)
			(xy 166.877994 -304.65988) (xy 166.918497 -304.687836) (xy 166.95399 -304.721928) (xy 166.983555 -304.761272)
			(xy 167.006426 -304.804849) (xy 167.02201 -304.85153) (xy 167.029905 -304.900107) (xy 167.0304 -304.924714)
			(xy 167.369248 -304.924714) (xy 167.373208 -304.87566) (xy 167.384985 -304.827876) (xy 167.404276 -304.7826)
			(xy 167.430579 -304.741004) (xy 167.463214 -304.704167) (xy 167.501335 -304.673042) (xy 167.543956 -304.648435)
			(xy 167.589972 -304.630983) (xy 167.638191 -304.621139) (xy 167.687366 -304.619158) (xy 167.736221 -304.62509)
			(xy 167.783492 -304.638782) (xy 167.827954 -304.65988) (xy 167.868457 -304.687836) (xy 167.90395 -304.721928)
			(xy 167.933515 -304.761272) (xy 167.956386 -304.804849) (xy 167.97197 -304.85153) (xy 167.979865 -304.900107)
			(xy 167.98036 -304.924714) (xy 168.319208 -304.924714) (xy 168.323168 -304.87566) (xy 168.334945 -304.827876)
			(xy 168.354236 -304.7826) (xy 168.380539 -304.741004) (xy 168.413174 -304.704167) (xy 168.451295 -304.673042)
			(xy 168.493916 -304.648435) (xy 168.539932 -304.630983) (xy 168.588151 -304.621139) (xy 168.637326 -304.619158)
			(xy 168.686181 -304.62509) (xy 168.733452 -304.638782) (xy 168.777914 -304.65988) (xy 168.818417 -304.687836)
			(xy 168.85391 -304.721928) (xy 168.883475 -304.761272) (xy 168.906346 -304.804849) (xy 168.92193 -304.85153)
			(xy 168.929825 -304.900107) (xy 168.93032 -304.924714) (xy 169.269168 -304.924714) (xy 169.273128 -304.87566)
			(xy 169.284905 -304.827876) (xy 169.304196 -304.7826) (xy 169.330499 -304.741004) (xy 169.363134 -304.704167)
			(xy 169.401255 -304.673042) (xy 169.443876 -304.648435) (xy 169.489892 -304.630983) (xy 169.538111 -304.621139)
			(xy 169.587286 -304.619158) (xy 169.636141 -304.62509) (xy 169.683412 -304.638782) (xy 169.727874 -304.65988)
			(xy 169.768377 -304.687836) (xy 169.80387 -304.721928) (xy 169.833435 -304.761272) (xy 169.856306 -304.804849)
			(xy 169.87189 -304.85153) (xy 169.879785 -304.900107) (xy 169.88028 -304.924714) (xy 170.219128 -304.924714)
			(xy 170.223088 -304.87566) (xy 170.234865 -304.827876) (xy 170.254156 -304.7826) (xy 170.280459 -304.741004)
			(xy 170.313094 -304.704167) (xy 170.351215 -304.673042) (xy 170.393836 -304.648435) (xy 170.439852 -304.630983)
			(xy 170.488071 -304.621139) (xy 170.537246 -304.619158) (xy 170.586101 -304.62509) (xy 170.633372 -304.638782)
			(xy 170.677834 -304.65988) (xy 170.718337 -304.687836) (xy 170.75383 -304.721928) (xy 170.783395 -304.761272)
			(xy 170.806266 -304.804849) (xy 170.82185 -304.85153) (xy 170.829745 -304.900107) (xy 170.83024 -304.924714)
			(xy 171.169088 -304.924714) (xy 171.173048 -304.87566) (xy 171.184825 -304.827876) (xy 171.204116 -304.7826)
			(xy 171.230419 -304.741004) (xy 171.263054 -304.704167) (xy 171.301175 -304.673042) (xy 171.343796 -304.648435)
			(xy 171.389812 -304.630983) (xy 171.438031 -304.621139) (xy 171.487206 -304.619158) (xy 171.536061 -304.62509)
			(xy 171.583332 -304.638782) (xy 171.627794 -304.65988) (xy 171.668297 -304.687836) (xy 171.70379 -304.721928)
			(xy 171.733355 -304.761272) (xy 171.756226 -304.804849) (xy 171.77181 -304.85153) (xy 171.779705 -304.900107)
			(xy 171.7802 -304.924714) (xy 172.119048 -304.924714) (xy 172.123008 -304.87566) (xy 172.134785 -304.827876)
			(xy 172.154076 -304.7826) (xy 172.180379 -304.741004) (xy 172.213014 -304.704167) (xy 172.251135 -304.673042)
			(xy 172.293756 -304.648435) (xy 172.339772 -304.630983) (xy 172.387991 -304.621139) (xy 172.437166 -304.619158)
			(xy 172.486021 -304.62509) (xy 172.533292 -304.638782) (xy 172.577754 -304.65988) (xy 172.618257 -304.687836)
			(xy 172.65375 -304.721928) (xy 172.683315 -304.761272) (xy 172.706186 -304.804849) (xy 172.72177 -304.85153)
			(xy 172.729665 -304.900107) (xy 172.73016 -304.924714) (xy 173.069262 -304.924714) (xy 173.073222 -304.87566)
			(xy 173.084999 -304.827876) (xy 173.10429 -304.7826) (xy 173.130593 -304.741004) (xy 173.163228 -304.704167)
			(xy 173.201349 -304.673042) (xy 173.24397 -304.648435) (xy 173.289986 -304.630983) (xy 173.338205 -304.621139)
			(xy 173.38738 -304.619158) (xy 173.436235 -304.62509) (xy 173.483506 -304.638782) (xy 173.527968 -304.65988)
			(xy 173.568471 -304.687836) (xy 173.603964 -304.721928) (xy 173.633529 -304.761272) (xy 173.6564 -304.804849)
			(xy 173.671984 -304.85153) (xy 173.679879 -304.900107) (xy 173.680374 -304.924714) (xy 174.019222 -304.924714)
			(xy 174.023182 -304.87566) (xy 174.034959 -304.827876) (xy 174.05425 -304.7826) (xy 174.080553 -304.741004)
			(xy 174.113188 -304.704167) (xy 174.151309 -304.673042) (xy 174.19393 -304.648435) (xy 174.239946 -304.630983)
			(xy 174.288165 -304.621139) (xy 174.33734 -304.619158) (xy 174.386195 -304.62509) (xy 174.433466 -304.638782)
			(xy 174.477928 -304.65988) (xy 174.518431 -304.687836) (xy 174.553924 -304.721928) (xy 174.583489 -304.761272)
			(xy 174.60636 -304.804849) (xy 174.621944 -304.85153) (xy 174.629839 -304.900107) (xy 174.630334 -304.924714)
			(xy 175.919142 -304.924714) (xy 175.923102 -304.87566) (xy 175.934879 -304.827876) (xy 175.95417 -304.7826)
			(xy 175.980473 -304.741004) (xy 176.013108 -304.704167) (xy 176.051229 -304.673042) (xy 176.09385 -304.648435)
			(xy 176.139866 -304.630983) (xy 176.188085 -304.621139) (xy 176.23726 -304.619158) (xy 176.286115 -304.62509)
			(xy 176.333386 -304.638782) (xy 176.377848 -304.65988) (xy 176.418351 -304.687836) (xy 176.453844 -304.721928)
			(xy 176.483409 -304.761272) (xy 176.50628 -304.804849) (xy 176.521864 -304.85153) (xy 176.529759 -304.900107)
			(xy 176.530254 -304.924714) (xy 176.869102 -304.924714) (xy 176.873062 -304.87566) (xy 176.884839 -304.827876)
			(xy 176.90413 -304.7826) (xy 176.930433 -304.741004) (xy 176.963068 -304.704167) (xy 177.001189 -304.673042)
			(xy 177.04381 -304.648435) (xy 177.089826 -304.630983) (xy 177.138045 -304.621139) (xy 177.18722 -304.619158)
			(xy 177.236075 -304.62509) (xy 177.283346 -304.638782) (xy 177.327808 -304.65988) (xy 177.368311 -304.687836)
			(xy 177.403804 -304.721928) (xy 177.433369 -304.761272) (xy 177.45624 -304.804849) (xy 177.471824 -304.85153)
			(xy 177.479719 -304.900107) (xy 177.480214 -304.924714) (xy 177.819062 -304.924714) (xy 177.823022 -304.87566)
			(xy 177.834799 -304.827876) (xy 177.85409 -304.7826) (xy 177.880393 -304.741004) (xy 177.913028 -304.704167)
			(xy 177.951149 -304.673042) (xy 177.99377 -304.648435) (xy 178.039786 -304.630983) (xy 178.088005 -304.621139)
			(xy 178.13718 -304.619158) (xy 178.186035 -304.62509) (xy 178.233306 -304.638782) (xy 178.277768 -304.65988)
			(xy 178.318271 -304.687836) (xy 178.353764 -304.721928) (xy 178.383329 -304.761272) (xy 178.4062 -304.804849)
			(xy 178.421784 -304.85153) (xy 178.429679 -304.900107) (xy 178.430174 -304.924714) (xy 178.769276 -304.924714)
			(xy 178.773236 -304.87566) (xy 178.785013 -304.827876) (xy 178.804304 -304.7826) (xy 178.830607 -304.741004)
			(xy 178.863242 -304.704167) (xy 178.901363 -304.673042) (xy 178.943984 -304.648435) (xy 178.99 -304.630983)
			(xy 179.038219 -304.621139) (xy 179.087394 -304.619158) (xy 179.136249 -304.62509) (xy 179.18352 -304.638782)
			(xy 179.227982 -304.65988) (xy 179.268485 -304.687836) (xy 179.303978 -304.721928) (xy 179.333543 -304.761272)
			(xy 179.356414 -304.804849) (xy 179.371998 -304.85153) (xy 179.379893 -304.900107) (xy 179.380388 -304.924714)
			(xy 179.719236 -304.924714) (xy 179.723196 -304.87566) (xy 179.734973 -304.827876) (xy 179.754264 -304.7826)
			(xy 179.780567 -304.741004) (xy 179.813202 -304.704167) (xy 179.851323 -304.673042) (xy 179.893944 -304.648435)
			(xy 179.93996 -304.630983) (xy 179.988179 -304.621139) (xy 180.037354 -304.619158) (xy 180.086209 -304.62509)
			(xy 180.13348 -304.638782) (xy 180.177942 -304.65988) (xy 180.218445 -304.687836) (xy 180.253938 -304.721928)
			(xy 180.283503 -304.761272) (xy 180.306374 -304.804849) (xy 180.321958 -304.85153) (xy 180.329853 -304.900107)
			(xy 180.330348 -304.924714) (xy 180.669196 -304.924714) (xy 180.673156 -304.87566) (xy 180.684933 -304.827876)
			(xy 180.704224 -304.7826) (xy 180.730527 -304.741004) (xy 180.763162 -304.704167) (xy 180.801283 -304.673042)
			(xy 180.843904 -304.648435) (xy 180.88992 -304.630983) (xy 180.938139 -304.621139) (xy 180.987314 -304.619158)
			(xy 181.036169 -304.62509) (xy 181.08344 -304.638782) (xy 181.127902 -304.65988) (xy 181.168405 -304.687836)
			(xy 181.203898 -304.721928) (xy 181.233463 -304.761272) (xy 181.256334 -304.804849) (xy 181.271918 -304.85153)
			(xy 181.279813 -304.900107) (xy 181.280308 -304.924714) (xy 181.619156 -304.924714) (xy 181.623116 -304.87566)
			(xy 181.634893 -304.827876) (xy 181.654184 -304.7826) (xy 181.680487 -304.741004) (xy 181.713122 -304.704167)
			(xy 181.751243 -304.673042) (xy 181.793864 -304.648435) (xy 181.83988 -304.630983) (xy 181.888099 -304.621139)
			(xy 181.937274 -304.619158) (xy 181.986129 -304.62509) (xy 182.0334 -304.638782) (xy 182.077862 -304.65988)
			(xy 182.118365 -304.687836) (xy 182.153858 -304.721928) (xy 182.183423 -304.761272) (xy 182.206294 -304.804849)
			(xy 182.221878 -304.85153) (xy 182.229773 -304.900107) (xy 182.230268 -304.924714) (xy 182.569116 -304.924714)
			(xy 182.573076 -304.87566) (xy 182.584853 -304.827876) (xy 182.604144 -304.7826) (xy 182.630447 -304.741004)
			(xy 182.663082 -304.704167) (xy 182.701203 -304.673042) (xy 182.743824 -304.648435) (xy 182.78984 -304.630983)
			(xy 182.838059 -304.621139) (xy 182.887234 -304.619158) (xy 182.936089 -304.62509) (xy 182.98336 -304.638782)
			(xy 183.027822 -304.65988) (xy 183.068325 -304.687836) (xy 183.103818 -304.721928) (xy 183.133383 -304.761272)
			(xy 183.156254 -304.804849) (xy 183.171838 -304.85153) (xy 183.179733 -304.900107) (xy 183.180228 -304.924714)
			(xy 183.519076 -304.924714) (xy 183.523036 -304.87566) (xy 183.534813 -304.827876) (xy 183.554104 -304.7826)
			(xy 183.580407 -304.741004) (xy 183.613042 -304.704167) (xy 183.651163 -304.673042) (xy 183.693784 -304.648435)
			(xy 183.7398 -304.630983) (xy 183.788019 -304.621139) (xy 183.837194 -304.619158) (xy 183.886049 -304.62509)
			(xy 183.93332 -304.638782) (xy 183.977782 -304.65988) (xy 184.018285 -304.687836) (xy 184.053778 -304.721928)
			(xy 184.083343 -304.761272) (xy 184.106214 -304.804849) (xy 184.121798 -304.85153) (xy 184.129693 -304.900107)
			(xy 184.130188 -304.924714) (xy 184.129693 -304.949321) (xy 184.121798 -304.997898) (xy 184.106214 -305.044579)
			(xy 184.083343 -305.088156) (xy 184.053778 -305.1275) (xy 184.018285 -305.161592) (xy 183.977782 -305.189548)
			(xy 183.93332 -305.210646) (xy 183.886049 -305.224338) (xy 183.837194 -305.23027) (xy 183.788019 -305.228289)
			(xy 183.7398 -305.218445) (xy 183.693784 -305.200993) (xy 183.651163 -305.176386) (xy 183.613042 -305.145261)
			(xy 183.580407 -305.108424) (xy 183.554104 -305.066828) (xy 183.534813 -305.021552) (xy 183.523036 -304.973768)
			(xy 183.519076 -304.924714) (xy 183.180228 -304.924714) (xy 183.179733 -304.949321) (xy 183.171838 -304.997898)
			(xy 183.156254 -305.044579) (xy 183.133383 -305.088156) (xy 183.103818 -305.1275) (xy 183.068325 -305.161592)
			(xy 183.027822 -305.189548) (xy 182.98336 -305.210646) (xy 182.936089 -305.224338) (xy 182.887234 -305.23027)
			(xy 182.838059 -305.228289) (xy 182.78984 -305.218445) (xy 182.743824 -305.200993) (xy 182.701203 -305.176386)
			(xy 182.663082 -305.145261) (xy 182.630447 -305.108424) (xy 182.604144 -305.066828) (xy 182.584853 -305.021552)
			(xy 182.573076 -304.973768) (xy 182.569116 -304.924714) (xy 182.230268 -304.924714) (xy 182.229773 -304.949321)
			(xy 182.221878 -304.997898) (xy 182.206294 -305.044579) (xy 182.183423 -305.088156) (xy 182.153858 -305.1275)
			(xy 182.118365 -305.161592) (xy 182.077862 -305.189548) (xy 182.0334 -305.210646) (xy 181.986129 -305.224338)
			(xy 181.937274 -305.23027) (xy 181.888099 -305.228289) (xy 181.83988 -305.218445) (xy 181.793864 -305.200993)
			(xy 181.751243 -305.176386) (xy 181.713122 -305.145261) (xy 181.680487 -305.108424) (xy 181.654184 -305.066828)
			(xy 181.634893 -305.021552) (xy 181.623116 -304.973768) (xy 181.619156 -304.924714) (xy 181.280308 -304.924714)
			(xy 181.279813 -304.949321) (xy 181.271918 -304.997898) (xy 181.256334 -305.044579) (xy 181.233463 -305.088156)
			(xy 181.203898 -305.1275) (xy 181.168405 -305.161592) (xy 181.127902 -305.189548) (xy 181.08344 -305.210646)
			(xy 181.036169 -305.224338) (xy 180.987314 -305.23027) (xy 180.938139 -305.228289) (xy 180.88992 -305.218445)
			(xy 180.843904 -305.200993) (xy 180.801283 -305.176386) (xy 180.763162 -305.145261) (xy 180.730527 -305.108424)
			(xy 180.704224 -305.066828) (xy 180.684933 -305.021552) (xy 180.673156 -304.973768) (xy 180.669196 -304.924714)
			(xy 180.330348 -304.924714) (xy 180.329853 -304.949321) (xy 180.321958 -304.997898) (xy 180.306374 -305.044579)
			(xy 180.283503 -305.088156) (xy 180.253938 -305.1275) (xy 180.218445 -305.161592) (xy 180.177942 -305.189548)
			(xy 180.13348 -305.210646) (xy 180.086209 -305.224338) (xy 180.037354 -305.23027) (xy 179.988179 -305.228289)
			(xy 179.93996 -305.218445) (xy 179.893944 -305.200993) (xy 179.851323 -305.176386) (xy 179.813202 -305.145261)
			(xy 179.780567 -305.108424) (xy 179.754264 -305.066828) (xy 179.734973 -305.021552) (xy 179.723196 -304.973768)
			(xy 179.719236 -304.924714) (xy 179.380388 -304.924714) (xy 179.379893 -304.949321) (xy 179.371998 -304.997898)
			(xy 179.356414 -305.044579) (xy 179.333543 -305.088156) (xy 179.303978 -305.1275) (xy 179.268485 -305.161592)
			(xy 179.227982 -305.189548) (xy 179.18352 -305.210646) (xy 179.136249 -305.224338) (xy 179.087394 -305.23027)
			(xy 179.038219 -305.228289) (xy 178.99 -305.218445) (xy 178.943984 -305.200993) (xy 178.901363 -305.176386)
			(xy 178.863242 -305.145261) (xy 178.830607 -305.108424) (xy 178.804304 -305.066828) (xy 178.785013 -305.021552)
			(xy 178.773236 -304.973768) (xy 178.769276 -304.924714) (xy 178.430174 -304.924714) (xy 178.429679 -304.949321)
			(xy 178.421784 -304.997898) (xy 178.4062 -305.044579) (xy 178.383329 -305.088156) (xy 178.353764 -305.1275)
			(xy 178.318271 -305.161592) (xy 178.277768 -305.189548) (xy 178.233306 -305.210646) (xy 178.186035 -305.224338)
			(xy 178.13718 -305.23027) (xy 178.088005 -305.228289) (xy 178.039786 -305.218445) (xy 177.99377 -305.200993)
			(xy 177.951149 -305.176386) (xy 177.913028 -305.145261) (xy 177.880393 -305.108424) (xy 177.85409 -305.066828)
			(xy 177.834799 -305.021552) (xy 177.823022 -304.973768) (xy 177.819062 -304.924714) (xy 177.480214 -304.924714)
			(xy 177.479719 -304.949321) (xy 177.471824 -304.997898) (xy 177.45624 -305.044579) (xy 177.433369 -305.088156)
			(xy 177.403804 -305.1275) (xy 177.368311 -305.161592) (xy 177.327808 -305.189548) (xy 177.283346 -305.210646)
			(xy 177.236075 -305.224338) (xy 177.18722 -305.23027) (xy 177.138045 -305.228289) (xy 177.089826 -305.218445)
			(xy 177.04381 -305.200993) (xy 177.001189 -305.176386) (xy 176.963068 -305.145261) (xy 176.930433 -305.108424)
			(xy 176.90413 -305.066828) (xy 176.884839 -305.021552) (xy 176.873062 -304.973768) (xy 176.869102 -304.924714)
			(xy 176.530254 -304.924714) (xy 176.529759 -304.949321) (xy 176.521864 -304.997898) (xy 176.50628 -305.044579)
			(xy 176.483409 -305.088156) (xy 176.453844 -305.1275) (xy 176.418351 -305.161592) (xy 176.377848 -305.189548)
			(xy 176.333386 -305.210646) (xy 176.286115 -305.224338) (xy 176.23726 -305.23027) (xy 176.188085 -305.228289)
			(xy 176.139866 -305.218445) (xy 176.09385 -305.200993) (xy 176.051229 -305.176386) (xy 176.013108 -305.145261)
			(xy 175.980473 -305.108424) (xy 175.95417 -305.066828) (xy 175.934879 -305.021552) (xy 175.923102 -304.973768)
			(xy 175.919142 -304.924714) (xy 174.630334 -304.924714) (xy 174.629839 -304.949321) (xy 174.621944 -304.997898)
			(xy 174.60636 -305.044579) (xy 174.583489 -305.088156) (xy 174.553924 -305.1275) (xy 174.518431 -305.161592)
			(xy 174.477928 -305.189548) (xy 174.433466 -305.210646) (xy 174.386195 -305.224338) (xy 174.33734 -305.23027)
			(xy 174.288165 -305.228289) (xy 174.239946 -305.218445) (xy 174.19393 -305.200993) (xy 174.151309 -305.176386)
			(xy 174.113188 -305.145261) (xy 174.080553 -305.108424) (xy 174.05425 -305.066828) (xy 174.034959 -305.021552)
			(xy 174.023182 -304.973768) (xy 174.019222 -304.924714) (xy 173.680374 -304.924714) (xy 173.679879 -304.949321)
			(xy 173.671984 -304.997898) (xy 173.6564 -305.044579) (xy 173.633529 -305.088156) (xy 173.603964 -305.1275)
			(xy 173.568471 -305.161592) (xy 173.527968 -305.189548) (xy 173.483506 -305.210646) (xy 173.436235 -305.224338)
			(xy 173.38738 -305.23027) (xy 173.338205 -305.228289) (xy 173.289986 -305.218445) (xy 173.24397 -305.200993)
			(xy 173.201349 -305.176386) (xy 173.163228 -305.145261) (xy 173.130593 -305.108424) (xy 173.10429 -305.066828)
			(xy 173.084999 -305.021552) (xy 173.073222 -304.973768) (xy 173.069262 -304.924714) (xy 172.73016 -304.924714)
			(xy 172.729665 -304.949321) (xy 172.72177 -304.997898) (xy 172.706186 -305.044579) (xy 172.683315 -305.088156)
			(xy 172.65375 -305.1275) (xy 172.618257 -305.161592) (xy 172.577754 -305.189548) (xy 172.533292 -305.210646)
			(xy 172.486021 -305.224338) (xy 172.437166 -305.23027) (xy 172.387991 -305.228289) (xy 172.339772 -305.218445)
			(xy 172.293756 -305.200993) (xy 172.251135 -305.176386) (xy 172.213014 -305.145261) (xy 172.180379 -305.108424)
			(xy 172.154076 -305.066828) (xy 172.134785 -305.021552) (xy 172.123008 -304.973768) (xy 172.119048 -304.924714)
			(xy 171.7802 -304.924714) (xy 171.779705 -304.949321) (xy 171.77181 -304.997898) (xy 171.756226 -305.044579)
			(xy 171.733355 -305.088156) (xy 171.70379 -305.1275) (xy 171.668297 -305.161592) (xy 171.627794 -305.189548)
			(xy 171.583332 -305.210646) (xy 171.536061 -305.224338) (xy 171.487206 -305.23027) (xy 171.438031 -305.228289)
			(xy 171.389812 -305.218445) (xy 171.343796 -305.200993) (xy 171.301175 -305.176386) (xy 171.263054 -305.145261)
			(xy 171.230419 -305.108424) (xy 171.204116 -305.066828) (xy 171.184825 -305.021552) (xy 171.173048 -304.973768)
			(xy 171.169088 -304.924714) (xy 170.83024 -304.924714) (xy 170.829745 -304.949321) (xy 170.82185 -304.997898)
			(xy 170.806266 -305.044579) (xy 170.783395 -305.088156) (xy 170.75383 -305.1275) (xy 170.718337 -305.161592)
			(xy 170.677834 -305.189548) (xy 170.633372 -305.210646) (xy 170.586101 -305.224338) (xy 170.537246 -305.23027)
			(xy 170.488071 -305.228289) (xy 170.439852 -305.218445) (xy 170.393836 -305.200993) (xy 170.351215 -305.176386)
			(xy 170.313094 -305.145261) (xy 170.280459 -305.108424) (xy 170.254156 -305.066828) (xy 170.234865 -305.021552)
			(xy 170.223088 -304.973768) (xy 170.219128 -304.924714) (xy 169.88028 -304.924714) (xy 169.879785 -304.949321)
			(xy 169.87189 -304.997898) (xy 169.856306 -305.044579) (xy 169.833435 -305.088156) (xy 169.80387 -305.1275)
			(xy 169.768377 -305.161592) (xy 169.727874 -305.189548) (xy 169.683412 -305.210646) (xy 169.636141 -305.224338)
			(xy 169.587286 -305.23027) (xy 169.538111 -305.228289) (xy 169.489892 -305.218445) (xy 169.443876 -305.200993)
			(xy 169.401255 -305.176386) (xy 169.363134 -305.145261) (xy 169.330499 -305.108424) (xy 169.304196 -305.066828)
			(xy 169.284905 -305.021552) (xy 169.273128 -304.973768) (xy 169.269168 -304.924714) (xy 168.93032 -304.924714)
			(xy 168.929825 -304.949321) (xy 168.92193 -304.997898) (xy 168.906346 -305.044579) (xy 168.883475 -305.088156)
			(xy 168.85391 -305.1275) (xy 168.818417 -305.161592) (xy 168.777914 -305.189548) (xy 168.733452 -305.210646)
			(xy 168.686181 -305.224338) (xy 168.637326 -305.23027) (xy 168.588151 -305.228289) (xy 168.539932 -305.218445)
			(xy 168.493916 -305.200993) (xy 168.451295 -305.176386) (xy 168.413174 -305.145261) (xy 168.380539 -305.108424)
			(xy 168.354236 -305.066828) (xy 168.334945 -305.021552) (xy 168.323168 -304.973768) (xy 168.319208 -304.924714)
			(xy 167.98036 -304.924714) (xy 167.979865 -304.949321) (xy 167.97197 -304.997898) (xy 167.956386 -305.044579)
			(xy 167.933515 -305.088156) (xy 167.90395 -305.1275) (xy 167.868457 -305.161592) (xy 167.827954 -305.189548)
			(xy 167.783492 -305.210646) (xy 167.736221 -305.224338) (xy 167.687366 -305.23027) (xy 167.638191 -305.228289)
			(xy 167.589972 -305.218445) (xy 167.543956 -305.200993) (xy 167.501335 -305.176386) (xy 167.463214 -305.145261)
			(xy 167.430579 -305.108424) (xy 167.404276 -305.066828) (xy 167.384985 -305.021552) (xy 167.373208 -304.973768)
			(xy 167.369248 -304.924714) (xy 167.0304 -304.924714) (xy 167.029905 -304.949321) (xy 167.02201 -304.997898)
			(xy 167.006426 -305.044579) (xy 166.983555 -305.088156) (xy 166.95399 -305.1275) (xy 166.918497 -305.161592)
			(xy 166.877994 -305.189548) (xy 166.833532 -305.210646) (xy 166.786261 -305.224338) (xy 166.737406 -305.23027)
			(xy 166.688231 -305.228289) (xy 166.640012 -305.218445) (xy 166.593996 -305.200993) (xy 166.551375 -305.176386)
			(xy 166.513254 -305.145261) (xy 166.480619 -305.108424) (xy 166.454316 -305.066828) (xy 166.435025 -305.021552)
			(xy 166.423248 -304.973768) (xy 166.419288 -304.924714) (xy 166.080186 -304.924714) (xy 166.079691 -304.949321)
			(xy 166.071796 -304.997898) (xy 166.056212 -305.044579) (xy 166.033341 -305.088156) (xy 166.003776 -305.1275)
			(xy 165.968283 -305.161592) (xy 165.92778 -305.189548) (xy 165.883318 -305.210646) (xy 165.836047 -305.224338)
			(xy 165.787192 -305.23027) (xy 165.738017 -305.228289) (xy 165.689798 -305.218445) (xy 165.643782 -305.200993)
			(xy 165.601161 -305.176386) (xy 165.56304 -305.145261) (xy 165.530405 -305.108424) (xy 165.504102 -305.066828)
			(xy 165.484811 -305.021552) (xy 165.473034 -304.973768) (xy 165.469074 -304.924714) (xy 165.130226 -304.924714)
			(xy 165.129704 -304.949969) (xy 165.121391 -304.999791) (xy 165.10499 -305.047565) (xy 165.080949 -305.091988)
			(xy 165.049925 -305.131848) (xy 165.012763 -305.166058) (xy 164.970477 -305.193684) (xy 164.924221 -305.213974)
			(xy 164.875256 -305.226374) (xy 164.824918 -305.230545) (xy 164.77458 -305.226374) (xy 164.725615 -305.213974)
			(xy 164.679359 -305.193684) (xy 164.637073 -305.166058) (xy 164.599911 -305.131848) (xy 164.568887 -305.091988)
			(xy 164.544846 -305.047565) (xy 164.528445 -304.999791) (xy 164.520132 -304.949969) (xy 164.51961 -304.924714)
			(xy 164.519781 -304.910855) (xy 164.522329 -304.883254) (xy 164.52469 -304.869596) (xy 164.526722 -304.85842)
			(xy 164.521134 -304.836576) (xy 164.46373 -304.767996) (xy 164.456078 -304.759803) (xy 164.435807 -304.750301)
			(xy 164.424614 -304.749708) (xy 164.275262 -304.749708) (xy 164.264049 -304.750215) (xy 164.243746 -304.759733)
			(xy 164.236146 -304.767996) (xy 164.178742 -304.836576) (xy 164.173154 -304.85842) (xy 164.175186 -304.869596)
			(xy 164.177556 -304.883252) (xy 164.180103 -304.910854) (xy 164.180266 -304.924714) (xy 164.179744 -304.949969)
			(xy 164.171431 -304.999791) (xy 164.15503 -305.047565) (xy 164.130989 -305.091988) (xy 164.099965 -305.131848)
			(xy 164.062803 -305.166058) (xy 164.020517 -305.193684) (xy 163.974261 -305.213974) (xy 163.925296 -305.226374)
			(xy 163.874958 -305.230545) (xy 163.82462 -305.226374) (xy 163.775655 -305.213974) (xy 163.729399 -305.193684)
			(xy 163.687113 -305.166058) (xy 163.649951 -305.131848) (xy 163.618927 -305.091988) (xy 163.594886 -305.047565)
			(xy 163.578485 -304.999791) (xy 163.570172 -304.949969) (xy 163.56965 -304.924714) (xy 163.569822 -304.910855)
			(xy 163.572369 -304.883254) (xy 163.57473 -304.869596) (xy 163.576762 -304.85842) (xy 163.571174 -304.836576)
			(xy 163.51377 -304.767996) (xy 163.506143 -304.759776) (xy 163.485853 -304.750289) (xy 163.474654 -304.749708)
			(xy 163.325302 -304.749708) (xy 163.314092 -304.750238) (xy 163.293789 -304.75974) (xy 163.286186 -304.767996)
			(xy 163.228782 -304.836576) (xy 163.223194 -304.85842) (xy 163.225226 -304.869596) (xy 163.227597 -304.883252)
			(xy 163.230143 -304.910854) (xy 163.230306 -304.924714) (xy 163.229784 -304.949969) (xy 163.221471 -304.999791)
			(xy 163.20507 -305.047565) (xy 163.181029 -305.091988) (xy 163.150005 -305.131848) (xy 163.112843 -305.166058)
			(xy 163.070557 -305.193684) (xy 163.024301 -305.213974) (xy 162.975336 -305.226374) (xy 162.924998 -305.230545)
			(xy 162.87466 -305.226374) (xy 162.825695 -305.213974) (xy 162.779439 -305.193684) (xy 162.737153 -305.166058)
			(xy 162.699991 -305.131848) (xy 162.668967 -305.091988) (xy 162.644926 -305.047565) (xy 162.628525 -304.999791)
			(xy 162.620212 -304.949969) (xy 162.61969 -304.924714) (xy 162.619861 -304.910855) (xy 162.622409 -304.883254)
			(xy 162.62477 -304.869596) (xy 162.626802 -304.85842) (xy 162.621214 -304.836576) (xy 162.56381 -304.767996)
			(xy 162.556166 -304.759794) (xy 162.535889 -304.750297) (xy 162.524694 -304.749708) (xy 161.557716 -304.749708)
			(xy 161.553398 -304.75047) (xy 161.540171 -304.752645) (xy 161.513462 -304.754933) (xy 161.500058 -304.755042)
			(xy 161.486654 -304.754927) (xy 161.459946 -304.752636) (xy 161.446718 -304.75047) (xy 161.4424 -304.749708)
			(xy 160.607502 -304.749708) (xy 160.603184 -304.75047) (xy 160.589958 -304.752647) (xy 160.563248 -304.754933)
			(xy 160.549844 -304.755042) (xy 160.53644 -304.754929) (xy 160.509732 -304.752637) (xy 160.496504 -304.75047)
			(xy 160.492186 -304.749708) (xy 159.657542 -304.749708) (xy 159.653224 -304.75047) (xy 159.639997 -304.752641)
			(xy 159.613288 -304.754931) (xy 159.599884 -304.755042) (xy 159.586481 -304.754923) (xy 159.559772 -304.752635)
			(xy 159.546544 -304.75047) (xy 159.542226 -304.749708) (xy 158.707582 -304.749708) (xy 158.703264 -304.75047)
			(xy 158.690036 -304.752636) (xy 158.663328 -304.75493) (xy 158.649924 -304.755042) (xy 158.636521 -304.754918)
			(xy 158.609812 -304.752633) (xy 158.596584 -304.75047) (xy 158.592266 -304.749708) (xy 157.757622 -304.749708)
			(xy 157.753304 -304.75047) (xy 157.740077 -304.752644) (xy 157.713368 -304.754932) (xy 157.699964 -304.755042)
			(xy 157.68656 -304.754926) (xy 157.659852 -304.752636) (xy 157.646624 -304.75047) (xy 157.642306 -304.749708)
			(xy 156.807662 -304.749708) (xy 156.803344 -304.75047) (xy 156.790116 -304.752639) (xy 156.763408 -304.75493)
			(xy 156.750004 -304.755042) (xy 156.736601 -304.754921) (xy 156.709892 -304.752634) (xy 156.696664 -304.75047)
			(xy 156.692346 -304.749708) (xy 155.857702 -304.749708) (xy 155.853384 -304.75047) (xy 155.840158 -304.752647)
			(xy 155.813448 -304.754933) (xy 155.800044 -304.755042) (xy 155.78664 -304.754929) (xy 155.759932 -304.752637)
			(xy 155.746704 -304.75047) (xy 155.742386 -304.749708) (xy 154.907742 -304.749708) (xy 154.903424 -304.75047)
			(xy 154.890197 -304.752641) (xy 154.863488 -304.754931) (xy 154.850084 -304.755042) (xy 154.836681 -304.754923)
			(xy 154.809972 -304.752635) (xy 154.796744 -304.75047) (xy 154.792426 -304.749708) (xy 153.957528 -304.749708)
			(xy 153.95321 -304.75047) (xy 153.939983 -304.752643) (xy 153.913274 -304.754932) (xy 153.89987 -304.755042)
			(xy 153.886466 -304.754925) (xy 153.859758 -304.752636) (xy 153.84653 -304.75047) (xy 153.842212 -304.749708)
			(xy 153.007568 -304.749708) (xy 153.00325 -304.75047) (xy 152.990022 -304.752638) (xy 152.963314 -304.75493)
			(xy 152.94991 -304.755042) (xy 152.936507 -304.75492) (xy 152.909798 -304.752634) (xy 152.89657 -304.75047)
			(xy 152.892252 -304.749708) (xy 152.058624 -304.749708) (xy 152.054052 -304.75047) (xy 152.040577 -304.752736)
			(xy 152.013359 -304.755154) (xy 151.999696 -304.755296) (xy 151.986033 -304.755154) (xy 151.958814 -304.752741)
			(xy 151.94534 -304.75047) (xy 151.940768 -304.749708) (xy 146.473672 -304.749708) (xy 146.463598 -304.749321)
			(xy 146.444999 -304.741576) (xy 146.437604 -304.734722) (xy 144.31899 -302.616108) (xy 144.31216 -302.6087)
			(xy 144.304435 -302.590107) (xy 144.304004 -302.58004) (xy 144.304004 -299.607478) (xy 144.305266 -299.582557)
			(xy 144.314926 -299.533605) (xy 144.332403 -299.486869) (xy 144.34439 -299.464984) (xy 144.363186 -299.435774)
			(xy 144.369366 -299.426446) (xy 144.373687 -299.404515) (xy 144.368273 -299.382828) (xy 144.361662 -299.373798)
			(xy 144.343894 -299.351006) (xy 144.314689 -299.301139) (xy 144.293337 -299.24744) (xy 144.280327 -299.191134)
			(xy 144.275956 -299.133511) (xy 144.150588 -299.133511) (xy 144.150588 -299.133514) (xy 144.150079 -299.1614)
			(xy 144.141959 -299.216576) (xy 144.125891 -299.269983) (xy 144.102219 -299.32048) (xy 144.071446 -299.366993)
			(xy 144.034229 -299.40853) (xy 143.991361 -299.444205) (xy 143.943755 -299.473259) (xy 143.892426 -299.495071)
			(xy 143.838469 -299.509177) (xy 143.783032 -299.515277) (xy 143.727298 -299.51324) (xy 143.672455 -299.50311)
			(xy 143.619671 -299.485103) (xy 143.570071 -299.459602) (xy 143.524713 -299.427151) (xy 143.484564 -299.388442)
			(xy 143.450478 -299.344299) (xy 143.423182 -299.295664) (xy 143.403259 -299.243573) (xy 143.391133 -299.189136)
			(xy 143.387062 -299.133514) (xy 142.675102 -299.133514) (xy 142.674593 -299.1614) (xy 142.666473 -299.216576)
			(xy 142.650405 -299.269983) (xy 142.626733 -299.32048) (xy 142.59596 -299.366993) (xy 142.558743 -299.40853)
			(xy 142.515875 -299.444205) (xy 142.468269 -299.473259) (xy 142.41694 -299.495071) (xy 142.362983 -299.509177)
			(xy 142.307546 -299.515277) (xy 142.251812 -299.51324) (xy 142.196969 -299.50311) (xy 142.144185 -299.485103)
			(xy 142.094585 -299.459602) (xy 142.049227 -299.427151) (xy 142.009078 -299.388442) (xy 141.974992 -299.344299)
			(xy 141.947696 -299.295664) (xy 141.927773 -299.243573) (xy 141.915647 -299.189136) (xy 141.911576 -299.133514)
			(xy 135.153908 -299.133514) (xy 135.153908 -301.031656) (xy 141.911576 -301.031656) (xy 141.915647 -300.976034)
			(xy 141.927773 -300.921597) (xy 141.947696 -300.869506) (xy 141.974992 -300.820871) (xy 142.009078 -300.776728)
			(xy 142.049227 -300.738019) (xy 142.094585 -300.705568) (xy 142.144185 -300.680067) (xy 142.196969 -300.66206)
			(xy 142.251812 -300.65193) (xy 142.307546 -300.649893) (xy 142.362983 -300.655993) (xy 142.41694 -300.670099)
			(xy 142.468269 -300.691911) (xy 142.515875 -300.720965) (xy 142.558743 -300.75664) (xy 142.59596 -300.798177)
			(xy 142.626733 -300.84469) (xy 142.650405 -300.895187) (xy 142.666473 -300.948594) (xy 142.674593 -301.00377)
			(xy 142.675102 -301.031656) (xy 143.396714 -301.031656) (xy 143.400785 -300.976034) (xy 143.412911 -300.921597)
			(xy 143.432834 -300.869506) (xy 143.46013 -300.820871) (xy 143.494216 -300.776728) (xy 143.534365 -300.738019)
			(xy 143.579723 -300.705568) (xy 143.629323 -300.680067) (xy 143.682107 -300.66206) (xy 143.73695 -300.65193)
			(xy 143.792684 -300.649893) (xy 143.848121 -300.655993) (xy 143.902078 -300.670099) (xy 143.953407 -300.691911)
			(xy 144.001013 -300.720965) (xy 144.043881 -300.75664) (xy 144.081098 -300.798177) (xy 144.111871 -300.84469)
			(xy 144.135543 -300.895187) (xy 144.151611 -300.948594) (xy 144.159731 -301.00377) (xy 144.16024 -301.031656)
			(xy 144.159731 -301.059542) (xy 144.151611 -301.114718) (xy 144.135543 -301.168125) (xy 144.111871 -301.218622)
			(xy 144.081098 -301.265135) (xy 144.043881 -301.306672) (xy 144.001013 -301.342347) (xy 143.953407 -301.371401)
			(xy 143.902078 -301.393213) (xy 143.848121 -301.407319) (xy 143.792684 -301.413419) (xy 143.73695 -301.411382)
			(xy 143.682107 -301.401252) (xy 143.629323 -301.383245) (xy 143.579723 -301.357744) (xy 143.534365 -301.325293)
			(xy 143.494216 -301.286584) (xy 143.46013 -301.242441) (xy 143.432834 -301.193806) (xy 143.412911 -301.141715)
			(xy 143.400785 -301.087278) (xy 143.396714 -301.031656) (xy 142.675102 -301.031656) (xy 142.674593 -301.059542)
			(xy 142.666473 -301.114718) (xy 142.650405 -301.168125) (xy 142.626733 -301.218622) (xy 142.59596 -301.265135)
			(xy 142.558743 -301.306672) (xy 142.515875 -301.342347) (xy 142.468269 -301.371401) (xy 142.41694 -301.393213)
			(xy 142.362983 -301.407319) (xy 142.307546 -301.413419) (xy 142.251812 -301.411382) (xy 142.196969 -301.401252)
			(xy 142.144185 -301.383245) (xy 142.094585 -301.357744) (xy 142.049227 -301.325293) (xy 142.009078 -301.286584)
			(xy 141.974992 -301.242441) (xy 141.947696 -301.193806) (xy 141.927773 -301.141715) (xy 141.915647 -301.087278)
			(xy 141.911576 -301.031656) (xy 135.153908 -301.031656) (xy 135.153908 -305.306951) (xy 143.510416 -305.306951)
			(xy 143.518174 -305.252993) (xy 143.533531 -305.200689) (xy 143.556176 -305.151102) (xy 143.585647 -305.105243)
			(xy 143.621345 -305.064045) (xy 143.662543 -305.028347) (xy 143.708403 -304.998876) (xy 143.757989 -304.976231)
			(xy 143.810294 -304.960873) (xy 143.864252 -304.953116) (xy 143.891508 -304.952654) (xy 143.891762 -304.952654)
			(xy 143.919448 -304.95367) (xy 143.930624 -304.954432) (xy 143.951706 -304.946558) (xy 144.02181 -304.873914)
			(xy 144.029176 -304.852578) (xy 144.027906 -304.841402) (xy 144.026845 -304.831148) (xy 144.025701 -304.810562)
			(xy 144.02562 -304.800254) (xy 144.026127 -304.773007) (xy 144.033889 -304.719069) (xy 144.049247 -304.666785)
			(xy 144.07189 -304.617218) (xy 144.101356 -304.571378) (xy 144.137045 -304.530197) (xy 144.178232 -304.494515)
			(xy 144.224077 -304.465057) (xy 144.273648 -304.442424) (xy 144.325935 -304.427074) (xy 144.379874 -304.419323)
			(xy 144.434368 -304.419326) (xy 144.488307 -304.427084) (xy 144.540592 -304.442438) (xy 144.590161 -304.465078)
			(xy 144.636003 -304.494541) (xy 144.677185 -304.530228) (xy 144.71287 -304.571412) (xy 144.742331 -304.617255)
			(xy 144.764968 -304.666825) (xy 144.78032 -304.719111) (xy 144.788076 -304.77305) (xy 144.788076 -304.827543)
			(xy 144.780322 -304.881483) (xy 144.76497 -304.933769) (xy 144.742334 -304.983339) (xy 144.712874 -305.029183)
			(xy 144.67719 -305.070368) (xy 144.636008 -305.106055) (xy 144.590166 -305.135519) (xy 144.540599 -305.158159)
			(xy 144.488313 -305.173515) (xy 144.434375 -305.181274) (xy 144.407128 -305.181762) (xy 144.406874 -305.181762)
			(xy 144.379188 -305.180746) (xy 144.368012 -305.179984) (xy 144.34693 -305.187858) (xy 144.276826 -305.260502)
			(xy 144.26946 -305.281838) (xy 144.27073 -305.293014) (xy 144.271792 -305.303268) (xy 144.272935 -305.323853)
			(xy 144.273016 -305.334162) (xy 144.272586 -305.361418) (xy 144.26705 -305.399948) (xy 152.644106 -305.399948)
			(xy 152.648066 -305.350894) (xy 152.659843 -305.30311) (xy 152.679134 -305.257834) (xy 152.705437 -305.216238)
			(xy 152.738072 -305.179401) (xy 152.776193 -305.148276) (xy 152.818814 -305.123669) (xy 152.86483 -305.106217)
			(xy 152.913049 -305.096373) (xy 152.962224 -305.094392) (xy 153.011079 -305.100324) (xy 153.05835 -305.114016)
			(xy 153.102812 -305.135114) (xy 153.143315 -305.16307) (xy 153.178808 -305.197162) (xy 153.208373 -305.236506)
			(xy 153.231244 -305.280083) (xy 153.246828 -305.326764) (xy 153.254723 -305.375341) (xy 153.255218 -305.399948)
			(xy 153.594066 -305.399948) (xy 153.598026 -305.350894) (xy 153.609803 -305.30311) (xy 153.629094 -305.257834)
			(xy 153.655397 -305.216238) (xy 153.688032 -305.179401) (xy 153.726153 -305.148276) (xy 153.768774 -305.123669)
			(xy 153.81479 -305.106217) (xy 153.863009 -305.096373) (xy 153.912184 -305.094392) (xy 153.961039 -305.100324)
			(xy 154.00831 -305.114016) (xy 154.052772 -305.135114) (xy 154.093275 -305.16307) (xy 154.128768 -305.197162)
			(xy 154.158333 -305.236506) (xy 154.181204 -305.280083) (xy 154.196788 -305.326764) (xy 154.204683 -305.375341)
			(xy 154.205178 -305.399948) (xy 154.54428 -305.399948) (xy 154.54824 -305.350894) (xy 154.560017 -305.30311)
			(xy 154.579308 -305.257834) (xy 154.605611 -305.216238) (xy 154.638246 -305.179401) (xy 154.676367 -305.148276)
			(xy 154.718988 -305.123669) (xy 154.765004 -305.106217) (xy 154.813223 -305.096373) (xy 154.862398 -305.094392)
			(xy 154.911253 -305.100324) (xy 154.958524 -305.114016) (xy 155.002986 -305.135114) (xy 155.043489 -305.16307)
			(xy 155.078982 -305.197162) (xy 155.108547 -305.236506) (xy 155.131418 -305.280083) (xy 155.147002 -305.326764)
			(xy 155.154897 -305.375341) (xy 155.155392 -305.399948) (xy 155.49424 -305.399948) (xy 155.4982 -305.350894)
			(xy 155.509977 -305.30311) (xy 155.529268 -305.257834) (xy 155.555571 -305.216238) (xy 155.588206 -305.179401)
			(xy 155.626327 -305.148276) (xy 155.668948 -305.123669) (xy 155.714964 -305.106217) (xy 155.763183 -305.096373)
			(xy 155.812358 -305.094392) (xy 155.861213 -305.100324) (xy 155.908484 -305.114016) (xy 155.952946 -305.135114)
			(xy 155.993449 -305.16307) (xy 156.028942 -305.197162) (xy 156.058507 -305.236506) (xy 156.081378 -305.280083)
			(xy 156.096962 -305.326764) (xy 156.104857 -305.375341) (xy 156.105352 -305.399948) (xy 156.4442 -305.399948)
			(xy 156.44816 -305.350894) (xy 156.459937 -305.30311) (xy 156.479228 -305.257834) (xy 156.505531 -305.216238)
			(xy 156.538166 -305.179401) (xy 156.576287 -305.148276) (xy 156.618908 -305.123669) (xy 156.664924 -305.106217)
			(xy 156.713143 -305.096373) (xy 156.762318 -305.094392) (xy 156.811173 -305.100324) (xy 156.858444 -305.114016)
			(xy 156.902906 -305.135114) (xy 156.943409 -305.16307) (xy 156.978902 -305.197162) (xy 157.008467 -305.236506)
			(xy 157.031338 -305.280083) (xy 157.046922 -305.326764) (xy 157.054817 -305.375341) (xy 157.055312 -305.399948)
			(xy 157.39416 -305.399948) (xy 157.39812 -305.350894) (xy 157.409897 -305.30311) (xy 157.429188 -305.257834)
			(xy 157.455491 -305.216238) (xy 157.488126 -305.179401) (xy 157.526247 -305.148276) (xy 157.568868 -305.123669)
			(xy 157.614884 -305.106217) (xy 157.663103 -305.096373) (xy 157.712278 -305.094392) (xy 157.761133 -305.100324)
			(xy 157.808404 -305.114016) (xy 157.852866 -305.135114) (xy 157.893369 -305.16307) (xy 157.928862 -305.197162)
			(xy 157.958427 -305.236506) (xy 157.981298 -305.280083) (xy 157.996882 -305.326764) (xy 158.004777 -305.375341)
			(xy 158.005272 -305.399948) (xy 158.34412 -305.399948) (xy 158.34808 -305.350894) (xy 158.359857 -305.30311)
			(xy 158.379148 -305.257834) (xy 158.405451 -305.216238) (xy 158.438086 -305.179401) (xy 158.476207 -305.148276)
			(xy 158.518828 -305.123669) (xy 158.564844 -305.106217) (xy 158.613063 -305.096373) (xy 158.662238 -305.094392)
			(xy 158.711093 -305.100324) (xy 158.758364 -305.114016) (xy 158.802826 -305.135114) (xy 158.843329 -305.16307)
			(xy 158.878822 -305.197162) (xy 158.908387 -305.236506) (xy 158.931258 -305.280083) (xy 158.946842 -305.326764)
			(xy 158.954737 -305.375341) (xy 158.955232 -305.399948) (xy 159.29408 -305.399948) (xy 159.29804 -305.350894)
			(xy 159.309817 -305.30311) (xy 159.329108 -305.257834) (xy 159.355411 -305.216238) (xy 159.388046 -305.179401)
			(xy 159.426167 -305.148276) (xy 159.468788 -305.123669) (xy 159.514804 -305.106217) (xy 159.563023 -305.096373)
			(xy 159.612198 -305.094392) (xy 159.661053 -305.100324) (xy 159.708324 -305.114016) (xy 159.752786 -305.135114)
			(xy 159.793289 -305.16307) (xy 159.828782 -305.197162) (xy 159.858347 -305.236506) (xy 159.881218 -305.280083)
			(xy 159.896802 -305.326764) (xy 159.904697 -305.375341) (xy 159.905192 -305.399948) (xy 160.24404 -305.399948)
			(xy 160.248 -305.350894) (xy 160.259777 -305.30311) (xy 160.279068 -305.257834) (xy 160.305371 -305.216238)
			(xy 160.338006 -305.179401) (xy 160.376127 -305.148276) (xy 160.418748 -305.123669) (xy 160.464764 -305.106217)
			(xy 160.512983 -305.096373) (xy 160.562158 -305.094392) (xy 160.611013 -305.100324) (xy 160.658284 -305.114016)
			(xy 160.702746 -305.135114) (xy 160.743249 -305.16307) (xy 160.778742 -305.197162) (xy 160.808307 -305.236506)
			(xy 160.831178 -305.280083) (xy 160.846762 -305.326764) (xy 160.854657 -305.375341) (xy 160.855152 -305.399948)
			(xy 161.194254 -305.399948) (xy 161.198214 -305.350894) (xy 161.209991 -305.30311) (xy 161.229282 -305.257834)
			(xy 161.255585 -305.216238) (xy 161.28822 -305.179401) (xy 161.326341 -305.148276) (xy 161.368962 -305.123669)
			(xy 161.414978 -305.106217) (xy 161.463197 -305.096373) (xy 161.512372 -305.094392) (xy 161.561227 -305.100324)
			(xy 161.608498 -305.114016) (xy 161.65296 -305.135114) (xy 161.693463 -305.16307) (xy 161.728956 -305.197162)
			(xy 161.758521 -305.236506) (xy 161.781392 -305.280083) (xy 161.796976 -305.326764) (xy 161.804871 -305.375341)
			(xy 161.805366 -305.399948) (xy 161.804871 -305.424555) (xy 161.796976 -305.473132) (xy 161.781392 -305.519813)
			(xy 161.758521 -305.56339) (xy 161.728956 -305.602734) (xy 161.693463 -305.636826) (xy 161.65296 -305.664782)
			(xy 161.608498 -305.68588) (xy 161.561227 -305.699572) (xy 161.512372 -305.705504) (xy 161.463197 -305.703523)
			(xy 161.414978 -305.693679) (xy 161.368962 -305.676227) (xy 161.326341 -305.65162) (xy 161.28822 -305.620495)
			(xy 161.255585 -305.583658) (xy 161.229282 -305.542062) (xy 161.209991 -305.496786) (xy 161.198214 -305.449002)
			(xy 161.194254 -305.399948) (xy 160.855152 -305.399948) (xy 160.854657 -305.424555) (xy 160.846762 -305.473132)
			(xy 160.831178 -305.519813) (xy 160.808307 -305.56339) (xy 160.778742 -305.602734) (xy 160.743249 -305.636826)
			(xy 160.702746 -305.664782) (xy 160.658284 -305.68588) (xy 160.611013 -305.699572) (xy 160.562158 -305.705504)
			(xy 160.512983 -305.703523) (xy 160.464764 -305.693679) (xy 160.418748 -305.676227) (xy 160.376127 -305.65162)
			(xy 160.338006 -305.620495) (xy 160.305371 -305.583658) (xy 160.279068 -305.542062) (xy 160.259777 -305.496786)
			(xy 160.248 -305.449002) (xy 160.24404 -305.399948) (xy 159.905192 -305.399948) (xy 159.904697 -305.424555)
			(xy 159.896802 -305.473132) (xy 159.881218 -305.519813) (xy 159.858347 -305.56339) (xy 159.828782 -305.602734)
			(xy 159.793289 -305.636826) (xy 159.752786 -305.664782) (xy 159.708324 -305.68588) (xy 159.661053 -305.699572)
			(xy 159.612198 -305.705504) (xy 159.563023 -305.703523) (xy 159.514804 -305.693679) (xy 159.468788 -305.676227)
			(xy 159.426167 -305.65162) (xy 159.388046 -305.620495) (xy 159.355411 -305.583658) (xy 159.329108 -305.542062)
			(xy 159.309817 -305.496786) (xy 159.29804 -305.449002) (xy 159.29408 -305.399948) (xy 158.955232 -305.399948)
			(xy 158.954737 -305.424555) (xy 158.946842 -305.473132) (xy 158.931258 -305.519813) (xy 158.908387 -305.56339)
			(xy 158.878822 -305.602734) (xy 158.843329 -305.636826) (xy 158.802826 -305.664782) (xy 158.758364 -305.68588)
			(xy 158.711093 -305.699572) (xy 158.662238 -305.705504) (xy 158.613063 -305.703523) (xy 158.564844 -305.693679)
			(xy 158.518828 -305.676227) (xy 158.476207 -305.65162) (xy 158.438086 -305.620495) (xy 158.405451 -305.583658)
			(xy 158.379148 -305.542062) (xy 158.359857 -305.496786) (xy 158.34808 -305.449002) (xy 158.34412 -305.399948)
			(xy 158.005272 -305.399948) (xy 158.004777 -305.424555) (xy 157.996882 -305.473132) (xy 157.981298 -305.519813)
			(xy 157.958427 -305.56339) (xy 157.928862 -305.602734) (xy 157.893369 -305.636826) (xy 157.852866 -305.664782)
			(xy 157.808404 -305.68588) (xy 157.761133 -305.699572) (xy 157.712278 -305.705504) (xy 157.663103 -305.703523)
			(xy 157.614884 -305.693679) (xy 157.568868 -305.676227) (xy 157.526247 -305.65162) (xy 157.488126 -305.620495)
			(xy 157.455491 -305.583658) (xy 157.429188 -305.542062) (xy 157.409897 -305.496786) (xy 157.39812 -305.449002)
			(xy 157.39416 -305.399948) (xy 157.055312 -305.399948) (xy 157.054817 -305.424555) (xy 157.046922 -305.473132)
			(xy 157.031338 -305.519813) (xy 157.008467 -305.56339) (xy 156.978902 -305.602734) (xy 156.943409 -305.636826)
			(xy 156.902906 -305.664782) (xy 156.858444 -305.68588) (xy 156.811173 -305.699572) (xy 156.762318 -305.705504)
			(xy 156.713143 -305.703523) (xy 156.664924 -305.693679) (xy 156.618908 -305.676227) (xy 156.576287 -305.65162)
			(xy 156.538166 -305.620495) (xy 156.505531 -305.583658) (xy 156.479228 -305.542062) (xy 156.459937 -305.496786)
			(xy 156.44816 -305.449002) (xy 156.4442 -305.399948) (xy 156.105352 -305.399948) (xy 156.104857 -305.424555)
			(xy 156.096962 -305.473132) (xy 156.081378 -305.519813) (xy 156.058507 -305.56339) (xy 156.028942 -305.602734)
			(xy 155.993449 -305.636826) (xy 155.952946 -305.664782) (xy 155.908484 -305.68588) (xy 155.861213 -305.699572)
			(xy 155.812358 -305.705504) (xy 155.763183 -305.703523) (xy 155.714964 -305.693679) (xy 155.668948 -305.676227)
			(xy 155.626327 -305.65162) (xy 155.588206 -305.620495) (xy 155.555571 -305.583658) (xy 155.529268 -305.542062)
			(xy 155.509977 -305.496786) (xy 155.4982 -305.449002) (xy 155.49424 -305.399948) (xy 155.155392 -305.399948)
			(xy 155.154897 -305.424555) (xy 155.147002 -305.473132) (xy 155.131418 -305.519813) (xy 155.108547 -305.56339)
			(xy 155.078982 -305.602734) (xy 155.043489 -305.636826) (xy 155.002986 -305.664782) (xy 154.958524 -305.68588)
			(xy 154.911253 -305.699572) (xy 154.862398 -305.705504) (xy 154.813223 -305.703523) (xy 154.765004 -305.693679)
			(xy 154.718988 -305.676227) (xy 154.676367 -305.65162) (xy 154.638246 -305.620495) (xy 154.605611 -305.583658)
			(xy 154.579308 -305.542062) (xy 154.560017 -305.496786) (xy 154.54824 -305.449002) (xy 154.54428 -305.399948)
			(xy 154.205178 -305.399948) (xy 154.204683 -305.424555) (xy 154.196788 -305.473132) (xy 154.181204 -305.519813)
			(xy 154.158333 -305.56339) (xy 154.128768 -305.602734) (xy 154.093275 -305.636826) (xy 154.052772 -305.664782)
			(xy 154.00831 -305.68588) (xy 153.961039 -305.699572) (xy 153.912184 -305.705504) (xy 153.863009 -305.703523)
			(xy 153.81479 -305.693679) (xy 153.768774 -305.676227) (xy 153.726153 -305.65162) (xy 153.688032 -305.620495)
			(xy 153.655397 -305.583658) (xy 153.629094 -305.542062) (xy 153.609803 -305.496786) (xy 153.598026 -305.449002)
			(xy 153.594066 -305.399948) (xy 153.255218 -305.399948) (xy 153.254723 -305.424555) (xy 153.246828 -305.473132)
			(xy 153.231244 -305.519813) (xy 153.208373 -305.56339) (xy 153.178808 -305.602734) (xy 153.143315 -305.636826)
			(xy 153.102812 -305.664782) (xy 153.05835 -305.68588) (xy 153.011079 -305.699572) (xy 152.962224 -305.705504)
			(xy 152.913049 -305.703523) (xy 152.86483 -305.693679) (xy 152.818814 -305.676227) (xy 152.776193 -305.65162)
			(xy 152.738072 -305.620495) (xy 152.705437 -305.583658) (xy 152.679134 -305.542062) (xy 152.659843 -305.496786)
			(xy 152.648066 -305.449002) (xy 152.644106 -305.399948) (xy 144.26705 -305.399948) (xy 144.264833 -305.415377)
			(xy 144.24948 -305.467683) (xy 144.226839 -305.517271) (xy 144.197371 -305.563132) (xy 144.161676 -305.604333)
			(xy 144.120481 -305.640035) (xy 144.074624 -305.66951) (xy 144.02504 -305.692159) (xy 143.972736 -305.70752)
			(xy 143.918779 -305.715281) (xy 143.864266 -305.715285) (xy 143.810308 -305.70753) (xy 143.758003 -305.692174)
			(xy 143.708415 -305.669531) (xy 143.662555 -305.640062) (xy 143.621356 -305.604365) (xy 143.585656 -305.563169)
			(xy 143.556183 -305.517311) (xy 143.533536 -305.467725) (xy 143.518177 -305.415421) (xy 143.510418 -305.361464)
			(xy 143.510416 -305.306951) (xy 135.153908 -305.306951) (xy 135.153908 -306.052728) (xy 142.790924 -306.052728)
			(xy 142.794995 -305.997106) (xy 142.807121 -305.942669) (xy 142.827044 -305.890578) (xy 142.85434 -305.841943)
			(xy 142.888426 -305.7978) (xy 142.928575 -305.759091) (xy 142.973933 -305.72664) (xy 143.023533 -305.701139)
			(xy 143.076317 -305.683132) (xy 143.13116 -305.673002) (xy 143.186894 -305.670965) (xy 143.242331 -305.677065)
			(xy 143.296288 -305.691171) (xy 143.347617 -305.712983) (xy 143.395223 -305.742037) (xy 143.438091 -305.777712)
			(xy 143.475308 -305.819249) (xy 143.506081 -305.865762) (xy 143.510378 -305.874928) (xy 162.619194 -305.874928)
			(xy 162.623154 -305.825874) (xy 162.634931 -305.77809) (xy 162.654222 -305.732814) (xy 162.680525 -305.691218)
			(xy 162.71316 -305.654381) (xy 162.751281 -305.623256) (xy 162.793902 -305.598649) (xy 162.839918 -305.581197)
			(xy 162.888137 -305.571353) (xy 162.937312 -305.569372) (xy 162.986167 -305.575304) (xy 163.033438 -305.588996)
			(xy 163.0779 -305.610094) (xy 163.118403 -305.63805) (xy 163.153896 -305.672142) (xy 163.183461 -305.711486)
			(xy 163.206332 -305.755063) (xy 163.221916 -305.801744) (xy 163.229811 -305.850321) (xy 163.230306 -305.874928)
			(xy 163.569154 -305.874928) (xy 163.573114 -305.825874) (xy 163.584891 -305.77809) (xy 163.604182 -305.732814)
			(xy 163.630485 -305.691218) (xy 163.66312 -305.654381) (xy 163.701241 -305.623256) (xy 163.743862 -305.598649)
			(xy 163.789878 -305.581197) (xy 163.838097 -305.571353) (xy 163.887272 -305.569372) (xy 163.936127 -305.575304)
			(xy 163.983398 -305.588996) (xy 164.02786 -305.610094) (xy 164.068363 -305.63805) (xy 164.103856 -305.672142)
			(xy 164.133421 -305.711486) (xy 164.156292 -305.755063) (xy 164.171876 -305.801744) (xy 164.179771 -305.850321)
			(xy 164.180266 -305.874928) (xy 164.519114 -305.874928) (xy 164.523074 -305.825874) (xy 164.534851 -305.77809)
			(xy 164.554142 -305.732814) (xy 164.580445 -305.691218) (xy 164.61308 -305.654381) (xy 164.651201 -305.623256)
			(xy 164.693822 -305.598649) (xy 164.739838 -305.581197) (xy 164.788057 -305.571353) (xy 164.837232 -305.569372)
			(xy 164.886087 -305.575304) (xy 164.933358 -305.588996) (xy 164.97782 -305.610094) (xy 165.018323 -305.63805)
			(xy 165.053816 -305.672142) (xy 165.083381 -305.711486) (xy 165.106252 -305.755063) (xy 165.121836 -305.801744)
			(xy 165.129731 -305.850321) (xy 165.130226 -305.874928) (xy 165.469074 -305.874928) (xy 165.473034 -305.825874)
			(xy 165.484811 -305.77809) (xy 165.504102 -305.732814) (xy 165.530405 -305.691218) (xy 165.56304 -305.654381)
			(xy 165.601161 -305.623256) (xy 165.643782 -305.598649) (xy 165.689798 -305.581197) (xy 165.738017 -305.571353)
			(xy 165.787192 -305.569372) (xy 165.836047 -305.575304) (xy 165.883318 -305.588996) (xy 165.92778 -305.610094)
			(xy 165.968283 -305.63805) (xy 166.003776 -305.672142) (xy 166.033341 -305.711486) (xy 166.056212 -305.755063)
			(xy 166.071796 -305.801744) (xy 166.079691 -305.850321) (xy 166.080186 -305.874928) (xy 166.419288 -305.874928)
			(xy 166.423248 -305.825874) (xy 166.435025 -305.77809) (xy 166.454316 -305.732814) (xy 166.480619 -305.691218)
			(xy 166.513254 -305.654381) (xy 166.551375 -305.623256) (xy 166.593996 -305.598649) (xy 166.640012 -305.581197)
			(xy 166.688231 -305.571353) (xy 166.737406 -305.569372) (xy 166.786261 -305.575304) (xy 166.833532 -305.588996)
			(xy 166.877994 -305.610094) (xy 166.918497 -305.63805) (xy 166.95399 -305.672142) (xy 166.983555 -305.711486)
			(xy 167.006426 -305.755063) (xy 167.02201 -305.801744) (xy 167.029905 -305.850321) (xy 167.0304 -305.874928)
			(xy 167.369248 -305.874928) (xy 167.373208 -305.825874) (xy 167.384985 -305.77809) (xy 167.404276 -305.732814)
			(xy 167.430579 -305.691218) (xy 167.463214 -305.654381) (xy 167.501335 -305.623256) (xy 167.543956 -305.598649)
			(xy 167.589972 -305.581197) (xy 167.638191 -305.571353) (xy 167.687366 -305.569372) (xy 167.736221 -305.575304)
			(xy 167.783492 -305.588996) (xy 167.827954 -305.610094) (xy 167.868457 -305.63805) (xy 167.90395 -305.672142)
			(xy 167.933515 -305.711486) (xy 167.956386 -305.755063) (xy 167.97197 -305.801744) (xy 167.979865 -305.850321)
			(xy 167.98036 -305.874928) (xy 168.319208 -305.874928) (xy 168.323168 -305.825874) (xy 168.334945 -305.77809)
			(xy 168.354236 -305.732814) (xy 168.380539 -305.691218) (xy 168.413174 -305.654381) (xy 168.451295 -305.623256)
			(xy 168.493916 -305.598649) (xy 168.539932 -305.581197) (xy 168.588151 -305.571353) (xy 168.637326 -305.569372)
			(xy 168.686181 -305.575304) (xy 168.733452 -305.588996) (xy 168.777914 -305.610094) (xy 168.818417 -305.63805)
			(xy 168.85391 -305.672142) (xy 168.883475 -305.711486) (xy 168.906346 -305.755063) (xy 168.92193 -305.801744)
			(xy 168.929825 -305.850321) (xy 168.93032 -305.874928) (xy 169.269168 -305.874928) (xy 169.273128 -305.825874)
			(xy 169.284905 -305.77809) (xy 169.304196 -305.732814) (xy 169.330499 -305.691218) (xy 169.363134 -305.654381)
			(xy 169.401255 -305.623256) (xy 169.443876 -305.598649) (xy 169.489892 -305.581197) (xy 169.538111 -305.571353)
			(xy 169.587286 -305.569372) (xy 169.636141 -305.575304) (xy 169.683412 -305.588996) (xy 169.727874 -305.610094)
			(xy 169.768377 -305.63805) (xy 169.80387 -305.672142) (xy 169.833435 -305.711486) (xy 169.856306 -305.755063)
			(xy 169.87189 -305.801744) (xy 169.879785 -305.850321) (xy 169.88028 -305.874928) (xy 170.219128 -305.874928)
			(xy 170.223088 -305.825874) (xy 170.234865 -305.77809) (xy 170.254156 -305.732814) (xy 170.280459 -305.691218)
			(xy 170.313094 -305.654381) (xy 170.351215 -305.623256) (xy 170.393836 -305.598649) (xy 170.439852 -305.581197)
			(xy 170.488071 -305.571353) (xy 170.537246 -305.569372) (xy 170.586101 -305.575304) (xy 170.633372 -305.588996)
			(xy 170.677834 -305.610094) (xy 170.718337 -305.63805) (xy 170.75383 -305.672142) (xy 170.783395 -305.711486)
			(xy 170.806266 -305.755063) (xy 170.82185 -305.801744) (xy 170.829745 -305.850321) (xy 170.83024 -305.874928)
			(xy 171.169088 -305.874928) (xy 171.173048 -305.825874) (xy 171.184825 -305.77809) (xy 171.204116 -305.732814)
			(xy 171.230419 -305.691218) (xy 171.263054 -305.654381) (xy 171.301175 -305.623256) (xy 171.343796 -305.598649)
			(xy 171.389812 -305.581197) (xy 171.438031 -305.571353) (xy 171.487206 -305.569372) (xy 171.536061 -305.575304)
			(xy 171.583332 -305.588996) (xy 171.627794 -305.610094) (xy 171.668297 -305.63805) (xy 171.70379 -305.672142)
			(xy 171.733355 -305.711486) (xy 171.756226 -305.755063) (xy 171.77181 -305.801744) (xy 171.779705 -305.850321)
			(xy 171.7802 -305.874928) (xy 172.119048 -305.874928) (xy 172.123008 -305.825874) (xy 172.134785 -305.77809)
			(xy 172.154076 -305.732814) (xy 172.180379 -305.691218) (xy 172.213014 -305.654381) (xy 172.251135 -305.623256)
			(xy 172.293756 -305.598649) (xy 172.339772 -305.581197) (xy 172.387991 -305.571353) (xy 172.437166 -305.569372)
			(xy 172.486021 -305.575304) (xy 172.533292 -305.588996) (xy 172.577754 -305.610094) (xy 172.618257 -305.63805)
			(xy 172.65375 -305.672142) (xy 172.683315 -305.711486) (xy 172.706186 -305.755063) (xy 172.72177 -305.801744)
			(xy 172.729665 -305.850321) (xy 172.73016 -305.874928) (xy 173.069262 -305.874928) (xy 173.073222 -305.825874)
			(xy 173.084999 -305.77809) (xy 173.10429 -305.732814) (xy 173.130593 -305.691218) (xy 173.163228 -305.654381)
			(xy 173.201349 -305.623256) (xy 173.24397 -305.598649) (xy 173.289986 -305.581197) (xy 173.338205 -305.571353)
			(xy 173.38738 -305.569372) (xy 173.436235 -305.575304) (xy 173.483506 -305.588996) (xy 173.527968 -305.610094)
			(xy 173.568471 -305.63805) (xy 173.603964 -305.672142) (xy 173.633529 -305.711486) (xy 173.6564 -305.755063)
			(xy 173.671984 -305.801744) (xy 173.679879 -305.850321) (xy 173.680374 -305.874928) (xy 174.019222 -305.874928)
			(xy 174.023182 -305.825874) (xy 174.034959 -305.77809) (xy 174.05425 -305.732814) (xy 174.080553 -305.691218)
			(xy 174.113188 -305.654381) (xy 174.151309 -305.623256) (xy 174.19393 -305.598649) (xy 174.239946 -305.581197)
			(xy 174.288165 -305.571353) (xy 174.33734 -305.569372) (xy 174.386195 -305.575304) (xy 174.433466 -305.588996)
			(xy 174.477928 -305.610094) (xy 174.518431 -305.63805) (xy 174.553924 -305.672142) (xy 174.583489 -305.711486)
			(xy 174.60636 -305.755063) (xy 174.621944 -305.801744) (xy 174.629839 -305.850321) (xy 174.630334 -305.874928)
			(xy 175.919142 -305.874928) (xy 175.923102 -305.825874) (xy 175.934879 -305.77809) (xy 175.95417 -305.732814)
			(xy 175.980473 -305.691218) (xy 176.013108 -305.654381) (xy 176.051229 -305.623256) (xy 176.09385 -305.598649)
			(xy 176.139866 -305.581197) (xy 176.188085 -305.571353) (xy 176.23726 -305.569372) (xy 176.286115 -305.575304)
			(xy 176.333386 -305.588996) (xy 176.377848 -305.610094) (xy 176.418351 -305.63805) (xy 176.453844 -305.672142)
			(xy 176.483409 -305.711486) (xy 176.50628 -305.755063) (xy 176.521864 -305.801744) (xy 176.529759 -305.850321)
			(xy 176.530254 -305.874928) (xy 176.529759 -305.899535) (xy 176.521864 -305.948112) (xy 176.50628 -305.994793)
			(xy 176.483409 -306.03837) (xy 176.453844 -306.077714) (xy 176.418351 -306.111806) (xy 176.377848 -306.139762)
			(xy 176.333386 -306.16086) (xy 176.286115 -306.174552) (xy 176.23726 -306.180484) (xy 176.188085 -306.178503)
			(xy 176.139866 -306.168659) (xy 176.09385 -306.151207) (xy 176.051229 -306.1266) (xy 176.013108 -306.095475)
			(xy 175.980473 -306.058638) (xy 175.95417 -306.017042) (xy 175.934879 -305.971766) (xy 175.923102 -305.923982)
			(xy 175.919142 -305.874928) (xy 174.630334 -305.874928) (xy 174.629839 -305.899535) (xy 174.621944 -305.948112)
			(xy 174.60636 -305.994793) (xy 174.583489 -306.03837) (xy 174.553924 -306.077714) (xy 174.518431 -306.111806)
			(xy 174.477928 -306.139762) (xy 174.433466 -306.16086) (xy 174.386195 -306.174552) (xy 174.33734 -306.180484)
			(xy 174.288165 -306.178503) (xy 174.239946 -306.168659) (xy 174.19393 -306.151207) (xy 174.151309 -306.1266)
			(xy 174.113188 -306.095475) (xy 174.080553 -306.058638) (xy 174.05425 -306.017042) (xy 174.034959 -305.971766)
			(xy 174.023182 -305.923982) (xy 174.019222 -305.874928) (xy 173.680374 -305.874928) (xy 173.679879 -305.899535)
			(xy 173.671984 -305.948112) (xy 173.6564 -305.994793) (xy 173.633529 -306.03837) (xy 173.603964 -306.077714)
			(xy 173.568471 -306.111806) (xy 173.527968 -306.139762) (xy 173.483506 -306.16086) (xy 173.436235 -306.174552)
			(xy 173.38738 -306.180484) (xy 173.338205 -306.178503) (xy 173.289986 -306.168659) (xy 173.24397 -306.151207)
			(xy 173.201349 -306.1266) (xy 173.163228 -306.095475) (xy 173.130593 -306.058638) (xy 173.10429 -306.017042)
			(xy 173.084999 -305.971766) (xy 173.073222 -305.923982) (xy 173.069262 -305.874928) (xy 172.73016 -305.874928)
			(xy 172.729665 -305.899535) (xy 172.72177 -305.948112) (xy 172.706186 -305.994793) (xy 172.683315 -306.03837)
			(xy 172.65375 -306.077714) (xy 172.618257 -306.111806) (xy 172.577754 -306.139762) (xy 172.533292 -306.16086)
			(xy 172.486021 -306.174552) (xy 172.437166 -306.180484) (xy 172.387991 -306.178503) (xy 172.339772 -306.168659)
			(xy 172.293756 -306.151207) (xy 172.251135 -306.1266) (xy 172.213014 -306.095475) (xy 172.180379 -306.058638)
			(xy 172.154076 -306.017042) (xy 172.134785 -305.971766) (xy 172.123008 -305.923982) (xy 172.119048 -305.874928)
			(xy 171.7802 -305.874928) (xy 171.779705 -305.899535) (xy 171.77181 -305.948112) (xy 171.756226 -305.994793)
			(xy 171.733355 -306.03837) (xy 171.70379 -306.077714) (xy 171.668297 -306.111806) (xy 171.627794 -306.139762)
			(xy 171.583332 -306.16086) (xy 171.536061 -306.174552) (xy 171.487206 -306.180484) (xy 171.438031 -306.178503)
			(xy 171.389812 -306.168659) (xy 171.343796 -306.151207) (xy 171.301175 -306.1266) (xy 171.263054 -306.095475)
			(xy 171.230419 -306.058638) (xy 171.204116 -306.017042) (xy 171.184825 -305.971766) (xy 171.173048 -305.923982)
			(xy 171.169088 -305.874928) (xy 170.83024 -305.874928) (xy 170.829745 -305.899535) (xy 170.82185 -305.948112)
			(xy 170.806266 -305.994793) (xy 170.783395 -306.03837) (xy 170.75383 -306.077714) (xy 170.718337 -306.111806)
			(xy 170.677834 -306.139762) (xy 170.633372 -306.16086) (xy 170.586101 -306.174552) (xy 170.537246 -306.180484)
			(xy 170.488071 -306.178503) (xy 170.439852 -306.168659) (xy 170.393836 -306.151207) (xy 170.351215 -306.1266)
			(xy 170.313094 -306.095475) (xy 170.280459 -306.058638) (xy 170.254156 -306.017042) (xy 170.234865 -305.971766)
			(xy 170.223088 -305.923982) (xy 170.219128 -305.874928) (xy 169.88028 -305.874928) (xy 169.879785 -305.899535)
			(xy 169.87189 -305.948112) (xy 169.856306 -305.994793) (xy 169.833435 -306.03837) (xy 169.80387 -306.077714)
			(xy 169.768377 -306.111806) (xy 169.727874 -306.139762) (xy 169.683412 -306.16086) (xy 169.636141 -306.174552)
			(xy 169.587286 -306.180484) (xy 169.538111 -306.178503) (xy 169.489892 -306.168659) (xy 169.443876 -306.151207)
			(xy 169.401255 -306.1266) (xy 169.363134 -306.095475) (xy 169.330499 -306.058638) (xy 169.304196 -306.017042)
			(xy 169.284905 -305.971766) (xy 169.273128 -305.923982) (xy 169.269168 -305.874928) (xy 168.93032 -305.874928)
			(xy 168.929825 -305.899535) (xy 168.92193 -305.948112) (xy 168.906346 -305.994793) (xy 168.883475 -306.03837)
			(xy 168.85391 -306.077714) (xy 168.818417 -306.111806) (xy 168.777914 -306.139762) (xy 168.733452 -306.16086)
			(xy 168.686181 -306.174552) (xy 168.637326 -306.180484) (xy 168.588151 -306.178503) (xy 168.539932 -306.168659)
			(xy 168.493916 -306.151207) (xy 168.451295 -306.1266) (xy 168.413174 -306.095475) (xy 168.380539 -306.058638)
			(xy 168.354236 -306.017042) (xy 168.334945 -305.971766) (xy 168.323168 -305.923982) (xy 168.319208 -305.874928)
			(xy 167.98036 -305.874928) (xy 167.979865 -305.899535) (xy 167.97197 -305.948112) (xy 167.956386 -305.994793)
			(xy 167.933515 -306.03837) (xy 167.90395 -306.077714) (xy 167.868457 -306.111806) (xy 167.827954 -306.139762)
			(xy 167.783492 -306.16086) (xy 167.736221 -306.174552) (xy 167.687366 -306.180484) (xy 167.638191 -306.178503)
			(xy 167.589972 -306.168659) (xy 167.543956 -306.151207) (xy 167.501335 -306.1266) (xy 167.463214 -306.095475)
			(xy 167.430579 -306.058638) (xy 167.404276 -306.017042) (xy 167.384985 -305.971766) (xy 167.373208 -305.923982)
			(xy 167.369248 -305.874928) (xy 167.0304 -305.874928) (xy 167.029905 -305.899535) (xy 167.02201 -305.948112)
			(xy 167.006426 -305.994793) (xy 166.983555 -306.03837) (xy 166.95399 -306.077714) (xy 166.918497 -306.111806)
			(xy 166.877994 -306.139762) (xy 166.833532 -306.16086) (xy 166.786261 -306.174552) (xy 166.737406 -306.180484)
			(xy 166.688231 -306.178503) (xy 166.640012 -306.168659) (xy 166.593996 -306.151207) (xy 166.551375 -306.1266)
			(xy 166.513254 -306.095475) (xy 166.480619 -306.058638) (xy 166.454316 -306.017042) (xy 166.435025 -305.971766)
			(xy 166.423248 -305.923982) (xy 166.419288 -305.874928) (xy 166.080186 -305.874928) (xy 166.079691 -305.899535)
			(xy 166.071796 -305.948112) (xy 166.056212 -305.994793) (xy 166.033341 -306.03837) (xy 166.003776 -306.077714)
			(xy 165.968283 -306.111806) (xy 165.92778 -306.139762) (xy 165.883318 -306.16086) (xy 165.836047 -306.174552)
			(xy 165.787192 -306.180484) (xy 165.738017 -306.178503) (xy 165.689798 -306.168659) (xy 165.643782 -306.151207)
			(xy 165.601161 -306.1266) (xy 165.56304 -306.095475) (xy 165.530405 -306.058638) (xy 165.504102 -306.017042)
			(xy 165.484811 -305.971766) (xy 165.473034 -305.923982) (xy 165.469074 -305.874928) (xy 165.130226 -305.874928)
			(xy 165.129731 -305.899535) (xy 165.121836 -305.948112) (xy 165.106252 -305.994793) (xy 165.083381 -306.03837)
			(xy 165.053816 -306.077714) (xy 165.018323 -306.111806) (xy 164.97782 -306.139762) (xy 164.933358 -306.16086)
			(xy 164.886087 -306.174552) (xy 164.837232 -306.180484) (xy 164.788057 -306.178503) (xy 164.739838 -306.168659)
			(xy 164.693822 -306.151207) (xy 164.651201 -306.1266) (xy 164.61308 -306.095475) (xy 164.580445 -306.058638)
			(xy 164.554142 -306.017042) (xy 164.534851 -305.971766) (xy 164.523074 -305.923982) (xy 164.519114 -305.874928)
			(xy 164.180266 -305.874928) (xy 164.179771 -305.899535) (xy 164.171876 -305.948112) (xy 164.156292 -305.994793)
			(xy 164.133421 -306.03837) (xy 164.103856 -306.077714) (xy 164.068363 -306.111806) (xy 164.02786 -306.139762)
			(xy 163.983398 -306.16086) (xy 163.936127 -306.174552) (xy 163.887272 -306.180484) (xy 163.838097 -306.178503)
			(xy 163.789878 -306.168659) (xy 163.743862 -306.151207) (xy 163.701241 -306.1266) (xy 163.66312 -306.095475)
			(xy 163.630485 -306.058638) (xy 163.604182 -306.017042) (xy 163.584891 -305.971766) (xy 163.573114 -305.923982)
			(xy 163.569154 -305.874928) (xy 163.230306 -305.874928) (xy 163.229811 -305.899535) (xy 163.221916 -305.948112)
			(xy 163.206332 -305.994793) (xy 163.183461 -306.03837) (xy 163.153896 -306.077714) (xy 163.118403 -306.111806)
			(xy 163.0779 -306.139762) (xy 163.033438 -306.16086) (xy 162.986167 -306.174552) (xy 162.937312 -306.180484)
			(xy 162.888137 -306.178503) (xy 162.839918 -306.168659) (xy 162.793902 -306.151207) (xy 162.751281 -306.1266)
			(xy 162.71316 -306.095475) (xy 162.680525 -306.058638) (xy 162.654222 -306.017042) (xy 162.634931 -305.971766)
			(xy 162.623154 -305.923982) (xy 162.619194 -305.874928) (xy 143.510378 -305.874928) (xy 143.529753 -305.916259)
			(xy 143.545821 -305.969666) (xy 143.553941 -306.024842) (xy 143.55445 -306.052728) (xy 143.553941 -306.080614)
			(xy 143.545821 -306.13579) (xy 143.529753 -306.189197) (xy 143.506081 -306.239694) (xy 143.475308 -306.286207)
			(xy 143.438091 -306.327744) (xy 143.411153 -306.350162) (xy 151.693892 -306.350162) (xy 151.697852 -306.301108)
			(xy 151.709629 -306.253324) (xy 151.72892 -306.208048) (xy 151.755223 -306.166452) (xy 151.787858 -306.129615)
			(xy 151.825979 -306.09849) (xy 151.8686 -306.073883) (xy 151.914616 -306.056431) (xy 151.962835 -306.046587)
			(xy 152.01201 -306.044606) (xy 152.060865 -306.050538) (xy 152.108136 -306.06423) (xy 152.152598 -306.085328)
			(xy 152.193101 -306.113284) (xy 152.228594 -306.147376) (xy 152.258159 -306.18672) (xy 152.28103 -306.230297)
			(xy 152.296614 -306.276978) (xy 152.304509 -306.325555) (xy 152.304999 -306.349908) (xy 152.644106 -306.349908)
			(xy 152.648066 -306.300854) (xy 152.659843 -306.25307) (xy 152.679134 -306.207794) (xy 152.705437 -306.166198)
			(xy 152.738072 -306.129361) (xy 152.776193 -306.098236) (xy 152.818814 -306.073629) (xy 152.86483 -306.056177)
			(xy 152.913049 -306.046333) (xy 152.962224 -306.044352) (xy 153.011079 -306.050284) (xy 153.05835 -306.063976)
			(xy 153.102812 -306.085074) (xy 153.143315 -306.11303) (xy 153.178808 -306.147122) (xy 153.208373 -306.186466)
			(xy 153.231244 -306.230043) (xy 153.246828 -306.276724) (xy 153.254723 -306.325301) (xy 153.255218 -306.349908)
			(xy 153.594066 -306.349908) (xy 153.598026 -306.300854) (xy 153.609803 -306.25307) (xy 153.629094 -306.207794)
			(xy 153.655397 -306.166198) (xy 153.688032 -306.129361) (xy 153.726153 -306.098236) (xy 153.768774 -306.073629)
			(xy 153.81479 -306.056177) (xy 153.863009 -306.046333) (xy 153.912184 -306.044352) (xy 153.961039 -306.050284)
			(xy 154.00831 -306.063976) (xy 154.052772 -306.085074) (xy 154.093275 -306.11303) (xy 154.128768 -306.147122)
			(xy 154.158333 -306.186466) (xy 154.181204 -306.230043) (xy 154.196788 -306.276724) (xy 154.204683 -306.325301)
			(xy 154.205178 -306.349908) (xy 154.54428 -306.349908) (xy 154.54824 -306.300854) (xy 154.560017 -306.25307)
			(xy 154.579308 -306.207794) (xy 154.605611 -306.166198) (xy 154.638246 -306.129361) (xy 154.676367 -306.098236)
			(xy 154.718988 -306.073629) (xy 154.765004 -306.056177) (xy 154.813223 -306.046333) (xy 154.862398 -306.044352)
			(xy 154.911253 -306.050284) (xy 154.958524 -306.063976) (xy 155.002986 -306.085074) (xy 155.043489 -306.11303)
			(xy 155.078982 -306.147122) (xy 155.108547 -306.186466) (xy 155.131418 -306.230043) (xy 155.147002 -306.276724)
			(xy 155.154897 -306.325301) (xy 155.155392 -306.349908) (xy 155.49424 -306.349908) (xy 155.4982 -306.300854)
			(xy 155.509977 -306.25307) (xy 155.529268 -306.207794) (xy 155.555571 -306.166198) (xy 155.588206 -306.129361)
			(xy 155.626327 -306.098236) (xy 155.668948 -306.073629) (xy 155.714964 -306.056177) (xy 155.763183 -306.046333)
			(xy 155.812358 -306.044352) (xy 155.861213 -306.050284) (xy 155.908484 -306.063976) (xy 155.952946 -306.085074)
			(xy 155.993449 -306.11303) (xy 156.028942 -306.147122) (xy 156.058507 -306.186466) (xy 156.081378 -306.230043)
			(xy 156.096962 -306.276724) (xy 156.104857 -306.325301) (xy 156.105352 -306.349908) (xy 156.4442 -306.349908)
			(xy 156.44816 -306.300854) (xy 156.459937 -306.25307) (xy 156.479228 -306.207794) (xy 156.505531 -306.166198)
			(xy 156.538166 -306.129361) (xy 156.576287 -306.098236) (xy 156.618908 -306.073629) (xy 156.664924 -306.056177)
			(xy 156.713143 -306.046333) (xy 156.762318 -306.044352) (xy 156.811173 -306.050284) (xy 156.858444 -306.063976)
			(xy 156.902906 -306.085074) (xy 156.943409 -306.11303) (xy 156.978902 -306.147122) (xy 157.008467 -306.186466)
			(xy 157.031338 -306.230043) (xy 157.046922 -306.276724) (xy 157.054817 -306.325301) (xy 157.055312 -306.349908)
			(xy 157.39416 -306.349908) (xy 157.39812 -306.300854) (xy 157.409897 -306.25307) (xy 157.429188 -306.207794)
			(xy 157.455491 -306.166198) (xy 157.488126 -306.129361) (xy 157.526247 -306.098236) (xy 157.568868 -306.073629)
			(xy 157.614884 -306.056177) (xy 157.663103 -306.046333) (xy 157.712278 -306.044352) (xy 157.761133 -306.050284)
			(xy 157.808404 -306.063976) (xy 157.852866 -306.085074) (xy 157.893369 -306.11303) (xy 157.928862 -306.147122)
			(xy 157.958427 -306.186466) (xy 157.981298 -306.230043) (xy 157.996882 -306.276724) (xy 158.004777 -306.325301)
			(xy 158.005272 -306.349908) (xy 158.34412 -306.349908) (xy 158.34808 -306.300854) (xy 158.359857 -306.25307)
			(xy 158.379148 -306.207794) (xy 158.405451 -306.166198) (xy 158.438086 -306.129361) (xy 158.476207 -306.098236)
			(xy 158.518828 -306.073629) (xy 158.564844 -306.056177) (xy 158.613063 -306.046333) (xy 158.662238 -306.044352)
			(xy 158.711093 -306.050284) (xy 158.758364 -306.063976) (xy 158.802826 -306.085074) (xy 158.843329 -306.11303)
			(xy 158.878822 -306.147122) (xy 158.908387 -306.186466) (xy 158.931258 -306.230043) (xy 158.946842 -306.276724)
			(xy 158.954737 -306.325301) (xy 158.955232 -306.349908) (xy 159.29408 -306.349908) (xy 159.29804 -306.300854)
			(xy 159.309817 -306.25307) (xy 159.329108 -306.207794) (xy 159.355411 -306.166198) (xy 159.388046 -306.129361)
			(xy 159.426167 -306.098236) (xy 159.468788 -306.073629) (xy 159.514804 -306.056177) (xy 159.563023 -306.046333)
			(xy 159.612198 -306.044352) (xy 159.661053 -306.050284) (xy 159.708324 -306.063976) (xy 159.752786 -306.085074)
			(xy 159.793289 -306.11303) (xy 159.828782 -306.147122) (xy 159.858347 -306.186466) (xy 159.881218 -306.230043)
			(xy 159.896802 -306.276724) (xy 159.904697 -306.325301) (xy 159.905192 -306.349908) (xy 160.24404 -306.349908)
			(xy 160.248 -306.300854) (xy 160.259777 -306.25307) (xy 160.279068 -306.207794) (xy 160.305371 -306.166198)
			(xy 160.338006 -306.129361) (xy 160.376127 -306.098236) (xy 160.418748 -306.073629) (xy 160.464764 -306.056177)
			(xy 160.512983 -306.046333) (xy 160.562158 -306.044352) (xy 160.611013 -306.050284) (xy 160.658284 -306.063976)
			(xy 160.702746 -306.085074) (xy 160.743249 -306.11303) (xy 160.778742 -306.147122) (xy 160.808307 -306.186466)
			(xy 160.831178 -306.230043) (xy 160.846762 -306.276724) (xy 160.854657 -306.325301) (xy 160.855152 -306.349908)
			(xy 161.194254 -306.349908) (xy 161.198214 -306.300854) (xy 161.209991 -306.25307) (xy 161.229282 -306.207794)
			(xy 161.255585 -306.166198) (xy 161.28822 -306.129361) (xy 161.326341 -306.098236) (xy 161.368962 -306.073629)
			(xy 161.414978 -306.056177) (xy 161.463197 -306.046333) (xy 161.512372 -306.044352) (xy 161.561227 -306.050284)
			(xy 161.608498 -306.063976) (xy 161.65296 -306.085074) (xy 161.693463 -306.11303) (xy 161.728956 -306.147122)
			(xy 161.758521 -306.186466) (xy 161.781392 -306.230043) (xy 161.796976 -306.276724) (xy 161.804871 -306.325301)
			(xy 161.805366 -306.349908) (xy 161.804871 -306.374515) (xy 161.796976 -306.423092) (xy 161.781392 -306.469773)
			(xy 161.758521 -306.51335) (xy 161.728956 -306.552694) (xy 161.693463 -306.586786) (xy 161.65296 -306.614742)
			(xy 161.608498 -306.63584) (xy 161.561227 -306.649532) (xy 161.512372 -306.655464) (xy 161.463197 -306.653483)
			(xy 161.414978 -306.643639) (xy 161.368962 -306.626187) (xy 161.326341 -306.60158) (xy 161.28822 -306.570455)
			(xy 161.255585 -306.533618) (xy 161.229282 -306.492022) (xy 161.209991 -306.446746) (xy 161.198214 -306.398962)
			(xy 161.194254 -306.349908) (xy 160.855152 -306.349908) (xy 160.854657 -306.374515) (xy 160.846762 -306.423092)
			(xy 160.831178 -306.469773) (xy 160.808307 -306.51335) (xy 160.778742 -306.552694) (xy 160.743249 -306.586786)
			(xy 160.702746 -306.614742) (xy 160.658284 -306.63584) (xy 160.611013 -306.649532) (xy 160.562158 -306.655464)
			(xy 160.512983 -306.653483) (xy 160.464764 -306.643639) (xy 160.418748 -306.626187) (xy 160.376127 -306.60158)
			(xy 160.338006 -306.570455) (xy 160.305371 -306.533618) (xy 160.279068 -306.492022) (xy 160.259777 -306.446746)
			(xy 160.248 -306.398962) (xy 160.24404 -306.349908) (xy 159.905192 -306.349908) (xy 159.904697 -306.374515)
			(xy 159.896802 -306.423092) (xy 159.881218 -306.469773) (xy 159.858347 -306.51335) (xy 159.828782 -306.552694)
			(xy 159.793289 -306.586786) (xy 159.752786 -306.614742) (xy 159.708324 -306.63584) (xy 159.661053 -306.649532)
			(xy 159.612198 -306.655464) (xy 159.563023 -306.653483) (xy 159.514804 -306.643639) (xy 159.468788 -306.626187)
			(xy 159.426167 -306.60158) (xy 159.388046 -306.570455) (xy 159.355411 -306.533618) (xy 159.329108 -306.492022)
			(xy 159.309817 -306.446746) (xy 159.29804 -306.398962) (xy 159.29408 -306.349908) (xy 158.955232 -306.349908)
			(xy 158.954737 -306.374515) (xy 158.946842 -306.423092) (xy 158.931258 -306.469773) (xy 158.908387 -306.51335)
			(xy 158.878822 -306.552694) (xy 158.843329 -306.586786) (xy 158.802826 -306.614742) (xy 158.758364 -306.63584)
			(xy 158.711093 -306.649532) (xy 158.662238 -306.655464) (xy 158.613063 -306.653483) (xy 158.564844 -306.643639)
			(xy 158.518828 -306.626187) (xy 158.476207 -306.60158) (xy 158.438086 -306.570455) (xy 158.405451 -306.533618)
			(xy 158.379148 -306.492022) (xy 158.359857 -306.446746) (xy 158.34808 -306.398962) (xy 158.34412 -306.349908)
			(xy 158.005272 -306.349908) (xy 158.004777 -306.374515) (xy 157.996882 -306.423092) (xy 157.981298 -306.469773)
			(xy 157.958427 -306.51335) (xy 157.928862 -306.552694) (xy 157.893369 -306.586786) (xy 157.852866 -306.614742)
			(xy 157.808404 -306.63584) (xy 157.761133 -306.649532) (xy 157.712278 -306.655464) (xy 157.663103 -306.653483)
			(xy 157.614884 -306.643639) (xy 157.568868 -306.626187) (xy 157.526247 -306.60158) (xy 157.488126 -306.570455)
			(xy 157.455491 -306.533618) (xy 157.429188 -306.492022) (xy 157.409897 -306.446746) (xy 157.39812 -306.398962)
			(xy 157.39416 -306.349908) (xy 157.055312 -306.349908) (xy 157.054817 -306.374515) (xy 157.046922 -306.423092)
			(xy 157.031338 -306.469773) (xy 157.008467 -306.51335) (xy 156.978902 -306.552694) (xy 156.943409 -306.586786)
			(xy 156.902906 -306.614742) (xy 156.858444 -306.63584) (xy 156.811173 -306.649532) (xy 156.762318 -306.655464)
			(xy 156.713143 -306.653483) (xy 156.664924 -306.643639) (xy 156.618908 -306.626187) (xy 156.576287 -306.60158)
			(xy 156.538166 -306.570455) (xy 156.505531 -306.533618) (xy 156.479228 -306.492022) (xy 156.459937 -306.446746)
			(xy 156.44816 -306.398962) (xy 156.4442 -306.349908) (xy 156.105352 -306.349908) (xy 156.104857 -306.374515)
			(xy 156.096962 -306.423092) (xy 156.081378 -306.469773) (xy 156.058507 -306.51335) (xy 156.028942 -306.552694)
			(xy 155.993449 -306.586786) (xy 155.952946 -306.614742) (xy 155.908484 -306.63584) (xy 155.861213 -306.649532)
			(xy 155.812358 -306.655464) (xy 155.763183 -306.653483) (xy 155.714964 -306.643639) (xy 155.668948 -306.626187)
			(xy 155.626327 -306.60158) (xy 155.588206 -306.570455) (xy 155.555571 -306.533618) (xy 155.529268 -306.492022)
			(xy 155.509977 -306.446746) (xy 155.4982 -306.398962) (xy 155.49424 -306.349908) (xy 155.155392 -306.349908)
			(xy 155.154897 -306.374515) (xy 155.147002 -306.423092) (xy 155.131418 -306.469773) (xy 155.108547 -306.51335)
			(xy 155.078982 -306.552694) (xy 155.043489 -306.586786) (xy 155.002986 -306.614742) (xy 154.958524 -306.63584)
			(xy 154.911253 -306.649532) (xy 154.862398 -306.655464) (xy 154.813223 -306.653483) (xy 154.765004 -306.643639)
			(xy 154.718988 -306.626187) (xy 154.676367 -306.60158) (xy 154.638246 -306.570455) (xy 154.605611 -306.533618)
			(xy 154.579308 -306.492022) (xy 154.560017 -306.446746) (xy 154.54824 -306.398962) (xy 154.54428 -306.349908)
			(xy 154.205178 -306.349908) (xy 154.204683 -306.374515) (xy 154.196788 -306.423092) (xy 154.181204 -306.469773)
			(xy 154.158333 -306.51335) (xy 154.128768 -306.552694) (xy 154.093275 -306.586786) (xy 154.052772 -306.614742)
			(xy 154.00831 -306.63584) (xy 153.961039 -306.649532) (xy 153.912184 -306.655464) (xy 153.863009 -306.653483)
			(xy 153.81479 -306.643639) (xy 153.768774 -306.626187) (xy 153.726153 -306.60158) (xy 153.688032 -306.570455)
			(xy 153.655397 -306.533618) (xy 153.629094 -306.492022) (xy 153.609803 -306.446746) (xy 153.598026 -306.398962)
			(xy 153.594066 -306.349908) (xy 153.255218 -306.349908) (xy 153.254723 -306.374515) (xy 153.246828 -306.423092)
			(xy 153.231244 -306.469773) (xy 153.208373 -306.51335) (xy 153.178808 -306.552694) (xy 153.143315 -306.586786)
			(xy 153.102812 -306.614742) (xy 153.05835 -306.63584) (xy 153.011079 -306.649532) (xy 152.962224 -306.655464)
			(xy 152.913049 -306.653483) (xy 152.86483 -306.643639) (xy 152.818814 -306.626187) (xy 152.776193 -306.60158)
			(xy 152.738072 -306.570455) (xy 152.705437 -306.533618) (xy 152.679134 -306.492022) (xy 152.659843 -306.446746)
			(xy 152.648066 -306.398962) (xy 152.644106 -306.349908) (xy 152.304999 -306.349908) (xy 152.305004 -306.350162)
			(xy 152.304509 -306.374769) (xy 152.296614 -306.423346) (xy 152.28103 -306.470027) (xy 152.258159 -306.513604)
			(xy 152.228594 -306.552948) (xy 152.193101 -306.58704) (xy 152.152598 -306.614996) (xy 152.108136 -306.636094)
			(xy 152.060865 -306.649786) (xy 152.01201 -306.655718) (xy 151.962835 -306.653737) (xy 151.914616 -306.643893)
			(xy 151.8686 -306.626441) (xy 151.825979 -306.601834) (xy 151.787858 -306.570709) (xy 151.755223 -306.533872)
			(xy 151.72892 -306.492276) (xy 151.709629 -306.447) (xy 151.697852 -306.399216) (xy 151.693892 -306.350162)
			(xy 143.411153 -306.350162) (xy 143.395223 -306.363419) (xy 143.347617 -306.392473) (xy 143.296288 -306.414285)
			(xy 143.242331 -306.428391) (xy 143.186894 -306.434491) (xy 143.13116 -306.432454) (xy 143.076317 -306.422324)
			(xy 143.023533 -306.404317) (xy 142.973933 -306.378816) (xy 142.928575 -306.346365) (xy 142.888426 -306.307656)
			(xy 142.85434 -306.263513) (xy 142.827044 -306.214878) (xy 142.807121 -306.162787) (xy 142.794995 -306.10835)
			(xy 142.790924 -306.052728) (xy 135.153908 -306.052728) (xy 135.153908 -306.765198) (xy 145.825462 -306.765198)
			(xy 145.829533 -306.709576) (xy 145.841659 -306.655139) (xy 145.861582 -306.603048) (xy 145.888878 -306.554413)
			(xy 145.922964 -306.51027) (xy 145.963113 -306.471561) (xy 146.008471 -306.43911) (xy 146.058071 -306.413609)
			(xy 146.110855 -306.395602) (xy 146.165698 -306.385472) (xy 146.221432 -306.383435) (xy 146.276869 -306.389535)
			(xy 146.330826 -306.403641) (xy 146.382155 -306.425453) (xy 146.429761 -306.454507) (xy 146.472629 -306.490182)
			(xy 146.509846 -306.531719) (xy 146.540619 -306.578232) (xy 146.564291 -306.628729) (xy 146.580359 -306.682136)
			(xy 146.588479 -306.737312) (xy 146.588988 -306.765198) (xy 146.588479 -306.793084) (xy 146.583799 -306.824888)
			(xy 162.619194 -306.824888) (xy 162.623154 -306.775834) (xy 162.634931 -306.72805) (xy 162.654222 -306.682774)
			(xy 162.680525 -306.641178) (xy 162.71316 -306.604341) (xy 162.751281 -306.573216) (xy 162.793902 -306.548609)
			(xy 162.839918 -306.531157) (xy 162.888137 -306.521313) (xy 162.937312 -306.519332) (xy 162.986167 -306.525264)
			(xy 163.033438 -306.538956) (xy 163.0779 -306.560054) (xy 163.118403 -306.58801) (xy 163.153896 -306.622102)
			(xy 163.183461 -306.661446) (xy 163.206332 -306.705023) (xy 163.221916 -306.751704) (xy 163.229811 -306.800281)
			(xy 163.230306 -306.824888) (xy 163.569154 -306.824888) (xy 163.573114 -306.775834) (xy 163.584891 -306.72805)
			(xy 163.604182 -306.682774) (xy 163.630485 -306.641178) (xy 163.66312 -306.604341) (xy 163.701241 -306.573216)
			(xy 163.743862 -306.548609) (xy 163.789878 -306.531157) (xy 163.838097 -306.521313) (xy 163.887272 -306.519332)
			(xy 163.936127 -306.525264) (xy 163.983398 -306.538956) (xy 164.02786 -306.560054) (xy 164.068363 -306.58801)
			(xy 164.103856 -306.622102) (xy 164.133421 -306.661446) (xy 164.156292 -306.705023) (xy 164.171876 -306.751704)
			(xy 164.179771 -306.800281) (xy 164.180266 -306.824888) (xy 164.519114 -306.824888) (xy 164.523074 -306.775834)
			(xy 164.534851 -306.72805) (xy 164.554142 -306.682774) (xy 164.580445 -306.641178) (xy 164.61308 -306.604341)
			(xy 164.651201 -306.573216) (xy 164.693822 -306.548609) (xy 164.739838 -306.531157) (xy 164.788057 -306.521313)
			(xy 164.837232 -306.519332) (xy 164.886087 -306.525264) (xy 164.933358 -306.538956) (xy 164.97782 -306.560054)
			(xy 165.018323 -306.58801) (xy 165.053816 -306.622102) (xy 165.083381 -306.661446) (xy 165.106252 -306.705023)
			(xy 165.121836 -306.751704) (xy 165.129731 -306.800281) (xy 165.130226 -306.824888) (xy 165.469074 -306.824888)
			(xy 165.473034 -306.775834) (xy 165.484811 -306.72805) (xy 165.504102 -306.682774) (xy 165.530405 -306.641178)
			(xy 165.56304 -306.604341) (xy 165.601161 -306.573216) (xy 165.643782 -306.548609) (xy 165.689798 -306.531157)
			(xy 165.738017 -306.521313) (xy 165.787192 -306.519332) (xy 165.836047 -306.525264) (xy 165.883318 -306.538956)
			(xy 165.92778 -306.560054) (xy 165.968283 -306.58801) (xy 166.003776 -306.622102) (xy 166.033341 -306.661446)
			(xy 166.056212 -306.705023) (xy 166.071796 -306.751704) (xy 166.079691 -306.800281) (xy 166.080186 -306.824888)
			(xy 166.419288 -306.824888) (xy 166.423248 -306.775834) (xy 166.435025 -306.72805) (xy 166.454316 -306.682774)
			(xy 166.480619 -306.641178) (xy 166.513254 -306.604341) (xy 166.551375 -306.573216) (xy 166.593996 -306.548609)
			(xy 166.640012 -306.531157) (xy 166.688231 -306.521313) (xy 166.737406 -306.519332) (xy 166.786261 -306.525264)
			(xy 166.833532 -306.538956) (xy 166.877994 -306.560054) (xy 166.918497 -306.58801) (xy 166.95399 -306.622102)
			(xy 166.983555 -306.661446) (xy 167.006426 -306.705023) (xy 167.02201 -306.751704) (xy 167.029905 -306.800281)
			(xy 167.0304 -306.824888) (xy 167.369248 -306.824888) (xy 167.373208 -306.775834) (xy 167.384985 -306.72805)
			(xy 167.404276 -306.682774) (xy 167.430579 -306.641178) (xy 167.463214 -306.604341) (xy 167.501335 -306.573216)
			(xy 167.543956 -306.548609) (xy 167.589972 -306.531157) (xy 167.638191 -306.521313) (xy 167.687366 -306.519332)
			(xy 167.736221 -306.525264) (xy 167.783492 -306.538956) (xy 167.827954 -306.560054) (xy 167.868457 -306.58801)
			(xy 167.90395 -306.622102) (xy 167.933515 -306.661446) (xy 167.956386 -306.705023) (xy 167.97197 -306.751704)
			(xy 167.979865 -306.800281) (xy 167.98036 -306.824888) (xy 168.319208 -306.824888) (xy 168.323168 -306.775834)
			(xy 168.334945 -306.72805) (xy 168.354236 -306.682774) (xy 168.380539 -306.641178) (xy 168.413174 -306.604341)
			(xy 168.451295 -306.573216) (xy 168.493916 -306.548609) (xy 168.539932 -306.531157) (xy 168.588151 -306.521313)
			(xy 168.637326 -306.519332) (xy 168.686181 -306.525264) (xy 168.733452 -306.538956) (xy 168.777914 -306.560054)
			(xy 168.818417 -306.58801) (xy 168.85391 -306.622102) (xy 168.883475 -306.661446) (xy 168.906346 -306.705023)
			(xy 168.92193 -306.751704) (xy 168.929825 -306.800281) (xy 168.93032 -306.824888) (xy 169.269168 -306.824888)
			(xy 169.273128 -306.775834) (xy 169.284905 -306.72805) (xy 169.304196 -306.682774) (xy 169.330499 -306.641178)
			(xy 169.363134 -306.604341) (xy 169.401255 -306.573216) (xy 169.443876 -306.548609) (xy 169.489892 -306.531157)
			(xy 169.538111 -306.521313) (xy 169.587286 -306.519332) (xy 169.636141 -306.525264) (xy 169.683412 -306.538956)
			(xy 169.727874 -306.560054) (xy 169.768377 -306.58801) (xy 169.80387 -306.622102) (xy 169.833435 -306.661446)
			(xy 169.856306 -306.705023) (xy 169.87189 -306.751704) (xy 169.879785 -306.800281) (xy 169.88028 -306.824888)
			(xy 170.219128 -306.824888) (xy 170.223088 -306.775834) (xy 170.234865 -306.72805) (xy 170.254156 -306.682774)
			(xy 170.280459 -306.641178) (xy 170.313094 -306.604341) (xy 170.351215 -306.573216) (xy 170.393836 -306.548609)
			(xy 170.439852 -306.531157) (xy 170.488071 -306.521313) (xy 170.537246 -306.519332) (xy 170.586101 -306.525264)
			(xy 170.633372 -306.538956) (xy 170.677834 -306.560054) (xy 170.718337 -306.58801) (xy 170.75383 -306.622102)
			(xy 170.783395 -306.661446) (xy 170.806266 -306.705023) (xy 170.82185 -306.751704) (xy 170.829745 -306.800281)
			(xy 170.83024 -306.824888) (xy 171.169088 -306.824888) (xy 171.173048 -306.775834) (xy 171.184825 -306.72805)
			(xy 171.204116 -306.682774) (xy 171.230419 -306.641178) (xy 171.263054 -306.604341) (xy 171.301175 -306.573216)
			(xy 171.343796 -306.548609) (xy 171.389812 -306.531157) (xy 171.438031 -306.521313) (xy 171.487206 -306.519332)
			(xy 171.536061 -306.525264) (xy 171.583332 -306.538956) (xy 171.627794 -306.560054) (xy 171.668297 -306.58801)
			(xy 171.70379 -306.622102) (xy 171.733355 -306.661446) (xy 171.756226 -306.705023) (xy 171.77181 -306.751704)
			(xy 171.779705 -306.800281) (xy 171.7802 -306.824888) (xy 172.119048 -306.824888) (xy 172.123008 -306.775834)
			(xy 172.134785 -306.72805) (xy 172.154076 -306.682774) (xy 172.180379 -306.641178) (xy 172.213014 -306.604341)
			(xy 172.251135 -306.573216) (xy 172.293756 -306.548609) (xy 172.339772 -306.531157) (xy 172.387991 -306.521313)
			(xy 172.437166 -306.519332) (xy 172.486021 -306.525264) (xy 172.533292 -306.538956) (xy 172.577754 -306.560054)
			(xy 172.618257 -306.58801) (xy 172.65375 -306.622102) (xy 172.683315 -306.661446) (xy 172.706186 -306.705023)
			(xy 172.72177 -306.751704) (xy 172.729665 -306.800281) (xy 172.73016 -306.824888) (xy 173.069262 -306.824888)
			(xy 173.073222 -306.775834) (xy 173.084999 -306.72805) (xy 173.10429 -306.682774) (xy 173.130593 -306.641178)
			(xy 173.163228 -306.604341) (xy 173.201349 -306.573216) (xy 173.24397 -306.548609) (xy 173.289986 -306.531157)
			(xy 173.338205 -306.521313) (xy 173.38738 -306.519332) (xy 173.436235 -306.525264) (xy 173.483506 -306.538956)
			(xy 173.527968 -306.560054) (xy 173.568471 -306.58801) (xy 173.603964 -306.622102) (xy 173.633529 -306.661446)
			(xy 173.6564 -306.705023) (xy 173.671984 -306.751704) (xy 173.679879 -306.800281) (xy 173.680374 -306.824888)
			(xy 174.019222 -306.824888) (xy 174.023182 -306.775834) (xy 174.034959 -306.72805) (xy 174.05425 -306.682774)
			(xy 174.080553 -306.641178) (xy 174.113188 -306.604341) (xy 174.151309 -306.573216) (xy 174.19393 -306.548609)
			(xy 174.239946 -306.531157) (xy 174.288165 -306.521313) (xy 174.33734 -306.519332) (xy 174.386195 -306.525264)
			(xy 174.433466 -306.538956) (xy 174.477928 -306.560054) (xy 174.518431 -306.58801) (xy 174.553924 -306.622102)
			(xy 174.583489 -306.661446) (xy 174.60636 -306.705023) (xy 174.621944 -306.751704) (xy 174.629839 -306.800281)
			(xy 174.630334 -306.824888) (xy 175.919142 -306.824888) (xy 175.923102 -306.775834) (xy 175.934879 -306.72805)
			(xy 175.95417 -306.682774) (xy 175.980473 -306.641178) (xy 176.013108 -306.604341) (xy 176.051229 -306.573216)
			(xy 176.09385 -306.548609) (xy 176.139866 -306.531157) (xy 176.188085 -306.521313) (xy 176.23726 -306.519332)
			(xy 176.286115 -306.525264) (xy 176.333386 -306.538956) (xy 176.377848 -306.560054) (xy 176.418351 -306.58801)
			(xy 176.453844 -306.622102) (xy 176.483409 -306.661446) (xy 176.50628 -306.705023) (xy 176.521864 -306.751704)
			(xy 176.529759 -306.800281) (xy 176.530254 -306.824888) (xy 176.529759 -306.849495) (xy 176.521864 -306.898072)
			(xy 176.50628 -306.944753) (xy 176.483409 -306.98833) (xy 176.453844 -307.027674) (xy 176.418351 -307.061766)
			(xy 176.377848 -307.089722) (xy 176.333386 -307.11082) (xy 176.286115 -307.124512) (xy 176.23726 -307.130444)
			(xy 176.188085 -307.128463) (xy 176.139866 -307.118619) (xy 176.09385 -307.101167) (xy 176.051229 -307.07656)
			(xy 176.013108 -307.045435) (xy 175.980473 -307.008598) (xy 175.95417 -306.967002) (xy 175.934879 -306.921726)
			(xy 175.923102 -306.873942) (xy 175.919142 -306.824888) (xy 174.630334 -306.824888) (xy 174.629839 -306.849495)
			(xy 174.621944 -306.898072) (xy 174.60636 -306.944753) (xy 174.583489 -306.98833) (xy 174.553924 -307.027674)
			(xy 174.518431 -307.061766) (xy 174.477928 -307.089722) (xy 174.433466 -307.11082) (xy 174.386195 -307.124512)
			(xy 174.33734 -307.130444) (xy 174.288165 -307.128463) (xy 174.239946 -307.118619) (xy 174.19393 -307.101167)
			(xy 174.151309 -307.07656) (xy 174.113188 -307.045435) (xy 174.080553 -307.008598) (xy 174.05425 -306.967002)
			(xy 174.034959 -306.921726) (xy 174.023182 -306.873942) (xy 174.019222 -306.824888) (xy 173.680374 -306.824888)
			(xy 173.679879 -306.849495) (xy 173.671984 -306.898072) (xy 173.6564 -306.944753) (xy 173.633529 -306.98833)
			(xy 173.603964 -307.027674) (xy 173.568471 -307.061766) (xy 173.527968 -307.089722) (xy 173.483506 -307.11082)
			(xy 173.436235 -307.124512) (xy 173.38738 -307.130444) (xy 173.338205 -307.128463) (xy 173.289986 -307.118619)
			(xy 173.24397 -307.101167) (xy 173.201349 -307.07656) (xy 173.163228 -307.045435) (xy 173.130593 -307.008598)
			(xy 173.10429 -306.967002) (xy 173.084999 -306.921726) (xy 173.073222 -306.873942) (xy 173.069262 -306.824888)
			(xy 172.73016 -306.824888) (xy 172.729665 -306.849495) (xy 172.72177 -306.898072) (xy 172.706186 -306.944753)
			(xy 172.683315 -306.98833) (xy 172.65375 -307.027674) (xy 172.618257 -307.061766) (xy 172.577754 -307.089722)
			(xy 172.533292 -307.11082) (xy 172.486021 -307.124512) (xy 172.437166 -307.130444) (xy 172.387991 -307.128463)
			(xy 172.339772 -307.118619) (xy 172.293756 -307.101167) (xy 172.251135 -307.07656) (xy 172.213014 -307.045435)
			(xy 172.180379 -307.008598) (xy 172.154076 -306.967002) (xy 172.134785 -306.921726) (xy 172.123008 -306.873942)
			(xy 172.119048 -306.824888) (xy 171.7802 -306.824888) (xy 171.779705 -306.849495) (xy 171.77181 -306.898072)
			(xy 171.756226 -306.944753) (xy 171.733355 -306.98833) (xy 171.70379 -307.027674) (xy 171.668297 -307.061766)
			(xy 171.627794 -307.089722) (xy 171.583332 -307.11082) (xy 171.536061 -307.124512) (xy 171.487206 -307.130444)
			(xy 171.438031 -307.128463) (xy 171.389812 -307.118619) (xy 171.343796 -307.101167) (xy 171.301175 -307.07656)
			(xy 171.263054 -307.045435) (xy 171.230419 -307.008598) (xy 171.204116 -306.967002) (xy 171.184825 -306.921726)
			(xy 171.173048 -306.873942) (xy 171.169088 -306.824888) (xy 170.83024 -306.824888) (xy 170.829745 -306.849495)
			(xy 170.82185 -306.898072) (xy 170.806266 -306.944753) (xy 170.783395 -306.98833) (xy 170.75383 -307.027674)
			(xy 170.718337 -307.061766) (xy 170.677834 -307.089722) (xy 170.633372 -307.11082) (xy 170.586101 -307.124512)
			(xy 170.537246 -307.130444) (xy 170.488071 -307.128463) (xy 170.439852 -307.118619) (xy 170.393836 -307.101167)
			(xy 170.351215 -307.07656) (xy 170.313094 -307.045435) (xy 170.280459 -307.008598) (xy 170.254156 -306.967002)
			(xy 170.234865 -306.921726) (xy 170.223088 -306.873942) (xy 170.219128 -306.824888) (xy 169.88028 -306.824888)
			(xy 169.879785 -306.849495) (xy 169.87189 -306.898072) (xy 169.856306 -306.944753) (xy 169.833435 -306.98833)
			(xy 169.80387 -307.027674) (xy 169.768377 -307.061766) (xy 169.727874 -307.089722) (xy 169.683412 -307.11082)
			(xy 169.636141 -307.124512) (xy 169.587286 -307.130444) (xy 169.538111 -307.128463) (xy 169.489892 -307.118619)
			(xy 169.443876 -307.101167) (xy 169.401255 -307.07656) (xy 169.363134 -307.045435) (xy 169.330499 -307.008598)
			(xy 169.304196 -306.967002) (xy 169.284905 -306.921726) (xy 169.273128 -306.873942) (xy 169.269168 -306.824888)
			(xy 168.93032 -306.824888) (xy 168.929825 -306.849495) (xy 168.92193 -306.898072) (xy 168.906346 -306.944753)
			(xy 168.883475 -306.98833) (xy 168.85391 -307.027674) (xy 168.818417 -307.061766) (xy 168.777914 -307.089722)
			(xy 168.733452 -307.11082) (xy 168.686181 -307.124512) (xy 168.637326 -307.130444) (xy 168.588151 -307.128463)
			(xy 168.539932 -307.118619) (xy 168.493916 -307.101167) (xy 168.451295 -307.07656) (xy 168.413174 -307.045435)
			(xy 168.380539 -307.008598) (xy 168.354236 -306.967002) (xy 168.334945 -306.921726) (xy 168.323168 -306.873942)
			(xy 168.319208 -306.824888) (xy 167.98036 -306.824888) (xy 167.979865 -306.849495) (xy 167.97197 -306.898072)
			(xy 167.956386 -306.944753) (xy 167.933515 -306.98833) (xy 167.90395 -307.027674) (xy 167.868457 -307.061766)
			(xy 167.827954 -307.089722) (xy 167.783492 -307.11082) (xy 167.736221 -307.124512) (xy 167.687366 -307.130444)
			(xy 167.638191 -307.128463) (xy 167.589972 -307.118619) (xy 167.543956 -307.101167) (xy 167.501335 -307.07656)
			(xy 167.463214 -307.045435) (xy 167.430579 -307.008598) (xy 167.404276 -306.967002) (xy 167.384985 -306.921726)
			(xy 167.373208 -306.873942) (xy 167.369248 -306.824888) (xy 167.0304 -306.824888) (xy 167.029905 -306.849495)
			(xy 167.02201 -306.898072) (xy 167.006426 -306.944753) (xy 166.983555 -306.98833) (xy 166.95399 -307.027674)
			(xy 166.918497 -307.061766) (xy 166.877994 -307.089722) (xy 166.833532 -307.11082) (xy 166.786261 -307.124512)
			(xy 166.737406 -307.130444) (xy 166.688231 -307.128463) (xy 166.640012 -307.118619) (xy 166.593996 -307.101167)
			(xy 166.551375 -307.07656) (xy 166.513254 -307.045435) (xy 166.480619 -307.008598) (xy 166.454316 -306.967002)
			(xy 166.435025 -306.921726) (xy 166.423248 -306.873942) (xy 166.419288 -306.824888) (xy 166.080186 -306.824888)
			(xy 166.079691 -306.849495) (xy 166.071796 -306.898072) (xy 166.056212 -306.944753) (xy 166.033341 -306.98833)
			(xy 166.003776 -307.027674) (xy 165.968283 -307.061766) (xy 165.92778 -307.089722) (xy 165.883318 -307.11082)
			(xy 165.836047 -307.124512) (xy 165.787192 -307.130444) (xy 165.738017 -307.128463) (xy 165.689798 -307.118619)
			(xy 165.643782 -307.101167) (xy 165.601161 -307.07656) (xy 165.56304 -307.045435) (xy 165.530405 -307.008598)
			(xy 165.504102 -306.967002) (xy 165.484811 -306.921726) (xy 165.473034 -306.873942) (xy 165.469074 -306.824888)
			(xy 165.130226 -306.824888) (xy 165.129731 -306.849495) (xy 165.121836 -306.898072) (xy 165.106252 -306.944753)
			(xy 165.083381 -306.98833) (xy 165.053816 -307.027674) (xy 165.018323 -307.061766) (xy 164.97782 -307.089722)
			(xy 164.933358 -307.11082) (xy 164.886087 -307.124512) (xy 164.837232 -307.130444) (xy 164.788057 -307.128463)
			(xy 164.739838 -307.118619) (xy 164.693822 -307.101167) (xy 164.651201 -307.07656) (xy 164.61308 -307.045435)
			(xy 164.580445 -307.008598) (xy 164.554142 -306.967002) (xy 164.534851 -306.921726) (xy 164.523074 -306.873942)
			(xy 164.519114 -306.824888) (xy 164.180266 -306.824888) (xy 164.179771 -306.849495) (xy 164.171876 -306.898072)
			(xy 164.156292 -306.944753) (xy 164.133421 -306.98833) (xy 164.103856 -307.027674) (xy 164.068363 -307.061766)
			(xy 164.02786 -307.089722) (xy 163.983398 -307.11082) (xy 163.936127 -307.124512) (xy 163.887272 -307.130444)
			(xy 163.838097 -307.128463) (xy 163.789878 -307.118619) (xy 163.743862 -307.101167) (xy 163.701241 -307.07656)
			(xy 163.66312 -307.045435) (xy 163.630485 -307.008598) (xy 163.604182 -306.967002) (xy 163.584891 -306.921726)
			(xy 163.573114 -306.873942) (xy 163.569154 -306.824888) (xy 163.230306 -306.824888) (xy 163.229811 -306.849495)
			(xy 163.221916 -306.898072) (xy 163.206332 -306.944753) (xy 163.183461 -306.98833) (xy 163.153896 -307.027674)
			(xy 163.118403 -307.061766) (xy 163.0779 -307.089722) (xy 163.033438 -307.11082) (xy 162.986167 -307.124512)
			(xy 162.937312 -307.130444) (xy 162.888137 -307.128463) (xy 162.839918 -307.118619) (xy 162.793902 -307.101167)
			(xy 162.751281 -307.07656) (xy 162.71316 -307.045435) (xy 162.680525 -307.008598) (xy 162.654222 -306.967002)
			(xy 162.634931 -306.921726) (xy 162.623154 -306.873942) (xy 162.619194 -306.824888) (xy 146.583799 -306.824888)
			(xy 146.580359 -306.84826) (xy 146.564291 -306.901667) (xy 146.540619 -306.952164) (xy 146.509846 -306.998677)
			(xy 146.472629 -307.040214) (xy 146.429761 -307.075889) (xy 146.382155 -307.104943) (xy 146.330826 -307.126755)
			(xy 146.276869 -307.140861) (xy 146.221432 -307.146961) (xy 146.165698 -307.144924) (xy 146.110855 -307.134794)
			(xy 146.058071 -307.116787) (xy 146.008471 -307.091286) (xy 145.963113 -307.058835) (xy 145.922964 -307.020126)
			(xy 145.888878 -306.975983) (xy 145.861582 -306.927348) (xy 145.841659 -306.875257) (xy 145.829533 -306.82082)
			(xy 145.825462 -306.765198) (xy 135.153908 -306.765198) (xy 135.153908 -307.240178) (xy 147.960078 -307.240178)
			(xy 147.964149 -307.184556) (xy 147.976275 -307.130119) (xy 147.996198 -307.078028) (xy 148.023494 -307.029393)
			(xy 148.05758 -306.98525) (xy 148.097729 -306.946541) (xy 148.143087 -306.91409) (xy 148.192687 -306.888589)
			(xy 148.245471 -306.870582) (xy 148.300314 -306.860452) (xy 148.356048 -306.858415) (xy 148.411485 -306.864515)
			(xy 148.465442 -306.878621) (xy 148.516771 -306.900433) (xy 148.564377 -306.929487) (xy 148.607245 -306.965162)
			(xy 148.644462 -307.006699) (xy 148.675235 -307.053212) (xy 148.698907 -307.103709) (xy 148.714975 -307.157116)
			(xy 148.723095 -307.212292) (xy 148.723604 -307.240178) (xy 148.723095 -307.268064) (xy 148.718415 -307.299868)
			(xy 152.644106 -307.299868) (xy 152.648066 -307.250814) (xy 152.659843 -307.20303) (xy 152.679134 -307.157754)
			(xy 152.705437 -307.116158) (xy 152.738072 -307.079321) (xy 152.776193 -307.048196) (xy 152.818814 -307.023589)
			(xy 152.86483 -307.006137) (xy 152.913049 -306.996293) (xy 152.962224 -306.994312) (xy 153.011079 -307.000244)
			(xy 153.05835 -307.013936) (xy 153.102812 -307.035034) (xy 153.143315 -307.06299) (xy 153.178808 -307.097082)
			(xy 153.208373 -307.136426) (xy 153.231244 -307.180003) (xy 153.246828 -307.226684) (xy 153.254723 -307.275261)
			(xy 153.255218 -307.299868) (xy 153.594066 -307.299868) (xy 153.598026 -307.250814) (xy 153.609803 -307.20303)
			(xy 153.629094 -307.157754) (xy 153.655397 -307.116158) (xy 153.688032 -307.079321) (xy 153.726153 -307.048196)
			(xy 153.768774 -307.023589) (xy 153.81479 -307.006137) (xy 153.863009 -306.996293) (xy 153.912184 -306.994312)
			(xy 153.961039 -307.000244) (xy 154.00831 -307.013936) (xy 154.052772 -307.035034) (xy 154.093275 -307.06299)
			(xy 154.128768 -307.097082) (xy 154.158333 -307.136426) (xy 154.181204 -307.180003) (xy 154.196788 -307.226684)
			(xy 154.204683 -307.275261) (xy 154.205178 -307.299868) (xy 154.54428 -307.299868) (xy 154.54824 -307.250814)
			(xy 154.560017 -307.20303) (xy 154.579308 -307.157754) (xy 154.605611 -307.116158) (xy 154.638246 -307.079321)
			(xy 154.676367 -307.048196) (xy 154.718988 -307.023589) (xy 154.765004 -307.006137) (xy 154.813223 -306.996293)
			(xy 154.862398 -306.994312) (xy 154.911253 -307.000244) (xy 154.958524 -307.013936) (xy 155.002986 -307.035034)
			(xy 155.043489 -307.06299) (xy 155.078982 -307.097082) (xy 155.108547 -307.136426) (xy 155.131418 -307.180003)
			(xy 155.147002 -307.226684) (xy 155.154897 -307.275261) (xy 155.155392 -307.299868) (xy 155.49424 -307.299868)
			(xy 155.4982 -307.250814) (xy 155.509977 -307.20303) (xy 155.529268 -307.157754) (xy 155.555571 -307.116158)
			(xy 155.588206 -307.079321) (xy 155.626327 -307.048196) (xy 155.668948 -307.023589) (xy 155.714964 -307.006137)
			(xy 155.763183 -306.996293) (xy 155.812358 -306.994312) (xy 155.861213 -307.000244) (xy 155.908484 -307.013936)
			(xy 155.952946 -307.035034) (xy 155.993449 -307.06299) (xy 156.028942 -307.097082) (xy 156.058507 -307.136426)
			(xy 156.081378 -307.180003) (xy 156.096962 -307.226684) (xy 156.104857 -307.275261) (xy 156.105352 -307.299868)
			(xy 156.4442 -307.299868) (xy 156.44816 -307.250814) (xy 156.459937 -307.20303) (xy 156.479228 -307.157754)
			(xy 156.505531 -307.116158) (xy 156.538166 -307.079321) (xy 156.576287 -307.048196) (xy 156.618908 -307.023589)
			(xy 156.664924 -307.006137) (xy 156.713143 -306.996293) (xy 156.762318 -306.994312) (xy 156.811173 -307.000244)
			(xy 156.858444 -307.013936) (xy 156.902906 -307.035034) (xy 156.943409 -307.06299) (xy 156.978902 -307.097082)
			(xy 157.008467 -307.136426) (xy 157.031338 -307.180003) (xy 157.046922 -307.226684) (xy 157.054817 -307.275261)
			(xy 157.055312 -307.299868) (xy 157.39416 -307.299868) (xy 157.39812 -307.250814) (xy 157.409897 -307.20303)
			(xy 157.429188 -307.157754) (xy 157.455491 -307.116158) (xy 157.488126 -307.079321) (xy 157.526247 -307.048196)
			(xy 157.568868 -307.023589) (xy 157.614884 -307.006137) (xy 157.663103 -306.996293) (xy 157.712278 -306.994312)
			(xy 157.761133 -307.000244) (xy 157.808404 -307.013936) (xy 157.852866 -307.035034) (xy 157.893369 -307.06299)
			(xy 157.928862 -307.097082) (xy 157.958427 -307.136426) (xy 157.981298 -307.180003) (xy 157.996882 -307.226684)
			(xy 158.004777 -307.275261) (xy 158.005272 -307.299868) (xy 158.34412 -307.299868) (xy 158.34808 -307.250814)
			(xy 158.359857 -307.20303) (xy 158.379148 -307.157754) (xy 158.405451 -307.116158) (xy 158.438086 -307.079321)
			(xy 158.476207 -307.048196) (xy 158.518828 -307.023589) (xy 158.564844 -307.006137) (xy 158.613063 -306.996293)
			(xy 158.662238 -306.994312) (xy 158.711093 -307.000244) (xy 158.758364 -307.013936) (xy 158.802826 -307.035034)
			(xy 158.843329 -307.06299) (xy 158.878822 -307.097082) (xy 158.908387 -307.136426) (xy 158.931258 -307.180003)
			(xy 158.946842 -307.226684) (xy 158.954737 -307.275261) (xy 158.955232 -307.299868) (xy 159.29408 -307.299868)
			(xy 159.29804 -307.250814) (xy 159.309817 -307.20303) (xy 159.329108 -307.157754) (xy 159.355411 -307.116158)
			(xy 159.388046 -307.079321) (xy 159.426167 -307.048196) (xy 159.468788 -307.023589) (xy 159.514804 -307.006137)
			(xy 159.563023 -306.996293) (xy 159.612198 -306.994312) (xy 159.661053 -307.000244) (xy 159.708324 -307.013936)
			(xy 159.752786 -307.035034) (xy 159.793289 -307.06299) (xy 159.828782 -307.097082) (xy 159.858347 -307.136426)
			(xy 159.881218 -307.180003) (xy 159.896802 -307.226684) (xy 159.904697 -307.275261) (xy 159.905192 -307.299868)
			(xy 160.24404 -307.299868) (xy 160.248 -307.250814) (xy 160.259777 -307.20303) (xy 160.279068 -307.157754)
			(xy 160.305371 -307.116158) (xy 160.338006 -307.079321) (xy 160.376127 -307.048196) (xy 160.418748 -307.023589)
			(xy 160.464764 -307.006137) (xy 160.512983 -306.996293) (xy 160.562158 -306.994312) (xy 160.611013 -307.000244)
			(xy 160.658284 -307.013936) (xy 160.702746 -307.035034) (xy 160.743249 -307.06299) (xy 160.778742 -307.097082)
			(xy 160.808307 -307.136426) (xy 160.831178 -307.180003) (xy 160.846762 -307.226684) (xy 160.854657 -307.275261)
			(xy 160.855152 -307.299868) (xy 161.194254 -307.299868) (xy 161.198214 -307.250814) (xy 161.209991 -307.20303)
			(xy 161.229282 -307.157754) (xy 161.255585 -307.116158) (xy 161.28822 -307.079321) (xy 161.326341 -307.048196)
			(xy 161.368962 -307.023589) (xy 161.414978 -307.006137) (xy 161.463197 -306.996293) (xy 161.512372 -306.994312)
			(xy 161.561227 -307.000244) (xy 161.608498 -307.013936) (xy 161.65296 -307.035034) (xy 161.693463 -307.06299)
			(xy 161.728956 -307.097082) (xy 161.758521 -307.136426) (xy 161.781392 -307.180003) (xy 161.796976 -307.226684)
			(xy 161.804871 -307.275261) (xy 161.805366 -307.299868) (xy 161.804871 -307.324475) (xy 161.796976 -307.373052)
			(xy 161.781392 -307.419733) (xy 161.758521 -307.46331) (xy 161.728956 -307.502654) (xy 161.693463 -307.536746)
			(xy 161.65296 -307.564702) (xy 161.608498 -307.5858) (xy 161.561227 -307.599492) (xy 161.512372 -307.605424)
			(xy 161.463197 -307.603443) (xy 161.414978 -307.593599) (xy 161.368962 -307.576147) (xy 161.326341 -307.55154)
			(xy 161.28822 -307.520415) (xy 161.255585 -307.483578) (xy 161.229282 -307.441982) (xy 161.209991 -307.396706)
			(xy 161.198214 -307.348922) (xy 161.194254 -307.299868) (xy 160.855152 -307.299868) (xy 160.854657 -307.324475)
			(xy 160.846762 -307.373052) (xy 160.831178 -307.419733) (xy 160.808307 -307.46331) (xy 160.778742 -307.502654)
			(xy 160.743249 -307.536746) (xy 160.702746 -307.564702) (xy 160.658284 -307.5858) (xy 160.611013 -307.599492)
			(xy 160.562158 -307.605424) (xy 160.512983 -307.603443) (xy 160.464764 -307.593599) (xy 160.418748 -307.576147)
			(xy 160.376127 -307.55154) (xy 160.338006 -307.520415) (xy 160.305371 -307.483578) (xy 160.279068 -307.441982)
			(xy 160.259777 -307.396706) (xy 160.248 -307.348922) (xy 160.24404 -307.299868) (xy 159.905192 -307.299868)
			(xy 159.904697 -307.324475) (xy 159.896802 -307.373052) (xy 159.881218 -307.419733) (xy 159.858347 -307.46331)
			(xy 159.828782 -307.502654) (xy 159.793289 -307.536746) (xy 159.752786 -307.564702) (xy 159.708324 -307.5858)
			(xy 159.661053 -307.599492) (xy 159.612198 -307.605424) (xy 159.563023 -307.603443) (xy 159.514804 -307.593599)
			(xy 159.468788 -307.576147) (xy 159.426167 -307.55154) (xy 159.388046 -307.520415) (xy 159.355411 -307.483578)
			(xy 159.329108 -307.441982) (xy 159.309817 -307.396706) (xy 159.29804 -307.348922) (xy 159.29408 -307.299868)
			(xy 158.955232 -307.299868) (xy 158.954737 -307.324475) (xy 158.946842 -307.373052) (xy 158.931258 -307.419733)
			(xy 158.908387 -307.46331) (xy 158.878822 -307.502654) (xy 158.843329 -307.536746) (xy 158.802826 -307.564702)
			(xy 158.758364 -307.5858) (xy 158.711093 -307.599492) (xy 158.662238 -307.605424) (xy 158.613063 -307.603443)
			(xy 158.564844 -307.593599) (xy 158.518828 -307.576147) (xy 158.476207 -307.55154) (xy 158.438086 -307.520415)
			(xy 158.405451 -307.483578) (xy 158.379148 -307.441982) (xy 158.359857 -307.396706) (xy 158.34808 -307.348922)
			(xy 158.34412 -307.299868) (xy 158.005272 -307.299868) (xy 158.004777 -307.324475) (xy 157.996882 -307.373052)
			(xy 157.981298 -307.419733) (xy 157.958427 -307.46331) (xy 157.928862 -307.502654) (xy 157.893369 -307.536746)
			(xy 157.852866 -307.564702) (xy 157.808404 -307.5858) (xy 157.761133 -307.599492) (xy 157.712278 -307.605424)
			(xy 157.663103 -307.603443) (xy 157.614884 -307.593599) (xy 157.568868 -307.576147) (xy 157.526247 -307.55154)
			(xy 157.488126 -307.520415) (xy 157.455491 -307.483578) (xy 157.429188 -307.441982) (xy 157.409897 -307.396706)
			(xy 157.39812 -307.348922) (xy 157.39416 -307.299868) (xy 157.055312 -307.299868) (xy 157.054817 -307.324475)
			(xy 157.046922 -307.373052) (xy 157.031338 -307.419733) (xy 157.008467 -307.46331) (xy 156.978902 -307.502654)
			(xy 156.943409 -307.536746) (xy 156.902906 -307.564702) (xy 156.858444 -307.5858) (xy 156.811173 -307.599492)
			(xy 156.762318 -307.605424) (xy 156.713143 -307.603443) (xy 156.664924 -307.593599) (xy 156.618908 -307.576147)
			(xy 156.576287 -307.55154) (xy 156.538166 -307.520415) (xy 156.505531 -307.483578) (xy 156.479228 -307.441982)
			(xy 156.459937 -307.396706) (xy 156.44816 -307.348922) (xy 156.4442 -307.299868) (xy 156.105352 -307.299868)
			(xy 156.104857 -307.324475) (xy 156.096962 -307.373052) (xy 156.081378 -307.419733) (xy 156.058507 -307.46331)
			(xy 156.028942 -307.502654) (xy 155.993449 -307.536746) (xy 155.952946 -307.564702) (xy 155.908484 -307.5858)
			(xy 155.861213 -307.599492) (xy 155.812358 -307.605424) (xy 155.763183 -307.603443) (xy 155.714964 -307.593599)
			(xy 155.668948 -307.576147) (xy 155.626327 -307.55154) (xy 155.588206 -307.520415) (xy 155.555571 -307.483578)
			(xy 155.529268 -307.441982) (xy 155.509977 -307.396706) (xy 155.4982 -307.348922) (xy 155.49424 -307.299868)
			(xy 155.155392 -307.299868) (xy 155.154897 -307.324475) (xy 155.147002 -307.373052) (xy 155.131418 -307.419733)
			(xy 155.108547 -307.46331) (xy 155.078982 -307.502654) (xy 155.043489 -307.536746) (xy 155.002986 -307.564702)
			(xy 154.958524 -307.5858) (xy 154.911253 -307.599492) (xy 154.862398 -307.605424) (xy 154.813223 -307.603443)
			(xy 154.765004 -307.593599) (xy 154.718988 -307.576147) (xy 154.676367 -307.55154) (xy 154.638246 -307.520415)
			(xy 154.605611 -307.483578) (xy 154.579308 -307.441982) (xy 154.560017 -307.396706) (xy 154.54824 -307.348922)
			(xy 154.54428 -307.299868) (xy 154.205178 -307.299868) (xy 154.204683 -307.324475) (xy 154.196788 -307.373052)
			(xy 154.181204 -307.419733) (xy 154.158333 -307.46331) (xy 154.128768 -307.502654) (xy 154.093275 -307.536746)
			(xy 154.052772 -307.564702) (xy 154.00831 -307.5858) (xy 153.961039 -307.599492) (xy 153.912184 -307.605424)
			(xy 153.863009 -307.603443) (xy 153.81479 -307.593599) (xy 153.768774 -307.576147) (xy 153.726153 -307.55154)
			(xy 153.688032 -307.520415) (xy 153.655397 -307.483578) (xy 153.629094 -307.441982) (xy 153.609803 -307.396706)
			(xy 153.598026 -307.348922) (xy 153.594066 -307.299868) (xy 153.255218 -307.299868) (xy 153.254723 -307.324475)
			(xy 153.246828 -307.373052) (xy 153.231244 -307.419733) (xy 153.208373 -307.46331) (xy 153.178808 -307.502654)
			(xy 153.143315 -307.536746) (xy 153.102812 -307.564702) (xy 153.05835 -307.5858) (xy 153.011079 -307.599492)
			(xy 152.962224 -307.605424) (xy 152.913049 -307.603443) (xy 152.86483 -307.593599) (xy 152.818814 -307.576147)
			(xy 152.776193 -307.55154) (xy 152.738072 -307.520415) (xy 152.705437 -307.483578) (xy 152.679134 -307.441982)
			(xy 152.659843 -307.396706) (xy 152.648066 -307.348922) (xy 152.644106 -307.299868) (xy 148.718415 -307.299868)
			(xy 148.714975 -307.32324) (xy 148.698907 -307.376647) (xy 148.675235 -307.427144) (xy 148.644462 -307.473657)
			(xy 148.607245 -307.515194) (xy 148.564377 -307.550869) (xy 148.516771 -307.579923) (xy 148.465442 -307.601735)
			(xy 148.411485 -307.615841) (xy 148.356048 -307.621941) (xy 148.300314 -307.619904) (xy 148.245471 -307.609774)
			(xy 148.192687 -307.591767) (xy 148.143087 -307.566266) (xy 148.097729 -307.533815) (xy 148.05758 -307.495106)
			(xy 148.023494 -307.450963) (xy 147.996198 -307.402328) (xy 147.976275 -307.350237) (xy 147.964149 -307.2958)
			(xy 147.960078 -307.240178) (xy 135.153908 -307.240178) (xy 135.153908 -307.593238) (xy 135.153478 -307.603305)
			(xy 135.145755 -307.621901) (xy 135.138922 -307.629306) (xy 134.99338 -307.774848) (xy 162.619194 -307.774848)
			(xy 162.623154 -307.725794) (xy 162.634931 -307.67801) (xy 162.654222 -307.632734) (xy 162.680525 -307.591138)
			(xy 162.71316 -307.554301) (xy 162.751281 -307.523176) (xy 162.793902 -307.498569) (xy 162.839918 -307.481117)
			(xy 162.888137 -307.471273) (xy 162.937312 -307.469292) (xy 162.986167 -307.475224) (xy 163.033438 -307.488916)
			(xy 163.0779 -307.510014) (xy 163.118403 -307.53797) (xy 163.153896 -307.572062) (xy 163.183461 -307.611406)
			(xy 163.206332 -307.654983) (xy 163.221916 -307.701664) (xy 163.229811 -307.750241) (xy 163.230306 -307.774848)
			(xy 163.569154 -307.774848) (xy 163.573114 -307.725794) (xy 163.584891 -307.67801) (xy 163.604182 -307.632734)
			(xy 163.630485 -307.591138) (xy 163.66312 -307.554301) (xy 163.701241 -307.523176) (xy 163.743862 -307.498569)
			(xy 163.789878 -307.481117) (xy 163.838097 -307.471273) (xy 163.887272 -307.469292) (xy 163.936127 -307.475224)
			(xy 163.983398 -307.488916) (xy 164.02786 -307.510014) (xy 164.068363 -307.53797) (xy 164.103856 -307.572062)
			(xy 164.133421 -307.611406) (xy 164.156292 -307.654983) (xy 164.171876 -307.701664) (xy 164.179771 -307.750241)
			(xy 164.180266 -307.774848) (xy 164.519114 -307.774848) (xy 164.523074 -307.725794) (xy 164.534851 -307.67801)
			(xy 164.554142 -307.632734) (xy 164.580445 -307.591138) (xy 164.61308 -307.554301) (xy 164.651201 -307.523176)
			(xy 164.693822 -307.498569) (xy 164.739838 -307.481117) (xy 164.788057 -307.471273) (xy 164.837232 -307.469292)
			(xy 164.886087 -307.475224) (xy 164.933358 -307.488916) (xy 164.97782 -307.510014) (xy 165.018323 -307.53797)
			(xy 165.053816 -307.572062) (xy 165.083381 -307.611406) (xy 165.106252 -307.654983) (xy 165.121836 -307.701664)
			(xy 165.129731 -307.750241) (xy 165.130226 -307.774848) (xy 165.469074 -307.774848) (xy 165.473034 -307.725794)
			(xy 165.484811 -307.67801) (xy 165.504102 -307.632734) (xy 165.530405 -307.591138) (xy 165.56304 -307.554301)
			(xy 165.601161 -307.523176) (xy 165.643782 -307.498569) (xy 165.689798 -307.481117) (xy 165.738017 -307.471273)
			(xy 165.787192 -307.469292) (xy 165.836047 -307.475224) (xy 165.883318 -307.488916) (xy 165.92778 -307.510014)
			(xy 165.968283 -307.53797) (xy 166.003776 -307.572062) (xy 166.033341 -307.611406) (xy 166.056212 -307.654983)
			(xy 166.071796 -307.701664) (xy 166.079691 -307.750241) (xy 166.080186 -307.774848) (xy 166.419288 -307.774848)
			(xy 166.423248 -307.725794) (xy 166.435025 -307.67801) (xy 166.454316 -307.632734) (xy 166.480619 -307.591138)
			(xy 166.513254 -307.554301) (xy 166.551375 -307.523176) (xy 166.593996 -307.498569) (xy 166.640012 -307.481117)
			(xy 166.688231 -307.471273) (xy 166.737406 -307.469292) (xy 166.786261 -307.475224) (xy 166.833532 -307.488916)
			(xy 166.877994 -307.510014) (xy 166.918497 -307.53797) (xy 166.95399 -307.572062) (xy 166.983555 -307.611406)
			(xy 167.006426 -307.654983) (xy 167.02201 -307.701664) (xy 167.029905 -307.750241) (xy 167.0304 -307.774848)
			(xy 167.369248 -307.774848) (xy 167.373208 -307.725794) (xy 167.384985 -307.67801) (xy 167.404276 -307.632734)
			(xy 167.430579 -307.591138) (xy 167.463214 -307.554301) (xy 167.501335 -307.523176) (xy 167.543956 -307.498569)
			(xy 167.589972 -307.481117) (xy 167.638191 -307.471273) (xy 167.687366 -307.469292) (xy 167.736221 -307.475224)
			(xy 167.783492 -307.488916) (xy 167.827954 -307.510014) (xy 167.868457 -307.53797) (xy 167.90395 -307.572062)
			(xy 167.933515 -307.611406) (xy 167.956386 -307.654983) (xy 167.97197 -307.701664) (xy 167.979865 -307.750241)
			(xy 167.98036 -307.774848) (xy 168.319208 -307.774848) (xy 168.323168 -307.725794) (xy 168.334945 -307.67801)
			(xy 168.354236 -307.632734) (xy 168.380539 -307.591138) (xy 168.413174 -307.554301) (xy 168.451295 -307.523176)
			(xy 168.493916 -307.498569) (xy 168.539932 -307.481117) (xy 168.588151 -307.471273) (xy 168.637326 -307.469292)
			(xy 168.686181 -307.475224) (xy 168.733452 -307.488916) (xy 168.777914 -307.510014) (xy 168.818417 -307.53797)
			(xy 168.85391 -307.572062) (xy 168.883475 -307.611406) (xy 168.906346 -307.654983) (xy 168.92193 -307.701664)
			(xy 168.929825 -307.750241) (xy 168.93032 -307.774848) (xy 169.269168 -307.774848) (xy 169.273128 -307.725794)
			(xy 169.284905 -307.67801) (xy 169.304196 -307.632734) (xy 169.330499 -307.591138) (xy 169.363134 -307.554301)
			(xy 169.401255 -307.523176) (xy 169.443876 -307.498569) (xy 169.489892 -307.481117) (xy 169.538111 -307.471273)
			(xy 169.587286 -307.469292) (xy 169.636141 -307.475224) (xy 169.683412 -307.488916) (xy 169.727874 -307.510014)
			(xy 169.768377 -307.53797) (xy 169.80387 -307.572062) (xy 169.833435 -307.611406) (xy 169.856306 -307.654983)
			(xy 169.87189 -307.701664) (xy 169.879785 -307.750241) (xy 169.88028 -307.774848) (xy 170.219128 -307.774848)
			(xy 170.223088 -307.725794) (xy 170.234865 -307.67801) (xy 170.254156 -307.632734) (xy 170.280459 -307.591138)
			(xy 170.313094 -307.554301) (xy 170.351215 -307.523176) (xy 170.393836 -307.498569) (xy 170.439852 -307.481117)
			(xy 170.488071 -307.471273) (xy 170.537246 -307.469292) (xy 170.586101 -307.475224) (xy 170.633372 -307.488916)
			(xy 170.677834 -307.510014) (xy 170.718337 -307.53797) (xy 170.75383 -307.572062) (xy 170.783395 -307.611406)
			(xy 170.806266 -307.654983) (xy 170.82185 -307.701664) (xy 170.829745 -307.750241) (xy 170.83024 -307.774848)
			(xy 171.169088 -307.774848) (xy 171.173048 -307.725794) (xy 171.184825 -307.67801) (xy 171.204116 -307.632734)
			(xy 171.230419 -307.591138) (xy 171.263054 -307.554301) (xy 171.301175 -307.523176) (xy 171.343796 -307.498569)
			(xy 171.389812 -307.481117) (xy 171.438031 -307.471273) (xy 171.487206 -307.469292) (xy 171.536061 -307.475224)
			(xy 171.583332 -307.488916) (xy 171.627794 -307.510014) (xy 171.668297 -307.53797) (xy 171.70379 -307.572062)
			(xy 171.733355 -307.611406) (xy 171.756226 -307.654983) (xy 171.77181 -307.701664) (xy 171.779705 -307.750241)
			(xy 171.7802 -307.774848) (xy 172.119302 -307.774848) (xy 172.123262 -307.725794) (xy 172.135039 -307.67801)
			(xy 172.15433 -307.632734) (xy 172.180633 -307.591138) (xy 172.213268 -307.554301) (xy 172.251389 -307.523176)
			(xy 172.29401 -307.498569) (xy 172.340026 -307.481117) (xy 172.388245 -307.471273) (xy 172.43742 -307.469292)
			(xy 172.486275 -307.475224) (xy 172.533546 -307.488916) (xy 172.578008 -307.510014) (xy 172.618511 -307.53797)
			(xy 172.654004 -307.572062) (xy 172.683569 -307.611406) (xy 172.70644 -307.654983) (xy 172.722024 -307.701664)
			(xy 172.729919 -307.750241) (xy 172.730414 -307.774848) (xy 173.069262 -307.774848) (xy 173.073222 -307.725794)
			(xy 173.084999 -307.67801) (xy 173.10429 -307.632734) (xy 173.130593 -307.591138) (xy 173.163228 -307.554301)
			(xy 173.201349 -307.523176) (xy 173.24397 -307.498569) (xy 173.289986 -307.481117) (xy 173.338205 -307.471273)
			(xy 173.38738 -307.469292) (xy 173.436235 -307.475224) (xy 173.483506 -307.488916) (xy 173.527968 -307.510014)
			(xy 173.568471 -307.53797) (xy 173.603964 -307.572062) (xy 173.633529 -307.611406) (xy 173.6564 -307.654983)
			(xy 173.671984 -307.701664) (xy 173.679879 -307.750241) (xy 173.680374 -307.774848) (xy 174.019222 -307.774848)
			(xy 174.023182 -307.725794) (xy 174.034959 -307.67801) (xy 174.05425 -307.632734) (xy 174.080553 -307.591138)
			(xy 174.113188 -307.554301) (xy 174.151309 -307.523176) (xy 174.19393 -307.498569) (xy 174.239946 -307.481117)
			(xy 174.288165 -307.471273) (xy 174.33734 -307.469292) (xy 174.386195 -307.475224) (xy 174.433466 -307.488916)
			(xy 174.477928 -307.510014) (xy 174.518431 -307.53797) (xy 174.553924 -307.572062) (xy 174.583489 -307.611406)
			(xy 174.60636 -307.654983) (xy 174.621944 -307.701664) (xy 174.629839 -307.750241) (xy 174.630334 -307.774848)
			(xy 175.919142 -307.774848) (xy 175.923102 -307.725794) (xy 175.934879 -307.67801) (xy 175.95417 -307.632734)
			(xy 175.980473 -307.591138) (xy 176.013108 -307.554301) (xy 176.051229 -307.523176) (xy 176.09385 -307.498569)
			(xy 176.139866 -307.481117) (xy 176.188085 -307.471273) (xy 176.23726 -307.469292) (xy 176.286115 -307.475224)
			(xy 176.333386 -307.488916) (xy 176.377848 -307.510014) (xy 176.418351 -307.53797) (xy 176.453844 -307.572062)
			(xy 176.483409 -307.611406) (xy 176.50628 -307.654983) (xy 176.521864 -307.701664) (xy 176.529759 -307.750241)
			(xy 176.530254 -307.774848) (xy 176.529759 -307.799455) (xy 176.521864 -307.848032) (xy 176.50628 -307.894713)
			(xy 176.483409 -307.93829) (xy 176.453844 -307.977634) (xy 176.418351 -308.011726) (xy 176.377848 -308.039682)
			(xy 176.333386 -308.06078) (xy 176.286115 -308.074472) (xy 176.23726 -308.080404) (xy 176.188085 -308.078423)
			(xy 176.139866 -308.068579) (xy 176.09385 -308.051127) (xy 176.051229 -308.02652) (xy 176.013108 -307.995395)
			(xy 175.980473 -307.958558) (xy 175.95417 -307.916962) (xy 175.934879 -307.871686) (xy 175.923102 -307.823902)
			(xy 175.919142 -307.774848) (xy 174.630334 -307.774848) (xy 174.629839 -307.799455) (xy 174.621944 -307.848032)
			(xy 174.60636 -307.894713) (xy 174.583489 -307.93829) (xy 174.553924 -307.977634) (xy 174.518431 -308.011726)
			(xy 174.477928 -308.039682) (xy 174.433466 -308.06078) (xy 174.386195 -308.074472) (xy 174.33734 -308.080404)
			(xy 174.288165 -308.078423) (xy 174.239946 -308.068579) (xy 174.19393 -308.051127) (xy 174.151309 -308.02652)
			(xy 174.113188 -307.995395) (xy 174.080553 -307.958558) (xy 174.05425 -307.916962) (xy 174.034959 -307.871686)
			(xy 174.023182 -307.823902) (xy 174.019222 -307.774848) (xy 173.680374 -307.774848) (xy 173.679879 -307.799455)
			(xy 173.671984 -307.848032) (xy 173.6564 -307.894713) (xy 173.633529 -307.93829) (xy 173.603964 -307.977634)
			(xy 173.568471 -308.011726) (xy 173.527968 -308.039682) (xy 173.483506 -308.06078) (xy 173.436235 -308.074472)
			(xy 173.38738 -308.080404) (xy 173.338205 -308.078423) (xy 173.289986 -308.068579) (xy 173.24397 -308.051127)
			(xy 173.201349 -308.02652) (xy 173.163228 -307.995395) (xy 173.130593 -307.958558) (xy 173.10429 -307.916962)
			(xy 173.084999 -307.871686) (xy 173.073222 -307.823902) (xy 173.069262 -307.774848) (xy 172.730414 -307.774848)
			(xy 172.729919 -307.799455) (xy 172.722024 -307.848032) (xy 172.70644 -307.894713) (xy 172.683569 -307.93829)
			(xy 172.654004 -307.977634) (xy 172.618511 -308.011726) (xy 172.578008 -308.039682) (xy 172.533546 -308.06078)
			(xy 172.486275 -308.074472) (xy 172.43742 -308.080404) (xy 172.388245 -308.078423) (xy 172.340026 -308.068579)
			(xy 172.29401 -308.051127) (xy 172.251389 -308.02652) (xy 172.213268 -307.995395) (xy 172.180633 -307.958558)
			(xy 172.15433 -307.916962) (xy 172.135039 -307.871686) (xy 172.123262 -307.823902) (xy 172.119302 -307.774848)
			(xy 171.7802 -307.774848) (xy 171.779705 -307.799455) (xy 171.77181 -307.848032) (xy 171.756226 -307.894713)
			(xy 171.733355 -307.93829) (xy 171.70379 -307.977634) (xy 171.668297 -308.011726) (xy 171.627794 -308.039682)
			(xy 171.583332 -308.06078) (xy 171.536061 -308.074472) (xy 171.487206 -308.080404) (xy 171.438031 -308.078423)
			(xy 171.389812 -308.068579) (xy 171.343796 -308.051127) (xy 171.301175 -308.02652) (xy 171.263054 -307.995395)
			(xy 171.230419 -307.958558) (xy 171.204116 -307.916962) (xy 171.184825 -307.871686) (xy 171.173048 -307.823902)
			(xy 171.169088 -307.774848) (xy 170.83024 -307.774848) (xy 170.829745 -307.799455) (xy 170.82185 -307.848032)
			(xy 170.806266 -307.894713) (xy 170.783395 -307.93829) (xy 170.75383 -307.977634) (xy 170.718337 -308.011726)
			(xy 170.677834 -308.039682) (xy 170.633372 -308.06078) (xy 170.586101 -308.074472) (xy 170.537246 -308.080404)
			(xy 170.488071 -308.078423) (xy 170.439852 -308.068579) (xy 170.393836 -308.051127) (xy 170.351215 -308.02652)
			(xy 170.313094 -307.995395) (xy 170.280459 -307.958558) (xy 170.254156 -307.916962) (xy 170.234865 -307.871686)
			(xy 170.223088 -307.823902) (xy 170.219128 -307.774848) (xy 169.88028 -307.774848) (xy 169.879785 -307.799455)
			(xy 169.87189 -307.848032) (xy 169.856306 -307.894713) (xy 169.833435 -307.93829) (xy 169.80387 -307.977634)
			(xy 169.768377 -308.011726) (xy 169.727874 -308.039682) (xy 169.683412 -308.06078) (xy 169.636141 -308.074472)
			(xy 169.587286 -308.080404) (xy 169.538111 -308.078423) (xy 169.489892 -308.068579) (xy 169.443876 -308.051127)
			(xy 169.401255 -308.02652) (xy 169.363134 -307.995395) (xy 169.330499 -307.958558) (xy 169.304196 -307.916962)
			(xy 169.284905 -307.871686) (xy 169.273128 -307.823902) (xy 169.269168 -307.774848) (xy 168.93032 -307.774848)
			(xy 168.929825 -307.799455) (xy 168.92193 -307.848032) (xy 168.906346 -307.894713) (xy 168.883475 -307.93829)
			(xy 168.85391 -307.977634) (xy 168.818417 -308.011726) (xy 168.777914 -308.039682) (xy 168.733452 -308.06078)
			(xy 168.686181 -308.074472) (xy 168.637326 -308.080404) (xy 168.588151 -308.078423) (xy 168.539932 -308.068579)
			(xy 168.493916 -308.051127) (xy 168.451295 -308.02652) (xy 168.413174 -307.995395) (xy 168.380539 -307.958558)
			(xy 168.354236 -307.916962) (xy 168.334945 -307.871686) (xy 168.323168 -307.823902) (xy 168.319208 -307.774848)
			(xy 167.98036 -307.774848) (xy 167.979865 -307.799455) (xy 167.97197 -307.848032) (xy 167.956386 -307.894713)
			(xy 167.933515 -307.93829) (xy 167.90395 -307.977634) (xy 167.868457 -308.011726) (xy 167.827954 -308.039682)
			(xy 167.783492 -308.06078) (xy 167.736221 -308.074472) (xy 167.687366 -308.080404) (xy 167.638191 -308.078423)
			(xy 167.589972 -308.068579) (xy 167.543956 -308.051127) (xy 167.501335 -308.02652) (xy 167.463214 -307.995395)
			(xy 167.430579 -307.958558) (xy 167.404276 -307.916962) (xy 167.384985 -307.871686) (xy 167.373208 -307.823902)
			(xy 167.369248 -307.774848) (xy 167.0304 -307.774848) (xy 167.029905 -307.799455) (xy 167.02201 -307.848032)
			(xy 167.006426 -307.894713) (xy 166.983555 -307.93829) (xy 166.95399 -307.977634) (xy 166.918497 -308.011726)
			(xy 166.877994 -308.039682) (xy 166.833532 -308.06078) (xy 166.786261 -308.074472) (xy 166.737406 -308.080404)
			(xy 166.688231 -308.078423) (xy 166.640012 -308.068579) (xy 166.593996 -308.051127) (xy 166.551375 -308.02652)
			(xy 166.513254 -307.995395) (xy 166.480619 -307.958558) (xy 166.454316 -307.916962) (xy 166.435025 -307.871686)
			(xy 166.423248 -307.823902) (xy 166.419288 -307.774848) (xy 166.080186 -307.774848) (xy 166.079691 -307.799455)
			(xy 166.071796 -307.848032) (xy 166.056212 -307.894713) (xy 166.033341 -307.93829) (xy 166.003776 -307.977634)
			(xy 165.968283 -308.011726) (xy 165.92778 -308.039682) (xy 165.883318 -308.06078) (xy 165.836047 -308.074472)
			(xy 165.787192 -308.080404) (xy 165.738017 -308.078423) (xy 165.689798 -308.068579) (xy 165.643782 -308.051127)
			(xy 165.601161 -308.02652) (xy 165.56304 -307.995395) (xy 165.530405 -307.958558) (xy 165.504102 -307.916962)
			(xy 165.484811 -307.871686) (xy 165.473034 -307.823902) (xy 165.469074 -307.774848) (xy 165.130226 -307.774848)
			(xy 165.129731 -307.799455) (xy 165.121836 -307.848032) (xy 165.106252 -307.894713) (xy 165.083381 -307.93829)
			(xy 165.053816 -307.977634) (xy 165.018323 -308.011726) (xy 164.97782 -308.039682) (xy 164.933358 -308.06078)
			(xy 164.886087 -308.074472) (xy 164.837232 -308.080404) (xy 164.788057 -308.078423) (xy 164.739838 -308.068579)
			(xy 164.693822 -308.051127) (xy 164.651201 -308.02652) (xy 164.61308 -307.995395) (xy 164.580445 -307.958558)
			(xy 164.554142 -307.916962) (xy 164.534851 -307.871686) (xy 164.523074 -307.823902) (xy 164.519114 -307.774848)
			(xy 164.180266 -307.774848) (xy 164.179771 -307.799455) (xy 164.171876 -307.848032) (xy 164.156292 -307.894713)
			(xy 164.133421 -307.93829) (xy 164.103856 -307.977634) (xy 164.068363 -308.011726) (xy 164.02786 -308.039682)
			(xy 163.983398 -308.06078) (xy 163.936127 -308.074472) (xy 163.887272 -308.080404) (xy 163.838097 -308.078423)
			(xy 163.789878 -308.068579) (xy 163.743862 -308.051127) (xy 163.701241 -308.02652) (xy 163.66312 -307.995395)
			(xy 163.630485 -307.958558) (xy 163.604182 -307.916962) (xy 163.584891 -307.871686) (xy 163.573114 -307.823902)
			(xy 163.569154 -307.774848) (xy 163.230306 -307.774848) (xy 163.229811 -307.799455) (xy 163.221916 -307.848032)
			(xy 163.206332 -307.894713) (xy 163.183461 -307.93829) (xy 163.153896 -307.977634) (xy 163.118403 -308.011726)
			(xy 163.0779 -308.039682) (xy 163.033438 -308.06078) (xy 162.986167 -308.074472) (xy 162.937312 -308.080404)
			(xy 162.888137 -308.078423) (xy 162.839918 -308.068579) (xy 162.793902 -308.051127) (xy 162.751281 -308.02652)
			(xy 162.71316 -307.995395) (xy 162.680525 -307.958558) (xy 162.654222 -307.916962) (xy 162.634931 -307.871686)
			(xy 162.623154 -307.823902) (xy 162.619194 -307.774848) (xy 134.99338 -307.774848) (xy 134.31774 -308.450488)
			(xy 144.178272 -308.450488) (xy 144.182343 -308.394866) (xy 144.194469 -308.340429) (xy 144.214392 -308.288338)
			(xy 144.241688 -308.239703) (xy 144.275774 -308.19556) (xy 144.315923 -308.156851) (xy 144.361281 -308.1244)
			(xy 144.410881 -308.098899) (xy 144.463665 -308.080892) (xy 144.518508 -308.070762) (xy 144.574242 -308.068725)
			(xy 144.629679 -308.074825) (xy 144.683636 -308.088931) (xy 144.734965 -308.110743) (xy 144.782571 -308.139797)
			(xy 144.825439 -308.175472) (xy 144.862656 -308.217009) (xy 144.884537 -308.250082) (xy 151.693892 -308.250082)
			(xy 151.697852 -308.201028) (xy 151.709629 -308.153244) (xy 151.72892 -308.107968) (xy 151.755223 -308.066372)
			(xy 151.787858 -308.029535) (xy 151.825979 -307.99841) (xy 151.8686 -307.973803) (xy 151.914616 -307.956351)
			(xy 151.962835 -307.946507) (xy 152.01201 -307.944526) (xy 152.060865 -307.950458) (xy 152.108136 -307.96415)
			(xy 152.152598 -307.985248) (xy 152.193101 -308.013204) (xy 152.228594 -308.047296) (xy 152.258159 -308.08664)
			(xy 152.28103 -308.130217) (xy 152.296614 -308.176898) (xy 152.304509 -308.225475) (xy 152.304999 -308.249828)
			(xy 152.644106 -308.249828) (xy 152.648066 -308.200774) (xy 152.659843 -308.15299) (xy 152.679134 -308.107714)
			(xy 152.705437 -308.066118) (xy 152.738072 -308.029281) (xy 152.776193 -307.998156) (xy 152.818814 -307.973549)
			(xy 152.86483 -307.956097) (xy 152.913049 -307.946253) (xy 152.962224 -307.944272) (xy 153.011079 -307.950204)
			(xy 153.05835 -307.963896) (xy 153.102812 -307.984994) (xy 153.143315 -308.01295) (xy 153.178808 -308.047042)
			(xy 153.208373 -308.086386) (xy 153.231244 -308.129963) (xy 153.246828 -308.176644) (xy 153.254723 -308.225221)
			(xy 153.255218 -308.249828) (xy 153.594066 -308.249828) (xy 153.598026 -308.200774) (xy 153.609803 -308.15299)
			(xy 153.629094 -308.107714) (xy 153.655397 -308.066118) (xy 153.688032 -308.029281) (xy 153.726153 -307.998156)
			(xy 153.768774 -307.973549) (xy 153.81479 -307.956097) (xy 153.863009 -307.946253) (xy 153.912184 -307.944272)
			(xy 153.961039 -307.950204) (xy 154.00831 -307.963896) (xy 154.052772 -307.984994) (xy 154.093275 -308.01295)
			(xy 154.128768 -308.047042) (xy 154.158333 -308.086386) (xy 154.181204 -308.129963) (xy 154.196788 -308.176644)
			(xy 154.204683 -308.225221) (xy 154.205178 -308.249828) (xy 154.54428 -308.249828) (xy 154.54824 -308.200774)
			(xy 154.560017 -308.15299) (xy 154.579308 -308.107714) (xy 154.605611 -308.066118) (xy 154.638246 -308.029281)
			(xy 154.676367 -307.998156) (xy 154.718988 -307.973549) (xy 154.765004 -307.956097) (xy 154.813223 -307.946253)
			(xy 154.862398 -307.944272) (xy 154.911253 -307.950204) (xy 154.958524 -307.963896) (xy 155.002986 -307.984994)
			(xy 155.043489 -308.01295) (xy 155.078982 -308.047042) (xy 155.108547 -308.086386) (xy 155.131418 -308.129963)
			(xy 155.147002 -308.176644) (xy 155.154897 -308.225221) (xy 155.155392 -308.249828) (xy 155.49424 -308.249828)
			(xy 155.4982 -308.200774) (xy 155.509977 -308.15299) (xy 155.529268 -308.107714) (xy 155.555571 -308.066118)
			(xy 155.588206 -308.029281) (xy 155.626327 -307.998156) (xy 155.668948 -307.973549) (xy 155.714964 -307.956097)
			(xy 155.763183 -307.946253) (xy 155.812358 -307.944272) (xy 155.861213 -307.950204) (xy 155.908484 -307.963896)
			(xy 155.952946 -307.984994) (xy 155.993449 -308.01295) (xy 156.028942 -308.047042) (xy 156.058507 -308.086386)
			(xy 156.081378 -308.129963) (xy 156.096962 -308.176644) (xy 156.104857 -308.225221) (xy 156.105352 -308.249828)
			(xy 156.4442 -308.249828) (xy 156.44816 -308.200774) (xy 156.459937 -308.15299) (xy 156.479228 -308.107714)
			(xy 156.505531 -308.066118) (xy 156.538166 -308.029281) (xy 156.576287 -307.998156) (xy 156.618908 -307.973549)
			(xy 156.664924 -307.956097) (xy 156.713143 -307.946253) (xy 156.762318 -307.944272) (xy 156.811173 -307.950204)
			(xy 156.858444 -307.963896) (xy 156.902906 -307.984994) (xy 156.943409 -308.01295) (xy 156.978902 -308.047042)
			(xy 157.008467 -308.086386) (xy 157.031338 -308.129963) (xy 157.046922 -308.176644) (xy 157.054817 -308.225221)
			(xy 157.055312 -308.249828) (xy 157.39416 -308.249828) (xy 157.39812 -308.200774) (xy 157.409897 -308.15299)
			(xy 157.429188 -308.107714) (xy 157.455491 -308.066118) (xy 157.488126 -308.029281) (xy 157.526247 -307.998156)
			(xy 157.568868 -307.973549) (xy 157.614884 -307.956097) (xy 157.663103 -307.946253) (xy 157.712278 -307.944272)
			(xy 157.761133 -307.950204) (xy 157.808404 -307.963896) (xy 157.852866 -307.984994) (xy 157.893369 -308.01295)
			(xy 157.928862 -308.047042) (xy 157.958427 -308.086386) (xy 157.981298 -308.129963) (xy 157.996882 -308.176644)
			(xy 158.004777 -308.225221) (xy 158.005272 -308.249828) (xy 158.34412 -308.249828) (xy 158.34808 -308.200774)
			(xy 158.359857 -308.15299) (xy 158.379148 -308.107714) (xy 158.405451 -308.066118) (xy 158.438086 -308.029281)
			(xy 158.476207 -307.998156) (xy 158.518828 -307.973549) (xy 158.564844 -307.956097) (xy 158.613063 -307.946253)
			(xy 158.662238 -307.944272) (xy 158.711093 -307.950204) (xy 158.758364 -307.963896) (xy 158.802826 -307.984994)
			(xy 158.843329 -308.01295) (xy 158.878822 -308.047042) (xy 158.908387 -308.086386) (xy 158.931258 -308.129963)
			(xy 158.946842 -308.176644) (xy 158.954737 -308.225221) (xy 158.955232 -308.249828) (xy 159.29408 -308.249828)
			(xy 159.29804 -308.200774) (xy 159.309817 -308.15299) (xy 159.329108 -308.107714) (xy 159.355411 -308.066118)
			(xy 159.388046 -308.029281) (xy 159.426167 -307.998156) (xy 159.468788 -307.973549) (xy 159.514804 -307.956097)
			(xy 159.563023 -307.946253) (xy 159.612198 -307.944272) (xy 159.661053 -307.950204) (xy 159.708324 -307.963896)
			(xy 159.752786 -307.984994) (xy 159.793289 -308.01295) (xy 159.828782 -308.047042) (xy 159.858347 -308.086386)
			(xy 159.881218 -308.129963) (xy 159.896802 -308.176644) (xy 159.904697 -308.225221) (xy 159.905192 -308.249828)
			(xy 160.24404 -308.249828) (xy 160.248 -308.200774) (xy 160.259777 -308.15299) (xy 160.279068 -308.107714)
			(xy 160.305371 -308.066118) (xy 160.338006 -308.029281) (xy 160.376127 -307.998156) (xy 160.418748 -307.973549)
			(xy 160.464764 -307.956097) (xy 160.512983 -307.946253) (xy 160.562158 -307.944272) (xy 160.611013 -307.950204)
			(xy 160.658284 -307.963896) (xy 160.702746 -307.984994) (xy 160.743249 -308.01295) (xy 160.778742 -308.047042)
			(xy 160.808307 -308.086386) (xy 160.831178 -308.129963) (xy 160.846762 -308.176644) (xy 160.854657 -308.225221)
			(xy 160.855152 -308.249828) (xy 161.194254 -308.249828) (xy 161.198214 -308.200774) (xy 161.209991 -308.15299)
			(xy 161.229282 -308.107714) (xy 161.255585 -308.066118) (xy 161.28822 -308.029281) (xy 161.326341 -307.998156)
			(xy 161.368962 -307.973549) (xy 161.414978 -307.956097) (xy 161.463197 -307.946253) (xy 161.512372 -307.944272)
			(xy 161.561227 -307.950204) (xy 161.608498 -307.963896) (xy 161.65296 -307.984994) (xy 161.693463 -308.01295)
			(xy 161.728956 -308.047042) (xy 161.758521 -308.086386) (xy 161.781392 -308.129963) (xy 161.796976 -308.176644)
			(xy 161.804871 -308.225221) (xy 161.805366 -308.249828) (xy 161.804871 -308.274435) (xy 161.796976 -308.323012)
			(xy 161.781392 -308.369693) (xy 161.758521 -308.41327) (xy 161.728956 -308.452614) (xy 161.693463 -308.486706)
			(xy 161.65296 -308.514662) (xy 161.608498 -308.53576) (xy 161.561227 -308.549452) (xy 161.512372 -308.555384)
			(xy 161.463197 -308.553403) (xy 161.414978 -308.543559) (xy 161.368962 -308.526107) (xy 161.326341 -308.5015)
			(xy 161.28822 -308.470375) (xy 161.255585 -308.433538) (xy 161.229282 -308.391942) (xy 161.209991 -308.346666)
			(xy 161.198214 -308.298882) (xy 161.194254 -308.249828) (xy 160.855152 -308.249828) (xy 160.854657 -308.274435)
			(xy 160.846762 -308.323012) (xy 160.831178 -308.369693) (xy 160.808307 -308.41327) (xy 160.778742 -308.452614)
			(xy 160.743249 -308.486706) (xy 160.702746 -308.514662) (xy 160.658284 -308.53576) (xy 160.611013 -308.549452)
			(xy 160.562158 -308.555384) (xy 160.512983 -308.553403) (xy 160.464764 -308.543559) (xy 160.418748 -308.526107)
			(xy 160.376127 -308.5015) (xy 160.338006 -308.470375) (xy 160.305371 -308.433538) (xy 160.279068 -308.391942)
			(xy 160.259777 -308.346666) (xy 160.248 -308.298882) (xy 160.24404 -308.249828) (xy 159.905192 -308.249828)
			(xy 159.904697 -308.274435) (xy 159.896802 -308.323012) (xy 159.881218 -308.369693) (xy 159.858347 -308.41327)
			(xy 159.828782 -308.452614) (xy 159.793289 -308.486706) (xy 159.752786 -308.514662) (xy 159.708324 -308.53576)
			(xy 159.661053 -308.549452) (xy 159.612198 -308.555384) (xy 159.563023 -308.553403) (xy 159.514804 -308.543559)
			(xy 159.468788 -308.526107) (xy 159.426167 -308.5015) (xy 159.388046 -308.470375) (xy 159.355411 -308.433538)
			(xy 159.329108 -308.391942) (xy 159.309817 -308.346666) (xy 159.29804 -308.298882) (xy 159.29408 -308.249828)
			(xy 158.955232 -308.249828) (xy 158.954737 -308.274435) (xy 158.946842 -308.323012) (xy 158.931258 -308.369693)
			(xy 158.908387 -308.41327) (xy 158.878822 -308.452614) (xy 158.843329 -308.486706) (xy 158.802826 -308.514662)
			(xy 158.758364 -308.53576) (xy 158.711093 -308.549452) (xy 158.662238 -308.555384) (xy 158.613063 -308.553403)
			(xy 158.564844 -308.543559) (xy 158.518828 -308.526107) (xy 158.476207 -308.5015) (xy 158.438086 -308.470375)
			(xy 158.405451 -308.433538) (xy 158.379148 -308.391942) (xy 158.359857 -308.346666) (xy 158.34808 -308.298882)
			(xy 158.34412 -308.249828) (xy 158.005272 -308.249828) (xy 158.004777 -308.274435) (xy 157.996882 -308.323012)
			(xy 157.981298 -308.369693) (xy 157.958427 -308.41327) (xy 157.928862 -308.452614) (xy 157.893369 -308.486706)
			(xy 157.852866 -308.514662) (xy 157.808404 -308.53576) (xy 157.761133 -308.549452) (xy 157.712278 -308.555384)
			(xy 157.663103 -308.553403) (xy 157.614884 -308.543559) (xy 157.568868 -308.526107) (xy 157.526247 -308.5015)
			(xy 157.488126 -308.470375) (xy 157.455491 -308.433538) (xy 157.429188 -308.391942) (xy 157.409897 -308.346666)
			(xy 157.39812 -308.298882) (xy 157.39416 -308.249828) (xy 157.055312 -308.249828) (xy 157.054817 -308.274435)
			(xy 157.046922 -308.323012) (xy 157.031338 -308.369693) (xy 157.008467 -308.41327) (xy 156.978902 -308.452614)
			(xy 156.943409 -308.486706) (xy 156.902906 -308.514662) (xy 156.858444 -308.53576) (xy 156.811173 -308.549452)
			(xy 156.762318 -308.555384) (xy 156.713143 -308.553403) (xy 156.664924 -308.543559) (xy 156.618908 -308.526107)
			(xy 156.576287 -308.5015) (xy 156.538166 -308.470375) (xy 156.505531 -308.433538) (xy 156.479228 -308.391942)
			(xy 156.459937 -308.346666) (xy 156.44816 -308.298882) (xy 156.4442 -308.249828) (xy 156.105352 -308.249828)
			(xy 156.104857 -308.274435) (xy 156.096962 -308.323012) (xy 156.081378 -308.369693) (xy 156.058507 -308.41327)
			(xy 156.028942 -308.452614) (xy 155.993449 -308.486706) (xy 155.952946 -308.514662) (xy 155.908484 -308.53576)
			(xy 155.861213 -308.549452) (xy 155.812358 -308.555384) (xy 155.763183 -308.553403) (xy 155.714964 -308.543559)
			(xy 155.668948 -308.526107) (xy 155.626327 -308.5015) (xy 155.588206 -308.470375) (xy 155.555571 -308.433538)
			(xy 155.529268 -308.391942) (xy 155.509977 -308.346666) (xy 155.4982 -308.298882) (xy 155.49424 -308.249828)
			(xy 155.155392 -308.249828) (xy 155.154897 -308.274435) (xy 155.147002 -308.323012) (xy 155.131418 -308.369693)
			(xy 155.108547 -308.41327) (xy 155.078982 -308.452614) (xy 155.043489 -308.486706) (xy 155.002986 -308.514662)
			(xy 154.958524 -308.53576) (xy 154.911253 -308.549452) (xy 154.862398 -308.555384) (xy 154.813223 -308.553403)
			(xy 154.765004 -308.543559) (xy 154.718988 -308.526107) (xy 154.676367 -308.5015) (xy 154.638246 -308.470375)
			(xy 154.605611 -308.433538) (xy 154.579308 -308.391942) (xy 154.560017 -308.346666) (xy 154.54824 -308.298882)
			(xy 154.54428 -308.249828) (xy 154.205178 -308.249828) (xy 154.204683 -308.274435) (xy 154.196788 -308.323012)
			(xy 154.181204 -308.369693) (xy 154.158333 -308.41327) (xy 154.128768 -308.452614) (xy 154.093275 -308.486706)
			(xy 154.052772 -308.514662) (xy 154.00831 -308.53576) (xy 153.961039 -308.549452) (xy 153.912184 -308.555384)
			(xy 153.863009 -308.553403) (xy 153.81479 -308.543559) (xy 153.768774 -308.526107) (xy 153.726153 -308.5015)
			(xy 153.688032 -308.470375) (xy 153.655397 -308.433538) (xy 153.629094 -308.391942) (xy 153.609803 -308.346666)
			(xy 153.598026 -308.298882) (xy 153.594066 -308.249828) (xy 153.255218 -308.249828) (xy 153.254723 -308.274435)
			(xy 153.246828 -308.323012) (xy 153.231244 -308.369693) (xy 153.208373 -308.41327) (xy 153.178808 -308.452614)
			(xy 153.143315 -308.486706) (xy 153.102812 -308.514662) (xy 153.05835 -308.53576) (xy 153.011079 -308.549452)
			(xy 152.962224 -308.555384) (xy 152.913049 -308.553403) (xy 152.86483 -308.543559) (xy 152.818814 -308.526107)
			(xy 152.776193 -308.5015) (xy 152.738072 -308.470375) (xy 152.705437 -308.433538) (xy 152.679134 -308.391942)
			(xy 152.659843 -308.346666) (xy 152.648066 -308.298882) (xy 152.644106 -308.249828) (xy 152.304999 -308.249828)
			(xy 152.305004 -308.250082) (xy 152.304509 -308.274689) (xy 152.296614 -308.323266) (xy 152.28103 -308.369947)
			(xy 152.258159 -308.413524) (xy 152.228594 -308.452868) (xy 152.193101 -308.48696) (xy 152.152598 -308.514916)
			(xy 152.108136 -308.536014) (xy 152.060865 -308.549706) (xy 152.01201 -308.555638) (xy 151.962835 -308.553657)
			(xy 151.914616 -308.543813) (xy 151.8686 -308.526361) (xy 151.825979 -308.501754) (xy 151.787858 -308.470629)
			(xy 151.755223 -308.433792) (xy 151.72892 -308.392196) (xy 151.709629 -308.34692) (xy 151.697852 -308.299136)
			(xy 151.693892 -308.250082) (xy 144.884537 -308.250082) (xy 144.893429 -308.263522) (xy 144.917101 -308.314019)
			(xy 144.933169 -308.367426) (xy 144.941289 -308.422602) (xy 144.941798 -308.450488) (xy 144.941289 -308.478374)
			(xy 144.933169 -308.53355) (xy 144.917101 -308.586957) (xy 144.893429 -308.637454) (xy 144.878824 -308.65953)
			(xy 146.505674 -308.65953) (xy 146.509745 -308.603908) (xy 146.521871 -308.549471) (xy 146.541794 -308.49738)
			(xy 146.56909 -308.448745) (xy 146.603176 -308.404602) (xy 146.643325 -308.365893) (xy 146.688683 -308.333442)
			(xy 146.738283 -308.307941) (xy 146.791067 -308.289934) (xy 146.84591 -308.279804) (xy 146.901644 -308.277767)
			(xy 146.957081 -308.283867) (xy 147.011038 -308.297973) (xy 147.062367 -308.319785) (xy 147.109973 -308.348839)
			(xy 147.152841 -308.384514) (xy 147.190058 -308.426051) (xy 147.220831 -308.472564) (xy 147.244503 -308.523061)
			(xy 147.260571 -308.576468) (xy 147.268691 -308.631644) (xy 147.2692 -308.65953) (xy 147.268691 -308.687416)
			(xy 147.263188 -308.724808) (xy 162.619194 -308.724808) (xy 162.623154 -308.675754) (xy 162.634931 -308.62797)
			(xy 162.654222 -308.582694) (xy 162.680525 -308.541098) (xy 162.71316 -308.504261) (xy 162.751281 -308.473136)
			(xy 162.793902 -308.448529) (xy 162.839918 -308.431077) (xy 162.888137 -308.421233) (xy 162.937312 -308.419252)
			(xy 162.986167 -308.425184) (xy 163.033438 -308.438876) (xy 163.0779 -308.459974) (xy 163.118403 -308.48793)
			(xy 163.153896 -308.522022) (xy 163.183461 -308.561366) (xy 163.206332 -308.604943) (xy 163.221916 -308.651624)
			(xy 163.229811 -308.700201) (xy 163.230306 -308.724808) (xy 163.569154 -308.724808) (xy 163.573114 -308.675754)
			(xy 163.584891 -308.62797) (xy 163.604182 -308.582694) (xy 163.630485 -308.541098) (xy 163.66312 -308.504261)
			(xy 163.701241 -308.473136) (xy 163.743862 -308.448529) (xy 163.789878 -308.431077) (xy 163.838097 -308.421233)
			(xy 163.887272 -308.419252) (xy 163.936127 -308.425184) (xy 163.983398 -308.438876) (xy 164.02786 -308.459974)
			(xy 164.068363 -308.48793) (xy 164.103856 -308.522022) (xy 164.133421 -308.561366) (xy 164.156292 -308.604943)
			(xy 164.171876 -308.651624) (xy 164.179771 -308.700201) (xy 164.180266 -308.724808) (xy 164.519114 -308.724808)
			(xy 164.523074 -308.675754) (xy 164.534851 -308.62797) (xy 164.554142 -308.582694) (xy 164.580445 -308.541098)
			(xy 164.61308 -308.504261) (xy 164.651201 -308.473136) (xy 164.693822 -308.448529) (xy 164.739838 -308.431077)
			(xy 164.788057 -308.421233) (xy 164.837232 -308.419252) (xy 164.886087 -308.425184) (xy 164.933358 -308.438876)
			(xy 164.97782 -308.459974) (xy 165.018323 -308.48793) (xy 165.053816 -308.522022) (xy 165.083381 -308.561366)
			(xy 165.106252 -308.604943) (xy 165.121836 -308.651624) (xy 165.129731 -308.700201) (xy 165.130226 -308.724808)
			(xy 165.469074 -308.724808) (xy 165.473034 -308.675754) (xy 165.484811 -308.62797) (xy 165.504102 -308.582694)
			(xy 165.530405 -308.541098) (xy 165.56304 -308.504261) (xy 165.601161 -308.473136) (xy 165.643782 -308.448529)
			(xy 165.689798 -308.431077) (xy 165.738017 -308.421233) (xy 165.787192 -308.419252) (xy 165.836047 -308.425184)
			(xy 165.883318 -308.438876) (xy 165.92778 -308.459974) (xy 165.968283 -308.48793) (xy 166.003776 -308.522022)
			(xy 166.033341 -308.561366) (xy 166.056212 -308.604943) (xy 166.071796 -308.651624) (xy 166.079691 -308.700201)
			(xy 166.080186 -308.724808) (xy 166.419288 -308.724808) (xy 166.423248 -308.675754) (xy 166.435025 -308.62797)
			(xy 166.454316 -308.582694) (xy 166.480619 -308.541098) (xy 166.513254 -308.504261) (xy 166.551375 -308.473136)
			(xy 166.593996 -308.448529) (xy 166.640012 -308.431077) (xy 166.688231 -308.421233) (xy 166.737406 -308.419252)
			(xy 166.786261 -308.425184) (xy 166.833532 -308.438876) (xy 166.877994 -308.459974) (xy 166.918497 -308.48793)
			(xy 166.95399 -308.522022) (xy 166.983555 -308.561366) (xy 167.006426 -308.604943) (xy 167.02201 -308.651624)
			(xy 167.029905 -308.700201) (xy 167.0304 -308.724808) (xy 167.369248 -308.724808) (xy 167.373208 -308.675754)
			(xy 167.384985 -308.62797) (xy 167.404276 -308.582694) (xy 167.430579 -308.541098) (xy 167.463214 -308.504261)
			(xy 167.501335 -308.473136) (xy 167.543956 -308.448529) (xy 167.589972 -308.431077) (xy 167.638191 -308.421233)
			(xy 167.687366 -308.419252) (xy 167.736221 -308.425184) (xy 167.783492 -308.438876) (xy 167.827954 -308.459974)
			(xy 167.868457 -308.48793) (xy 167.90395 -308.522022) (xy 167.933515 -308.561366) (xy 167.956386 -308.604943)
			(xy 167.97197 -308.651624) (xy 167.979865 -308.700201) (xy 167.98036 -308.724808) (xy 168.319208 -308.724808)
			(xy 168.323168 -308.675754) (xy 168.334945 -308.62797) (xy 168.354236 -308.582694) (xy 168.380539 -308.541098)
			(xy 168.413174 -308.504261) (xy 168.451295 -308.473136) (xy 168.493916 -308.448529) (xy 168.539932 -308.431077)
			(xy 168.588151 -308.421233) (xy 168.637326 -308.419252) (xy 168.686181 -308.425184) (xy 168.733452 -308.438876)
			(xy 168.777914 -308.459974) (xy 168.818417 -308.48793) (xy 168.85391 -308.522022) (xy 168.883475 -308.561366)
			(xy 168.906346 -308.604943) (xy 168.92193 -308.651624) (xy 168.929825 -308.700201) (xy 168.93032 -308.724808)
			(xy 169.269168 -308.724808) (xy 169.273128 -308.675754) (xy 169.284905 -308.62797) (xy 169.304196 -308.582694)
			(xy 169.330499 -308.541098) (xy 169.363134 -308.504261) (xy 169.401255 -308.473136) (xy 169.443876 -308.448529)
			(xy 169.489892 -308.431077) (xy 169.538111 -308.421233) (xy 169.587286 -308.419252) (xy 169.636141 -308.425184)
			(xy 169.683412 -308.438876) (xy 169.727874 -308.459974) (xy 169.768377 -308.48793) (xy 169.80387 -308.522022)
			(xy 169.833435 -308.561366) (xy 169.856306 -308.604943) (xy 169.87189 -308.651624) (xy 169.879785 -308.700201)
			(xy 169.88028 -308.724808) (xy 170.219128 -308.724808) (xy 170.223088 -308.675754) (xy 170.234865 -308.62797)
			(xy 170.254156 -308.582694) (xy 170.280459 -308.541098) (xy 170.313094 -308.504261) (xy 170.351215 -308.473136)
			(xy 170.393836 -308.448529) (xy 170.439852 -308.431077) (xy 170.488071 -308.421233) (xy 170.537246 -308.419252)
			(xy 170.586101 -308.425184) (xy 170.633372 -308.438876) (xy 170.677834 -308.459974) (xy 170.718337 -308.48793)
			(xy 170.75383 -308.522022) (xy 170.783395 -308.561366) (xy 170.806266 -308.604943) (xy 170.82185 -308.651624)
			(xy 170.829745 -308.700201) (xy 170.83024 -308.724808) (xy 171.169088 -308.724808) (xy 171.173048 -308.675754)
			(xy 171.184825 -308.62797) (xy 171.204116 -308.582694) (xy 171.230419 -308.541098) (xy 171.263054 -308.504261)
			(xy 171.301175 -308.473136) (xy 171.343796 -308.448529) (xy 171.389812 -308.431077) (xy 171.438031 -308.421233)
			(xy 171.487206 -308.419252) (xy 171.536061 -308.425184) (xy 171.583332 -308.438876) (xy 171.627794 -308.459974)
			(xy 171.668297 -308.48793) (xy 171.70379 -308.522022) (xy 171.733355 -308.561366) (xy 171.756226 -308.604943)
			(xy 171.77181 -308.651624) (xy 171.779705 -308.700201) (xy 171.7802 -308.724808) (xy 172.119302 -308.724808)
			(xy 172.123262 -308.675754) (xy 172.135039 -308.62797) (xy 172.15433 -308.582694) (xy 172.180633 -308.541098)
			(xy 172.213268 -308.504261) (xy 172.251389 -308.473136) (xy 172.29401 -308.448529) (xy 172.340026 -308.431077)
			(xy 172.388245 -308.421233) (xy 172.43742 -308.419252) (xy 172.486275 -308.425184) (xy 172.533546 -308.438876)
			(xy 172.578008 -308.459974) (xy 172.618511 -308.48793) (xy 172.654004 -308.522022) (xy 172.683569 -308.561366)
			(xy 172.70644 -308.604943) (xy 172.722024 -308.651624) (xy 172.729919 -308.700201) (xy 172.730414 -308.724808)
			(xy 174.019222 -308.724808) (xy 174.023182 -308.675754) (xy 174.034959 -308.62797) (xy 174.05425 -308.582694)
			(xy 174.080553 -308.541098) (xy 174.113188 -308.504261) (xy 174.151309 -308.473136) (xy 174.19393 -308.448529)
			(xy 174.239946 -308.431077) (xy 174.288165 -308.421233) (xy 174.33734 -308.419252) (xy 174.386195 -308.425184)
			(xy 174.433466 -308.438876) (xy 174.477928 -308.459974) (xy 174.518431 -308.48793) (xy 174.553924 -308.522022)
			(xy 174.583489 -308.561366) (xy 174.60636 -308.604943) (xy 174.621944 -308.651624) (xy 174.629839 -308.700201)
			(xy 174.630334 -308.724808) (xy 174.629839 -308.749415) (xy 174.621944 -308.797992) (xy 174.60636 -308.844673)
			(xy 174.583489 -308.88825) (xy 174.553924 -308.927594) (xy 174.518431 -308.961686) (xy 174.477928 -308.989642)
			(xy 174.433466 -309.01074) (xy 174.386195 -309.024432) (xy 174.33734 -309.030364) (xy 174.288165 -309.028383)
			(xy 174.239946 -309.018539) (xy 174.19393 -309.001087) (xy 174.151309 -308.97648) (xy 174.113188 -308.945355)
			(xy 174.080553 -308.908518) (xy 174.05425 -308.866922) (xy 174.034959 -308.821646) (xy 174.023182 -308.773862)
			(xy 174.019222 -308.724808) (xy 172.730414 -308.724808) (xy 172.729919 -308.749415) (xy 172.722024 -308.797992)
			(xy 172.70644 -308.844673) (xy 172.683569 -308.88825) (xy 172.654004 -308.927594) (xy 172.618511 -308.961686)
			(xy 172.578008 -308.989642) (xy 172.533546 -309.01074) (xy 172.486275 -309.024432) (xy 172.43742 -309.030364)
			(xy 172.388245 -309.028383) (xy 172.340026 -309.018539) (xy 172.29401 -309.001087) (xy 172.251389 -308.97648)
			(xy 172.213268 -308.945355) (xy 172.180633 -308.908518) (xy 172.15433 -308.866922) (xy 172.135039 -308.821646)
			(xy 172.123262 -308.773862) (xy 172.119302 -308.724808) (xy 171.7802 -308.724808) (xy 171.779705 -308.749415)
			(xy 171.77181 -308.797992) (xy 171.756226 -308.844673) (xy 171.733355 -308.88825) (xy 171.70379 -308.927594)
			(xy 171.668297 -308.961686) (xy 171.627794 -308.989642) (xy 171.583332 -309.01074) (xy 171.536061 -309.024432)
			(xy 171.487206 -309.030364) (xy 171.438031 -309.028383) (xy 171.389812 -309.018539) (xy 171.343796 -309.001087)
			(xy 171.301175 -308.97648) (xy 171.263054 -308.945355) (xy 171.230419 -308.908518) (xy 171.204116 -308.866922)
			(xy 171.184825 -308.821646) (xy 171.173048 -308.773862) (xy 171.169088 -308.724808) (xy 170.83024 -308.724808)
			(xy 170.829745 -308.749415) (xy 170.82185 -308.797992) (xy 170.806266 -308.844673) (xy 170.783395 -308.88825)
			(xy 170.75383 -308.927594) (xy 170.718337 -308.961686) (xy 170.677834 -308.989642) (xy 170.633372 -309.01074)
			(xy 170.586101 -309.024432) (xy 170.537246 -309.030364) (xy 170.488071 -309.028383) (xy 170.439852 -309.018539)
			(xy 170.393836 -309.001087) (xy 170.351215 -308.97648) (xy 170.313094 -308.945355) (xy 170.280459 -308.908518)
			(xy 170.254156 -308.866922) (xy 170.234865 -308.821646) (xy 170.223088 -308.773862) (xy 170.219128 -308.724808)
			(xy 169.88028 -308.724808) (xy 169.879785 -308.749415) (xy 169.87189 -308.797992) (xy 169.856306 -308.844673)
			(xy 169.833435 -308.88825) (xy 169.80387 -308.927594) (xy 169.768377 -308.961686) (xy 169.727874 -308.989642)
			(xy 169.683412 -309.01074) (xy 169.636141 -309.024432) (xy 169.587286 -309.030364) (xy 169.538111 -309.028383)
			(xy 169.489892 -309.018539) (xy 169.443876 -309.001087) (xy 169.401255 -308.97648) (xy 169.363134 -308.945355)
			(xy 169.330499 -308.908518) (xy 169.304196 -308.866922) (xy 169.284905 -308.821646) (xy 169.273128 -308.773862)
			(xy 169.269168 -308.724808) (xy 168.93032 -308.724808) (xy 168.929825 -308.749415) (xy 168.92193 -308.797992)
			(xy 168.906346 -308.844673) (xy 168.883475 -308.88825) (xy 168.85391 -308.927594) (xy 168.818417 -308.961686)
			(xy 168.777914 -308.989642) (xy 168.733452 -309.01074) (xy 168.686181 -309.024432) (xy 168.637326 -309.030364)
			(xy 168.588151 -309.028383) (xy 168.539932 -309.018539) (xy 168.493916 -309.001087) (xy 168.451295 -308.97648)
			(xy 168.413174 -308.945355) (xy 168.380539 -308.908518) (xy 168.354236 -308.866922) (xy 168.334945 -308.821646)
			(xy 168.323168 -308.773862) (xy 168.319208 -308.724808) (xy 167.98036 -308.724808) (xy 167.979865 -308.749415)
			(xy 167.97197 -308.797992) (xy 167.956386 -308.844673) (xy 167.933515 -308.88825) (xy 167.90395 -308.927594)
			(xy 167.868457 -308.961686) (xy 167.827954 -308.989642) (xy 167.783492 -309.01074) (xy 167.736221 -309.024432)
			(xy 167.687366 -309.030364) (xy 167.638191 -309.028383) (xy 167.589972 -309.018539) (xy 167.543956 -309.001087)
			(xy 167.501335 -308.97648) (xy 167.463214 -308.945355) (xy 167.430579 -308.908518) (xy 167.404276 -308.866922)
			(xy 167.384985 -308.821646) (xy 167.373208 -308.773862) (xy 167.369248 -308.724808) (xy 167.0304 -308.724808)
			(xy 167.029905 -308.749415) (xy 167.02201 -308.797992) (xy 167.006426 -308.844673) (xy 166.983555 -308.88825)
			(xy 166.95399 -308.927594) (xy 166.918497 -308.961686) (xy 166.877994 -308.989642) (xy 166.833532 -309.01074)
			(xy 166.786261 -309.024432) (xy 166.737406 -309.030364) (xy 166.688231 -309.028383) (xy 166.640012 -309.018539)
			(xy 166.593996 -309.001087) (xy 166.551375 -308.97648) (xy 166.513254 -308.945355) (xy 166.480619 -308.908518)
			(xy 166.454316 -308.866922) (xy 166.435025 -308.821646) (xy 166.423248 -308.773862) (xy 166.419288 -308.724808)
			(xy 166.080186 -308.724808) (xy 166.079691 -308.749415) (xy 166.071796 -308.797992) (xy 166.056212 -308.844673)
			(xy 166.033341 -308.88825) (xy 166.003776 -308.927594) (xy 165.968283 -308.961686) (xy 165.92778 -308.989642)
			(xy 165.883318 -309.01074) (xy 165.836047 -309.024432) (xy 165.787192 -309.030364) (xy 165.738017 -309.028383)
			(xy 165.689798 -309.018539) (xy 165.643782 -309.001087) (xy 165.601161 -308.97648) (xy 165.56304 -308.945355)
			(xy 165.530405 -308.908518) (xy 165.504102 -308.866922) (xy 165.484811 -308.821646) (xy 165.473034 -308.773862)
			(xy 165.469074 -308.724808) (xy 165.130226 -308.724808) (xy 165.129731 -308.749415) (xy 165.121836 -308.797992)
			(xy 165.106252 -308.844673) (xy 165.083381 -308.88825) (xy 165.053816 -308.927594) (xy 165.018323 -308.961686)
			(xy 164.97782 -308.989642) (xy 164.933358 -309.01074) (xy 164.886087 -309.024432) (xy 164.837232 -309.030364)
			(xy 164.788057 -309.028383) (xy 164.739838 -309.018539) (xy 164.693822 -309.001087) (xy 164.651201 -308.97648)
			(xy 164.61308 -308.945355) (xy 164.580445 -308.908518) (xy 164.554142 -308.866922) (xy 164.534851 -308.821646)
			(xy 164.523074 -308.773862) (xy 164.519114 -308.724808) (xy 164.180266 -308.724808) (xy 164.179771 -308.749415)
			(xy 164.171876 -308.797992) (xy 164.156292 -308.844673) (xy 164.133421 -308.88825) (xy 164.103856 -308.927594)
			(xy 164.068363 -308.961686) (xy 164.02786 -308.989642) (xy 163.983398 -309.01074) (xy 163.936127 -309.024432)
			(xy 163.887272 -309.030364) (xy 163.838097 -309.028383) (xy 163.789878 -309.018539) (xy 163.743862 -309.001087)
			(xy 163.701241 -308.97648) (xy 163.66312 -308.945355) (xy 163.630485 -308.908518) (xy 163.604182 -308.866922)
			(xy 163.584891 -308.821646) (xy 163.573114 -308.773862) (xy 163.569154 -308.724808) (xy 163.230306 -308.724808)
			(xy 163.229811 -308.749415) (xy 163.221916 -308.797992) (xy 163.206332 -308.844673) (xy 163.183461 -308.88825)
			(xy 163.153896 -308.927594) (xy 163.118403 -308.961686) (xy 163.0779 -308.989642) (xy 163.033438 -309.01074)
			(xy 162.986167 -309.024432) (xy 162.937312 -309.030364) (xy 162.888137 -309.028383) (xy 162.839918 -309.018539)
			(xy 162.793902 -309.001087) (xy 162.751281 -308.97648) (xy 162.71316 -308.945355) (xy 162.680525 -308.908518)
			(xy 162.654222 -308.866922) (xy 162.634931 -308.821646) (xy 162.623154 -308.773862) (xy 162.619194 -308.724808)
			(xy 147.263188 -308.724808) (xy 147.260571 -308.742592) (xy 147.244503 -308.795999) (xy 147.220831 -308.846496)
			(xy 147.190058 -308.893009) (xy 147.152841 -308.934546) (xy 147.109973 -308.970221) (xy 147.062367 -308.999275)
			(xy 147.011038 -309.021087) (xy 146.957081 -309.035193) (xy 146.901644 -309.041293) (xy 146.84591 -309.039256)
			(xy 146.791067 -309.029126) (xy 146.738283 -309.011119) (xy 146.688683 -308.985618) (xy 146.643325 -308.953167)
			(xy 146.603176 -308.914458) (xy 146.56909 -308.870315) (xy 146.541794 -308.82168) (xy 146.521871 -308.769589)
			(xy 146.509745 -308.715152) (xy 146.505674 -308.65953) (xy 144.878824 -308.65953) (xy 144.862656 -308.683967)
			(xy 144.825439 -308.725504) (xy 144.782571 -308.761179) (xy 144.734965 -308.790233) (xy 144.683636 -308.812045)
			(xy 144.629679 -308.826151) (xy 144.574242 -308.832251) (xy 144.518508 -308.830214) (xy 144.463665 -308.820084)
			(xy 144.410881 -308.802077) (xy 144.361281 -308.776576) (xy 144.315923 -308.744125) (xy 144.275774 -308.705416)
			(xy 144.241688 -308.661273) (xy 144.214392 -308.612638) (xy 144.194469 -308.560547) (xy 144.182343 -308.50611)
			(xy 144.178272 -308.450488) (xy 134.31774 -308.450488) (xy 134.1755 -308.592728) (xy 134.168105 -308.599582)
			(xy 134.149506 -308.607328) (xy 134.139432 -308.607714) (xy 120.636792 -308.607714) (xy 120.630781 -308.607876)
			(xy 120.619095 -308.610692) (xy 120.613678 -308.613302) (xy 120.610204 -308.615142) (xy 120.603826 -308.619736)
			(xy 120.600978 -308.622446) (xy 119.808498 -309.414926) (xy 143.100042 -309.414926) (xy 143.104113 -309.359304)
			(xy 143.116239 -309.304867) (xy 143.136162 -309.252776) (xy 143.163458 -309.204141) (xy 143.197544 -309.159998)
			(xy 143.237693 -309.121289) (xy 143.283051 -309.088838) (xy 143.332651 -309.063337) (xy 143.385435 -309.04533)
			(xy 143.440278 -309.0352) (xy 143.496012 -309.033163) (xy 143.551449 -309.039263) (xy 143.605406 -309.053369)
			(xy 143.656735 -309.075181) (xy 143.704341 -309.104235) (xy 143.747209 -309.13991) (xy 143.784426 -309.181447)
			(xy 143.79656 -309.199788) (xy 152.644106 -309.199788) (xy 152.648066 -309.150734) (xy 152.659843 -309.10295)
			(xy 152.679134 -309.057674) (xy 152.705437 -309.016078) (xy 152.738072 -308.979241) (xy 152.776193 -308.948116)
			(xy 152.818814 -308.923509) (xy 152.86483 -308.906057) (xy 152.913049 -308.896213) (xy 152.962224 -308.894232)
			(xy 153.011079 -308.900164) (xy 153.05835 -308.913856) (xy 153.102812 -308.934954) (xy 153.143315 -308.96291)
			(xy 153.178808 -308.997002) (xy 153.208373 -309.036346) (xy 153.231244 -309.079923) (xy 153.246828 -309.126604)
			(xy 153.254723 -309.175181) (xy 153.255218 -309.199788) (xy 153.594066 -309.199788) (xy 153.598026 -309.150734)
			(xy 153.609803 -309.10295) (xy 153.629094 -309.057674) (xy 153.655397 -309.016078) (xy 153.688032 -308.979241)
			(xy 153.726153 -308.948116) (xy 153.768774 -308.923509) (xy 153.81479 -308.906057) (xy 153.863009 -308.896213)
			(xy 153.912184 -308.894232) (xy 153.961039 -308.900164) (xy 154.00831 -308.913856) (xy 154.052772 -308.934954)
			(xy 154.093275 -308.96291) (xy 154.128768 -308.997002) (xy 154.158333 -309.036346) (xy 154.181204 -309.079923)
			(xy 154.196788 -309.126604) (xy 154.204683 -309.175181) (xy 154.205178 -309.199788) (xy 154.54428 -309.199788)
			(xy 154.54824 -309.150734) (xy 154.560017 -309.10295) (xy 154.579308 -309.057674) (xy 154.605611 -309.016078)
			(xy 154.638246 -308.979241) (xy 154.676367 -308.948116) (xy 154.718988 -308.923509) (xy 154.765004 -308.906057)
			(xy 154.813223 -308.896213) (xy 154.862398 -308.894232) (xy 154.911253 -308.900164) (xy 154.958524 -308.913856)
			(xy 155.002986 -308.934954) (xy 155.043489 -308.96291) (xy 155.078982 -308.997002) (xy 155.108547 -309.036346)
			(xy 155.131418 -309.079923) (xy 155.147002 -309.126604) (xy 155.154897 -309.175181) (xy 155.155392 -309.199788)
			(xy 155.49424 -309.199788) (xy 155.4982 -309.150734) (xy 155.509977 -309.10295) (xy 155.529268 -309.057674)
			(xy 155.555571 -309.016078) (xy 155.588206 -308.979241) (xy 155.626327 -308.948116) (xy 155.668948 -308.923509)
			(xy 155.714964 -308.906057) (xy 155.763183 -308.896213) (xy 155.812358 -308.894232) (xy 155.861213 -308.900164)
			(xy 155.908484 -308.913856) (xy 155.952946 -308.934954) (xy 155.993449 -308.96291) (xy 156.028942 -308.997002)
			(xy 156.058507 -309.036346) (xy 156.081378 -309.079923) (xy 156.096962 -309.126604) (xy 156.104857 -309.175181)
			(xy 156.105352 -309.199788) (xy 156.4442 -309.199788) (xy 156.44816 -309.150734) (xy 156.459937 -309.10295)
			(xy 156.479228 -309.057674) (xy 156.505531 -309.016078) (xy 156.538166 -308.979241) (xy 156.576287 -308.948116)
			(xy 156.618908 -308.923509) (xy 156.664924 -308.906057) (xy 156.713143 -308.896213) (xy 156.762318 -308.894232)
			(xy 156.811173 -308.900164) (xy 156.858444 -308.913856) (xy 156.902906 -308.934954) (xy 156.943409 -308.96291)
			(xy 156.978902 -308.997002) (xy 157.008467 -309.036346) (xy 157.031338 -309.079923) (xy 157.046922 -309.126604)
			(xy 157.054817 -309.175181) (xy 157.055312 -309.199788) (xy 157.39416 -309.199788) (xy 157.39812 -309.150734)
			(xy 157.409897 -309.10295) (xy 157.429188 -309.057674) (xy 157.455491 -309.016078) (xy 157.488126 -308.979241)
			(xy 157.526247 -308.948116) (xy 157.568868 -308.923509) (xy 157.614884 -308.906057) (xy 157.663103 -308.896213)
			(xy 157.712278 -308.894232) (xy 157.761133 -308.900164) (xy 157.808404 -308.913856) (xy 157.852866 -308.934954)
			(xy 157.893369 -308.96291) (xy 157.928862 -308.997002) (xy 157.958427 -309.036346) (xy 157.981298 -309.079923)
			(xy 157.996882 -309.126604) (xy 158.004777 -309.175181) (xy 158.005272 -309.199788) (xy 158.34412 -309.199788)
			(xy 158.34808 -309.150734) (xy 158.359857 -309.10295) (xy 158.379148 -309.057674) (xy 158.405451 -309.016078)
			(xy 158.438086 -308.979241) (xy 158.476207 -308.948116) (xy 158.518828 -308.923509) (xy 158.564844 -308.906057)
			(xy 158.613063 -308.896213) (xy 158.662238 -308.894232) (xy 158.711093 -308.900164) (xy 158.758364 -308.913856)
			(xy 158.802826 -308.934954) (xy 158.843329 -308.96291) (xy 158.878822 -308.997002) (xy 158.908387 -309.036346)
			(xy 158.931258 -309.079923) (xy 158.946842 -309.126604) (xy 158.954737 -309.175181) (xy 158.955232 -309.199788)
			(xy 159.29408 -309.199788) (xy 159.29804 -309.150734) (xy 159.309817 -309.10295) (xy 159.329108 -309.057674)
			(xy 159.355411 -309.016078) (xy 159.388046 -308.979241) (xy 159.426167 -308.948116) (xy 159.468788 -308.923509)
			(xy 159.514804 -308.906057) (xy 159.563023 -308.896213) (xy 159.612198 -308.894232) (xy 159.661053 -308.900164)
			(xy 159.708324 -308.913856) (xy 159.752786 -308.934954) (xy 159.793289 -308.96291) (xy 159.828782 -308.997002)
			(xy 159.858347 -309.036346) (xy 159.881218 -309.079923) (xy 159.896802 -309.126604) (xy 159.904697 -309.175181)
			(xy 159.905192 -309.199788) (xy 160.24404 -309.199788) (xy 160.248 -309.150734) (xy 160.259777 -309.10295)
			(xy 160.279068 -309.057674) (xy 160.305371 -309.016078) (xy 160.338006 -308.979241) (xy 160.376127 -308.948116)
			(xy 160.418748 -308.923509) (xy 160.464764 -308.906057) (xy 160.512983 -308.896213) (xy 160.562158 -308.894232)
			(xy 160.611013 -308.900164) (xy 160.658284 -308.913856) (xy 160.702746 -308.934954) (xy 160.743249 -308.96291)
			(xy 160.778742 -308.997002) (xy 160.808307 -309.036346) (xy 160.831178 -309.079923) (xy 160.846762 -309.126604)
			(xy 160.854657 -309.175181) (xy 160.855152 -309.199788) (xy 161.194254 -309.199788) (xy 161.198214 -309.150734)
			(xy 161.209991 -309.10295) (xy 161.229282 -309.057674) (xy 161.255585 -309.016078) (xy 161.28822 -308.979241)
			(xy 161.326341 -308.948116) (xy 161.368962 -308.923509) (xy 161.414978 -308.906057) (xy 161.463197 -308.896213)
			(xy 161.512372 -308.894232) (xy 161.561227 -308.900164) (xy 161.608498 -308.913856) (xy 161.65296 -308.934954)
			(xy 161.693463 -308.96291) (xy 161.728956 -308.997002) (xy 161.758521 -309.036346) (xy 161.781392 -309.079923)
			(xy 161.796976 -309.126604) (xy 161.804871 -309.175181) (xy 161.805366 -309.199788) (xy 161.804871 -309.224395)
			(xy 161.796976 -309.272972) (xy 161.781392 -309.319653) (xy 161.758521 -309.36323) (xy 161.728956 -309.402574)
			(xy 161.693463 -309.436666) (xy 161.65296 -309.464622) (xy 161.608498 -309.48572) (xy 161.561227 -309.499412)
			(xy 161.512372 -309.505344) (xy 161.463197 -309.503363) (xy 161.414978 -309.493519) (xy 161.368962 -309.476067)
			(xy 161.326341 -309.45146) (xy 161.28822 -309.420335) (xy 161.255585 -309.383498) (xy 161.229282 -309.341902)
			(xy 161.209991 -309.296626) (xy 161.198214 -309.248842) (xy 161.194254 -309.199788) (xy 160.855152 -309.199788)
			(xy 160.854657 -309.224395) (xy 160.846762 -309.272972) (xy 160.831178 -309.319653) (xy 160.808307 -309.36323)
			(xy 160.778742 -309.402574) (xy 160.743249 -309.436666) (xy 160.702746 -309.464622) (xy 160.658284 -309.48572)
			(xy 160.611013 -309.499412) (xy 160.562158 -309.505344) (xy 160.512983 -309.503363) (xy 160.464764 -309.493519)
			(xy 160.418748 -309.476067) (xy 160.376127 -309.45146) (xy 160.338006 -309.420335) (xy 160.305371 -309.383498)
			(xy 160.279068 -309.341902) (xy 160.259777 -309.296626) (xy 160.248 -309.248842) (xy 160.24404 -309.199788)
			(xy 159.905192 -309.199788) (xy 159.904697 -309.224395) (xy 159.896802 -309.272972) (xy 159.881218 -309.319653)
			(xy 159.858347 -309.36323) (xy 159.828782 -309.402574) (xy 159.793289 -309.436666) (xy 159.752786 -309.464622)
			(xy 159.708324 -309.48572) (xy 159.661053 -309.499412) (xy 159.612198 -309.505344) (xy 159.563023 -309.503363)
			(xy 159.514804 -309.493519) (xy 159.468788 -309.476067) (xy 159.426167 -309.45146) (xy 159.388046 -309.420335)
			(xy 159.355411 -309.383498) (xy 159.329108 -309.341902) (xy 159.309817 -309.296626) (xy 159.29804 -309.248842)
			(xy 159.29408 -309.199788) (xy 158.955232 -309.199788) (xy 158.954737 -309.224395) (xy 158.946842 -309.272972)
			(xy 158.931258 -309.319653) (xy 158.908387 -309.36323) (xy 158.878822 -309.402574) (xy 158.843329 -309.436666)
			(xy 158.802826 -309.464622) (xy 158.758364 -309.48572) (xy 158.711093 -309.499412) (xy 158.662238 -309.505344)
			(xy 158.613063 -309.503363) (xy 158.564844 -309.493519) (xy 158.518828 -309.476067) (xy 158.476207 -309.45146)
			(xy 158.438086 -309.420335) (xy 158.405451 -309.383498) (xy 158.379148 -309.341902) (xy 158.359857 -309.296626)
			(xy 158.34808 -309.248842) (xy 158.34412 -309.199788) (xy 158.005272 -309.199788) (xy 158.004777 -309.224395)
			(xy 157.996882 -309.272972) (xy 157.981298 -309.319653) (xy 157.958427 -309.36323) (xy 157.928862 -309.402574)
			(xy 157.893369 -309.436666) (xy 157.852866 -309.464622) (xy 157.808404 -309.48572) (xy 157.761133 -309.499412)
			(xy 157.712278 -309.505344) (xy 157.663103 -309.503363) (xy 157.614884 -309.493519) (xy 157.568868 -309.476067)
			(xy 157.526247 -309.45146) (xy 157.488126 -309.420335) (xy 157.455491 -309.383498) (xy 157.429188 -309.341902)
			(xy 157.409897 -309.296626) (xy 157.39812 -309.248842) (xy 157.39416 -309.199788) (xy 157.055312 -309.199788)
			(xy 157.054817 -309.224395) (xy 157.046922 -309.272972) (xy 157.031338 -309.319653) (xy 157.008467 -309.36323)
			(xy 156.978902 -309.402574) (xy 156.943409 -309.436666) (xy 156.902906 -309.464622) (xy 156.858444 -309.48572)
			(xy 156.811173 -309.499412) (xy 156.762318 -309.505344) (xy 156.713143 -309.503363) (xy 156.664924 -309.493519)
			(xy 156.618908 -309.476067) (xy 156.576287 -309.45146) (xy 156.538166 -309.420335) (xy 156.505531 -309.383498)
			(xy 156.479228 -309.341902) (xy 156.459937 -309.296626) (xy 156.44816 -309.248842) (xy 156.4442 -309.199788)
			(xy 156.105352 -309.199788) (xy 156.104857 -309.224395) (xy 156.096962 -309.272972) (xy 156.081378 -309.319653)
			(xy 156.058507 -309.36323) (xy 156.028942 -309.402574) (xy 155.993449 -309.436666) (xy 155.952946 -309.464622)
			(xy 155.908484 -309.48572) (xy 155.861213 -309.499412) (xy 155.812358 -309.505344) (xy 155.763183 -309.503363)
			(xy 155.714964 -309.493519) (xy 155.668948 -309.476067) (xy 155.626327 -309.45146) (xy 155.588206 -309.420335)
			(xy 155.555571 -309.383498) (xy 155.529268 -309.341902) (xy 155.509977 -309.296626) (xy 155.4982 -309.248842)
			(xy 155.49424 -309.199788) (xy 155.155392 -309.199788) (xy 155.154897 -309.224395) (xy 155.147002 -309.272972)
			(xy 155.131418 -309.319653) (xy 155.108547 -309.36323) (xy 155.078982 -309.402574) (xy 155.043489 -309.436666)
			(xy 155.002986 -309.464622) (xy 154.958524 -309.48572) (xy 154.911253 -309.499412) (xy 154.862398 -309.505344)
			(xy 154.813223 -309.503363) (xy 154.765004 -309.493519) (xy 154.718988 -309.476067) (xy 154.676367 -309.45146)
			(xy 154.638246 -309.420335) (xy 154.605611 -309.383498) (xy 154.579308 -309.341902) (xy 154.560017 -309.296626)
			(xy 154.54824 -309.248842) (xy 154.54428 -309.199788) (xy 154.205178 -309.199788) (xy 154.204683 -309.224395)
			(xy 154.196788 -309.272972) (xy 154.181204 -309.319653) (xy 154.158333 -309.36323) (xy 154.128768 -309.402574)
			(xy 154.093275 -309.436666) (xy 154.052772 -309.464622) (xy 154.00831 -309.48572) (xy 153.961039 -309.499412)
			(xy 153.912184 -309.505344) (xy 153.863009 -309.503363) (xy 153.81479 -309.493519) (xy 153.768774 -309.476067)
			(xy 153.726153 -309.45146) (xy 153.688032 -309.420335) (xy 153.655397 -309.383498) (xy 153.629094 -309.341902)
			(xy 153.609803 -309.296626) (xy 153.598026 -309.248842) (xy 153.594066 -309.199788) (xy 153.255218 -309.199788)
			(xy 153.254723 -309.224395) (xy 153.246828 -309.272972) (xy 153.231244 -309.319653) (xy 153.208373 -309.36323)
			(xy 153.178808 -309.402574) (xy 153.143315 -309.436666) (xy 153.102812 -309.464622) (xy 153.05835 -309.48572)
			(xy 153.011079 -309.499412) (xy 152.962224 -309.505344) (xy 152.913049 -309.503363) (xy 152.86483 -309.493519)
			(xy 152.818814 -309.476067) (xy 152.776193 -309.45146) (xy 152.738072 -309.420335) (xy 152.705437 -309.383498)
			(xy 152.679134 -309.341902) (xy 152.659843 -309.296626) (xy 152.648066 -309.248842) (xy 152.644106 -309.199788)
			(xy 143.79656 -309.199788) (xy 143.815199 -309.22796) (xy 143.838871 -309.278457) (xy 143.854939 -309.331864)
			(xy 143.863059 -309.38704) (xy 143.863568 -309.414926) (xy 143.863059 -309.442812) (xy 143.854939 -309.497988)
			(xy 143.838871 -309.551395) (xy 143.815199 -309.601892) (xy 143.784426 -309.648405) (xy 143.747209 -309.689942)
			(xy 143.704341 -309.725617) (xy 143.656735 -309.754671) (xy 143.605406 -309.776483) (xy 143.551449 -309.790589)
			(xy 143.496012 -309.796689) (xy 143.440278 -309.794652) (xy 143.385435 -309.784522) (xy 143.332651 -309.766515)
			(xy 143.283051 -309.741014) (xy 143.237693 -309.708563) (xy 143.197544 -309.669854) (xy 143.163458 -309.625711)
			(xy 143.136162 -309.577076) (xy 143.116239 -309.524985) (xy 143.104113 -309.470548) (xy 143.100042 -309.414926)
			(xy 119.808498 -309.414926) (xy 119.645938 -309.577486) (xy 119.643231 -309.580336) (xy 119.638637 -309.586714)
			(xy 119.636794 -309.590186) (xy 119.634216 -309.595614) (xy 119.631402 -309.607294) (xy 119.631206 -309.6133)
			(xy 119.631206 -309.897272) (xy 150.540464 -309.897272) (xy 150.544535 -309.84165) (xy 150.556661 -309.787213)
			(xy 150.576584 -309.735122) (xy 150.60388 -309.686487) (xy 150.637966 -309.642344) (xy 150.678115 -309.603635)
			(xy 150.723473 -309.571184) (xy 150.773073 -309.545683) (xy 150.825857 -309.527676) (xy 150.8807 -309.517546)
			(xy 150.936434 -309.515509) (xy 150.991871 -309.521609) (xy 151.045828 -309.535715) (xy 151.097157 -309.557527)
			(xy 151.144763 -309.586581) (xy 151.187631 -309.622256) (xy 151.224848 -309.663793) (xy 151.255621 -309.710306)
			(xy 151.279293 -309.760803) (xy 151.295361 -309.81421) (xy 151.303481 -309.869386) (xy 151.30399 -309.897272)
			(xy 151.303481 -309.925158) (xy 151.295361 -309.980334) (xy 151.279293 -310.033741) (xy 151.255621 -310.084238)
			(xy 151.224848 -310.130751) (xy 151.207599 -310.150002) (xy 151.693892 -310.150002) (xy 151.697852 -310.100948)
			(xy 151.709629 -310.053164) (xy 151.72892 -310.007888) (xy 151.755223 -309.966292) (xy 151.787858 -309.929455)
			(xy 151.825979 -309.89833) (xy 151.8686 -309.873723) (xy 151.914616 -309.856271) (xy 151.962835 -309.846427)
			(xy 152.01201 -309.844446) (xy 152.060865 -309.850378) (xy 152.108136 -309.86407) (xy 152.152598 -309.885168)
			(xy 152.193101 -309.913124) (xy 152.228594 -309.947216) (xy 152.258159 -309.98656) (xy 152.28103 -310.030137)
			(xy 152.296614 -310.076818) (xy 152.304509 -310.125395) (xy 152.304999 -310.149748) (xy 152.644106 -310.149748)
			(xy 152.648066 -310.100694) (xy 152.659843 -310.05291) (xy 152.679134 -310.007634) (xy 152.705437 -309.966038)
			(xy 152.738072 -309.929201) (xy 152.776193 -309.898076) (xy 152.818814 -309.873469) (xy 152.86483 -309.856017)
			(xy 152.913049 -309.846173) (xy 152.962224 -309.844192) (xy 153.011079 -309.850124) (xy 153.05835 -309.863816)
			(xy 153.102812 -309.884914) (xy 153.143315 -309.91287) (xy 153.178808 -309.946962) (xy 153.208373 -309.986306)
			(xy 153.231244 -310.029883) (xy 153.246828 -310.076564) (xy 153.254723 -310.125141) (xy 153.255218 -310.149748)
			(xy 153.594066 -310.149748) (xy 153.598026 -310.100694) (xy 153.609803 -310.05291) (xy 153.629094 -310.007634)
			(xy 153.655397 -309.966038) (xy 153.688032 -309.929201) (xy 153.726153 -309.898076) (xy 153.768774 -309.873469)
			(xy 153.81479 -309.856017) (xy 153.863009 -309.846173) (xy 153.912184 -309.844192) (xy 153.961039 -309.850124)
			(xy 154.00831 -309.863816) (xy 154.052772 -309.884914) (xy 154.093275 -309.91287) (xy 154.128768 -309.946962)
			(xy 154.158333 -309.986306) (xy 154.181204 -310.029883) (xy 154.196788 -310.076564) (xy 154.204683 -310.125141)
			(xy 154.205178 -310.149748) (xy 154.54428 -310.149748) (xy 154.54824 -310.100694) (xy 154.560017 -310.05291)
			(xy 154.579308 -310.007634) (xy 154.605611 -309.966038) (xy 154.638246 -309.929201) (xy 154.676367 -309.898076)
			(xy 154.718988 -309.873469) (xy 154.765004 -309.856017) (xy 154.813223 -309.846173) (xy 154.862398 -309.844192)
			(xy 154.911253 -309.850124) (xy 154.958524 -309.863816) (xy 155.002986 -309.884914) (xy 155.043489 -309.91287)
			(xy 155.078982 -309.946962) (xy 155.108547 -309.986306) (xy 155.131418 -310.029883) (xy 155.147002 -310.076564)
			(xy 155.154897 -310.125141) (xy 155.155392 -310.149748) (xy 155.49424 -310.149748) (xy 155.4982 -310.100694)
			(xy 155.509977 -310.05291) (xy 155.529268 -310.007634) (xy 155.555571 -309.966038) (xy 155.588206 -309.929201)
			(xy 155.626327 -309.898076) (xy 155.668948 -309.873469) (xy 155.714964 -309.856017) (xy 155.763183 -309.846173)
			(xy 155.812358 -309.844192) (xy 155.861213 -309.850124) (xy 155.908484 -309.863816) (xy 155.952946 -309.884914)
			(xy 155.993449 -309.91287) (xy 156.028942 -309.946962) (xy 156.058507 -309.986306) (xy 156.081378 -310.029883)
			(xy 156.096962 -310.076564) (xy 156.104857 -310.125141) (xy 156.105352 -310.149748) (xy 156.4442 -310.149748)
			(xy 156.44816 -310.100694) (xy 156.459937 -310.05291) (xy 156.479228 -310.007634) (xy 156.505531 -309.966038)
			(xy 156.538166 -309.929201) (xy 156.576287 -309.898076) (xy 156.618908 -309.873469) (xy 156.664924 -309.856017)
			(xy 156.713143 -309.846173) (xy 156.762318 -309.844192) (xy 156.811173 -309.850124) (xy 156.858444 -309.863816)
			(xy 156.902906 -309.884914) (xy 156.943409 -309.91287) (xy 156.978902 -309.946962) (xy 157.008467 -309.986306)
			(xy 157.031338 -310.029883) (xy 157.046922 -310.076564) (xy 157.054817 -310.125141) (xy 157.055312 -310.149748)
			(xy 157.39416 -310.149748) (xy 157.39812 -310.100694) (xy 157.409897 -310.05291) (xy 157.429188 -310.007634)
			(xy 157.455491 -309.966038) (xy 157.488126 -309.929201) (xy 157.526247 -309.898076) (xy 157.568868 -309.873469)
			(xy 157.614884 -309.856017) (xy 157.663103 -309.846173) (xy 157.712278 -309.844192) (xy 157.761133 -309.850124)
			(xy 157.808404 -309.863816) (xy 157.852866 -309.884914) (xy 157.893369 -309.91287) (xy 157.928862 -309.946962)
			(xy 157.958427 -309.986306) (xy 157.981298 -310.029883) (xy 157.996882 -310.076564) (xy 158.004777 -310.125141)
			(xy 158.005272 -310.149748) (xy 158.34412 -310.149748) (xy 158.34808 -310.100694) (xy 158.359857 -310.05291)
			(xy 158.379148 -310.007634) (xy 158.405451 -309.966038) (xy 158.438086 -309.929201) (xy 158.476207 -309.898076)
			(xy 158.518828 -309.873469) (xy 158.564844 -309.856017) (xy 158.613063 -309.846173) (xy 158.662238 -309.844192)
			(xy 158.711093 -309.850124) (xy 158.758364 -309.863816) (xy 158.802826 -309.884914) (xy 158.843329 -309.91287)
			(xy 158.878822 -309.946962) (xy 158.908387 -309.986306) (xy 158.931258 -310.029883) (xy 158.946842 -310.076564)
			(xy 158.954737 -310.125141) (xy 158.955232 -310.149748) (xy 159.29408 -310.149748) (xy 159.29804 -310.100694)
			(xy 159.309817 -310.05291) (xy 159.329108 -310.007634) (xy 159.355411 -309.966038) (xy 159.388046 -309.929201)
			(xy 159.426167 -309.898076) (xy 159.468788 -309.873469) (xy 159.514804 -309.856017) (xy 159.563023 -309.846173)
			(xy 159.612198 -309.844192) (xy 159.661053 -309.850124) (xy 159.708324 -309.863816) (xy 159.752786 -309.884914)
			(xy 159.793289 -309.91287) (xy 159.828782 -309.946962) (xy 159.858347 -309.986306) (xy 159.881218 -310.029883)
			(xy 159.896802 -310.076564) (xy 159.904697 -310.125141) (xy 159.905192 -310.149748) (xy 160.24404 -310.149748)
			(xy 160.248 -310.100694) (xy 160.259777 -310.05291) (xy 160.279068 -310.007634) (xy 160.305371 -309.966038)
			(xy 160.338006 -309.929201) (xy 160.376127 -309.898076) (xy 160.418748 -309.873469) (xy 160.464764 -309.856017)
			(xy 160.512983 -309.846173) (xy 160.562158 -309.844192) (xy 160.611013 -309.850124) (xy 160.658284 -309.863816)
			(xy 160.702746 -309.884914) (xy 160.743249 -309.91287) (xy 160.778742 -309.946962) (xy 160.808307 -309.986306)
			(xy 160.831178 -310.029883) (xy 160.846762 -310.076564) (xy 160.854657 -310.125141) (xy 160.855152 -310.149748)
			(xy 161.194254 -310.149748) (xy 161.198214 -310.100694) (xy 161.209991 -310.05291) (xy 161.229282 -310.007634)
			(xy 161.255585 -309.966038) (xy 161.28822 -309.929201) (xy 161.326341 -309.898076) (xy 161.368962 -309.873469)
			(xy 161.414978 -309.856017) (xy 161.463197 -309.846173) (xy 161.512372 -309.844192) (xy 161.561227 -309.850124)
			(xy 161.608498 -309.863816) (xy 161.65296 -309.884914) (xy 161.693463 -309.91287) (xy 161.728956 -309.946962)
			(xy 161.758521 -309.986306) (xy 161.781392 -310.029883) (xy 161.796976 -310.076564) (xy 161.804871 -310.125141)
			(xy 161.805198 -310.141392) (xy 162.14433 -310.141392) (xy 162.149701 -310.09205) (xy 162.162983 -310.044228)
			(xy 162.183827 -309.999184) (xy 162.211684 -309.958105) (xy 162.245819 -309.922075) (xy 162.285333 -309.892041)
			(xy 162.329186 -309.868796) (xy 162.376222 -309.852951) (xy 162.425202 -309.844924) (xy 162.450018 -309.84444)
			(xy 162.464201 -309.844613) (xy 162.492441 -309.847288) (xy 162.506406 -309.849774) (xy 162.518852 -309.85206)
			(xy 162.542474 -309.844694) (xy 162.619944 -309.767224) (xy 162.62731 -309.743602) (xy 162.625024 -309.731156)
			(xy 162.622546 -309.71719) (xy 162.619875 -309.688951) (xy 162.61969 -309.674768) (xy 162.620212 -309.649513)
			(xy 162.628525 -309.599691) (xy 162.644926 -309.551917) (xy 162.668967 -309.507494) (xy 162.699991 -309.467634)
			(xy 162.737153 -309.433424) (xy 162.779439 -309.405798) (xy 162.825695 -309.385508) (xy 162.87466 -309.373108)
			(xy 162.924998 -309.368937) (xy 162.975336 -309.373108) (xy 163.024301 -309.385508) (xy 163.070557 -309.405798)
			(xy 163.112843 -309.433424) (xy 163.150005 -309.467634) (xy 163.181029 -309.507494) (xy 163.20507 -309.551917)
			(xy 163.221471 -309.599691) (xy 163.229784 -309.649513) (xy 163.230306 -309.674768) (xy 163.230125 -309.688951)
			(xy 163.227456 -309.717191) (xy 163.224972 -309.731156) (xy 163.222686 -309.743602) (xy 163.230052 -309.767224)
			(xy 163.307522 -309.844694) (xy 163.331144 -309.85206) (xy 163.34359 -309.849774) (xy 163.357557 -309.847303)
			(xy 163.385796 -309.844627) (xy 163.399978 -309.84444) (xy 163.4248 -309.844854) (xy 163.473791 -309.852882)
			(xy 163.520838 -309.86873) (xy 163.564701 -309.89198) (xy 163.604225 -309.92202) (xy 163.638369 -309.958059)
			(xy 163.666232 -309.999147) (xy 163.687082 -310.044201) (xy 163.700368 -310.092034) (xy 163.705739 -310.141378)
			(xy 164.04423 -310.141378) (xy 164.049603 -310.092036) (xy 164.062888 -310.044214) (xy 164.083735 -309.99917)
			(xy 164.111594 -309.958093) (xy 164.145731 -309.922063) (xy 164.185248 -309.892032) (xy 164.229103 -309.868788)
			(xy 164.27614 -309.852946) (xy 164.325121 -309.844923) (xy 164.349938 -309.84444) (xy 164.364121 -309.844611)
			(xy 164.392361 -309.847287) (xy 164.406326 -309.849774) (xy 164.418772 -309.85206) (xy 164.442394 -309.844694)
			(xy 164.519864 -309.767224) (xy 164.52723 -309.743602) (xy 164.524944 -309.731156) (xy 164.522466 -309.71719)
			(xy 164.519795 -309.688951) (xy 164.51961 -309.674768) (xy 164.520132 -309.649513) (xy 164.528445 -309.599691)
			(xy 164.544846 -309.551917) (xy 164.568887 -309.507494) (xy 164.599911 -309.467634) (xy 164.637073 -309.433424)
			(xy 164.679359 -309.405798) (xy 164.725615 -309.385508) (xy 164.77458 -309.373108) (xy 164.824918 -309.368937)
			(xy 164.875256 -309.373108) (xy 164.924221 -309.385508) (xy 164.970477 -309.405798) (xy 165.012763 -309.433424)
			(xy 165.049925 -309.467634) (xy 165.080949 -309.507494) (xy 165.10499 -309.551917) (xy 165.121391 -309.599691)
			(xy 165.129704 -309.649513) (xy 165.130226 -309.674768) (xy 165.130045 -309.688951) (xy 165.127376 -309.717191)
			(xy 165.124892 -309.731156) (xy 165.122606 -309.743602) (xy 165.129972 -309.767224) (xy 165.207442 -309.844694)
			(xy 165.231064 -309.85206) (xy 165.24351 -309.849774) (xy 165.257476 -309.8473) (xy 165.285716 -309.844627)
			(xy 165.299898 -309.84444) (xy 165.314081 -309.844616) (xy 165.342321 -309.847288) (xy 165.356286 -309.849774)
			(xy 165.368732 -309.85206) (xy 165.392354 -309.844694) (xy 165.469824 -309.767224) (xy 165.47719 -309.743602)
			(xy 165.474904 -309.731156) (xy 165.472425 -309.71719) (xy 165.469755 -309.688951) (xy 165.46957 -309.674768)
			(xy 165.470092 -309.649513) (xy 165.478405 -309.599691) (xy 165.494806 -309.551917) (xy 165.518847 -309.507494)
			(xy 165.549871 -309.467634) (xy 165.587033 -309.433424) (xy 165.629319 -309.405798) (xy 165.675575 -309.385508)
			(xy 165.72454 -309.373108) (xy 165.774878 -309.368937) (xy 165.825216 -309.373108) (xy 165.874181 -309.385508)
			(xy 165.920437 -309.405798) (xy 165.962723 -309.433424) (xy 165.999885 -309.467634) (xy 166.030909 -309.507494)
			(xy 166.05495 -309.551917) (xy 166.071351 -309.599691) (xy 166.079664 -309.649513) (xy 166.080186 -309.674768)
			(xy 166.080005 -309.688951) (xy 166.077336 -309.717191) (xy 166.074852 -309.731156) (xy 166.072566 -309.743602)
			(xy 166.079932 -309.767224) (xy 166.157402 -309.844694) (xy 166.181024 -309.85206) (xy 166.19347 -309.849774)
			(xy 166.207435 -309.847292) (xy 166.235675 -309.844624) (xy 166.249858 -309.84444) (xy 166.274682 -309.844833)
			(xy 166.323678 -309.852858) (xy 166.370729 -309.868704) (xy 166.414597 -309.891954) (xy 166.454126 -309.921994)
			(xy 166.488274 -309.958034) (xy 166.516142 -309.999123) (xy 166.536995 -310.04418) (xy 166.550285 -310.092017)
			(xy 166.55566 -310.141373) (xy 166.555207 -310.149748) (xy 166.894268 -310.149748) (xy 166.898228 -310.100694)
			(xy 166.910005 -310.05291) (xy 166.929296 -310.007634) (xy 166.955599 -309.966038) (xy 166.988234 -309.929201)
			(xy 167.026355 -309.898076) (xy 167.068976 -309.873469) (xy 167.114992 -309.856017) (xy 167.163211 -309.846173)
			(xy 167.212386 -309.844192) (xy 167.261241 -309.850124) (xy 167.308512 -309.863816) (xy 167.352974 -309.884914)
			(xy 167.393477 -309.91287) (xy 167.42897 -309.946962) (xy 167.458535 -309.986306) (xy 167.481406 -310.029883)
			(xy 167.49699 -310.076564) (xy 167.504885 -310.125141) (xy 167.50538 -310.149748) (xy 167.844228 -310.149748)
			(xy 167.848188 -310.100694) (xy 167.859965 -310.05291) (xy 167.879256 -310.007634) (xy 167.905559 -309.966038)
			(xy 167.938194 -309.929201) (xy 167.976315 -309.898076) (xy 168.018936 -309.873469) (xy 168.064952 -309.856017)
			(xy 168.113171 -309.846173) (xy 168.162346 -309.844192) (xy 168.211201 -309.850124) (xy 168.258472 -309.863816)
			(xy 168.302934 -309.884914) (xy 168.343437 -309.91287) (xy 168.37893 -309.946962) (xy 168.408495 -309.986306)
			(xy 168.431366 -310.029883) (xy 168.44695 -310.076564) (xy 168.454845 -310.125141) (xy 168.45534 -310.149748)
			(xy 168.794188 -310.149748) (xy 168.798148 -310.100694) (xy 168.809925 -310.05291) (xy 168.829216 -310.007634)
			(xy 168.855519 -309.966038) (xy 168.888154 -309.929201) (xy 168.926275 -309.898076) (xy 168.968896 -309.873469)
			(xy 169.014912 -309.856017) (xy 169.063131 -309.846173) (xy 169.112306 -309.844192) (xy 169.161161 -309.850124)
			(xy 169.208432 -309.863816) (xy 169.252894 -309.884914) (xy 169.293397 -309.91287) (xy 169.32889 -309.946962)
			(xy 169.358455 -309.986306) (xy 169.381326 -310.029883) (xy 169.39691 -310.076564) (xy 169.404805 -310.125141)
			(xy 169.4053 -310.149748) (xy 169.744148 -310.149748) (xy 169.748108 -310.100694) (xy 169.759885 -310.05291)
			(xy 169.779176 -310.007634) (xy 169.805479 -309.966038) (xy 169.838114 -309.929201) (xy 169.876235 -309.898076)
			(xy 169.918856 -309.873469) (xy 169.964872 -309.856017) (xy 170.013091 -309.846173) (xy 170.062266 -309.844192)
			(xy 170.111121 -309.850124) (xy 170.158392 -309.863816) (xy 170.202854 -309.884914) (xy 170.243357 -309.91287)
			(xy 170.27885 -309.946962) (xy 170.308415 -309.986306) (xy 170.331286 -310.029883) (xy 170.34687 -310.076564)
			(xy 170.354765 -310.125141) (xy 170.35526 -310.149748) (xy 170.694108 -310.149748) (xy 170.698068 -310.100694)
			(xy 170.709845 -310.05291) (xy 170.729136 -310.007634) (xy 170.755439 -309.966038) (xy 170.788074 -309.929201)
			(xy 170.826195 -309.898076) (xy 170.868816 -309.873469) (xy 170.914832 -309.856017) (xy 170.963051 -309.846173)
			(xy 171.012226 -309.844192) (xy 171.061081 -309.850124) (xy 171.108352 -309.863816) (xy 171.152814 -309.884914)
			(xy 171.193317 -309.91287) (xy 171.22881 -309.946962) (xy 171.258375 -309.986306) (xy 171.281246 -310.029883)
			(xy 171.29683 -310.076564) (xy 171.304725 -310.125141) (xy 171.305053 -310.141423) (xy 171.644229 -310.141423)
			(xy 171.649594 -310.092082) (xy 171.662871 -310.04426) (xy 171.683709 -309.999215) (xy 171.71156 -309.958134)
			(xy 171.74569 -309.922101) (xy 171.785199 -309.892063) (xy 171.829047 -309.868812) (xy 171.87608 -309.852961)
			(xy 171.925056 -309.844928) (xy 171.949872 -309.84444) (xy 171.964055 -309.84462) (xy 171.992295 -309.84729)
			(xy 172.00626 -309.849774) (xy 172.018706 -309.85206) (xy 172.042328 -309.844694) (xy 172.119798 -309.767224)
			(xy 172.127164 -309.743602) (xy 172.124878 -309.731156) (xy 172.122399 -309.71719) (xy 172.119729 -309.688951)
			(xy 172.119544 -309.674768) (xy 172.120066 -309.649513) (xy 172.128379 -309.599691) (xy 172.14478 -309.551917)
			(xy 172.168821 -309.507494) (xy 172.199845 -309.467634) (xy 172.237007 -309.433424) (xy 172.279293 -309.405798)
			(xy 172.325549 -309.385508) (xy 172.374514 -309.373108) (xy 172.424852 -309.368937) (xy 172.47519 -309.373108)
			(xy 172.524155 -309.385508) (xy 172.570411 -309.405798) (xy 172.612697 -309.433424) (xy 172.649859 -309.467634)
			(xy 172.680883 -309.507494) (xy 172.704924 -309.551917) (xy 172.721325 -309.599691) (xy 172.729638 -309.649513)
			(xy 172.73016 -309.674768) (xy 172.72998 -309.688951) (xy 172.72731 -309.717191) (xy 172.724826 -309.731156)
			(xy 172.724826 -309.73141) (xy 172.72337 -309.743641) (xy 172.730654 -309.767127) (xy 172.738796 -309.776368)
			(xy 172.807376 -309.844694) (xy 172.830998 -309.85206) (xy 172.843444 -309.849774) (xy 172.857472 -309.847286)
			(xy 172.88584 -309.844616) (xy 172.900086 -309.84444) (xy 172.924907 -309.844863) (xy 172.973897 -309.852892)
			(xy 173.020942 -309.86874) (xy 173.064803 -309.891991) (xy 173.104325 -309.922031) (xy 173.138467 -309.958069)
			(xy 173.166329 -309.999156) (xy 173.187176 -310.044209) (xy 173.200461 -310.092041) (xy 173.205832 -310.141393)
			(xy 173.20538 -310.149748) (xy 173.544242 -310.149748) (xy 173.548202 -310.100694) (xy 173.559979 -310.05291)
			(xy 173.57927 -310.007634) (xy 173.605573 -309.966038) (xy 173.638208 -309.929201) (xy 173.676329 -309.898076)
			(xy 173.71895 -309.873469) (xy 173.764966 -309.856017) (xy 173.813185 -309.846173) (xy 173.86236 -309.844192)
			(xy 173.911215 -309.850124) (xy 173.958486 -309.863816) (xy 174.002948 -309.884914) (xy 174.043451 -309.91287)
			(xy 174.078944 -309.946962) (xy 174.108509 -309.986306) (xy 174.13138 -310.029883) (xy 174.146964 -310.076564)
			(xy 174.154859 -310.125141) (xy 174.155354 -310.149748) (xy 174.494202 -310.149748) (xy 174.498162 -310.100694)
			(xy 174.509939 -310.05291) (xy 174.52923 -310.007634) (xy 174.555533 -309.966038) (xy 174.588168 -309.929201)
			(xy 174.626289 -309.898076) (xy 174.66891 -309.873469) (xy 174.714926 -309.856017) (xy 174.763145 -309.846173)
			(xy 174.81232 -309.844192) (xy 174.861175 -309.850124) (xy 174.908446 -309.863816) (xy 174.952908 -309.884914)
			(xy 174.993411 -309.91287) (xy 175.028904 -309.946962) (xy 175.058469 -309.986306) (xy 175.08134 -310.029883)
			(xy 175.096924 -310.076564) (xy 175.104819 -310.125141) (xy 175.105314 -310.149748) (xy 175.444162 -310.149748)
			(xy 175.448122 -310.100694) (xy 175.459899 -310.05291) (xy 175.47919 -310.007634) (xy 175.505493 -309.966038)
			(xy 175.538128 -309.929201) (xy 175.576249 -309.898076) (xy 175.61887 -309.873469) (xy 175.664886 -309.856017)
			(xy 175.713105 -309.846173) (xy 175.76228 -309.844192) (xy 175.811135 -309.850124) (xy 175.858406 -309.863816)
			(xy 175.902868 -309.884914) (xy 175.943371 -309.91287) (xy 175.978864 -309.946962) (xy 176.008429 -309.986306)
			(xy 176.0313 -310.029883) (xy 176.046884 -310.076564) (xy 176.054779 -310.125141) (xy 176.055274 -310.149748)
			(xy 176.054779 -310.174355) (xy 176.046884 -310.222932) (xy 176.0313 -310.269613) (xy 176.008429 -310.31319)
			(xy 175.978864 -310.352534) (xy 175.943371 -310.386626) (xy 175.902868 -310.414582) (xy 175.858406 -310.43568)
			(xy 175.811135 -310.449372) (xy 175.76228 -310.455304) (xy 175.713105 -310.453323) (xy 175.664886 -310.443479)
			(xy 175.61887 -310.426027) (xy 175.576249 -310.40142) (xy 175.538128 -310.370295) (xy 175.505493 -310.333458)
			(xy 175.47919 -310.291862) (xy 175.459899 -310.246586) (xy 175.448122 -310.198802) (xy 175.444162 -310.149748)
			(xy 175.105314 -310.149748) (xy 175.104819 -310.174355) (xy 175.096924 -310.222932) (xy 175.08134 -310.269613)
			(xy 175.058469 -310.31319) (xy 175.028904 -310.352534) (xy 174.993411 -310.386626) (xy 174.952908 -310.414582)
			(xy 174.908446 -310.43568) (xy 174.861175 -310.449372) (xy 174.81232 -310.455304) (xy 174.763145 -310.453323)
			(xy 174.714926 -310.443479) (xy 174.66891 -310.426027) (xy 174.626289 -310.40142) (xy 174.588168 -310.370295)
			(xy 174.555533 -310.333458) (xy 174.52923 -310.291862) (xy 174.509939 -310.246586) (xy 174.498162 -310.198802)
			(xy 174.494202 -310.149748) (xy 174.155354 -310.149748) (xy 174.154859 -310.174355) (xy 174.146964 -310.222932)
			(xy 174.13138 -310.269613) (xy 174.108509 -310.31319) (xy 174.078944 -310.352534) (xy 174.043451 -310.386626)
			(xy 174.002948 -310.414582) (xy 173.958486 -310.43568) (xy 173.911215 -310.449372) (xy 173.86236 -310.455304)
			(xy 173.813185 -310.453323) (xy 173.764966 -310.443479) (xy 173.71895 -310.426027) (xy 173.676329 -310.40142)
			(xy 173.638208 -310.370295) (xy 173.605573 -310.333458) (xy 173.57927 -310.291862) (xy 173.559979 -310.246586)
			(xy 173.548202 -310.198802) (xy 173.544242 -310.149748) (xy 173.20538 -310.149748) (xy 173.203149 -310.190963)
			(xy 173.192481 -310.239446) (xy 173.174111 -310.285565) (xy 173.148521 -310.328104) (xy 173.116387 -310.365943)
			(xy 173.078554 -310.398085) (xy 173.03602 -310.423683) (xy 172.989905 -310.442063) (xy 172.941425 -310.45274)
			(xy 172.891855 -310.455434) (xy 172.842502 -310.450073) (xy 172.794667 -310.436798) (xy 172.74961 -310.415959)
			(xy 172.708517 -310.388106) (xy 172.672472 -310.353971) (xy 172.642424 -310.314455) (xy 172.619165 -310.270599)
			(xy 172.603307 -310.223557) (xy 172.595268 -310.174569) (xy 172.594778 -310.149748) (xy 172.594962 -310.135565)
			(xy 172.597629 -310.107325) (xy 172.600112 -310.09336) (xy 172.600112 -310.093106) (xy 172.601613 -310.080877)
			(xy 172.594296 -310.057387) (xy 172.586142 -310.048148) (xy 172.517562 -309.979822) (xy 172.49394 -309.972456)
			(xy 172.481494 -309.974742) (xy 172.467465 -309.977225) (xy 172.439098 -309.979898) (xy 172.424852 -309.980076)
			(xy 172.410669 -309.979893) (xy 172.382429 -309.977225) (xy 172.368464 -309.974742) (xy 172.356018 -309.972456)
			(xy 172.332396 -309.979822) (xy 172.254926 -310.057292) (xy 172.24756 -310.080914) (xy 172.249846 -310.09336)
			(xy 172.252326 -310.107325) (xy 172.254996 -310.135565) (xy 172.25518 -310.149748) (xy 172.25467 -310.174564)
			(xy 172.246634 -310.22354) (xy 172.23078 -310.270571) (xy 172.207526 -310.314418) (xy 172.177486 -310.353925)
			(xy 172.14145 -310.388052) (xy 172.100368 -310.415901) (xy 172.055321 -310.436736) (xy 172.007498 -310.450009)
			(xy 171.958157 -310.455371) (xy 171.908599 -310.452681) (xy 171.860129 -310.442009) (xy 171.814023 -310.423636)
			(xy 171.771498 -310.398046) (xy 171.733672 -310.365914) (xy 171.701542 -310.328086) (xy 171.675955 -310.285559)
			(xy 171.657585 -310.239452) (xy 171.646916 -310.190981) (xy 171.644229 -310.141423) (xy 171.305053 -310.141423)
			(xy 171.30522 -310.149748) (xy 171.304725 -310.174355) (xy 171.29683 -310.222932) (xy 171.281246 -310.269613)
			(xy 171.258375 -310.31319) (xy 171.22881 -310.352534) (xy 171.193317 -310.386626) (xy 171.152814 -310.414582)
			(xy 171.108352 -310.43568) (xy 171.061081 -310.449372) (xy 171.012226 -310.455304) (xy 170.963051 -310.453323)
			(xy 170.914832 -310.443479) (xy 170.868816 -310.426027) (xy 170.826195 -310.40142) (xy 170.788074 -310.370295)
			(xy 170.755439 -310.333458) (xy 170.729136 -310.291862) (xy 170.709845 -310.246586) (xy 170.698068 -310.198802)
			(xy 170.694108 -310.149748) (xy 170.35526 -310.149748) (xy 170.354765 -310.174355) (xy 170.34687 -310.222932)
			(xy 170.331286 -310.269613) (xy 170.308415 -310.31319) (xy 170.27885 -310.352534) (xy 170.243357 -310.386626)
			(xy 170.202854 -310.414582) (xy 170.158392 -310.43568) (xy 170.111121 -310.449372) (xy 170.062266 -310.455304)
			(xy 170.013091 -310.453323) (xy 169.964872 -310.443479) (xy 169.918856 -310.426027) (xy 169.876235 -310.40142)
			(xy 169.838114 -310.370295) (xy 169.805479 -310.333458) (xy 169.779176 -310.291862) (xy 169.759885 -310.246586)
			(xy 169.748108 -310.198802) (xy 169.744148 -310.149748) (xy 169.4053 -310.149748) (xy 169.404805 -310.174355)
			(xy 169.39691 -310.222932) (xy 169.381326 -310.269613) (xy 169.358455 -310.31319) (xy 169.32889 -310.352534)
			(xy 169.293397 -310.386626) (xy 169.252894 -310.414582) (xy 169.208432 -310.43568) (xy 169.161161 -310.449372)
			(xy 169.112306 -310.455304) (xy 169.063131 -310.453323) (xy 169.014912 -310.443479) (xy 168.968896 -310.426027)
			(xy 168.926275 -310.40142) (xy 168.888154 -310.370295) (xy 168.855519 -310.333458) (xy 168.829216 -310.291862)
			(xy 168.809925 -310.246586) (xy 168.798148 -310.198802) (xy 168.794188 -310.149748) (xy 168.45534 -310.149748)
			(xy 168.454845 -310.174355) (xy 168.44695 -310.222932) (xy 168.431366 -310.269613) (xy 168.408495 -310.31319)
			(xy 168.37893 -310.352534) (xy 168.343437 -310.386626) (xy 168.302934 -310.414582) (xy 168.258472 -310.43568)
			(xy 168.211201 -310.449372) (xy 168.162346 -310.455304) (xy 168.113171 -310.453323) (xy 168.064952 -310.443479)
			(xy 168.018936 -310.426027) (xy 167.976315 -310.40142) (xy 167.938194 -310.370295) (xy 167.905559 -310.333458)
			(xy 167.879256 -310.291862) (xy 167.859965 -310.246586) (xy 167.848188 -310.198802) (xy 167.844228 -310.149748)
			(xy 167.50538 -310.149748) (xy 167.504885 -310.174355) (xy 167.49699 -310.222932) (xy 167.481406 -310.269613)
			(xy 167.458535 -310.31319) (xy 167.42897 -310.352534) (xy 167.393477 -310.386626) (xy 167.352974 -310.414582)
			(xy 167.308512 -310.43568) (xy 167.261241 -310.449372) (xy 167.212386 -310.455304) (xy 167.163211 -310.453323)
			(xy 167.114992 -310.443479) (xy 167.068976 -310.426027) (xy 167.026355 -310.40142) (xy 166.988234 -310.370295)
			(xy 166.955599 -310.333458) (xy 166.929296 -310.291862) (xy 166.910005 -310.246586) (xy 166.898228 -310.198802)
			(xy 166.894268 -310.149748) (xy 166.555207 -310.149748) (xy 166.552979 -310.190949) (xy 166.542313 -310.239438)
			(xy 166.523943 -310.285563) (xy 166.498353 -310.328108) (xy 166.466217 -310.365953) (xy 166.428381 -310.3981)
			(xy 166.385844 -310.423703) (xy 166.339724 -310.442087) (xy 166.291238 -310.452767) (xy 166.241663 -310.455462)
			(xy 166.192305 -310.450102) (xy 166.144465 -310.436827) (xy 166.099402 -310.415987) (xy 166.058304 -310.388131)
			(xy 166.022254 -310.353993) (xy 165.992202 -310.314473) (xy 165.96894 -310.270612) (xy 165.95308 -310.223565)
			(xy 165.94504 -310.174572) (xy 165.94455 -310.149748) (xy 165.944734 -310.135565) (xy 165.947401 -310.107325)
			(xy 165.949884 -310.09336) (xy 165.95217 -310.080914) (xy 165.944804 -310.057292) (xy 165.867334 -309.979822)
			(xy 165.843712 -309.972456) (xy 165.831266 -309.974742) (xy 165.8173 -309.977219) (xy 165.789061 -309.97989)
			(xy 165.774878 -309.980076) (xy 165.760695 -309.979903) (xy 165.732455 -309.977229) (xy 165.71849 -309.974742)
			(xy 165.706044 -309.972456) (xy 165.682422 -309.979822) (xy 165.604952 -310.057292) (xy 165.597586 -310.080914)
			(xy 165.599872 -310.09336) (xy 165.602353 -310.107325) (xy 165.605022 -310.135565) (xy 165.605206 -310.149748)
			(xy 165.604684 -310.175003) (xy 165.596371 -310.224825) (xy 165.57997 -310.272599) (xy 165.555929 -310.317022)
			(xy 165.524905 -310.356882) (xy 165.487743 -310.391092) (xy 165.445457 -310.418718) (xy 165.399201 -310.439008)
			(xy 165.350236 -310.451408) (xy 165.299898 -310.455579) (xy 165.24956 -310.451408) (xy 165.200595 -310.439008)
			(xy 165.154339 -310.418718) (xy 165.112053 -310.391092) (xy 165.074891 -310.356882) (xy 165.043867 -310.317022)
			(xy 165.019826 -310.272599) (xy 165.003425 -310.224825) (xy 164.995112 -310.175003) (xy 164.99459 -310.149748)
			(xy 164.994773 -310.135565) (xy 164.997441 -310.107325) (xy 164.999924 -310.09336) (xy 165.00221 -310.080914)
			(xy 164.994844 -310.057292) (xy 164.917374 -309.979822) (xy 164.893752 -309.972456) (xy 164.881306 -309.974742)
			(xy 164.867339 -309.977213) (xy 164.8391 -309.979889) (xy 164.824918 -309.980076) (xy 164.810735 -309.979897)
			(xy 164.782495 -309.977227) (xy 164.76853 -309.974742) (xy 164.756084 -309.972456) (xy 164.732462 -309.979822)
			(xy 164.654992 -310.057292) (xy 164.647626 -310.080914) (xy 164.649912 -310.09336) (xy 164.652393 -310.107325)
			(xy 164.655062 -310.135565) (xy 164.655246 -310.149748) (xy 164.65467 -310.174565) (xy 164.646633 -310.223543)
			(xy 164.630778 -310.270576) (xy 164.607522 -310.314424) (xy 164.577479 -310.353933) (xy 164.54144 -310.38806)
			(xy 164.500355 -310.415908) (xy 164.455305 -310.436742) (xy 164.407479 -310.450013) (xy 164.358136 -310.455372)
			(xy 164.308575 -310.452678) (xy 164.260104 -310.442001) (xy 164.213998 -310.423623) (xy 164.171473 -310.398028)
			(xy 164.133648 -310.365891) (xy 164.101522 -310.328057) (xy 164.075939 -310.285525) (xy 164.057574 -310.239414)
			(xy 164.046911 -310.190939) (xy 164.04423 -310.141378) (xy 163.705739 -310.141378) (xy 163.70574 -310.141387)
			(xy 163.703057 -310.190959) (xy 163.69239 -310.239444) (xy 163.67402 -310.285564) (xy 163.64843 -310.328105)
			(xy 163.616296 -310.365946) (xy 163.578462 -310.398089) (xy 163.535927 -310.423689) (xy 163.489811 -310.44207)
			(xy 163.441328 -310.452748) (xy 163.391757 -310.455442) (xy 163.342403 -310.450081) (xy 163.294567 -310.436806)
			(xy 163.249508 -310.415967) (xy 163.208414 -310.388113) (xy 163.172367 -310.353978) (xy 163.142318 -310.31446)
			(xy 163.119058 -310.270603) (xy 163.103199 -310.223559) (xy 163.09516 -310.17457) (xy 163.09467 -310.149748)
			(xy 163.094854 -310.135565) (xy 163.097521 -310.107325) (xy 163.100004 -310.09336) (xy 163.10229 -310.080914)
			(xy 163.094924 -310.057292) (xy 163.017454 -309.979822) (xy 162.993832 -309.972456) (xy 162.981386 -309.974742)
			(xy 162.96742 -309.977216) (xy 162.93918 -309.97989) (xy 162.924998 -309.980076) (xy 162.910815 -309.9799)
			(xy 162.882575 -309.977228) (xy 162.86861 -309.974742) (xy 162.856164 -309.972456) (xy 162.832542 -309.979822)
			(xy 162.755072 -310.057292) (xy 162.747706 -310.080914) (xy 162.749992 -310.09336) (xy 162.752473 -310.107325)
			(xy 162.755142 -310.135565) (xy 162.755326 -310.149748) (xy 162.75477 -310.174564) (xy 162.746733 -310.223542)
			(xy 162.730878 -310.270575) (xy 162.707623 -310.314422) (xy 162.677581 -310.35393) (xy 162.641543 -310.388058)
			(xy 162.600459 -310.415906) (xy 162.55541 -310.43674) (xy 162.507585 -310.450012) (xy 162.458242 -310.455372)
			(xy 162.408682 -310.452679) (xy 162.360211 -310.442003) (xy 162.314106 -310.423627) (xy 162.27158 -310.398034)
			(xy 162.233755 -310.365898) (xy 162.201628 -310.328066) (xy 162.176044 -310.285535) (xy 162.157677 -310.239426)
			(xy 162.147012 -310.190952) (xy 162.14433 -310.141392) (xy 161.805198 -310.141392) (xy 161.805366 -310.149748)
			(xy 161.804871 -310.174355) (xy 161.796976 -310.222932) (xy 161.781392 -310.269613) (xy 161.758521 -310.31319)
			(xy 161.728956 -310.352534) (xy 161.693463 -310.386626) (xy 161.65296 -310.414582) (xy 161.608498 -310.43568)
			(xy 161.561227 -310.449372) (xy 161.512372 -310.455304) (xy 161.463197 -310.453323) (xy 161.414978 -310.443479)
			(xy 161.368962 -310.426027) (xy 161.326341 -310.40142) (xy 161.28822 -310.370295) (xy 161.255585 -310.333458)
			(xy 161.229282 -310.291862) (xy 161.209991 -310.246586) (xy 161.198214 -310.198802) (xy 161.194254 -310.149748)
			(xy 160.855152 -310.149748) (xy 160.854657 -310.174355) (xy 160.846762 -310.222932) (xy 160.831178 -310.269613)
			(xy 160.808307 -310.31319) (xy 160.778742 -310.352534) (xy 160.743249 -310.386626) (xy 160.702746 -310.414582)
			(xy 160.658284 -310.43568) (xy 160.611013 -310.449372) (xy 160.562158 -310.455304) (xy 160.512983 -310.453323)
			(xy 160.464764 -310.443479) (xy 160.418748 -310.426027) (xy 160.376127 -310.40142) (xy 160.338006 -310.370295)
			(xy 160.305371 -310.333458) (xy 160.279068 -310.291862) (xy 160.259777 -310.246586) (xy 160.248 -310.198802)
			(xy 160.24404 -310.149748) (xy 159.905192 -310.149748) (xy 159.904697 -310.174355) (xy 159.896802 -310.222932)
			(xy 159.881218 -310.269613) (xy 159.858347 -310.31319) (xy 159.828782 -310.352534) (xy 159.793289 -310.386626)
			(xy 159.752786 -310.414582) (xy 159.708324 -310.43568) (xy 159.661053 -310.449372) (xy 159.612198 -310.455304)
			(xy 159.563023 -310.453323) (xy 159.514804 -310.443479) (xy 159.468788 -310.426027) (xy 159.426167 -310.40142)
			(xy 159.388046 -310.370295) (xy 159.355411 -310.333458) (xy 159.329108 -310.291862) (xy 159.309817 -310.246586)
			(xy 159.29804 -310.198802) (xy 159.29408 -310.149748) (xy 158.955232 -310.149748) (xy 158.954737 -310.174355)
			(xy 158.946842 -310.222932) (xy 158.931258 -310.269613) (xy 158.908387 -310.31319) (xy 158.878822 -310.352534)
			(xy 158.843329 -310.386626) (xy 158.802826 -310.414582) (xy 158.758364 -310.43568) (xy 158.711093 -310.449372)
			(xy 158.662238 -310.455304) (xy 158.613063 -310.453323) (xy 158.564844 -310.443479) (xy 158.518828 -310.426027)
			(xy 158.476207 -310.40142) (xy 158.438086 -310.370295) (xy 158.405451 -310.333458) (xy 158.379148 -310.291862)
			(xy 158.359857 -310.246586) (xy 158.34808 -310.198802) (xy 158.34412 -310.149748) (xy 158.005272 -310.149748)
			(xy 158.004777 -310.174355) (xy 157.996882 -310.222932) (xy 157.981298 -310.269613) (xy 157.958427 -310.31319)
			(xy 157.928862 -310.352534) (xy 157.893369 -310.386626) (xy 157.852866 -310.414582) (xy 157.808404 -310.43568)
			(xy 157.761133 -310.449372) (xy 157.712278 -310.455304) (xy 157.663103 -310.453323) (xy 157.614884 -310.443479)
			(xy 157.568868 -310.426027) (xy 157.526247 -310.40142) (xy 157.488126 -310.370295) (xy 157.455491 -310.333458)
			(xy 157.429188 -310.291862) (xy 157.409897 -310.246586) (xy 157.39812 -310.198802) (xy 157.39416 -310.149748)
			(xy 157.055312 -310.149748) (xy 157.054817 -310.174355) (xy 157.046922 -310.222932) (xy 157.031338 -310.269613)
			(xy 157.008467 -310.31319) (xy 156.978902 -310.352534) (xy 156.943409 -310.386626) (xy 156.902906 -310.414582)
			(xy 156.858444 -310.43568) (xy 156.811173 -310.449372) (xy 156.762318 -310.455304) (xy 156.713143 -310.453323)
			(xy 156.664924 -310.443479) (xy 156.618908 -310.426027) (xy 156.576287 -310.40142) (xy 156.538166 -310.370295)
			(xy 156.505531 -310.333458) (xy 156.479228 -310.291862) (xy 156.459937 -310.246586) (xy 156.44816 -310.198802)
			(xy 156.4442 -310.149748) (xy 156.105352 -310.149748) (xy 156.104857 -310.174355) (xy 156.096962 -310.222932)
			(xy 156.081378 -310.269613) (xy 156.058507 -310.31319) (xy 156.028942 -310.352534) (xy 155.993449 -310.386626)
			(xy 155.952946 -310.414582) (xy 155.908484 -310.43568) (xy 155.861213 -310.449372) (xy 155.812358 -310.455304)
			(xy 155.763183 -310.453323) (xy 155.714964 -310.443479) (xy 155.668948 -310.426027) (xy 155.626327 -310.40142)
			(xy 155.588206 -310.370295) (xy 155.555571 -310.333458) (xy 155.529268 -310.291862) (xy 155.509977 -310.246586)
			(xy 155.4982 -310.198802) (xy 155.49424 -310.149748) (xy 155.155392 -310.149748) (xy 155.154897 -310.174355)
			(xy 155.147002 -310.222932) (xy 155.131418 -310.269613) (xy 155.108547 -310.31319) (xy 155.078982 -310.352534)
			(xy 155.043489 -310.386626) (xy 155.002986 -310.414582) (xy 154.958524 -310.43568) (xy 154.911253 -310.449372)
			(xy 154.862398 -310.455304) (xy 154.813223 -310.453323) (xy 154.765004 -310.443479) (xy 154.718988 -310.426027)
			(xy 154.676367 -310.40142) (xy 154.638246 -310.370295) (xy 154.605611 -310.333458) (xy 154.579308 -310.291862)
			(xy 154.560017 -310.246586) (xy 154.54824 -310.198802) (xy 154.54428 -310.149748) (xy 154.205178 -310.149748)
			(xy 154.204683 -310.174355) (xy 154.196788 -310.222932) (xy 154.181204 -310.269613) (xy 154.158333 -310.31319)
			(xy 154.128768 -310.352534) (xy 154.093275 -310.386626) (xy 154.052772 -310.414582) (xy 154.00831 -310.43568)
			(xy 153.961039 -310.449372) (xy 153.912184 -310.455304) (xy 153.863009 -310.453323) (xy 153.81479 -310.443479)
			(xy 153.768774 -310.426027) (xy 153.726153 -310.40142) (xy 153.688032 -310.370295) (xy 153.655397 -310.333458)
			(xy 153.629094 -310.291862) (xy 153.609803 -310.246586) (xy 153.598026 -310.198802) (xy 153.594066 -310.149748)
			(xy 153.255218 -310.149748) (xy 153.254723 -310.174355) (xy 153.246828 -310.222932) (xy 153.231244 -310.269613)
			(xy 153.208373 -310.31319) (xy 153.178808 -310.352534) (xy 153.143315 -310.386626) (xy 153.102812 -310.414582)
			(xy 153.05835 -310.43568) (xy 153.011079 -310.449372) (xy 152.962224 -310.455304) (xy 152.913049 -310.453323)
			(xy 152.86483 -310.443479) (xy 152.818814 -310.426027) (xy 152.776193 -310.40142) (xy 152.738072 -310.370295)
			(xy 152.705437 -310.333458) (xy 152.679134 -310.291862) (xy 152.659843 -310.246586) (xy 152.648066 -310.198802)
			(xy 152.644106 -310.149748) (xy 152.304999 -310.149748) (xy 152.305004 -310.150002) (xy 152.304509 -310.174609)
			(xy 152.296614 -310.223186) (xy 152.28103 -310.269867) (xy 152.258159 -310.313444) (xy 152.228594 -310.352788)
			(xy 152.193101 -310.38688) (xy 152.152598 -310.414836) (xy 152.108136 -310.435934) (xy 152.060865 -310.449626)
			(xy 152.01201 -310.455558) (xy 151.962835 -310.453577) (xy 151.914616 -310.443733) (xy 151.8686 -310.426281)
			(xy 151.825979 -310.401674) (xy 151.787858 -310.370549) (xy 151.755223 -310.333712) (xy 151.72892 -310.292116)
			(xy 151.709629 -310.24684) (xy 151.697852 -310.199056) (xy 151.693892 -310.150002) (xy 151.207599 -310.150002)
			(xy 151.187631 -310.172288) (xy 151.144763 -310.207963) (xy 151.097157 -310.237017) (xy 151.045828 -310.258829)
			(xy 150.991871 -310.272935) (xy 150.936434 -310.279035) (xy 150.8807 -310.276998) (xy 150.825857 -310.266868)
			(xy 150.773073 -310.248861) (xy 150.723473 -310.22336) (xy 150.678115 -310.190909) (xy 150.637966 -310.1522)
			(xy 150.60388 -310.108057) (xy 150.576584 -310.059422) (xy 150.556661 -310.007331) (xy 150.544535 -309.952894)
			(xy 150.540464 -309.897272) (xy 119.631206 -309.897272) (xy 119.631206 -310.437276) (xy 125.23673 -310.437276)
			(xy 125.240801 -310.381654) (xy 125.252927 -310.327217) (xy 125.27285 -310.275126) (xy 125.300146 -310.226491)
			(xy 125.334232 -310.182348) (xy 125.374381 -310.143639) (xy 125.419739 -310.111188) (xy 125.469339 -310.085687)
			(xy 125.522123 -310.06768) (xy 125.576966 -310.05755) (xy 125.6327 -310.055513) (xy 125.688137 -310.061613)
			(xy 125.742094 -310.075719) (xy 125.793423 -310.097531) (xy 125.841029 -310.126585) (xy 125.883897 -310.16226)
			(xy 125.921114 -310.203797) (xy 125.951887 -310.25031) (xy 125.975559 -310.300807) (xy 125.991627 -310.354214)
			(xy 125.999747 -310.40939) (xy 126.000256 -310.437276) (xy 126.25273 -310.437276) (xy 126.256801 -310.381654)
			(xy 126.268927 -310.327217) (xy 126.28885 -310.275126) (xy 126.316146 -310.226491) (xy 126.350232 -310.182348)
			(xy 126.390381 -310.143639) (xy 126.435739 -310.111188) (xy 126.485339 -310.085687) (xy 126.538123 -310.06768)
			(xy 126.592966 -310.05755) (xy 126.6487 -310.055513) (xy 126.704137 -310.061613) (xy 126.758094 -310.075719)
			(xy 126.809423 -310.097531) (xy 126.857029 -310.126585) (xy 126.899897 -310.16226) (xy 126.937114 -310.203797)
			(xy 126.967887 -310.25031) (xy 126.991559 -310.300807) (xy 127.007627 -310.354214) (xy 127.015747 -310.40939)
			(xy 127.016256 -310.437276) (xy 127.26873 -310.437276) (xy 127.272801 -310.381654) (xy 127.284927 -310.327217)
			(xy 127.30485 -310.275126) (xy 127.332146 -310.226491) (xy 127.366232 -310.182348) (xy 127.406381 -310.143639)
			(xy 127.451739 -310.111188) (xy 127.501339 -310.085687) (xy 127.554123 -310.06768) (xy 127.608966 -310.05755)
			(xy 127.6647 -310.055513) (xy 127.720137 -310.061613) (xy 127.774094 -310.075719) (xy 127.825423 -310.097531)
			(xy 127.873029 -310.126585) (xy 127.915897 -310.16226) (xy 127.953114 -310.203797) (xy 127.983887 -310.25031)
			(xy 128.007559 -310.300807) (xy 128.023627 -310.354214) (xy 128.031747 -310.40939) (xy 128.032256 -310.437276)
			(xy 128.28473 -310.437276) (xy 128.288801 -310.381654) (xy 128.300927 -310.327217) (xy 128.32085 -310.275126)
			(xy 128.348146 -310.226491) (xy 128.382232 -310.182348) (xy 128.422381 -310.143639) (xy 128.467739 -310.111188)
			(xy 128.517339 -310.085687) (xy 128.570123 -310.06768) (xy 128.624966 -310.05755) (xy 128.6807 -310.055513)
			(xy 128.736137 -310.061613) (xy 128.790094 -310.075719) (xy 128.841423 -310.097531) (xy 128.889029 -310.126585)
			(xy 128.931897 -310.16226) (xy 128.969114 -310.203797) (xy 128.999887 -310.25031) (xy 129.023559 -310.300807)
			(xy 129.039627 -310.354214) (xy 129.047747 -310.40939) (xy 129.048256 -310.437276) (xy 129.30073 -310.437276)
			(xy 129.304801 -310.381654) (xy 129.316927 -310.327217) (xy 129.33685 -310.275126) (xy 129.364146 -310.226491)
			(xy 129.398232 -310.182348) (xy 129.438381 -310.143639) (xy 129.483739 -310.111188) (xy 129.533339 -310.085687)
			(xy 129.586123 -310.06768) (xy 129.640966 -310.05755) (xy 129.6967 -310.055513) (xy 129.752137 -310.061613)
			(xy 129.806094 -310.075719) (xy 129.857423 -310.097531) (xy 129.905029 -310.126585) (xy 129.947897 -310.16226)
			(xy 129.985114 -310.203797) (xy 130.015887 -310.25031) (xy 130.039559 -310.300807) (xy 130.055627 -310.354214)
			(xy 130.063747 -310.40939) (xy 130.064256 -310.437276) (xy 130.31673 -310.437276) (xy 130.320801 -310.381654)
			(xy 130.332927 -310.327217) (xy 130.35285 -310.275126) (xy 130.380146 -310.226491) (xy 130.414232 -310.182348)
			(xy 130.454381 -310.143639) (xy 130.499739 -310.111188) (xy 130.549339 -310.085687) (xy 130.602123 -310.06768)
			(xy 130.656966 -310.05755) (xy 130.7127 -310.055513) (xy 130.768137 -310.061613) (xy 130.822094 -310.075719)
			(xy 130.873423 -310.097531) (xy 130.921029 -310.126585) (xy 130.963897 -310.16226) (xy 131.001114 -310.203797)
			(xy 131.031887 -310.25031) (xy 131.055559 -310.300807) (xy 131.071627 -310.354214) (xy 131.079747 -310.40939)
			(xy 131.080256 -310.437276) (xy 131.33273 -310.437276) (xy 131.336801 -310.381654) (xy 131.348927 -310.327217)
			(xy 131.36885 -310.275126) (xy 131.396146 -310.226491) (xy 131.430232 -310.182348) (xy 131.470381 -310.143639)
			(xy 131.515739 -310.111188) (xy 131.565339 -310.085687) (xy 131.618123 -310.06768) (xy 131.672966 -310.05755)
			(xy 131.7287 -310.055513) (xy 131.784137 -310.061613) (xy 131.838094 -310.075719) (xy 131.889423 -310.097531)
			(xy 131.937029 -310.126585) (xy 131.979897 -310.16226) (xy 132.017114 -310.203797) (xy 132.047887 -310.25031)
			(xy 132.071559 -310.300807) (xy 132.087627 -310.354214) (xy 132.095747 -310.40939) (xy 132.096256 -310.437276)
			(xy 132.34873 -310.437276) (xy 132.352801 -310.381654) (xy 132.364927 -310.327217) (xy 132.38485 -310.275126)
			(xy 132.412146 -310.226491) (xy 132.446232 -310.182348) (xy 132.486381 -310.143639) (xy 132.531739 -310.111188)
			(xy 132.581339 -310.085687) (xy 132.634123 -310.06768) (xy 132.688966 -310.05755) (xy 132.7447 -310.055513)
			(xy 132.800137 -310.061613) (xy 132.854094 -310.075719) (xy 132.905423 -310.097531) (xy 132.953029 -310.126585)
			(xy 132.995897 -310.16226) (xy 133.033114 -310.203797) (xy 133.063887 -310.25031) (xy 133.087559 -310.300807)
			(xy 133.103627 -310.354214) (xy 133.111747 -310.40939) (xy 133.112256 -310.437276) (xy 133.111747 -310.465162)
			(xy 133.103627 -310.520338) (xy 133.087559 -310.573745) (xy 133.063887 -310.624242) (xy 133.033114 -310.670755)
			(xy 132.995897 -310.712292) (xy 132.953029 -310.747967) (xy 132.905423 -310.777021) (xy 132.854094 -310.798833)
			(xy 132.800137 -310.812939) (xy 132.7447 -310.819039) (xy 132.688966 -310.817002) (xy 132.634123 -310.806872)
			(xy 132.581339 -310.788865) (xy 132.531739 -310.763364) (xy 132.486381 -310.730913) (xy 132.446232 -310.692204)
			(xy 132.412146 -310.648061) (xy 132.38485 -310.599426) (xy 132.364927 -310.547335) (xy 132.352801 -310.492898)
			(xy 132.34873 -310.437276) (xy 132.096256 -310.437276) (xy 132.095747 -310.465162) (xy 132.087627 -310.520338)
			(xy 132.071559 -310.573745) (xy 132.047887 -310.624242) (xy 132.017114 -310.670755) (xy 131.979897 -310.712292)
			(xy 131.937029 -310.747967) (xy 131.889423 -310.777021) (xy 131.838094 -310.798833) (xy 131.784137 -310.812939)
			(xy 131.7287 -310.819039) (xy 131.672966 -310.817002) (xy 131.618123 -310.806872) (xy 131.565339 -310.788865)
			(xy 131.515739 -310.763364) (xy 131.470381 -310.730913) (xy 131.430232 -310.692204) (xy 131.396146 -310.648061)
			(xy 131.36885 -310.599426) (xy 131.348927 -310.547335) (xy 131.336801 -310.492898) (xy 131.33273 -310.437276)
			(xy 131.080256 -310.437276) (xy 131.079747 -310.465162) (xy 131.071627 -310.520338) (xy 131.055559 -310.573745)
			(xy 131.031887 -310.624242) (xy 131.001114 -310.670755) (xy 130.963897 -310.712292) (xy 130.921029 -310.747967)
			(xy 130.873423 -310.777021) (xy 130.822094 -310.798833) (xy 130.768137 -310.812939) (xy 130.7127 -310.819039)
			(xy 130.656966 -310.817002) (xy 130.602123 -310.806872) (xy 130.549339 -310.788865) (xy 130.499739 -310.763364)
			(xy 130.454381 -310.730913) (xy 130.414232 -310.692204) (xy 130.380146 -310.648061) (xy 130.35285 -310.599426)
			(xy 130.332927 -310.547335) (xy 130.320801 -310.492898) (xy 130.31673 -310.437276) (xy 130.064256 -310.437276)
			(xy 130.063747 -310.465162) (xy 130.055627 -310.520338) (xy 130.039559 -310.573745) (xy 130.015887 -310.624242)
			(xy 129.985114 -310.670755) (xy 129.947897 -310.712292) (xy 129.905029 -310.747967) (xy 129.857423 -310.777021)
			(xy 129.806094 -310.798833) (xy 129.752137 -310.812939) (xy 129.6967 -310.819039) (xy 129.640966 -310.817002)
			(xy 129.586123 -310.806872) (xy 129.533339 -310.788865) (xy 129.483739 -310.763364) (xy 129.438381 -310.730913)
			(xy 129.398232 -310.692204) (xy 129.364146 -310.648061) (xy 129.33685 -310.599426) (xy 129.316927 -310.547335)
			(xy 129.304801 -310.492898) (xy 129.30073 -310.437276) (xy 129.048256 -310.437276) (xy 129.047747 -310.465162)
			(xy 129.039627 -310.520338) (xy 129.023559 -310.573745) (xy 128.999887 -310.624242) (xy 128.969114 -310.670755)
			(xy 128.931897 -310.712292) (xy 128.889029 -310.747967) (xy 128.841423 -310.777021) (xy 128.790094 -310.798833)
			(xy 128.736137 -310.812939) (xy 128.6807 -310.819039) (xy 128.624966 -310.817002) (xy 128.570123 -310.806872)
			(xy 128.517339 -310.788865) (xy 128.467739 -310.763364) (xy 128.422381 -310.730913) (xy 128.382232 -310.692204)
			(xy 128.348146 -310.648061) (xy 128.32085 -310.599426) (xy 128.300927 -310.547335) (xy 128.288801 -310.492898)
			(xy 128.28473 -310.437276) (xy 128.032256 -310.437276) (xy 128.031747 -310.465162) (xy 128.023627 -310.520338)
			(xy 128.007559 -310.573745) (xy 127.983887 -310.624242) (xy 127.953114 -310.670755) (xy 127.915897 -310.712292)
			(xy 127.873029 -310.747967) (xy 127.825423 -310.777021) (xy 127.774094 -310.798833) (xy 127.720137 -310.812939)
			(xy 127.6647 -310.819039) (xy 127.608966 -310.817002) (xy 127.554123 -310.806872) (xy 127.501339 -310.788865)
			(xy 127.451739 -310.763364) (xy 127.406381 -310.730913) (xy 127.366232 -310.692204) (xy 127.332146 -310.648061)
			(xy 127.30485 -310.599426) (xy 127.284927 -310.547335) (xy 127.272801 -310.492898) (xy 127.26873 -310.437276)
			(xy 127.016256 -310.437276) (xy 127.015747 -310.465162) (xy 127.007627 -310.520338) (xy 126.991559 -310.573745)
			(xy 126.967887 -310.624242) (xy 126.937114 -310.670755) (xy 126.899897 -310.712292) (xy 126.857029 -310.747967)
			(xy 126.809423 -310.777021) (xy 126.758094 -310.798833) (xy 126.704137 -310.812939) (xy 126.6487 -310.819039)
			(xy 126.592966 -310.817002) (xy 126.538123 -310.806872) (xy 126.485339 -310.788865) (xy 126.435739 -310.763364)
			(xy 126.390381 -310.730913) (xy 126.350232 -310.692204) (xy 126.316146 -310.648061) (xy 126.28885 -310.599426)
			(xy 126.268927 -310.547335) (xy 126.256801 -310.492898) (xy 126.25273 -310.437276) (xy 126.000256 -310.437276)
			(xy 125.999747 -310.465162) (xy 125.991627 -310.520338) (xy 125.975559 -310.573745) (xy 125.951887 -310.624242)
			(xy 125.921114 -310.670755) (xy 125.883897 -310.712292) (xy 125.841029 -310.747967) (xy 125.793423 -310.777021)
			(xy 125.742094 -310.798833) (xy 125.688137 -310.812939) (xy 125.6327 -310.819039) (xy 125.576966 -310.817002)
			(xy 125.522123 -310.806872) (xy 125.469339 -310.788865) (xy 125.419739 -310.763364) (xy 125.374381 -310.730913)
			(xy 125.334232 -310.692204) (xy 125.300146 -310.648061) (xy 125.27285 -310.599426) (xy 125.252927 -310.547335)
			(xy 125.240801 -310.492898) (xy 125.23673 -310.437276) (xy 119.631206 -310.437276) (xy 119.631206 -310.832246)
			(xy 144.36801 -310.832246) (xy 144.372081 -310.776624) (xy 144.384207 -310.722187) (xy 144.40413 -310.670096)
			(xy 144.431426 -310.621461) (xy 144.465512 -310.577318) (xy 144.505661 -310.538609) (xy 144.551019 -310.506158)
			(xy 144.600619 -310.480657) (xy 144.653403 -310.46265) (xy 144.708246 -310.45252) (xy 144.76398 -310.450483)
			(xy 144.819417 -310.456583) (xy 144.873374 -310.470689) (xy 144.924703 -310.492501) (xy 144.972309 -310.521555)
			(xy 145.015177 -310.55723) (xy 145.052394 -310.598767) (xy 145.083167 -310.64528) (xy 145.106839 -310.695777)
			(xy 145.122907 -310.749184) (xy 145.131027 -310.80436) (xy 145.131536 -310.832246) (xy 145.131027 -310.860132)
			(xy 145.122907 -310.915308) (xy 145.106839 -310.968715) (xy 145.084725 -311.015888) (xy 150.371808 -311.015888)
			(xy 150.375879 -310.960266) (xy 150.388005 -310.905829) (xy 150.407928 -310.853738) (xy 150.435224 -310.805103)
			(xy 150.46931 -310.76096) (xy 150.509459 -310.722251) (xy 150.554817 -310.6898) (xy 150.604417 -310.664299)
			(xy 150.657201 -310.646292) (xy 150.712044 -310.636162) (xy 150.767778 -310.634125) (xy 150.823215 -310.640225)
			(xy 150.877172 -310.654331) (xy 150.928501 -310.676143) (xy 150.976107 -310.705197) (xy 151.018975 -310.740872)
			(xy 151.056192 -310.782409) (xy 151.086965 -310.828922) (xy 151.110637 -310.879419) (xy 151.126705 -310.932826)
			(xy 151.134825 -310.988002) (xy 151.135334 -311.015888) (xy 151.134825 -311.043774) (xy 151.126705 -311.09895)
			(xy 151.126401 -311.099962) (xy 152.644106 -311.099962) (xy 152.648066 -311.050908) (xy 152.659843 -311.003124)
			(xy 152.679134 -310.957848) (xy 152.705437 -310.916252) (xy 152.738072 -310.879415) (xy 152.776193 -310.84829)
			(xy 152.818814 -310.823683) (xy 152.86483 -310.806231) (xy 152.913049 -310.796387) (xy 152.962224 -310.794406)
			(xy 153.011079 -310.800338) (xy 153.05835 -310.81403) (xy 153.102812 -310.835128) (xy 153.143315 -310.863084)
			(xy 153.178808 -310.897176) (xy 153.208373 -310.93652) (xy 153.231244 -310.980097) (xy 153.246828 -311.026778)
			(xy 153.254723 -311.075355) (xy 153.255218 -311.099962) (xy 153.594066 -311.099962) (xy 153.598026 -311.050908)
			(xy 153.609803 -311.003124) (xy 153.629094 -310.957848) (xy 153.655397 -310.916252) (xy 153.688032 -310.879415)
			(xy 153.726153 -310.84829) (xy 153.768774 -310.823683) (xy 153.81479 -310.806231) (xy 153.863009 -310.796387)
			(xy 153.912184 -310.794406) (xy 153.961039 -310.800338) (xy 154.00831 -310.81403) (xy 154.052772 -310.835128)
			(xy 154.093275 -310.863084) (xy 154.128768 -310.897176) (xy 154.158333 -310.93652) (xy 154.181204 -310.980097)
			(xy 154.196788 -311.026778) (xy 154.204683 -311.075355) (xy 154.205178 -311.099962) (xy 154.54428 -311.099962)
			(xy 154.54824 -311.050908) (xy 154.560017 -311.003124) (xy 154.579308 -310.957848) (xy 154.605611 -310.916252)
			(xy 154.638246 -310.879415) (xy 154.676367 -310.84829) (xy 154.718988 -310.823683) (xy 154.765004 -310.806231)
			(xy 154.813223 -310.796387) (xy 154.862398 -310.794406) (xy 154.911253 -310.800338) (xy 154.958524 -310.81403)
			(xy 155.002986 -310.835128) (xy 155.043489 -310.863084) (xy 155.078982 -310.897176) (xy 155.108547 -310.93652)
			(xy 155.131418 -310.980097) (xy 155.147002 -311.026778) (xy 155.154897 -311.075355) (xy 155.155392 -311.099962)
			(xy 155.49424 -311.099962) (xy 155.4982 -311.050908) (xy 155.509977 -311.003124) (xy 155.529268 -310.957848)
			(xy 155.555571 -310.916252) (xy 155.588206 -310.879415) (xy 155.626327 -310.84829) (xy 155.668948 -310.823683)
			(xy 155.714964 -310.806231) (xy 155.763183 -310.796387) (xy 155.812358 -310.794406) (xy 155.861213 -310.800338)
			(xy 155.908484 -310.81403) (xy 155.952946 -310.835128) (xy 155.993449 -310.863084) (xy 156.028942 -310.897176)
			(xy 156.058507 -310.93652) (xy 156.081378 -310.980097) (xy 156.096962 -311.026778) (xy 156.104857 -311.075355)
			(xy 156.105352 -311.099962) (xy 156.4442 -311.099962) (xy 156.44816 -311.050908) (xy 156.459937 -311.003124)
			(xy 156.479228 -310.957848) (xy 156.505531 -310.916252) (xy 156.538166 -310.879415) (xy 156.576287 -310.84829)
			(xy 156.618908 -310.823683) (xy 156.664924 -310.806231) (xy 156.713143 -310.796387) (xy 156.762318 -310.794406)
			(xy 156.811173 -310.800338) (xy 156.858444 -310.81403) (xy 156.902906 -310.835128) (xy 156.943409 -310.863084)
			(xy 156.978902 -310.897176) (xy 157.008467 -310.93652) (xy 157.031338 -310.980097) (xy 157.046922 -311.026778)
			(xy 157.054817 -311.075355) (xy 157.055312 -311.099962) (xy 157.39416 -311.099962) (xy 157.39812 -311.050908)
			(xy 157.409897 -311.003124) (xy 157.429188 -310.957848) (xy 157.455491 -310.916252) (xy 157.488126 -310.879415)
			(xy 157.526247 -310.84829) (xy 157.568868 -310.823683) (xy 157.614884 -310.806231) (xy 157.663103 -310.796387)
			(xy 157.712278 -310.794406) (xy 157.761133 -310.800338) (xy 157.808404 -310.81403) (xy 157.852866 -310.835128)
			(xy 157.893369 -310.863084) (xy 157.928862 -310.897176) (xy 157.958427 -310.93652) (xy 157.981298 -310.980097)
			(xy 157.996882 -311.026778) (xy 158.004777 -311.075355) (xy 158.005272 -311.099962) (xy 158.34412 -311.099962)
			(xy 158.34808 -311.050908) (xy 158.359857 -311.003124) (xy 158.379148 -310.957848) (xy 158.405451 -310.916252)
			(xy 158.438086 -310.879415) (xy 158.476207 -310.84829) (xy 158.518828 -310.823683) (xy 158.564844 -310.806231)
			(xy 158.613063 -310.796387) (xy 158.662238 -310.794406) (xy 158.711093 -310.800338) (xy 158.758364 -310.81403)
			(xy 158.802826 -310.835128) (xy 158.843329 -310.863084) (xy 158.878822 -310.897176) (xy 158.908387 -310.93652)
			(xy 158.931258 -310.980097) (xy 158.946842 -311.026778) (xy 158.954737 -311.075355) (xy 158.955232 -311.099962)
			(xy 159.29408 -311.099962) (xy 159.29804 -311.050908) (xy 159.309817 -311.003124) (xy 159.329108 -310.957848)
			(xy 159.355411 -310.916252) (xy 159.388046 -310.879415) (xy 159.426167 -310.84829) (xy 159.468788 -310.823683)
			(xy 159.514804 -310.806231) (xy 159.563023 -310.796387) (xy 159.612198 -310.794406) (xy 159.661053 -310.800338)
			(xy 159.708324 -310.81403) (xy 159.752786 -310.835128) (xy 159.793289 -310.863084) (xy 159.828782 -310.897176)
			(xy 159.858347 -310.93652) (xy 159.881218 -310.980097) (xy 159.896802 -311.026778) (xy 159.904697 -311.075355)
			(xy 159.905192 -311.099962) (xy 160.24404 -311.099962) (xy 160.248 -311.050908) (xy 160.259777 -311.003124)
			(xy 160.279068 -310.957848) (xy 160.305371 -310.916252) (xy 160.338006 -310.879415) (xy 160.376127 -310.84829)
			(xy 160.418748 -310.823683) (xy 160.464764 -310.806231) (xy 160.512983 -310.796387) (xy 160.562158 -310.794406)
			(xy 160.611013 -310.800338) (xy 160.658284 -310.81403) (xy 160.702746 -310.835128) (xy 160.743249 -310.863084)
			(xy 160.778742 -310.897176) (xy 160.808307 -310.93652) (xy 160.831178 -310.980097) (xy 160.846762 -311.026778)
			(xy 160.854657 -311.075355) (xy 160.855152 -311.099962) (xy 161.194254 -311.099962) (xy 161.198214 -311.050908)
			(xy 161.209991 -311.003124) (xy 161.229282 -310.957848) (xy 161.255585 -310.916252) (xy 161.28822 -310.879415)
			(xy 161.326341 -310.84829) (xy 161.368962 -310.823683) (xy 161.414978 -310.806231) (xy 161.463197 -310.796387)
			(xy 161.512372 -310.794406) (xy 161.561227 -310.800338) (xy 161.608498 -310.81403) (xy 161.65296 -310.835128)
			(xy 161.693463 -310.863084) (xy 161.728956 -310.897176) (xy 161.758521 -310.93652) (xy 161.781392 -310.980097)
			(xy 161.796976 -311.026778) (xy 161.804871 -311.075355) (xy 161.805366 -311.099962) (xy 162.144214 -311.099962)
			(xy 162.148174 -311.050908) (xy 162.159951 -311.003124) (xy 162.179242 -310.957848) (xy 162.205545 -310.916252)
			(xy 162.23818 -310.879415) (xy 162.276301 -310.84829) (xy 162.318922 -310.823683) (xy 162.364938 -310.806231)
			(xy 162.413157 -310.796387) (xy 162.462332 -310.794406) (xy 162.511187 -310.800338) (xy 162.558458 -310.81403)
			(xy 162.60292 -310.835128) (xy 162.643423 -310.863084) (xy 162.678916 -310.897176) (xy 162.708481 -310.93652)
			(xy 162.731352 -310.980097) (xy 162.746936 -311.026778) (xy 162.754831 -311.075355) (xy 162.755326 -311.099962)
			(xy 163.094174 -311.099962) (xy 163.098134 -311.050908) (xy 163.109911 -311.003124) (xy 163.129202 -310.957848)
			(xy 163.155505 -310.916252) (xy 163.18814 -310.879415) (xy 163.226261 -310.84829) (xy 163.268882 -310.823683)
			(xy 163.314898 -310.806231) (xy 163.363117 -310.796387) (xy 163.412292 -310.794406) (xy 163.461147 -310.800338)
			(xy 163.508418 -310.81403) (xy 163.55288 -310.835128) (xy 163.593383 -310.863084) (xy 163.628876 -310.897176)
			(xy 163.658441 -310.93652) (xy 163.681312 -310.980097) (xy 163.696896 -311.026778) (xy 163.704791 -311.075355)
			(xy 163.705286 -311.099962) (xy 164.044134 -311.099962) (xy 164.048094 -311.050908) (xy 164.059871 -311.003124)
			(xy 164.079162 -310.957848) (xy 164.105465 -310.916252) (xy 164.1381 -310.879415) (xy 164.176221 -310.84829)
			(xy 164.218842 -310.823683) (xy 164.264858 -310.806231) (xy 164.313077 -310.796387) (xy 164.362252 -310.794406)
			(xy 164.411107 -310.800338) (xy 164.458378 -310.81403) (xy 164.50284 -310.835128) (xy 164.543343 -310.863084)
			(xy 164.578836 -310.897176) (xy 164.608401 -310.93652) (xy 164.631272 -310.980097) (xy 164.646856 -311.026778)
			(xy 164.654751 -311.075355) (xy 164.655246 -311.099962) (xy 164.994094 -311.099962) (xy 164.998054 -311.050908)
			(xy 165.009831 -311.003124) (xy 165.029122 -310.957848) (xy 165.055425 -310.916252) (xy 165.08806 -310.879415)
			(xy 165.126181 -310.84829) (xy 165.168802 -310.823683) (xy 165.214818 -310.806231) (xy 165.263037 -310.796387)
			(xy 165.312212 -310.794406) (xy 165.361067 -310.800338) (xy 165.408338 -310.81403) (xy 165.4528 -310.835128)
			(xy 165.493303 -310.863084) (xy 165.528796 -310.897176) (xy 165.558361 -310.93652) (xy 165.581232 -310.980097)
			(xy 165.596816 -311.026778) (xy 165.604711 -311.075355) (xy 165.605206 -311.099962) (xy 165.944054 -311.099962)
			(xy 165.948014 -311.050908) (xy 165.959791 -311.003124) (xy 165.979082 -310.957848) (xy 166.005385 -310.916252)
			(xy 166.03802 -310.879415) (xy 166.076141 -310.84829) (xy 166.118762 -310.823683) (xy 166.164778 -310.806231)
			(xy 166.212997 -310.796387) (xy 166.262172 -310.794406) (xy 166.311027 -310.800338) (xy 166.358298 -310.81403)
			(xy 166.40276 -310.835128) (xy 166.443263 -310.863084) (xy 166.478756 -310.897176) (xy 166.508321 -310.93652)
			(xy 166.531192 -310.980097) (xy 166.546776 -311.026778) (xy 166.554671 -311.075355) (xy 166.555166 -311.099962)
			(xy 166.894268 -311.099962) (xy 166.898228 -311.050908) (xy 166.910005 -311.003124) (xy 166.929296 -310.957848)
			(xy 166.955599 -310.916252) (xy 166.988234 -310.879415) (xy 167.026355 -310.84829) (xy 167.068976 -310.823683)
			(xy 167.114992 -310.806231) (xy 167.163211 -310.796387) (xy 167.212386 -310.794406) (xy 167.261241 -310.800338)
			(xy 167.308512 -310.81403) (xy 167.352974 -310.835128) (xy 167.393477 -310.863084) (xy 167.42897 -310.897176)
			(xy 167.458535 -310.93652) (xy 167.481406 -310.980097) (xy 167.49699 -311.026778) (xy 167.504885 -311.075355)
			(xy 167.50538 -311.099962) (xy 167.844228 -311.099962) (xy 167.848188 -311.050908) (xy 167.859965 -311.003124)
			(xy 167.879256 -310.957848) (xy 167.905559 -310.916252) (xy 167.938194 -310.879415) (xy 167.976315 -310.84829)
			(xy 168.018936 -310.823683) (xy 168.064952 -310.806231) (xy 168.113171 -310.796387) (xy 168.162346 -310.794406)
			(xy 168.211201 -310.800338) (xy 168.258472 -310.81403) (xy 168.302934 -310.835128) (xy 168.343437 -310.863084)
			(xy 168.37893 -310.897176) (xy 168.408495 -310.93652) (xy 168.431366 -310.980097) (xy 168.44695 -311.026778)
			(xy 168.454845 -311.075355) (xy 168.45534 -311.099962) (xy 168.794188 -311.099962) (xy 168.798148 -311.050908)
			(xy 168.809925 -311.003124) (xy 168.829216 -310.957848) (xy 168.855519 -310.916252) (xy 168.888154 -310.879415)
			(xy 168.926275 -310.84829) (xy 168.968896 -310.823683) (xy 169.014912 -310.806231) (xy 169.063131 -310.796387)
			(xy 169.112306 -310.794406) (xy 169.161161 -310.800338) (xy 169.208432 -310.81403) (xy 169.252894 -310.835128)
			(xy 169.293397 -310.863084) (xy 169.32889 -310.897176) (xy 169.358455 -310.93652) (xy 169.381326 -310.980097)
			(xy 169.39691 -311.026778) (xy 169.404805 -311.075355) (xy 169.4053 -311.099962) (xy 169.744148 -311.099962)
			(xy 169.748108 -311.050908) (xy 169.759885 -311.003124) (xy 169.779176 -310.957848) (xy 169.805479 -310.916252)
			(xy 169.838114 -310.879415) (xy 169.876235 -310.84829) (xy 169.918856 -310.823683) (xy 169.964872 -310.806231)
			(xy 170.013091 -310.796387) (xy 170.062266 -310.794406) (xy 170.111121 -310.800338) (xy 170.158392 -310.81403)
			(xy 170.202854 -310.835128) (xy 170.243357 -310.863084) (xy 170.27885 -310.897176) (xy 170.308415 -310.93652)
			(xy 170.331286 -310.980097) (xy 170.34687 -311.026778) (xy 170.354765 -311.075355) (xy 170.35526 -311.099962)
			(xy 170.694108 -311.099962) (xy 170.698068 -311.050908) (xy 170.709845 -311.003124) (xy 170.729136 -310.957848)
			(xy 170.755439 -310.916252) (xy 170.788074 -310.879415) (xy 170.826195 -310.84829) (xy 170.868816 -310.823683)
			(xy 170.914832 -310.806231) (xy 170.963051 -310.796387) (xy 171.012226 -310.794406) (xy 171.061081 -310.800338)
			(xy 171.108352 -310.81403) (xy 171.152814 -310.835128) (xy 171.193317 -310.863084) (xy 171.22881 -310.897176)
			(xy 171.258375 -310.93652) (xy 171.281246 -310.980097) (xy 171.29683 -311.026778) (xy 171.304725 -311.075355)
			(xy 171.30522 -311.099962) (xy 171.644068 -311.099962) (xy 171.648028 -311.050908) (xy 171.659805 -311.003124)
			(xy 171.679096 -310.957848) (xy 171.705399 -310.916252) (xy 171.738034 -310.879415) (xy 171.776155 -310.84829)
			(xy 171.818776 -310.823683) (xy 171.864792 -310.806231) (xy 171.913011 -310.796387) (xy 171.962186 -310.794406)
			(xy 172.011041 -310.800338) (xy 172.058312 -310.81403) (xy 172.102774 -310.835128) (xy 172.143277 -310.863084)
			(xy 172.17877 -310.897176) (xy 172.208335 -310.93652) (xy 172.231206 -310.980097) (xy 172.24679 -311.026778)
			(xy 172.254685 -311.075355) (xy 172.25518 -311.099962) (xy 172.594282 -311.099962) (xy 172.598242 -311.050908)
			(xy 172.610019 -311.003124) (xy 172.62931 -310.957848) (xy 172.655613 -310.916252) (xy 172.688248 -310.879415)
			(xy 172.726369 -310.84829) (xy 172.76899 -310.823683) (xy 172.815006 -310.806231) (xy 172.863225 -310.796387)
			(xy 172.9124 -310.794406) (xy 172.961255 -310.800338) (xy 173.008526 -310.81403) (xy 173.052988 -310.835128)
			(xy 173.093491 -310.863084) (xy 173.128984 -310.897176) (xy 173.158549 -310.93652) (xy 173.18142 -310.980097)
			(xy 173.197004 -311.026778) (xy 173.204899 -311.075355) (xy 173.205394 -311.099962) (xy 173.544242 -311.099962)
			(xy 173.548202 -311.050908) (xy 173.559979 -311.003124) (xy 173.57927 -310.957848) (xy 173.605573 -310.916252)
			(xy 173.638208 -310.879415) (xy 173.676329 -310.84829) (xy 173.71895 -310.823683) (xy 173.764966 -310.806231)
			(xy 173.813185 -310.796387) (xy 173.86236 -310.794406) (xy 173.911215 -310.800338) (xy 173.958486 -310.81403)
			(xy 174.002948 -310.835128) (xy 174.043451 -310.863084) (xy 174.078944 -310.897176) (xy 174.108509 -310.93652)
			(xy 174.13138 -310.980097) (xy 174.146964 -311.026778) (xy 174.154859 -311.075355) (xy 174.155354 -311.099962)
			(xy 174.494202 -311.099962) (xy 174.498162 -311.050908) (xy 174.509939 -311.003124) (xy 174.52923 -310.957848)
			(xy 174.555533 -310.916252) (xy 174.588168 -310.879415) (xy 174.626289 -310.84829) (xy 174.66891 -310.823683)
			(xy 174.714926 -310.806231) (xy 174.763145 -310.796387) (xy 174.81232 -310.794406) (xy 174.861175 -310.800338)
			(xy 174.908446 -310.81403) (xy 174.952908 -310.835128) (xy 174.993411 -310.863084) (xy 175.028904 -310.897176)
			(xy 175.058469 -310.93652) (xy 175.08134 -310.980097) (xy 175.096924 -311.026778) (xy 175.104819 -311.075355)
			(xy 175.105314 -311.099962) (xy 175.444162 -311.099962) (xy 175.448122 -311.050908) (xy 175.459899 -311.003124)
			(xy 175.47919 -310.957848) (xy 175.505493 -310.916252) (xy 175.538128 -310.879415) (xy 175.576249 -310.84829)
			(xy 175.61887 -310.823683) (xy 175.664886 -310.806231) (xy 175.713105 -310.796387) (xy 175.76228 -310.794406)
			(xy 175.811135 -310.800338) (xy 175.858406 -310.81403) (xy 175.902868 -310.835128) (xy 175.943371 -310.863084)
			(xy 175.978864 -310.897176) (xy 176.008429 -310.93652) (xy 176.0313 -310.980097) (xy 176.046884 -311.026778)
			(xy 176.054779 -311.075355) (xy 176.055274 -311.099962) (xy 176.054779 -311.124569) (xy 176.046884 -311.173146)
			(xy 176.0313 -311.219827) (xy 176.008429 -311.263404) (xy 175.978864 -311.302748) (xy 175.943371 -311.33684)
			(xy 175.902868 -311.364796) (xy 175.858406 -311.385894) (xy 175.811135 -311.399586) (xy 175.76228 -311.405518)
			(xy 175.713105 -311.403537) (xy 175.664886 -311.393693) (xy 175.61887 -311.376241) (xy 175.576249 -311.351634)
			(xy 175.538128 -311.320509) (xy 175.505493 -311.283672) (xy 175.47919 -311.242076) (xy 175.459899 -311.1968)
			(xy 175.448122 -311.149016) (xy 175.444162 -311.099962) (xy 175.105314 -311.099962) (xy 175.104819 -311.124569)
			(xy 175.096924 -311.173146) (xy 175.08134 -311.219827) (xy 175.058469 -311.263404) (xy 175.028904 -311.302748)
			(xy 174.993411 -311.33684) (xy 174.952908 -311.364796) (xy 174.908446 -311.385894) (xy 174.861175 -311.399586)
			(xy 174.81232 -311.405518) (xy 174.763145 -311.403537) (xy 174.714926 -311.393693) (xy 174.66891 -311.376241)
			(xy 174.626289 -311.351634) (xy 174.588168 -311.320509) (xy 174.555533 -311.283672) (xy 174.52923 -311.242076)
			(xy 174.509939 -311.1968) (xy 174.498162 -311.149016) (xy 174.494202 -311.099962) (xy 174.155354 -311.099962)
			(xy 174.154859 -311.124569) (xy 174.146964 -311.173146) (xy 174.13138 -311.219827) (xy 174.108509 -311.263404)
			(xy 174.078944 -311.302748) (xy 174.043451 -311.33684) (xy 174.002948 -311.364796) (xy 173.958486 -311.385894)
			(xy 173.911215 -311.399586) (xy 173.86236 -311.405518) (xy 173.813185 -311.403537) (xy 173.764966 -311.393693)
			(xy 173.71895 -311.376241) (xy 173.676329 -311.351634) (xy 173.638208 -311.320509) (xy 173.605573 -311.283672)
			(xy 173.57927 -311.242076) (xy 173.559979 -311.1968) (xy 173.548202 -311.149016) (xy 173.544242 -311.099962)
			(xy 173.205394 -311.099962) (xy 173.204899 -311.124569) (xy 173.197004 -311.173146) (xy 173.18142 -311.219827)
			(xy 173.158549 -311.263404) (xy 173.128984 -311.302748) (xy 173.093491 -311.33684) (xy 173.052988 -311.364796)
			(xy 173.008526 -311.385894) (xy 172.961255 -311.399586) (xy 172.9124 -311.405518) (xy 172.863225 -311.403537)
			(xy 172.815006 -311.393693) (xy 172.76899 -311.376241) (xy 172.726369 -311.351634) (xy 172.688248 -311.320509)
			(xy 172.655613 -311.283672) (xy 172.62931 -311.242076) (xy 172.610019 -311.1968) (xy 172.598242 -311.149016)
			(xy 172.594282 -311.099962) (xy 172.25518 -311.099962) (xy 172.254685 -311.124569) (xy 172.24679 -311.173146)
			(xy 172.231206 -311.219827) (xy 172.208335 -311.263404) (xy 172.17877 -311.302748) (xy 172.143277 -311.33684)
			(xy 172.102774 -311.364796) (xy 172.058312 -311.385894) (xy 172.011041 -311.399586) (xy 171.962186 -311.405518)
			(xy 171.913011 -311.403537) (xy 171.864792 -311.393693) (xy 171.818776 -311.376241) (xy 171.776155 -311.351634)
			(xy 171.738034 -311.320509) (xy 171.705399 -311.283672) (xy 171.679096 -311.242076) (xy 171.659805 -311.1968)
			(xy 171.648028 -311.149016) (xy 171.644068 -311.099962) (xy 171.30522 -311.099962) (xy 171.304725 -311.124569)
			(xy 171.29683 -311.173146) (xy 171.281246 -311.219827) (xy 171.258375 -311.263404) (xy 171.22881 -311.302748)
			(xy 171.193317 -311.33684) (xy 171.152814 -311.364796) (xy 171.108352 -311.385894) (xy 171.061081 -311.399586)
			(xy 171.012226 -311.405518) (xy 170.963051 -311.403537) (xy 170.914832 -311.393693) (xy 170.868816 -311.376241)
			(xy 170.826195 -311.351634) (xy 170.788074 -311.320509) (xy 170.755439 -311.283672) (xy 170.729136 -311.242076)
			(xy 170.709845 -311.1968) (xy 170.698068 -311.149016) (xy 170.694108 -311.099962) (xy 170.35526 -311.099962)
			(xy 170.354765 -311.124569) (xy 170.34687 -311.173146) (xy 170.331286 -311.219827) (xy 170.308415 -311.263404)
			(xy 170.27885 -311.302748) (xy 170.243357 -311.33684) (xy 170.202854 -311.364796) (xy 170.158392 -311.385894)
			(xy 170.111121 -311.399586) (xy 170.062266 -311.405518) (xy 170.013091 -311.403537) (xy 169.964872 -311.393693)
			(xy 169.918856 -311.376241) (xy 169.876235 -311.351634) (xy 169.838114 -311.320509) (xy 169.805479 -311.283672)
			(xy 169.779176 -311.242076) (xy 169.759885 -311.1968) (xy 169.748108 -311.149016) (xy 169.744148 -311.099962)
			(xy 169.4053 -311.099962) (xy 169.404805 -311.124569) (xy 169.39691 -311.173146) (xy 169.381326 -311.219827)
			(xy 169.358455 -311.263404) (xy 169.32889 -311.302748) (xy 169.293397 -311.33684) (xy 169.252894 -311.364796)
			(xy 169.208432 -311.385894) (xy 169.161161 -311.399586) (xy 169.112306 -311.405518) (xy 169.063131 -311.403537)
			(xy 169.014912 -311.393693) (xy 168.968896 -311.376241) (xy 168.926275 -311.351634) (xy 168.888154 -311.320509)
			(xy 168.855519 -311.283672) (xy 168.829216 -311.242076) (xy 168.809925 -311.1968) (xy 168.798148 -311.149016)
			(xy 168.794188 -311.099962) (xy 168.45534 -311.099962) (xy 168.454845 -311.124569) (xy 168.44695 -311.173146)
			(xy 168.431366 -311.219827) (xy 168.408495 -311.263404) (xy 168.37893 -311.302748) (xy 168.343437 -311.33684)
			(xy 168.302934 -311.364796) (xy 168.258472 -311.385894) (xy 168.211201 -311.399586) (xy 168.162346 -311.405518)
			(xy 168.113171 -311.403537) (xy 168.064952 -311.393693) (xy 168.018936 -311.376241) (xy 167.976315 -311.351634)
			(xy 167.938194 -311.320509) (xy 167.905559 -311.283672) (xy 167.879256 -311.242076) (xy 167.859965 -311.1968)
			(xy 167.848188 -311.149016) (xy 167.844228 -311.099962) (xy 167.50538 -311.099962) (xy 167.504885 -311.124569)
			(xy 167.49699 -311.173146) (xy 167.481406 -311.219827) (xy 167.458535 -311.263404) (xy 167.42897 -311.302748)
			(xy 167.393477 -311.33684) (xy 167.352974 -311.364796) (xy 167.308512 -311.385894) (xy 167.261241 -311.399586)
			(xy 167.212386 -311.405518) (xy 167.163211 -311.403537) (xy 167.114992 -311.393693) (xy 167.068976 -311.376241)
			(xy 167.026355 -311.351634) (xy 166.988234 -311.320509) (xy 166.955599 -311.283672) (xy 166.929296 -311.242076)
			(xy 166.910005 -311.1968) (xy 166.898228 -311.149016) (xy 166.894268 -311.099962) (xy 166.555166 -311.099962)
			(xy 166.554671 -311.124569) (xy 166.546776 -311.173146) (xy 166.531192 -311.219827) (xy 166.508321 -311.263404)
			(xy 166.478756 -311.302748) (xy 166.443263 -311.33684) (xy 166.40276 -311.364796) (xy 166.358298 -311.385894)
			(xy 166.311027 -311.399586) (xy 166.262172 -311.405518) (xy 166.212997 -311.403537) (xy 166.164778 -311.393693)
			(xy 166.118762 -311.376241) (xy 166.076141 -311.351634) (xy 166.03802 -311.320509) (xy 166.005385 -311.283672)
			(xy 165.979082 -311.242076) (xy 165.959791 -311.1968) (xy 165.948014 -311.149016) (xy 165.944054 -311.099962)
			(xy 165.605206 -311.099962) (xy 165.604711 -311.124569) (xy 165.596816 -311.173146) (xy 165.581232 -311.219827)
			(xy 165.558361 -311.263404) (xy 165.528796 -311.302748) (xy 165.493303 -311.33684) (xy 165.4528 -311.364796)
			(xy 165.408338 -311.385894) (xy 165.361067 -311.399586) (xy 165.312212 -311.405518) (xy 165.263037 -311.403537)
			(xy 165.214818 -311.393693) (xy 165.168802 -311.376241) (xy 165.126181 -311.351634) (xy 165.08806 -311.320509)
			(xy 165.055425 -311.283672) (xy 165.029122 -311.242076) (xy 165.009831 -311.1968) (xy 164.998054 -311.149016)
			(xy 164.994094 -311.099962) (xy 164.655246 -311.099962) (xy 164.654751 -311.124569) (xy 164.646856 -311.173146)
			(xy 164.631272 -311.219827) (xy 164.608401 -311.263404) (xy 164.578836 -311.302748) (xy 164.543343 -311.33684)
			(xy 164.50284 -311.364796) (xy 164.458378 -311.385894) (xy 164.411107 -311.399586) (xy 164.362252 -311.405518)
			(xy 164.313077 -311.403537) (xy 164.264858 -311.393693) (xy 164.218842 -311.376241) (xy 164.176221 -311.351634)
			(xy 164.1381 -311.320509) (xy 164.105465 -311.283672) (xy 164.079162 -311.242076) (xy 164.059871 -311.1968)
			(xy 164.048094 -311.149016) (xy 164.044134 -311.099962) (xy 163.705286 -311.099962) (xy 163.704791 -311.124569)
			(xy 163.696896 -311.173146) (xy 163.681312 -311.219827) (xy 163.658441 -311.263404) (xy 163.628876 -311.302748)
			(xy 163.593383 -311.33684) (xy 163.55288 -311.364796) (xy 163.508418 -311.385894) (xy 163.461147 -311.399586)
			(xy 163.412292 -311.405518) (xy 163.363117 -311.403537) (xy 163.314898 -311.393693) (xy 163.268882 -311.376241)
			(xy 163.226261 -311.351634) (xy 163.18814 -311.320509) (xy 163.155505 -311.283672) (xy 163.129202 -311.242076)
			(xy 163.109911 -311.1968) (xy 163.098134 -311.149016) (xy 163.094174 -311.099962) (xy 162.755326 -311.099962)
			(xy 162.754831 -311.124569) (xy 162.746936 -311.173146) (xy 162.731352 -311.219827) (xy 162.708481 -311.263404)
			(xy 162.678916 -311.302748) (xy 162.643423 -311.33684) (xy 162.60292 -311.364796) (xy 162.558458 -311.385894)
			(xy 162.511187 -311.399586) (xy 162.462332 -311.405518) (xy 162.413157 -311.403537) (xy 162.364938 -311.393693)
			(xy 162.318922 -311.376241) (xy 162.276301 -311.351634) (xy 162.23818 -311.320509) (xy 162.205545 -311.283672)
			(xy 162.179242 -311.242076) (xy 162.159951 -311.1968) (xy 162.148174 -311.149016) (xy 162.144214 -311.099962)
			(xy 161.805366 -311.099962) (xy 161.804871 -311.124569) (xy 161.796976 -311.173146) (xy 161.781392 -311.219827)
			(xy 161.758521 -311.263404) (xy 161.728956 -311.302748) (xy 161.693463 -311.33684) (xy 161.65296 -311.364796)
			(xy 161.608498 -311.385894) (xy 161.561227 -311.399586) (xy 161.512372 -311.405518) (xy 161.463197 -311.403537)
			(xy 161.414978 -311.393693) (xy 161.368962 -311.376241) (xy 161.326341 -311.351634) (xy 161.28822 -311.320509)
			(xy 161.255585 -311.283672) (xy 161.229282 -311.242076) (xy 161.209991 -311.1968) (xy 161.198214 -311.149016)
			(xy 161.194254 -311.099962) (xy 160.855152 -311.099962) (xy 160.854657 -311.124569) (xy 160.846762 -311.173146)
			(xy 160.831178 -311.219827) (xy 160.808307 -311.263404) (xy 160.778742 -311.302748) (xy 160.743249 -311.33684)
			(xy 160.702746 -311.364796) (xy 160.658284 -311.385894) (xy 160.611013 -311.399586) (xy 160.562158 -311.405518)
			(xy 160.512983 -311.403537) (xy 160.464764 -311.393693) (xy 160.418748 -311.376241) (xy 160.376127 -311.351634)
			(xy 160.338006 -311.320509) (xy 160.305371 -311.283672) (xy 160.279068 -311.242076) (xy 160.259777 -311.1968)
			(xy 160.248 -311.149016) (xy 160.24404 -311.099962) (xy 159.905192 -311.099962) (xy 159.904697 -311.124569)
			(xy 159.896802 -311.173146) (xy 159.881218 -311.219827) (xy 159.858347 -311.263404) (xy 159.828782 -311.302748)
			(xy 159.793289 -311.33684) (xy 159.752786 -311.364796) (xy 159.708324 -311.385894) (xy 159.661053 -311.399586)
			(xy 159.612198 -311.405518) (xy 159.563023 -311.403537) (xy 159.514804 -311.393693) (xy 159.468788 -311.376241)
			(xy 159.426167 -311.351634) (xy 159.388046 -311.320509) (xy 159.355411 -311.283672) (xy 159.329108 -311.242076)
			(xy 159.309817 -311.1968) (xy 159.29804 -311.149016) (xy 159.29408 -311.099962) (xy 158.955232 -311.099962)
			(xy 158.954737 -311.124569) (xy 158.946842 -311.173146) (xy 158.931258 -311.219827) (xy 158.908387 -311.263404)
			(xy 158.878822 -311.302748) (xy 158.843329 -311.33684) (xy 158.802826 -311.364796) (xy 158.758364 -311.385894)
			(xy 158.711093 -311.399586) (xy 158.662238 -311.405518) (xy 158.613063 -311.403537) (xy 158.564844 -311.393693)
			(xy 158.518828 -311.376241) (xy 158.476207 -311.351634) (xy 158.438086 -311.320509) (xy 158.405451 -311.283672)
			(xy 158.379148 -311.242076) (xy 158.359857 -311.1968) (xy 158.34808 -311.149016) (xy 158.34412 -311.099962)
			(xy 158.005272 -311.099962) (xy 158.004777 -311.124569) (xy 157.996882 -311.173146) (xy 157.981298 -311.219827)
			(xy 157.958427 -311.263404) (xy 157.928862 -311.302748) (xy 157.893369 -311.33684) (xy 157.852866 -311.364796)
			(xy 157.808404 -311.385894) (xy 157.761133 -311.399586) (xy 157.712278 -311.405518) (xy 157.663103 -311.403537)
			(xy 157.614884 -311.393693) (xy 157.568868 -311.376241) (xy 157.526247 -311.351634) (xy 157.488126 -311.320509)
			(xy 157.455491 -311.283672) (xy 157.429188 -311.242076) (xy 157.409897 -311.1968) (xy 157.39812 -311.149016)
			(xy 157.39416 -311.099962) (xy 157.055312 -311.099962) (xy 157.054817 -311.124569) (xy 157.046922 -311.173146)
			(xy 157.031338 -311.219827) (xy 157.008467 -311.263404) (xy 156.978902 -311.302748) (xy 156.943409 -311.33684)
			(xy 156.902906 -311.364796) (xy 156.858444 -311.385894) (xy 156.811173 -311.399586) (xy 156.762318 -311.405518)
			(xy 156.713143 -311.403537) (xy 156.664924 -311.393693) (xy 156.618908 -311.376241) (xy 156.576287 -311.351634)
			(xy 156.538166 -311.320509) (xy 156.505531 -311.283672) (xy 156.479228 -311.242076) (xy 156.459937 -311.1968)
			(xy 156.44816 -311.149016) (xy 156.4442 -311.099962) (xy 156.105352 -311.099962) (xy 156.104857 -311.124569)
			(xy 156.096962 -311.173146) (xy 156.081378 -311.219827) (xy 156.058507 -311.263404) (xy 156.028942 -311.302748)
			(xy 155.993449 -311.33684) (xy 155.952946 -311.364796) (xy 155.908484 -311.385894) (xy 155.861213 -311.399586)
			(xy 155.812358 -311.405518) (xy 155.763183 -311.403537) (xy 155.714964 -311.393693) (xy 155.668948 -311.376241)
			(xy 155.626327 -311.351634) (xy 155.588206 -311.320509) (xy 155.555571 -311.283672) (xy 155.529268 -311.242076)
			(xy 155.509977 -311.1968) (xy 155.4982 -311.149016) (xy 155.49424 -311.099962) (xy 155.155392 -311.099962)
			(xy 155.154897 -311.124569) (xy 155.147002 -311.173146) (xy 155.131418 -311.219827) (xy 155.108547 -311.263404)
			(xy 155.078982 -311.302748) (xy 155.043489 -311.33684) (xy 155.002986 -311.364796) (xy 154.958524 -311.385894)
			(xy 154.911253 -311.399586) (xy 154.862398 -311.405518) (xy 154.813223 -311.403537) (xy 154.765004 -311.393693)
			(xy 154.718988 -311.376241) (xy 154.676367 -311.351634) (xy 154.638246 -311.320509) (xy 154.605611 -311.283672)
			(xy 154.579308 -311.242076) (xy 154.560017 -311.1968) (xy 154.54824 -311.149016) (xy 154.54428 -311.099962)
			(xy 154.205178 -311.099962) (xy 154.204683 -311.124569) (xy 154.196788 -311.173146) (xy 154.181204 -311.219827)
			(xy 154.158333 -311.263404) (xy 154.128768 -311.302748) (xy 154.093275 -311.33684) (xy 154.052772 -311.364796)
			(xy 154.00831 -311.385894) (xy 153.961039 -311.399586) (xy 153.912184 -311.405518) (xy 153.863009 -311.403537)
			(xy 153.81479 -311.393693) (xy 153.768774 -311.376241) (xy 153.726153 -311.351634) (xy 153.688032 -311.320509)
			(xy 153.655397 -311.283672) (xy 153.629094 -311.242076) (xy 153.609803 -311.1968) (xy 153.598026 -311.149016)
			(xy 153.594066 -311.099962) (xy 153.255218 -311.099962) (xy 153.254723 -311.124569) (xy 153.246828 -311.173146)
			(xy 153.231244 -311.219827) (xy 153.208373 -311.263404) (xy 153.178808 -311.302748) (xy 153.143315 -311.33684)
			(xy 153.102812 -311.364796) (xy 153.05835 -311.385894) (xy 153.011079 -311.399586) (xy 152.962224 -311.405518)
			(xy 152.913049 -311.403537) (xy 152.86483 -311.393693) (xy 152.818814 -311.376241) (xy 152.776193 -311.351634)
			(xy 152.738072 -311.320509) (xy 152.705437 -311.283672) (xy 152.679134 -311.242076) (xy 152.659843 -311.1968)
			(xy 152.648066 -311.149016) (xy 152.644106 -311.099962) (xy 151.126401 -311.099962) (xy 151.110637 -311.152357)
			(xy 151.086965 -311.202854) (xy 151.056192 -311.249367) (xy 151.018975 -311.290904) (xy 150.976107 -311.326579)
			(xy 150.928501 -311.355633) (xy 150.877172 -311.377445) (xy 150.823215 -311.391551) (xy 150.767778 -311.397651)
			(xy 150.712044 -311.395614) (xy 150.657201 -311.385484) (xy 150.604417 -311.367477) (xy 150.554817 -311.341976)
			(xy 150.509459 -311.309525) (xy 150.46931 -311.270816) (xy 150.435224 -311.226673) (xy 150.407928 -311.178038)
			(xy 150.388005 -311.125947) (xy 150.375879 -311.07151) (xy 150.371808 -311.015888) (xy 145.084725 -311.015888)
			(xy 145.083167 -311.019212) (xy 145.052394 -311.065725) (xy 145.015177 -311.107262) (xy 144.972309 -311.142937)
			(xy 144.924703 -311.171991) (xy 144.873374 -311.193803) (xy 144.819417 -311.207909) (xy 144.76398 -311.214009)
			(xy 144.708246 -311.211972) (xy 144.653403 -311.201842) (xy 144.600619 -311.183835) (xy 144.551019 -311.158334)
			(xy 144.505661 -311.125883) (xy 144.465512 -311.087174) (xy 144.431426 -311.043031) (xy 144.40413 -310.994396)
			(xy 144.384207 -310.942305) (xy 144.372081 -310.887868) (xy 144.36801 -310.832246) (xy 119.631206 -310.832246)
			(xy 119.631206 -311.453276) (xy 125.23673 -311.453276) (xy 125.240801 -311.397654) (xy 125.252927 -311.343217)
			(xy 125.27285 -311.291126) (xy 125.300146 -311.242491) (xy 125.334232 -311.198348) (xy 125.374381 -311.159639)
			(xy 125.419739 -311.127188) (xy 125.469339 -311.101687) (xy 125.522123 -311.08368) (xy 125.576966 -311.07355)
			(xy 125.6327 -311.071513) (xy 125.688137 -311.077613) (xy 125.742094 -311.091719) (xy 125.793423 -311.113531)
			(xy 125.841029 -311.142585) (xy 125.883897 -311.17826) (xy 125.921114 -311.219797) (xy 125.951887 -311.26631)
			(xy 125.975559 -311.316807) (xy 125.991627 -311.370214) (xy 125.999747 -311.42539) (xy 126.000256 -311.453276)
			(xy 126.25273 -311.453276) (xy 126.256801 -311.397654) (xy 126.268927 -311.343217) (xy 126.28885 -311.291126)
			(xy 126.316146 -311.242491) (xy 126.350232 -311.198348) (xy 126.390381 -311.159639) (xy 126.435739 -311.127188)
			(xy 126.485339 -311.101687) (xy 126.538123 -311.08368) (xy 126.592966 -311.07355) (xy 126.6487 -311.071513)
			(xy 126.704137 -311.077613) (xy 126.758094 -311.091719) (xy 126.809423 -311.113531) (xy 126.857029 -311.142585)
			(xy 126.899897 -311.17826) (xy 126.937114 -311.219797) (xy 126.967887 -311.26631) (xy 126.991559 -311.316807)
			(xy 127.007627 -311.370214) (xy 127.015747 -311.42539) (xy 127.016256 -311.453276) (xy 127.26873 -311.453276)
			(xy 127.272801 -311.397654) (xy 127.284927 -311.343217) (xy 127.30485 -311.291126) (xy 127.332146 -311.242491)
			(xy 127.366232 -311.198348) (xy 127.406381 -311.159639) (xy 127.451739 -311.127188) (xy 127.501339 -311.101687)
			(xy 127.554123 -311.08368) (xy 127.608966 -311.07355) (xy 127.6647 -311.071513) (xy 127.720137 -311.077613)
			(xy 127.774094 -311.091719) (xy 127.825423 -311.113531) (xy 127.873029 -311.142585) (xy 127.915897 -311.17826)
			(xy 127.953114 -311.219797) (xy 127.983887 -311.26631) (xy 128.007559 -311.316807) (xy 128.023627 -311.370214)
			(xy 128.031747 -311.42539) (xy 128.032256 -311.453276) (xy 128.28473 -311.453276) (xy 128.288801 -311.397654)
			(xy 128.300927 -311.343217) (xy 128.32085 -311.291126) (xy 128.348146 -311.242491) (xy 128.382232 -311.198348)
			(xy 128.422381 -311.159639) (xy 128.467739 -311.127188) (xy 128.517339 -311.101687) (xy 128.570123 -311.08368)
			(xy 128.624966 -311.07355) (xy 128.6807 -311.071513) (xy 128.736137 -311.077613) (xy 128.790094 -311.091719)
			(xy 128.841423 -311.113531) (xy 128.889029 -311.142585) (xy 128.931897 -311.17826) (xy 128.969114 -311.219797)
			(xy 128.999887 -311.26631) (xy 129.023559 -311.316807) (xy 129.039627 -311.370214) (xy 129.047747 -311.42539)
			(xy 129.048256 -311.453276) (xy 129.30073 -311.453276) (xy 129.304801 -311.397654) (xy 129.316927 -311.343217)
			(xy 129.33685 -311.291126) (xy 129.364146 -311.242491) (xy 129.398232 -311.198348) (xy 129.438381 -311.159639)
			(xy 129.483739 -311.127188) (xy 129.533339 -311.101687) (xy 129.586123 -311.08368) (xy 129.640966 -311.07355)
			(xy 129.6967 -311.071513) (xy 129.752137 -311.077613) (xy 129.806094 -311.091719) (xy 129.857423 -311.113531)
			(xy 129.905029 -311.142585) (xy 129.947897 -311.17826) (xy 129.985114 -311.219797) (xy 130.015887 -311.26631)
			(xy 130.039559 -311.316807) (xy 130.055627 -311.370214) (xy 130.063747 -311.42539) (xy 130.064256 -311.453276)
			(xy 130.31673 -311.453276) (xy 130.320801 -311.397654) (xy 130.332927 -311.343217) (xy 130.35285 -311.291126)
			(xy 130.380146 -311.242491) (xy 130.414232 -311.198348) (xy 130.454381 -311.159639) (xy 130.499739 -311.127188)
			(xy 130.549339 -311.101687) (xy 130.602123 -311.08368) (xy 130.656966 -311.07355) (xy 130.7127 -311.071513)
			(xy 130.768137 -311.077613) (xy 130.822094 -311.091719) (xy 130.873423 -311.113531) (xy 130.921029 -311.142585)
			(xy 130.963897 -311.17826) (xy 131.001114 -311.219797) (xy 131.031887 -311.26631) (xy 131.055559 -311.316807)
			(xy 131.071627 -311.370214) (xy 131.079747 -311.42539) (xy 131.080256 -311.453276) (xy 131.33273 -311.453276)
			(xy 131.336801 -311.397654) (xy 131.348927 -311.343217) (xy 131.36885 -311.291126) (xy 131.396146 -311.242491)
			(xy 131.430232 -311.198348) (xy 131.470381 -311.159639) (xy 131.515739 -311.127188) (xy 131.565339 -311.101687)
			(xy 131.618123 -311.08368) (xy 131.672966 -311.07355) (xy 131.7287 -311.071513) (xy 131.784137 -311.077613)
			(xy 131.838094 -311.091719) (xy 131.889423 -311.113531) (xy 131.937029 -311.142585) (xy 131.979897 -311.17826)
			(xy 132.017114 -311.219797) (xy 132.047887 -311.26631) (xy 132.071559 -311.316807) (xy 132.087627 -311.370214)
			(xy 132.095747 -311.42539) (xy 132.096256 -311.453276) (xy 132.34873 -311.453276) (xy 132.352801 -311.397654)
			(xy 132.364927 -311.343217) (xy 132.38485 -311.291126) (xy 132.412146 -311.242491) (xy 132.446232 -311.198348)
			(xy 132.486381 -311.159639) (xy 132.531739 -311.127188) (xy 132.581339 -311.101687) (xy 132.634123 -311.08368)
			(xy 132.688966 -311.07355) (xy 132.7447 -311.071513) (xy 132.800137 -311.077613) (xy 132.854094 -311.091719)
			(xy 132.905423 -311.113531) (xy 132.953029 -311.142585) (xy 132.995897 -311.17826) (xy 133.033114 -311.219797)
			(xy 133.063887 -311.26631) (xy 133.087559 -311.316807) (xy 133.103627 -311.370214) (xy 133.111747 -311.42539)
			(xy 133.112256 -311.453276) (xy 133.111747 -311.481162) (xy 133.103627 -311.536338) (xy 133.087559 -311.589745)
			(xy 133.063887 -311.640242) (xy 133.033114 -311.686755) (xy 132.995897 -311.728292) (xy 132.988798 -311.7342)
			(xy 148.58949 -311.7342) (xy 148.593561 -311.678578) (xy 148.605687 -311.624141) (xy 148.62561 -311.57205)
			(xy 148.652906 -311.523415) (xy 148.686992 -311.479272) (xy 148.727141 -311.440563) (xy 148.772499 -311.408112)
			(xy 148.822099 -311.382611) (xy 148.874883 -311.364604) (xy 148.929726 -311.354474) (xy 148.98546 -311.352437)
			(xy 149.040897 -311.358537) (xy 149.094854 -311.372643) (xy 149.146183 -311.394455) (xy 149.193789 -311.423509)
			(xy 149.236657 -311.459184) (xy 149.273874 -311.500721) (xy 149.304647 -311.547234) (xy 149.328319 -311.597731)
			(xy 149.344387 -311.651138) (xy 149.352507 -311.706314) (xy 149.353016 -311.7342) (xy 149.352507 -311.762086)
			(xy 149.344387 -311.817262) (xy 149.328319 -311.870669) (xy 149.304647 -311.921166) (xy 149.273874 -311.967679)
			(xy 149.236657 -312.009216) (xy 149.193789 -312.044891) (xy 149.146183 -312.073945) (xy 149.094854 -312.095757)
			(xy 149.040897 -312.109863) (xy 148.98546 -312.115963) (xy 148.929726 -312.113926) (xy 148.874883 -312.103796)
			(xy 148.822099 -312.085789) (xy 148.772499 -312.060288) (xy 148.727141 -312.027837) (xy 148.686992 -311.989128)
			(xy 148.652906 -311.944985) (xy 148.62561 -311.89635) (xy 148.605687 -311.844259) (xy 148.593561 -311.789822)
			(xy 148.58949 -311.7342) (xy 132.988798 -311.7342) (xy 132.953029 -311.763967) (xy 132.905423 -311.793021)
			(xy 132.854094 -311.814833) (xy 132.800137 -311.828939) (xy 132.7447 -311.835039) (xy 132.688966 -311.833002)
			(xy 132.634123 -311.822872) (xy 132.581339 -311.804865) (xy 132.531739 -311.779364) (xy 132.486381 -311.746913)
			(xy 132.446232 -311.708204) (xy 132.412146 -311.664061) (xy 132.38485 -311.615426) (xy 132.364927 -311.563335)
			(xy 132.352801 -311.508898) (xy 132.34873 -311.453276) (xy 132.096256 -311.453276) (xy 132.095747 -311.481162)
			(xy 132.087627 -311.536338) (xy 132.071559 -311.589745) (xy 132.047887 -311.640242) (xy 132.017114 -311.686755)
			(xy 131.979897 -311.728292) (xy 131.937029 -311.763967) (xy 131.889423 -311.793021) (xy 131.838094 -311.814833)
			(xy 131.784137 -311.828939) (xy 131.7287 -311.835039) (xy 131.672966 -311.833002) (xy 131.618123 -311.822872)
			(xy 131.565339 -311.804865) (xy 131.515739 -311.779364) (xy 131.470381 -311.746913) (xy 131.430232 -311.708204)
			(xy 131.396146 -311.664061) (xy 131.36885 -311.615426) (xy 131.348927 -311.563335) (xy 131.336801 -311.508898)
			(xy 131.33273 -311.453276) (xy 131.080256 -311.453276) (xy 131.079747 -311.481162) (xy 131.071627 -311.536338)
			(xy 131.055559 -311.589745) (xy 131.031887 -311.640242) (xy 131.001114 -311.686755) (xy 130.963897 -311.728292)
			(xy 130.921029 -311.763967) (xy 130.873423 -311.793021) (xy 130.822094 -311.814833) (xy 130.768137 -311.828939)
			(xy 130.7127 -311.835039) (xy 130.656966 -311.833002) (xy 130.602123 -311.822872) (xy 130.549339 -311.804865)
			(xy 130.499739 -311.779364) (xy 130.454381 -311.746913) (xy 130.414232 -311.708204) (xy 130.380146 -311.664061)
			(xy 130.35285 -311.615426) (xy 130.332927 -311.563335) (xy 130.320801 -311.508898) (xy 130.31673 -311.453276)
			(xy 130.064256 -311.453276) (xy 130.063747 -311.481162) (xy 130.055627 -311.536338) (xy 130.039559 -311.589745)
			(xy 130.015887 -311.640242) (xy 129.985114 -311.686755) (xy 129.947897 -311.728292) (xy 129.905029 -311.763967)
			(xy 129.857423 -311.793021) (xy 129.806094 -311.814833) (xy 129.752137 -311.828939) (xy 129.6967 -311.835039)
			(xy 129.640966 -311.833002) (xy 129.586123 -311.822872) (xy 129.533339 -311.804865) (xy 129.483739 -311.779364)
			(xy 129.438381 -311.746913) (xy 129.398232 -311.708204) (xy 129.364146 -311.664061) (xy 129.33685 -311.615426)
			(xy 129.316927 -311.563335) (xy 129.304801 -311.508898) (xy 129.30073 -311.453276) (xy 129.048256 -311.453276)
			(xy 129.047747 -311.481162) (xy 129.039627 -311.536338) (xy 129.023559 -311.589745) (xy 128.999887 -311.640242)
			(xy 128.969114 -311.686755) (xy 128.931897 -311.728292) (xy 128.889029 -311.763967) (xy 128.841423 -311.793021)
			(xy 128.790094 -311.814833) (xy 128.736137 -311.828939) (xy 128.6807 -311.835039) (xy 128.624966 -311.833002)
			(xy 128.570123 -311.822872) (xy 128.517339 -311.804865) (xy 128.467739 -311.779364) (xy 128.422381 -311.746913)
			(xy 128.382232 -311.708204) (xy 128.348146 -311.664061) (xy 128.32085 -311.615426) (xy 128.300927 -311.563335)
			(xy 128.288801 -311.508898) (xy 128.28473 -311.453276) (xy 128.032256 -311.453276) (xy 128.031747 -311.481162)
			(xy 128.023627 -311.536338) (xy 128.007559 -311.589745) (xy 127.983887 -311.640242) (xy 127.953114 -311.686755)
			(xy 127.915897 -311.728292) (xy 127.873029 -311.763967) (xy 127.825423 -311.793021) (xy 127.774094 -311.814833)
			(xy 127.720137 -311.828939) (xy 127.6647 -311.835039) (xy 127.608966 -311.833002) (xy 127.554123 -311.822872)
			(xy 127.501339 -311.804865) (xy 127.451739 -311.779364) (xy 127.406381 -311.746913) (xy 127.366232 -311.708204)
			(xy 127.332146 -311.664061) (xy 127.30485 -311.615426) (xy 127.284927 -311.563335) (xy 127.272801 -311.508898)
			(xy 127.26873 -311.453276) (xy 127.016256 -311.453276) (xy 127.015747 -311.481162) (xy 127.007627 -311.536338)
			(xy 126.991559 -311.589745) (xy 126.967887 -311.640242) (xy 126.937114 -311.686755) (xy 126.899897 -311.728292)
			(xy 126.857029 -311.763967) (xy 126.809423 -311.793021) (xy 126.758094 -311.814833) (xy 126.704137 -311.828939)
			(xy 126.6487 -311.835039) (xy 126.592966 -311.833002) (xy 126.538123 -311.822872) (xy 126.485339 -311.804865)
			(xy 126.435739 -311.779364) (xy 126.390381 -311.746913) (xy 126.350232 -311.708204) (xy 126.316146 -311.664061)
			(xy 126.28885 -311.615426) (xy 126.268927 -311.563335) (xy 126.256801 -311.508898) (xy 126.25273 -311.453276)
			(xy 126.000256 -311.453276) (xy 125.999747 -311.481162) (xy 125.991627 -311.536338) (xy 125.975559 -311.589745)
			(xy 125.951887 -311.640242) (xy 125.921114 -311.686755) (xy 125.883897 -311.728292) (xy 125.841029 -311.763967)
			(xy 125.793423 -311.793021) (xy 125.742094 -311.814833) (xy 125.688137 -311.828939) (xy 125.6327 -311.835039)
			(xy 125.576966 -311.833002) (xy 125.522123 -311.822872) (xy 125.469339 -311.804865) (xy 125.419739 -311.779364)
			(xy 125.374381 -311.746913) (xy 125.334232 -311.708204) (xy 125.300146 -311.664061) (xy 125.27285 -311.615426)
			(xy 125.252927 -311.563335) (xy 125.240801 -311.508898) (xy 125.23673 -311.453276) (xy 119.631206 -311.453276)
			(xy 119.631206 -312.469276) (xy 125.23673 -312.469276) (xy 125.240801 -312.413654) (xy 125.252927 -312.359217)
			(xy 125.27285 -312.307126) (xy 125.300146 -312.258491) (xy 125.334232 -312.214348) (xy 125.374381 -312.175639)
			(xy 125.419739 -312.143188) (xy 125.469339 -312.117687) (xy 125.522123 -312.09968) (xy 125.576966 -312.08955)
			(xy 125.6327 -312.087513) (xy 125.688137 -312.093613) (xy 125.742094 -312.107719) (xy 125.793423 -312.129531)
			(xy 125.841029 -312.158585) (xy 125.883897 -312.19426) (xy 125.921114 -312.235797) (xy 125.951887 -312.28231)
			(xy 125.975559 -312.332807) (xy 125.991627 -312.386214) (xy 125.999747 -312.44139) (xy 126.000256 -312.469276)
			(xy 126.25273 -312.469276) (xy 126.256801 -312.413654) (xy 126.268927 -312.359217) (xy 126.28885 -312.307126)
			(xy 126.316146 -312.258491) (xy 126.350232 -312.214348) (xy 126.390381 -312.175639) (xy 126.435739 -312.143188)
			(xy 126.485339 -312.117687) (xy 126.538123 -312.09968) (xy 126.592966 -312.08955) (xy 126.6487 -312.087513)
			(xy 126.704137 -312.093613) (xy 126.758094 -312.107719) (xy 126.809423 -312.129531) (xy 126.857029 -312.158585)
			(xy 126.899897 -312.19426) (xy 126.937114 -312.235797) (xy 126.967887 -312.28231) (xy 126.991559 -312.332807)
			(xy 127.007627 -312.386214) (xy 127.015747 -312.44139) (xy 127.016256 -312.469276) (xy 127.26873 -312.469276)
			(xy 127.272801 -312.413654) (xy 127.284927 -312.359217) (xy 127.30485 -312.307126) (xy 127.332146 -312.258491)
			(xy 127.366232 -312.214348) (xy 127.406381 -312.175639) (xy 127.451739 -312.143188) (xy 127.501339 -312.117687)
			(xy 127.554123 -312.09968) (xy 127.608966 -312.08955) (xy 127.6647 -312.087513) (xy 127.720137 -312.093613)
			(xy 127.774094 -312.107719) (xy 127.825423 -312.129531) (xy 127.873029 -312.158585) (xy 127.915897 -312.19426)
			(xy 127.953114 -312.235797) (xy 127.983887 -312.28231) (xy 128.007559 -312.332807) (xy 128.023627 -312.386214)
			(xy 128.031747 -312.44139) (xy 128.032256 -312.469276) (xy 128.28473 -312.469276) (xy 128.288801 -312.413654)
			(xy 128.300927 -312.359217) (xy 128.32085 -312.307126) (xy 128.348146 -312.258491) (xy 128.382232 -312.214348)
			(xy 128.422381 -312.175639) (xy 128.467739 -312.143188) (xy 128.517339 -312.117687) (xy 128.570123 -312.09968)
			(xy 128.624966 -312.08955) (xy 128.6807 -312.087513) (xy 128.736137 -312.093613) (xy 128.790094 -312.107719)
			(xy 128.841423 -312.129531) (xy 128.889029 -312.158585) (xy 128.931897 -312.19426) (xy 128.969114 -312.235797)
			(xy 128.999887 -312.28231) (xy 129.023559 -312.332807) (xy 129.039627 -312.386214) (xy 129.047747 -312.44139)
			(xy 129.048256 -312.469276) (xy 129.30073 -312.469276) (xy 129.304801 -312.413654) (xy 129.316927 -312.359217)
			(xy 129.33685 -312.307126) (xy 129.364146 -312.258491) (xy 129.398232 -312.214348) (xy 129.438381 -312.175639)
			(xy 129.483739 -312.143188) (xy 129.533339 -312.117687) (xy 129.586123 -312.09968) (xy 129.640966 -312.08955)
			(xy 129.6967 -312.087513) (xy 129.752137 -312.093613) (xy 129.806094 -312.107719) (xy 129.857423 -312.129531)
			(xy 129.905029 -312.158585) (xy 129.947897 -312.19426) (xy 129.985114 -312.235797) (xy 130.015887 -312.28231)
			(xy 130.039559 -312.332807) (xy 130.055627 -312.386214) (xy 130.063747 -312.44139) (xy 130.064256 -312.469276)
			(xy 130.31673 -312.469276) (xy 130.320801 -312.413654) (xy 130.332927 -312.359217) (xy 130.35285 -312.307126)
			(xy 130.380146 -312.258491) (xy 130.414232 -312.214348) (xy 130.454381 -312.175639) (xy 130.499739 -312.143188)
			(xy 130.549339 -312.117687) (xy 130.602123 -312.09968) (xy 130.656966 -312.08955) (xy 130.7127 -312.087513)
			(xy 130.768137 -312.093613) (xy 130.822094 -312.107719) (xy 130.873423 -312.129531) (xy 130.921029 -312.158585)
			(xy 130.963897 -312.19426) (xy 131.001114 -312.235797) (xy 131.031887 -312.28231) (xy 131.055559 -312.332807)
			(xy 131.071627 -312.386214) (xy 131.079747 -312.44139) (xy 131.080256 -312.469276) (xy 131.33273 -312.469276)
			(xy 131.336801 -312.413654) (xy 131.348927 -312.359217) (xy 131.36885 -312.307126) (xy 131.396146 -312.258491)
			(xy 131.430232 -312.214348) (xy 131.470381 -312.175639) (xy 131.515739 -312.143188) (xy 131.565339 -312.117687)
			(xy 131.618123 -312.09968) (xy 131.672966 -312.08955) (xy 131.7287 -312.087513) (xy 131.784137 -312.093613)
			(xy 131.838094 -312.107719) (xy 131.889423 -312.129531) (xy 131.937029 -312.158585) (xy 131.979897 -312.19426)
			(xy 132.017114 -312.235797) (xy 132.047887 -312.28231) (xy 132.071559 -312.332807) (xy 132.087627 -312.386214)
			(xy 132.095747 -312.44139) (xy 132.096256 -312.469276) (xy 132.095747 -312.497162) (xy 132.091889 -312.523378)
			(xy 147.832062 -312.523378) (xy 147.836133 -312.467756) (xy 147.848259 -312.413319) (xy 147.868182 -312.361228)
			(xy 147.895478 -312.312593) (xy 147.929564 -312.26845) (xy 147.969713 -312.229741) (xy 148.015071 -312.19729)
			(xy 148.064671 -312.171789) (xy 148.117455 -312.153782) (xy 148.172298 -312.143652) (xy 148.228032 -312.141615)
			(xy 148.283469 -312.147715) (xy 148.337426 -312.161821) (xy 148.388755 -312.183633) (xy 148.436361 -312.212687)
			(xy 148.479229 -312.248362) (xy 148.496921 -312.268108) (xy 150.210772 -312.268108) (xy 150.214843 -312.212486)
			(xy 150.226969 -312.158049) (xy 150.246892 -312.105958) (xy 150.274188 -312.057323) (xy 150.308274 -312.01318)
			(xy 150.348423 -311.974471) (xy 150.393781 -311.94202) (xy 150.443381 -311.916519) (xy 150.496165 -311.898512)
			(xy 150.551008 -311.888382) (xy 150.606742 -311.886345) (xy 150.662179 -311.892445) (xy 150.716136 -311.906551)
			(xy 150.767465 -311.928363) (xy 150.815071 -311.957417) (xy 150.857939 -311.993092) (xy 150.895156 -312.034629)
			(xy 150.905106 -312.049668) (xy 151.693892 -312.049668) (xy 151.697852 -312.000614) (xy 151.709629 -311.95283)
			(xy 151.72892 -311.907554) (xy 151.755223 -311.865958) (xy 151.787858 -311.829121) (xy 151.825979 -311.797996)
			(xy 151.8686 -311.773389) (xy 151.914616 -311.755937) (xy 151.962835 -311.746093) (xy 152.01201 -311.744112)
			(xy 152.060865 -311.750044) (xy 152.108136 -311.763736) (xy 152.152598 -311.784834) (xy 152.193101 -311.81279)
			(xy 152.228594 -311.846882) (xy 152.258159 -311.886226) (xy 152.28103 -311.929803) (xy 152.296614 -311.976484)
			(xy 152.304509 -312.025061) (xy 152.305004 -312.049668) (xy 152.304999 -312.049922) (xy 152.644106 -312.049922)
			(xy 152.648066 -312.000868) (xy 152.659843 -311.953084) (xy 152.679134 -311.907808) (xy 152.705437 -311.866212)
			(xy 152.738072 -311.829375) (xy 152.776193 -311.79825) (xy 152.818814 -311.773643) (xy 152.86483 -311.756191)
			(xy 152.913049 -311.746347) (xy 152.962224 -311.744366) (xy 153.011079 -311.750298) (xy 153.05835 -311.76399)
			(xy 153.102812 -311.785088) (xy 153.143315 -311.813044) (xy 153.178808 -311.847136) (xy 153.208373 -311.88648)
			(xy 153.231244 -311.930057) (xy 153.246828 -311.976738) (xy 153.254723 -312.025315) (xy 153.255218 -312.049922)
			(xy 153.594066 -312.049922) (xy 153.598026 -312.000868) (xy 153.609803 -311.953084) (xy 153.629094 -311.907808)
			(xy 153.655397 -311.866212) (xy 153.688032 -311.829375) (xy 153.726153 -311.79825) (xy 153.768774 -311.773643)
			(xy 153.81479 -311.756191) (xy 153.863009 -311.746347) (xy 153.912184 -311.744366) (xy 153.961039 -311.750298)
			(xy 154.00831 -311.76399) (xy 154.052772 -311.785088) (xy 154.093275 -311.813044) (xy 154.128768 -311.847136)
			(xy 154.158333 -311.88648) (xy 154.181204 -311.930057) (xy 154.196788 -311.976738) (xy 154.204683 -312.025315)
			(xy 154.205178 -312.049922) (xy 154.54428 -312.049922) (xy 154.54824 -312.000868) (xy 154.560017 -311.953084)
			(xy 154.579308 -311.907808) (xy 154.605611 -311.866212) (xy 154.638246 -311.829375) (xy 154.676367 -311.79825)
			(xy 154.718988 -311.773643) (xy 154.765004 -311.756191) (xy 154.813223 -311.746347) (xy 154.862398 -311.744366)
			(xy 154.911253 -311.750298) (xy 154.958524 -311.76399) (xy 155.002986 -311.785088) (xy 155.043489 -311.813044)
			(xy 155.078982 -311.847136) (xy 155.108547 -311.88648) (xy 155.131418 -311.930057) (xy 155.147002 -311.976738)
			(xy 155.154897 -312.025315) (xy 155.155392 -312.049922) (xy 155.49424 -312.049922) (xy 155.4982 -312.000868)
			(xy 155.509977 -311.953084) (xy 155.529268 -311.907808) (xy 155.555571 -311.866212) (xy 155.588206 -311.829375)
			(xy 155.626327 -311.79825) (xy 155.668948 -311.773643) (xy 155.714964 -311.756191) (xy 155.763183 -311.746347)
			(xy 155.812358 -311.744366) (xy 155.861213 -311.750298) (xy 155.908484 -311.76399) (xy 155.952946 -311.785088)
			(xy 155.993449 -311.813044) (xy 156.028942 -311.847136) (xy 156.058507 -311.88648) (xy 156.081378 -311.930057)
			(xy 156.096962 -311.976738) (xy 156.104857 -312.025315) (xy 156.105352 -312.049922) (xy 156.4442 -312.049922)
			(xy 156.44816 -312.000868) (xy 156.459937 -311.953084) (xy 156.479228 -311.907808) (xy 156.505531 -311.866212)
			(xy 156.538166 -311.829375) (xy 156.576287 -311.79825) (xy 156.618908 -311.773643) (xy 156.664924 -311.756191)
			(xy 156.713143 -311.746347) (xy 156.762318 -311.744366) (xy 156.811173 -311.750298) (xy 156.858444 -311.76399)
			(xy 156.902906 -311.785088) (xy 156.943409 -311.813044) (xy 156.978902 -311.847136) (xy 157.008467 -311.88648)
			(xy 157.031338 -311.930057) (xy 157.046922 -311.976738) (xy 157.054817 -312.025315) (xy 157.055312 -312.049922)
			(xy 157.39416 -312.049922) (xy 157.39812 -312.000868) (xy 157.409897 -311.953084) (xy 157.429188 -311.907808)
			(xy 157.455491 -311.866212) (xy 157.488126 -311.829375) (xy 157.526247 -311.79825) (xy 157.568868 -311.773643)
			(xy 157.614884 -311.756191) (xy 157.663103 -311.746347) (xy 157.712278 -311.744366) (xy 157.761133 -311.750298)
			(xy 157.808404 -311.76399) (xy 157.852866 -311.785088) (xy 157.893369 -311.813044) (xy 157.928862 -311.847136)
			(xy 157.958427 -311.88648) (xy 157.981298 -311.930057) (xy 157.996882 -311.976738) (xy 158.004777 -312.025315)
			(xy 158.005272 -312.049922) (xy 158.34412 -312.049922) (xy 158.34808 -312.000868) (xy 158.359857 -311.953084)
			(xy 158.379148 -311.907808) (xy 158.405451 -311.866212) (xy 158.438086 -311.829375) (xy 158.476207 -311.79825)
			(xy 158.518828 -311.773643) (xy 158.564844 -311.756191) (xy 158.613063 -311.746347) (xy 158.662238 -311.744366)
			(xy 158.711093 -311.750298) (xy 158.758364 -311.76399) (xy 158.802826 -311.785088) (xy 158.843329 -311.813044)
			(xy 158.878822 -311.847136) (xy 158.908387 -311.88648) (xy 158.931258 -311.930057) (xy 158.946842 -311.976738)
			(xy 158.954737 -312.025315) (xy 158.955232 -312.049922) (xy 159.29408 -312.049922) (xy 159.29804 -312.000868)
			(xy 159.309817 -311.953084) (xy 159.329108 -311.907808) (xy 159.355411 -311.866212) (xy 159.388046 -311.829375)
			(xy 159.426167 -311.79825) (xy 159.468788 -311.773643) (xy 159.514804 -311.756191) (xy 159.563023 -311.746347)
			(xy 159.612198 -311.744366) (xy 159.661053 -311.750298) (xy 159.708324 -311.76399) (xy 159.752786 -311.785088)
			(xy 159.793289 -311.813044) (xy 159.828782 -311.847136) (xy 159.858347 -311.88648) (xy 159.881218 -311.930057)
			(xy 159.896802 -311.976738) (xy 159.904697 -312.025315) (xy 159.905192 -312.049922) (xy 160.24404 -312.049922)
			(xy 160.248 -312.000868) (xy 160.259777 -311.953084) (xy 160.279068 -311.907808) (xy 160.305371 -311.866212)
			(xy 160.338006 -311.829375) (xy 160.376127 -311.79825) (xy 160.418748 -311.773643) (xy 160.464764 -311.756191)
			(xy 160.512983 -311.746347) (xy 160.562158 -311.744366) (xy 160.611013 -311.750298) (xy 160.658284 -311.76399)
			(xy 160.702746 -311.785088) (xy 160.743249 -311.813044) (xy 160.778742 -311.847136) (xy 160.808307 -311.88648)
			(xy 160.831178 -311.930057) (xy 160.846762 -311.976738) (xy 160.854657 -312.025315) (xy 160.855152 -312.049922)
			(xy 161.194254 -312.049922) (xy 161.198214 -312.000868) (xy 161.209991 -311.953084) (xy 161.229282 -311.907808)
			(xy 161.255585 -311.866212) (xy 161.28822 -311.829375) (xy 161.326341 -311.79825) (xy 161.368962 -311.773643)
			(xy 161.414978 -311.756191) (xy 161.463197 -311.746347) (xy 161.512372 -311.744366) (xy 161.561227 -311.750298)
			(xy 161.608498 -311.76399) (xy 161.65296 -311.785088) (xy 161.693463 -311.813044) (xy 161.728956 -311.847136)
			(xy 161.758521 -311.88648) (xy 161.781392 -311.930057) (xy 161.796976 -311.976738) (xy 161.804871 -312.025315)
			(xy 161.805366 -312.049922) (xy 162.144214 -312.049922) (xy 162.148174 -312.000868) (xy 162.159951 -311.953084)
			(xy 162.179242 -311.907808) (xy 162.205545 -311.866212) (xy 162.23818 -311.829375) (xy 162.276301 -311.79825)
			(xy 162.318922 -311.773643) (xy 162.364938 -311.756191) (xy 162.413157 -311.746347) (xy 162.462332 -311.744366)
			(xy 162.511187 -311.750298) (xy 162.558458 -311.76399) (xy 162.60292 -311.785088) (xy 162.643423 -311.813044)
			(xy 162.678916 -311.847136) (xy 162.708481 -311.88648) (xy 162.731352 -311.930057) (xy 162.746936 -311.976738)
			(xy 162.754831 -312.025315) (xy 162.755326 -312.049922) (xy 163.094174 -312.049922) (xy 163.098134 -312.000868)
			(xy 163.109911 -311.953084) (xy 163.129202 -311.907808) (xy 163.155505 -311.866212) (xy 163.18814 -311.829375)
			(xy 163.226261 -311.79825) (xy 163.268882 -311.773643) (xy 163.314898 -311.756191) (xy 163.363117 -311.746347)
			(xy 163.412292 -311.744366) (xy 163.461147 -311.750298) (xy 163.508418 -311.76399) (xy 163.55288 -311.785088)
			(xy 163.593383 -311.813044) (xy 163.628876 -311.847136) (xy 163.658441 -311.88648) (xy 163.681312 -311.930057)
			(xy 163.696896 -311.976738) (xy 163.704791 -312.025315) (xy 163.705286 -312.049922) (xy 164.044134 -312.049922)
			(xy 164.048094 -312.000868) (xy 164.059871 -311.953084) (xy 164.079162 -311.907808) (xy 164.105465 -311.866212)
			(xy 164.1381 -311.829375) (xy 164.176221 -311.79825) (xy 164.218842 -311.773643) (xy 164.264858 -311.756191)
			(xy 164.313077 -311.746347) (xy 164.362252 -311.744366) (xy 164.411107 -311.750298) (xy 164.458378 -311.76399)
			(xy 164.50284 -311.785088) (xy 164.543343 -311.813044) (xy 164.578836 -311.847136) (xy 164.608401 -311.88648)
			(xy 164.631272 -311.930057) (xy 164.646856 -311.976738) (xy 164.654751 -312.025315) (xy 164.655246 -312.049922)
			(xy 164.994094 -312.049922) (xy 164.998054 -312.000868) (xy 165.009831 -311.953084) (xy 165.029122 -311.907808)
			(xy 165.055425 -311.866212) (xy 165.08806 -311.829375) (xy 165.126181 -311.79825) (xy 165.168802 -311.773643)
			(xy 165.214818 -311.756191) (xy 165.263037 -311.746347) (xy 165.312212 -311.744366) (xy 165.361067 -311.750298)
			(xy 165.408338 -311.76399) (xy 165.4528 -311.785088) (xy 165.493303 -311.813044) (xy 165.528796 -311.847136)
			(xy 165.558361 -311.88648) (xy 165.581232 -311.930057) (xy 165.596816 -311.976738) (xy 165.604711 -312.025315)
			(xy 165.605206 -312.049922) (xy 165.944054 -312.049922) (xy 165.948014 -312.000868) (xy 165.959791 -311.953084)
			(xy 165.979082 -311.907808) (xy 166.005385 -311.866212) (xy 166.03802 -311.829375) (xy 166.076141 -311.79825)
			(xy 166.118762 -311.773643) (xy 166.164778 -311.756191) (xy 166.212997 -311.746347) (xy 166.262172 -311.744366)
			(xy 166.311027 -311.750298) (xy 166.358298 -311.76399) (xy 166.40276 -311.785088) (xy 166.443263 -311.813044)
			(xy 166.478756 -311.847136) (xy 166.508321 -311.88648) (xy 166.531192 -311.930057) (xy 166.546776 -311.976738)
			(xy 166.554671 -312.025315) (xy 166.555166 -312.049922) (xy 166.894268 -312.049922) (xy 166.898228 -312.000868)
			(xy 166.910005 -311.953084) (xy 166.929296 -311.907808) (xy 166.955599 -311.866212) (xy 166.988234 -311.829375)
			(xy 167.026355 -311.79825) (xy 167.068976 -311.773643) (xy 167.114992 -311.756191) (xy 167.163211 -311.746347)
			(xy 167.212386 -311.744366) (xy 167.261241 -311.750298) (xy 167.308512 -311.76399) (xy 167.352974 -311.785088)
			(xy 167.393477 -311.813044) (xy 167.42897 -311.847136) (xy 167.458535 -311.88648) (xy 167.481406 -311.930057)
			(xy 167.49699 -311.976738) (xy 167.504885 -312.025315) (xy 167.50538 -312.049922) (xy 167.844228 -312.049922)
			(xy 167.848188 -312.000868) (xy 167.859965 -311.953084) (xy 167.879256 -311.907808) (xy 167.905559 -311.866212)
			(xy 167.938194 -311.829375) (xy 167.976315 -311.79825) (xy 168.018936 -311.773643) (xy 168.064952 -311.756191)
			(xy 168.113171 -311.746347) (xy 168.162346 -311.744366) (xy 168.211201 -311.750298) (xy 168.258472 -311.76399)
			(xy 168.302934 -311.785088) (xy 168.343437 -311.813044) (xy 168.37893 -311.847136) (xy 168.408495 -311.88648)
			(xy 168.431366 -311.930057) (xy 168.44695 -311.976738) (xy 168.454845 -312.025315) (xy 168.45534 -312.049922)
			(xy 168.794188 -312.049922) (xy 168.798148 -312.000868) (xy 168.809925 -311.953084) (xy 168.829216 -311.907808)
			(xy 168.855519 -311.866212) (xy 168.888154 -311.829375) (xy 168.926275 -311.79825) (xy 168.968896 -311.773643)
			(xy 169.014912 -311.756191) (xy 169.063131 -311.746347) (xy 169.112306 -311.744366) (xy 169.161161 -311.750298)
			(xy 169.208432 -311.76399) (xy 169.252894 -311.785088) (xy 169.293397 -311.813044) (xy 169.32889 -311.847136)
			(xy 169.358455 -311.88648) (xy 169.381326 -311.930057) (xy 169.39691 -311.976738) (xy 169.404805 -312.025315)
			(xy 169.4053 -312.049922) (xy 169.744148 -312.049922) (xy 169.748108 -312.000868) (xy 169.759885 -311.953084)
			(xy 169.779176 -311.907808) (xy 169.805479 -311.866212) (xy 169.838114 -311.829375) (xy 169.876235 -311.79825)
			(xy 169.918856 -311.773643) (xy 169.964872 -311.756191) (xy 170.013091 -311.746347) (xy 170.062266 -311.744366)
			(xy 170.111121 -311.750298) (xy 170.158392 -311.76399) (xy 170.202854 -311.785088) (xy 170.243357 -311.813044)
			(xy 170.27885 -311.847136) (xy 170.308415 -311.88648) (xy 170.331286 -311.930057) (xy 170.34687 -311.976738)
			(xy 170.354765 -312.025315) (xy 170.35526 -312.049922) (xy 170.694108 -312.049922) (xy 170.698068 -312.000868)
			(xy 170.709845 -311.953084) (xy 170.729136 -311.907808) (xy 170.755439 -311.866212) (xy 170.788074 -311.829375)
			(xy 170.826195 -311.79825) (xy 170.868816 -311.773643) (xy 170.914832 -311.756191) (xy 170.963051 -311.746347)
			(xy 171.012226 -311.744366) (xy 171.061081 -311.750298) (xy 171.108352 -311.76399) (xy 171.152814 -311.785088)
			(xy 171.193317 -311.813044) (xy 171.22881 -311.847136) (xy 171.258375 -311.88648) (xy 171.281246 -311.930057)
			(xy 171.29683 -311.976738) (xy 171.304725 -312.025315) (xy 171.30522 -312.049922) (xy 171.644068 -312.049922)
			(xy 171.648028 -312.000868) (xy 171.659805 -311.953084) (xy 171.679096 -311.907808) (xy 171.705399 -311.866212)
			(xy 171.738034 -311.829375) (xy 171.776155 -311.79825) (xy 171.818776 -311.773643) (xy 171.864792 -311.756191)
			(xy 171.913011 -311.746347) (xy 171.962186 -311.744366) (xy 172.011041 -311.750298) (xy 172.058312 -311.76399)
			(xy 172.102774 -311.785088) (xy 172.143277 -311.813044) (xy 172.17877 -311.847136) (xy 172.208335 -311.88648)
			(xy 172.231206 -311.930057) (xy 172.24679 -311.976738) (xy 172.254685 -312.025315) (xy 172.25518 -312.049922)
			(xy 172.594282 -312.049922) (xy 172.598242 -312.000868) (xy 172.610019 -311.953084) (xy 172.62931 -311.907808)
			(xy 172.655613 -311.866212) (xy 172.688248 -311.829375) (xy 172.726369 -311.79825) (xy 172.76899 -311.773643)
			(xy 172.815006 -311.756191) (xy 172.863225 -311.746347) (xy 172.9124 -311.744366) (xy 172.961255 -311.750298)
			(xy 173.008526 -311.76399) (xy 173.052988 -311.785088) (xy 173.093491 -311.813044) (xy 173.128984 -311.847136)
			(xy 173.158549 -311.88648) (xy 173.18142 -311.930057) (xy 173.197004 -311.976738) (xy 173.204899 -312.025315)
			(xy 173.205394 -312.049922) (xy 173.544242 -312.049922) (xy 173.548202 -312.000868) (xy 173.559979 -311.953084)
			(xy 173.57927 -311.907808) (xy 173.605573 -311.866212) (xy 173.638208 -311.829375) (xy 173.676329 -311.79825)
			(xy 173.71895 -311.773643) (xy 173.764966 -311.756191) (xy 173.813185 -311.746347) (xy 173.86236 -311.744366)
			(xy 173.911215 -311.750298) (xy 173.958486 -311.76399) (xy 174.002948 -311.785088) (xy 174.043451 -311.813044)
			(xy 174.078944 -311.847136) (xy 174.108509 -311.88648) (xy 174.13138 -311.930057) (xy 174.146964 -311.976738)
			(xy 174.154859 -312.025315) (xy 174.155354 -312.049922) (xy 174.494202 -312.049922) (xy 174.498162 -312.000868)
			(xy 174.509939 -311.953084) (xy 174.52923 -311.907808) (xy 174.555533 -311.866212) (xy 174.588168 -311.829375)
			(xy 174.626289 -311.79825) (xy 174.66891 -311.773643) (xy 174.714926 -311.756191) (xy 174.763145 -311.746347)
			(xy 174.81232 -311.744366) (xy 174.861175 -311.750298) (xy 174.908446 -311.76399) (xy 174.952908 -311.785088)
			(xy 174.993411 -311.813044) (xy 175.028904 -311.847136) (xy 175.058469 -311.88648) (xy 175.08134 -311.930057)
			(xy 175.096924 -311.976738) (xy 175.104819 -312.025315) (xy 175.105314 -312.049922) (xy 175.444162 -312.049922)
			(xy 175.448122 -312.000868) (xy 175.459899 -311.953084) (xy 175.47919 -311.907808) (xy 175.505493 -311.866212)
			(xy 175.538128 -311.829375) (xy 175.576249 -311.79825) (xy 175.61887 -311.773643) (xy 175.664886 -311.756191)
			(xy 175.713105 -311.746347) (xy 175.76228 -311.744366) (xy 175.811135 -311.750298) (xy 175.858406 -311.76399)
			(xy 175.902868 -311.785088) (xy 175.943371 -311.813044) (xy 175.978864 -311.847136) (xy 176.008429 -311.88648)
			(xy 176.0313 -311.930057) (xy 176.046884 -311.976738) (xy 176.054779 -312.025315) (xy 176.055274 -312.049922)
			(xy 176.054779 -312.074529) (xy 176.046884 -312.123106) (xy 176.0313 -312.169787) (xy 176.008429 -312.213364)
			(xy 175.978864 -312.252708) (xy 175.943371 -312.2868) (xy 175.902868 -312.314756) (xy 175.858406 -312.335854)
			(xy 175.811135 -312.349546) (xy 175.76228 -312.355478) (xy 175.713105 -312.353497) (xy 175.664886 -312.343653)
			(xy 175.61887 -312.326201) (xy 175.576249 -312.301594) (xy 175.538128 -312.270469) (xy 175.505493 -312.233632)
			(xy 175.47919 -312.192036) (xy 175.459899 -312.14676) (xy 175.448122 -312.098976) (xy 175.444162 -312.049922)
			(xy 175.105314 -312.049922) (xy 175.104819 -312.074529) (xy 175.096924 -312.123106) (xy 175.08134 -312.169787)
			(xy 175.058469 -312.213364) (xy 175.028904 -312.252708) (xy 174.993411 -312.2868) (xy 174.952908 -312.314756)
			(xy 174.908446 -312.335854) (xy 174.861175 -312.349546) (xy 174.81232 -312.355478) (xy 174.763145 -312.353497)
			(xy 174.714926 -312.343653) (xy 174.66891 -312.326201) (xy 174.626289 -312.301594) (xy 174.588168 -312.270469)
			(xy 174.555533 -312.233632) (xy 174.52923 -312.192036) (xy 174.509939 -312.14676) (xy 174.498162 -312.098976)
			(xy 174.494202 -312.049922) (xy 174.155354 -312.049922) (xy 174.154859 -312.074529) (xy 174.146964 -312.123106)
			(xy 174.13138 -312.169787) (xy 174.108509 -312.213364) (xy 174.078944 -312.252708) (xy 174.043451 -312.2868)
			(xy 174.002948 -312.314756) (xy 173.958486 -312.335854) (xy 173.911215 -312.349546) (xy 173.86236 -312.355478)
			(xy 173.813185 -312.353497) (xy 173.764966 -312.343653) (xy 173.71895 -312.326201) (xy 173.676329 -312.301594)
			(xy 173.638208 -312.270469) (xy 173.605573 -312.233632) (xy 173.57927 -312.192036) (xy 173.559979 -312.14676)
			(xy 173.548202 -312.098976) (xy 173.544242 -312.049922) (xy 173.205394 -312.049922) (xy 173.204899 -312.074529)
			(xy 173.197004 -312.123106) (xy 173.18142 -312.169787) (xy 173.158549 -312.213364) (xy 173.128984 -312.252708)
			(xy 173.093491 -312.2868) (xy 173.052988 -312.314756) (xy 173.008526 -312.335854) (xy 172.961255 -312.349546)
			(xy 172.9124 -312.355478) (xy 172.863225 -312.353497) (xy 172.815006 -312.343653) (xy 172.76899 -312.326201)
			(xy 172.726369 -312.301594) (xy 172.688248 -312.270469) (xy 172.655613 -312.233632) (xy 172.62931 -312.192036)
			(xy 172.610019 -312.14676) (xy 172.598242 -312.098976) (xy 172.594282 -312.049922) (xy 172.25518 -312.049922)
			(xy 172.254685 -312.074529) (xy 172.24679 -312.123106) (xy 172.231206 -312.169787) (xy 172.208335 -312.213364)
			(xy 172.17877 -312.252708) (xy 172.143277 -312.2868) (xy 172.102774 -312.314756) (xy 172.058312 -312.335854)
			(xy 172.011041 -312.349546) (xy 171.962186 -312.355478) (xy 171.913011 -312.353497) (xy 171.864792 -312.343653)
			(xy 171.818776 -312.326201) (xy 171.776155 -312.301594) (xy 171.738034 -312.270469) (xy 171.705399 -312.233632)
			(xy 171.679096 -312.192036) (xy 171.659805 -312.14676) (xy 171.648028 -312.098976) (xy 171.644068 -312.049922)
			(xy 171.30522 -312.049922) (xy 171.304725 -312.074529) (xy 171.29683 -312.123106) (xy 171.281246 -312.169787)
			(xy 171.258375 -312.213364) (xy 171.22881 -312.252708) (xy 171.193317 -312.2868) (xy 171.152814 -312.314756)
			(xy 171.108352 -312.335854) (xy 171.061081 -312.349546) (xy 171.012226 -312.355478) (xy 170.963051 -312.353497)
			(xy 170.914832 -312.343653) (xy 170.868816 -312.326201) (xy 170.826195 -312.301594) (xy 170.788074 -312.270469)
			(xy 170.755439 -312.233632) (xy 170.729136 -312.192036) (xy 170.709845 -312.14676) (xy 170.698068 -312.098976)
			(xy 170.694108 -312.049922) (xy 170.35526 -312.049922) (xy 170.354765 -312.074529) (xy 170.34687 -312.123106)
			(xy 170.331286 -312.169787) (xy 170.308415 -312.213364) (xy 170.27885 -312.252708) (xy 170.243357 -312.2868)
			(xy 170.202854 -312.314756) (xy 170.158392 -312.335854) (xy 170.111121 -312.349546) (xy 170.062266 -312.355478)
			(xy 170.013091 -312.353497) (xy 169.964872 -312.343653) (xy 169.918856 -312.326201) (xy 169.876235 -312.301594)
			(xy 169.838114 -312.270469) (xy 169.805479 -312.233632) (xy 169.779176 -312.192036) (xy 169.759885 -312.14676)
			(xy 169.748108 -312.098976) (xy 169.744148 -312.049922) (xy 169.4053 -312.049922) (xy 169.404805 -312.074529)
			(xy 169.39691 -312.123106) (xy 169.381326 -312.169787) (xy 169.358455 -312.213364) (xy 169.32889 -312.252708)
			(xy 169.293397 -312.2868) (xy 169.252894 -312.314756) (xy 169.208432 -312.335854) (xy 169.161161 -312.349546)
			(xy 169.112306 -312.355478) (xy 169.063131 -312.353497) (xy 169.014912 -312.343653) (xy 168.968896 -312.326201)
			(xy 168.926275 -312.301594) (xy 168.888154 -312.270469) (xy 168.855519 -312.233632) (xy 168.829216 -312.192036)
			(xy 168.809925 -312.14676) (xy 168.798148 -312.098976) (xy 168.794188 -312.049922) (xy 168.45534 -312.049922)
			(xy 168.454845 -312.074529) (xy 168.44695 -312.123106) (xy 168.431366 -312.169787) (xy 168.408495 -312.213364)
			(xy 168.37893 -312.252708) (xy 168.343437 -312.2868) (xy 168.302934 -312.314756) (xy 168.258472 -312.335854)
			(xy 168.211201 -312.349546) (xy 168.162346 -312.355478) (xy 168.113171 -312.353497) (xy 168.064952 -312.343653)
			(xy 168.018936 -312.326201) (xy 167.976315 -312.301594) (xy 167.938194 -312.270469) (xy 167.905559 -312.233632)
			(xy 167.879256 -312.192036) (xy 167.859965 -312.14676) (xy 167.848188 -312.098976) (xy 167.844228 -312.049922)
			(xy 167.50538 -312.049922) (xy 167.504885 -312.074529) (xy 167.49699 -312.123106) (xy 167.481406 -312.169787)
			(xy 167.458535 -312.213364) (xy 167.42897 -312.252708) (xy 167.393477 -312.2868) (xy 167.352974 -312.314756)
			(xy 167.308512 -312.335854) (xy 167.261241 -312.349546) (xy 167.212386 -312.355478) (xy 167.163211 -312.353497)
			(xy 167.114992 -312.343653) (xy 167.068976 -312.326201) (xy 167.026355 -312.301594) (xy 166.988234 -312.270469)
			(xy 166.955599 -312.233632) (xy 166.929296 -312.192036) (xy 166.910005 -312.14676) (xy 166.898228 -312.098976)
			(xy 166.894268 -312.049922) (xy 166.555166 -312.049922) (xy 166.554671 -312.074529) (xy 166.546776 -312.123106)
			(xy 166.531192 -312.169787) (xy 166.508321 -312.213364) (xy 166.478756 -312.252708) (xy 166.443263 -312.2868)
			(xy 166.40276 -312.314756) (xy 166.358298 -312.335854) (xy 166.311027 -312.349546) (xy 166.262172 -312.355478)
			(xy 166.212997 -312.353497) (xy 166.164778 -312.343653) (xy 166.118762 -312.326201) (xy 166.076141 -312.301594)
			(xy 166.03802 -312.270469) (xy 166.005385 -312.233632) (xy 165.979082 -312.192036) (xy 165.959791 -312.14676)
			(xy 165.948014 -312.098976) (xy 165.944054 -312.049922) (xy 165.605206 -312.049922) (xy 165.604711 -312.074529)
			(xy 165.596816 -312.123106) (xy 165.581232 -312.169787) (xy 165.558361 -312.213364) (xy 165.528796 -312.252708)
			(xy 165.493303 -312.2868) (xy 165.4528 -312.314756) (xy 165.408338 -312.335854) (xy 165.361067 -312.349546)
			(xy 165.312212 -312.355478) (xy 165.263037 -312.353497) (xy 165.214818 -312.343653) (xy 165.168802 -312.326201)
			(xy 165.126181 -312.301594) (xy 165.08806 -312.270469) (xy 165.055425 -312.233632) (xy 165.029122 -312.192036)
			(xy 165.009831 -312.14676) (xy 164.998054 -312.098976) (xy 164.994094 -312.049922) (xy 164.655246 -312.049922)
			(xy 164.654751 -312.074529) (xy 164.646856 -312.123106) (xy 164.631272 -312.169787) (xy 164.608401 -312.213364)
			(xy 164.578836 -312.252708) (xy 164.543343 -312.2868) (xy 164.50284 -312.314756) (xy 164.458378 -312.335854)
			(xy 164.411107 -312.349546) (xy 164.362252 -312.355478) (xy 164.313077 -312.353497) (xy 164.264858 -312.343653)
			(xy 164.218842 -312.326201) (xy 164.176221 -312.301594) (xy 164.1381 -312.270469) (xy 164.105465 -312.233632)
			(xy 164.079162 -312.192036) (xy 164.059871 -312.14676) (xy 164.048094 -312.098976) (xy 164.044134 -312.049922)
			(xy 163.705286 -312.049922) (xy 163.704791 -312.074529) (xy 163.696896 -312.123106) (xy 163.681312 -312.169787)
			(xy 163.658441 -312.213364) (xy 163.628876 -312.252708) (xy 163.593383 -312.2868) (xy 163.55288 -312.314756)
			(xy 163.508418 -312.335854) (xy 163.461147 -312.349546) (xy 163.412292 -312.355478) (xy 163.363117 -312.353497)
			(xy 163.314898 -312.343653) (xy 163.268882 -312.326201) (xy 163.226261 -312.301594) (xy 163.18814 -312.270469)
			(xy 163.155505 -312.233632) (xy 163.129202 -312.192036) (xy 163.109911 -312.14676) (xy 163.098134 -312.098976)
			(xy 163.094174 -312.049922) (xy 162.755326 -312.049922) (xy 162.754831 -312.074529) (xy 162.746936 -312.123106)
			(xy 162.731352 -312.169787) (xy 162.708481 -312.213364) (xy 162.678916 -312.252708) (xy 162.643423 -312.2868)
			(xy 162.60292 -312.314756) (xy 162.558458 -312.335854) (xy 162.511187 -312.349546) (xy 162.462332 -312.355478)
			(xy 162.413157 -312.353497) (xy 162.364938 -312.343653) (xy 162.318922 -312.326201) (xy 162.276301 -312.301594)
			(xy 162.23818 -312.270469) (xy 162.205545 -312.233632) (xy 162.179242 -312.192036) (xy 162.159951 -312.14676)
			(xy 162.148174 -312.098976) (xy 162.144214 -312.049922) (xy 161.805366 -312.049922) (xy 161.804871 -312.074529)
			(xy 161.796976 -312.123106) (xy 161.781392 -312.169787) (xy 161.758521 -312.213364) (xy 161.728956 -312.252708)
			(xy 161.693463 -312.2868) (xy 161.65296 -312.314756) (xy 161.608498 -312.335854) (xy 161.561227 -312.349546)
			(xy 161.512372 -312.355478) (xy 161.463197 -312.353497) (xy 161.414978 -312.343653) (xy 161.368962 -312.326201)
			(xy 161.326341 -312.301594) (xy 161.28822 -312.270469) (xy 161.255585 -312.233632) (xy 161.229282 -312.192036)
			(xy 161.209991 -312.14676) (xy 161.198214 -312.098976) (xy 161.194254 -312.049922) (xy 160.855152 -312.049922)
			(xy 160.854657 -312.074529) (xy 160.846762 -312.123106) (xy 160.831178 -312.169787) (xy 160.808307 -312.213364)
			(xy 160.778742 -312.252708) (xy 160.743249 -312.2868) (xy 160.702746 -312.314756) (xy 160.658284 -312.335854)
			(xy 160.611013 -312.349546) (xy 160.562158 -312.355478) (xy 160.512983 -312.353497) (xy 160.464764 -312.343653)
			(xy 160.418748 -312.326201) (xy 160.376127 -312.301594) (xy 160.338006 -312.270469) (xy 160.305371 -312.233632)
			(xy 160.279068 -312.192036) (xy 160.259777 -312.14676) (xy 160.248 -312.098976) (xy 160.24404 -312.049922)
			(xy 159.905192 -312.049922) (xy 159.904697 -312.074529) (xy 159.896802 -312.123106) (xy 159.881218 -312.169787)
			(xy 159.858347 -312.213364) (xy 159.828782 -312.252708) (xy 159.793289 -312.2868) (xy 159.752786 -312.314756)
			(xy 159.708324 -312.335854) (xy 159.661053 -312.349546) (xy 159.612198 -312.355478) (xy 159.563023 -312.353497)
			(xy 159.514804 -312.343653) (xy 159.468788 -312.326201) (xy 159.426167 -312.301594) (xy 159.388046 -312.270469)
			(xy 159.355411 -312.233632) (xy 159.329108 -312.192036) (xy 159.309817 -312.14676) (xy 159.29804 -312.098976)
			(xy 159.29408 -312.049922) (xy 158.955232 -312.049922) (xy 158.954737 -312.074529) (xy 158.946842 -312.123106)
			(xy 158.931258 -312.169787) (xy 158.908387 -312.213364) (xy 158.878822 -312.252708) (xy 158.843329 -312.2868)
			(xy 158.802826 -312.314756) (xy 158.758364 -312.335854) (xy 158.711093 -312.349546) (xy 158.662238 -312.355478)
			(xy 158.613063 -312.353497) (xy 158.564844 -312.343653) (xy 158.518828 -312.326201) (xy 158.476207 -312.301594)
			(xy 158.438086 -312.270469) (xy 158.405451 -312.233632) (xy 158.379148 -312.192036) (xy 158.359857 -312.14676)
			(xy 158.34808 -312.098976) (xy 158.34412 -312.049922) (xy 158.005272 -312.049922) (xy 158.004777 -312.074529)
			(xy 157.996882 -312.123106) (xy 157.981298 -312.169787) (xy 157.958427 -312.213364) (xy 157.928862 -312.252708)
			(xy 157.893369 -312.2868) (xy 157.852866 -312.314756) (xy 157.808404 -312.335854) (xy 157.761133 -312.349546)
			(xy 157.712278 -312.355478) (xy 157.663103 -312.353497) (xy 157.614884 -312.343653) (xy 157.568868 -312.326201)
			(xy 157.526247 -312.301594) (xy 157.488126 -312.270469) (xy 157.455491 -312.233632) (xy 157.429188 -312.192036)
			(xy 157.409897 -312.14676) (xy 157.39812 -312.098976) (xy 157.39416 -312.049922) (xy 157.055312 -312.049922)
			(xy 157.054817 -312.074529) (xy 157.046922 -312.123106) (xy 157.031338 -312.169787) (xy 157.008467 -312.213364)
			(xy 156.978902 -312.252708) (xy 156.943409 -312.2868) (xy 156.902906 -312.314756) (xy 156.858444 -312.335854)
			(xy 156.811173 -312.349546) (xy 156.762318 -312.355478) (xy 156.713143 -312.353497) (xy 156.664924 -312.343653)
			(xy 156.618908 -312.326201) (xy 156.576287 -312.301594) (xy 156.538166 -312.270469) (xy 156.505531 -312.233632)
			(xy 156.479228 -312.192036) (xy 156.459937 -312.14676) (xy 156.44816 -312.098976) (xy 156.4442 -312.049922)
			(xy 156.105352 -312.049922) (xy 156.104857 -312.074529) (xy 156.096962 -312.123106) (xy 156.081378 -312.169787)
			(xy 156.058507 -312.213364) (xy 156.028942 -312.252708) (xy 155.993449 -312.2868) (xy 155.952946 -312.314756)
			(xy 155.908484 -312.335854) (xy 155.861213 -312.349546) (xy 155.812358 -312.355478) (xy 155.763183 -312.353497)
			(xy 155.714964 -312.343653) (xy 155.668948 -312.326201) (xy 155.626327 -312.301594) (xy 155.588206 -312.270469)
			(xy 155.555571 -312.233632) (xy 155.529268 -312.192036) (xy 155.509977 -312.14676) (xy 155.4982 -312.098976)
			(xy 155.49424 -312.049922) (xy 155.155392 -312.049922) (xy 155.154897 -312.074529) (xy 155.147002 -312.123106)
			(xy 155.131418 -312.169787) (xy 155.108547 -312.213364) (xy 155.078982 -312.252708) (xy 155.043489 -312.2868)
			(xy 155.002986 -312.314756) (xy 154.958524 -312.335854) (xy 154.911253 -312.349546) (xy 154.862398 -312.355478)
			(xy 154.813223 -312.353497) (xy 154.765004 -312.343653) (xy 154.718988 -312.326201) (xy 154.676367 -312.301594)
			(xy 154.638246 -312.270469) (xy 154.605611 -312.233632) (xy 154.579308 -312.192036) (xy 154.560017 -312.14676)
			(xy 154.54824 -312.098976) (xy 154.54428 -312.049922) (xy 154.205178 -312.049922) (xy 154.204683 -312.074529)
			(xy 154.196788 -312.123106) (xy 154.181204 -312.169787) (xy 154.158333 -312.213364) (xy 154.128768 -312.252708)
			(xy 154.093275 -312.2868) (xy 154.052772 -312.314756) (xy 154.00831 -312.335854) (xy 153.961039 -312.349546)
			(xy 153.912184 -312.355478) (xy 153.863009 -312.353497) (xy 153.81479 -312.343653) (xy 153.768774 -312.326201)
			(xy 153.726153 -312.301594) (xy 153.688032 -312.270469) (xy 153.655397 -312.233632) (xy 153.629094 -312.192036)
			(xy 153.609803 -312.14676) (xy 153.598026 -312.098976) (xy 153.594066 -312.049922) (xy 153.255218 -312.049922)
			(xy 153.254723 -312.074529) (xy 153.246828 -312.123106) (xy 153.231244 -312.169787) (xy 153.208373 -312.213364)
			(xy 153.178808 -312.252708) (xy 153.143315 -312.2868) (xy 153.102812 -312.314756) (xy 153.05835 -312.335854)
			(xy 153.011079 -312.349546) (xy 152.962224 -312.355478) (xy 152.913049 -312.353497) (xy 152.86483 -312.343653)
			(xy 152.818814 -312.326201) (xy 152.776193 -312.301594) (xy 152.738072 -312.270469) (xy 152.705437 -312.233632)
			(xy 152.679134 -312.192036) (xy 152.659843 -312.14676) (xy 152.648066 -312.098976) (xy 152.644106 -312.049922)
			(xy 152.304999 -312.049922) (xy 152.304509 -312.074275) (xy 152.296614 -312.122852) (xy 152.28103 -312.169533)
			(xy 152.258159 -312.21311) (xy 152.228594 -312.252454) (xy 152.193101 -312.286546) (xy 152.152598 -312.314502)
			(xy 152.108136 -312.3356) (xy 152.060865 -312.349292) (xy 152.01201 -312.355224) (xy 151.962835 -312.353243)
			(xy 151.914616 -312.343399) (xy 151.8686 -312.325947) (xy 151.825979 -312.30134) (xy 151.787858 -312.270215)
			(xy 151.755223 -312.233378) (xy 151.72892 -312.191782) (xy 151.709629 -312.146506) (xy 151.697852 -312.098722)
			(xy 151.693892 -312.049668) (xy 150.905106 -312.049668) (xy 150.925929 -312.081142) (xy 150.949601 -312.131639)
			(xy 150.965669 -312.185046) (xy 150.973789 -312.240222) (xy 150.974298 -312.268108) (xy 150.973789 -312.295994)
			(xy 150.965669 -312.35117) (xy 150.949601 -312.404577) (xy 150.925929 -312.455074) (xy 150.895156 -312.501587)
			(xy 150.857939 -312.543124) (xy 150.815071 -312.578799) (xy 150.767465 -312.607853) (xy 150.716136 -312.629665)
			(xy 150.662179 -312.643771) (xy 150.606742 -312.649871) (xy 150.551008 -312.647834) (xy 150.496165 -312.637704)
			(xy 150.443381 -312.619697) (xy 150.393781 -312.594196) (xy 150.348423 -312.561745) (xy 150.308274 -312.523036)
			(xy 150.274188 -312.478893) (xy 150.246892 -312.430258) (xy 150.226969 -312.378167) (xy 150.214843 -312.32373)
			(xy 150.210772 -312.268108) (xy 148.496921 -312.268108) (xy 148.516446 -312.289899) (xy 148.547219 -312.336412)
			(xy 148.570891 -312.386909) (xy 148.586959 -312.440316) (xy 148.595079 -312.495492) (xy 148.595588 -312.523378)
			(xy 148.595079 -312.551264) (xy 148.586959 -312.60644) (xy 148.570891 -312.659847) (xy 148.547219 -312.710344)
			(xy 148.516446 -312.756857) (xy 148.479229 -312.798394) (xy 148.436361 -312.834069) (xy 148.388755 -312.863123)
			(xy 148.337426 -312.884935) (xy 148.283469 -312.899041) (xy 148.228032 -312.905141) (xy 148.172298 -312.903104)
			(xy 148.117455 -312.892974) (xy 148.064671 -312.874967) (xy 148.015071 -312.849466) (xy 147.969713 -312.817015)
			(xy 147.929564 -312.778306) (xy 147.895478 -312.734163) (xy 147.868182 -312.685528) (xy 147.848259 -312.633437)
			(xy 147.836133 -312.579) (xy 147.832062 -312.523378) (xy 132.091889 -312.523378) (xy 132.087627 -312.552338)
			(xy 132.071559 -312.605745) (xy 132.047887 -312.656242) (xy 132.017114 -312.702755) (xy 131.979897 -312.744292)
			(xy 131.937029 -312.779967) (xy 131.889423 -312.809021) (xy 131.838094 -312.830833) (xy 131.784137 -312.844939)
			(xy 131.7287 -312.851039) (xy 131.672966 -312.849002) (xy 131.618123 -312.838872) (xy 131.565339 -312.820865)
			(xy 131.515739 -312.795364) (xy 131.470381 -312.762913) (xy 131.430232 -312.724204) (xy 131.396146 -312.680061)
			(xy 131.36885 -312.631426) (xy 131.348927 -312.579335) (xy 131.336801 -312.524898) (xy 131.33273 -312.469276)
			(xy 131.080256 -312.469276) (xy 131.079747 -312.497162) (xy 131.071627 -312.552338) (xy 131.055559 -312.605745)
			(xy 131.031887 -312.656242) (xy 131.001114 -312.702755) (xy 130.963897 -312.744292) (xy 130.921029 -312.779967)
			(xy 130.873423 -312.809021) (xy 130.822094 -312.830833) (xy 130.768137 -312.844939) (xy 130.7127 -312.851039)
			(xy 130.656966 -312.849002) (xy 130.602123 -312.838872) (xy 130.549339 -312.820865) (xy 130.499739 -312.795364)
			(xy 130.454381 -312.762913) (xy 130.414232 -312.724204) (xy 130.380146 -312.680061) (xy 130.35285 -312.631426)
			(xy 130.332927 -312.579335) (xy 130.320801 -312.524898) (xy 130.31673 -312.469276) (xy 130.064256 -312.469276)
			(xy 130.063747 -312.497162) (xy 130.055627 -312.552338) (xy 130.039559 -312.605745) (xy 130.015887 -312.656242)
			(xy 129.985114 -312.702755) (xy 129.947897 -312.744292) (xy 129.905029 -312.779967) (xy 129.857423 -312.809021)
			(xy 129.806094 -312.830833) (xy 129.752137 -312.844939) (xy 129.6967 -312.851039) (xy 129.640966 -312.849002)
			(xy 129.586123 -312.838872) (xy 129.533339 -312.820865) (xy 129.483739 -312.795364) (xy 129.438381 -312.762913)
			(xy 129.398232 -312.724204) (xy 129.364146 -312.680061) (xy 129.33685 -312.631426) (xy 129.316927 -312.579335)
			(xy 129.304801 -312.524898) (xy 129.30073 -312.469276) (xy 129.048256 -312.469276) (xy 129.047747 -312.497162)
			(xy 129.039627 -312.552338) (xy 129.023559 -312.605745) (xy 128.999887 -312.656242) (xy 128.969114 -312.702755)
			(xy 128.931897 -312.744292) (xy 128.889029 -312.779967) (xy 128.841423 -312.809021) (xy 128.790094 -312.830833)
			(xy 128.736137 -312.844939) (xy 128.6807 -312.851039) (xy 128.624966 -312.849002) (xy 128.570123 -312.838872)
			(xy 128.517339 -312.820865) (xy 128.467739 -312.795364) (xy 128.422381 -312.762913) (xy 128.382232 -312.724204)
			(xy 128.348146 -312.680061) (xy 128.32085 -312.631426) (xy 128.300927 -312.579335) (xy 128.288801 -312.524898)
			(xy 128.28473 -312.469276) (xy 128.032256 -312.469276) (xy 128.031747 -312.497162) (xy 128.023627 -312.552338)
			(xy 128.007559 -312.605745) (xy 127.983887 -312.656242) (xy 127.953114 -312.702755) (xy 127.915897 -312.744292)
			(xy 127.873029 -312.779967) (xy 127.825423 -312.809021) (xy 127.774094 -312.830833) (xy 127.720137 -312.844939)
			(xy 127.6647 -312.851039) (xy 127.608966 -312.849002) (xy 127.554123 -312.838872) (xy 127.501339 -312.820865)
			(xy 127.451739 -312.795364) (xy 127.406381 -312.762913) (xy 127.366232 -312.724204) (xy 127.332146 -312.680061)
			(xy 127.30485 -312.631426) (xy 127.284927 -312.579335) (xy 127.272801 -312.524898) (xy 127.26873 -312.469276)
			(xy 127.016256 -312.469276) (xy 127.015747 -312.497162) (xy 127.007627 -312.552338) (xy 126.991559 -312.605745)
			(xy 126.967887 -312.656242) (xy 126.937114 -312.702755) (xy 126.899897 -312.744292) (xy 126.857029 -312.779967)
			(xy 126.809423 -312.809021) (xy 126.758094 -312.830833) (xy 126.704137 -312.844939) (xy 126.6487 -312.851039)
			(xy 126.592966 -312.849002) (xy 126.538123 -312.838872) (xy 126.485339 -312.820865) (xy 126.435739 -312.795364)
			(xy 126.390381 -312.762913) (xy 126.350232 -312.724204) (xy 126.316146 -312.680061) (xy 126.28885 -312.631426)
			(xy 126.268927 -312.579335) (xy 126.256801 -312.524898) (xy 126.25273 -312.469276) (xy 126.000256 -312.469276)
			(xy 125.999747 -312.497162) (xy 125.991627 -312.552338) (xy 125.975559 -312.605745) (xy 125.951887 -312.656242)
			(xy 125.921114 -312.702755) (xy 125.883897 -312.744292) (xy 125.841029 -312.779967) (xy 125.793423 -312.809021)
			(xy 125.742094 -312.830833) (xy 125.688137 -312.844939) (xy 125.6327 -312.851039) (xy 125.576966 -312.849002)
			(xy 125.522123 -312.838872) (xy 125.469339 -312.820865) (xy 125.419739 -312.795364) (xy 125.374381 -312.762913)
			(xy 125.334232 -312.724204) (xy 125.300146 -312.680061) (xy 125.27285 -312.631426) (xy 125.252927 -312.579335)
			(xy 125.240801 -312.524898) (xy 125.23673 -312.469276) (xy 119.631206 -312.469276) (xy 119.631206 -312.999882)
			(xy 152.644106 -312.999882) (xy 152.648066 -312.950828) (xy 152.659843 -312.903044) (xy 152.679134 -312.857768)
			(xy 152.705437 -312.816172) (xy 152.738072 -312.779335) (xy 152.776193 -312.74821) (xy 152.818814 -312.723603)
			(xy 152.86483 -312.706151) (xy 152.913049 -312.696307) (xy 152.962224 -312.694326) (xy 153.011079 -312.700258)
			(xy 153.05835 -312.71395) (xy 153.102812 -312.735048) (xy 153.143315 -312.763004) (xy 153.178808 -312.797096)
			(xy 153.208373 -312.83644) (xy 153.231244 -312.880017) (xy 153.246828 -312.926698) (xy 153.254723 -312.975275)
			(xy 153.255218 -312.999882) (xy 153.594066 -312.999882) (xy 153.598026 -312.950828) (xy 153.609803 -312.903044)
			(xy 153.629094 -312.857768) (xy 153.655397 -312.816172) (xy 153.688032 -312.779335) (xy 153.726153 -312.74821)
			(xy 153.768774 -312.723603) (xy 153.81479 -312.706151) (xy 153.863009 -312.696307) (xy 153.912184 -312.694326)
			(xy 153.961039 -312.700258) (xy 154.00831 -312.71395) (xy 154.052772 -312.735048) (xy 154.093275 -312.763004)
			(xy 154.128768 -312.797096) (xy 154.158333 -312.83644) (xy 154.181204 -312.880017) (xy 154.196788 -312.926698)
			(xy 154.204683 -312.975275) (xy 154.205178 -312.999882) (xy 154.54428 -312.999882) (xy 154.54824 -312.950828)
			(xy 154.560017 -312.903044) (xy 154.579308 -312.857768) (xy 154.605611 -312.816172) (xy 154.638246 -312.779335)
			(xy 154.676367 -312.74821) (xy 154.718988 -312.723603) (xy 154.765004 -312.706151) (xy 154.813223 -312.696307)
			(xy 154.862398 -312.694326) (xy 154.911253 -312.700258) (xy 154.958524 -312.71395) (xy 155.002986 -312.735048)
			(xy 155.043489 -312.763004) (xy 155.078982 -312.797096) (xy 155.108547 -312.83644) (xy 155.131418 -312.880017)
			(xy 155.147002 -312.926698) (xy 155.154897 -312.975275) (xy 155.155392 -312.999882) (xy 155.49424 -312.999882)
			(xy 155.4982 -312.950828) (xy 155.509977 -312.903044) (xy 155.529268 -312.857768) (xy 155.555571 -312.816172)
			(xy 155.588206 -312.779335) (xy 155.626327 -312.74821) (xy 155.668948 -312.723603) (xy 155.714964 -312.706151)
			(xy 155.763183 -312.696307) (xy 155.812358 -312.694326) (xy 155.861213 -312.700258) (xy 155.908484 -312.71395)
			(xy 155.952946 -312.735048) (xy 155.993449 -312.763004) (xy 156.028942 -312.797096) (xy 156.058507 -312.83644)
			(xy 156.081378 -312.880017) (xy 156.096962 -312.926698) (xy 156.104857 -312.975275) (xy 156.105352 -312.999882)
			(xy 156.4442 -312.999882) (xy 156.44816 -312.950828) (xy 156.459937 -312.903044) (xy 156.479228 -312.857768)
			(xy 156.505531 -312.816172) (xy 156.538166 -312.779335) (xy 156.576287 -312.74821) (xy 156.618908 -312.723603)
			(xy 156.664924 -312.706151) (xy 156.713143 -312.696307) (xy 156.762318 -312.694326) (xy 156.811173 -312.700258)
			(xy 156.858444 -312.71395) (xy 156.902906 -312.735048) (xy 156.943409 -312.763004) (xy 156.978902 -312.797096)
			(xy 157.008467 -312.83644) (xy 157.031338 -312.880017) (xy 157.046922 -312.926698) (xy 157.054817 -312.975275)
			(xy 157.055312 -312.999882) (xy 157.39416 -312.999882) (xy 157.39812 -312.950828) (xy 157.409897 -312.903044)
			(xy 157.429188 -312.857768) (xy 157.455491 -312.816172) (xy 157.488126 -312.779335) (xy 157.526247 -312.74821)
			(xy 157.568868 -312.723603) (xy 157.614884 -312.706151) (xy 157.663103 -312.696307) (xy 157.712278 -312.694326)
			(xy 157.761133 -312.700258) (xy 157.808404 -312.71395) (xy 157.852866 -312.735048) (xy 157.893369 -312.763004)
			(xy 157.928862 -312.797096) (xy 157.958427 -312.83644) (xy 157.981298 -312.880017) (xy 157.996882 -312.926698)
			(xy 158.004777 -312.975275) (xy 158.005272 -312.999882) (xy 158.34412 -312.999882) (xy 158.34808 -312.950828)
			(xy 158.359857 -312.903044) (xy 158.379148 -312.857768) (xy 158.405451 -312.816172) (xy 158.438086 -312.779335)
			(xy 158.476207 -312.74821) (xy 158.518828 -312.723603) (xy 158.564844 -312.706151) (xy 158.613063 -312.696307)
			(xy 158.662238 -312.694326) (xy 158.711093 -312.700258) (xy 158.758364 -312.71395) (xy 158.802826 -312.735048)
			(xy 158.843329 -312.763004) (xy 158.878822 -312.797096) (xy 158.908387 -312.83644) (xy 158.931258 -312.880017)
			(xy 158.946842 -312.926698) (xy 158.954737 -312.975275) (xy 158.955232 -312.999882) (xy 159.29408 -312.999882)
			(xy 159.29804 -312.950828) (xy 159.309817 -312.903044) (xy 159.329108 -312.857768) (xy 159.355411 -312.816172)
			(xy 159.388046 -312.779335) (xy 159.426167 -312.74821) (xy 159.468788 -312.723603) (xy 159.514804 -312.706151)
			(xy 159.563023 -312.696307) (xy 159.612198 -312.694326) (xy 159.661053 -312.700258) (xy 159.708324 -312.71395)
			(xy 159.752786 -312.735048) (xy 159.793289 -312.763004) (xy 159.828782 -312.797096) (xy 159.858347 -312.83644)
			(xy 159.881218 -312.880017) (xy 159.896802 -312.926698) (xy 159.904697 -312.975275) (xy 159.905192 -312.999882)
			(xy 160.24404 -312.999882) (xy 160.248 -312.950828) (xy 160.259777 -312.903044) (xy 160.279068 -312.857768)
			(xy 160.305371 -312.816172) (xy 160.338006 -312.779335) (xy 160.376127 -312.74821) (xy 160.418748 -312.723603)
			(xy 160.464764 -312.706151) (xy 160.512983 -312.696307) (xy 160.562158 -312.694326) (xy 160.611013 -312.700258)
			(xy 160.658284 -312.71395) (xy 160.702746 -312.735048) (xy 160.743249 -312.763004) (xy 160.778742 -312.797096)
			(xy 160.808307 -312.83644) (xy 160.831178 -312.880017) (xy 160.846762 -312.926698) (xy 160.854657 -312.975275)
			(xy 160.855152 -312.999882) (xy 161.194254 -312.999882) (xy 161.198214 -312.950828) (xy 161.209991 -312.903044)
			(xy 161.229282 -312.857768) (xy 161.255585 -312.816172) (xy 161.28822 -312.779335) (xy 161.326341 -312.74821)
			(xy 161.368962 -312.723603) (xy 161.414978 -312.706151) (xy 161.463197 -312.696307) (xy 161.512372 -312.694326)
			(xy 161.561227 -312.700258) (xy 161.608498 -312.71395) (xy 161.65296 -312.735048) (xy 161.693463 -312.763004)
			(xy 161.728956 -312.797096) (xy 161.758521 -312.83644) (xy 161.781392 -312.880017) (xy 161.796976 -312.926698)
			(xy 161.804871 -312.975275) (xy 161.805366 -312.999882) (xy 162.144214 -312.999882) (xy 162.148174 -312.950828)
			(xy 162.159951 -312.903044) (xy 162.179242 -312.857768) (xy 162.205545 -312.816172) (xy 162.23818 -312.779335)
			(xy 162.276301 -312.74821) (xy 162.318922 -312.723603) (xy 162.364938 -312.706151) (xy 162.413157 -312.696307)
			(xy 162.462332 -312.694326) (xy 162.511187 -312.700258) (xy 162.558458 -312.71395) (xy 162.60292 -312.735048)
			(xy 162.643423 -312.763004) (xy 162.678916 -312.797096) (xy 162.708481 -312.83644) (xy 162.731352 -312.880017)
			(xy 162.746936 -312.926698) (xy 162.754831 -312.975275) (xy 162.755326 -312.999882) (xy 162.754831 -313.024489)
			(xy 162.746936 -313.073066) (xy 162.731352 -313.119747) (xy 162.708481 -313.163324) (xy 162.678916 -313.202668)
			(xy 162.643423 -313.23676) (xy 162.60292 -313.264716) (xy 162.558458 -313.285814) (xy 162.511187 -313.299506)
			(xy 162.462332 -313.305438) (xy 162.413157 -313.303457) (xy 162.364938 -313.293613) (xy 162.318922 -313.276161)
			(xy 162.276301 -313.251554) (xy 162.23818 -313.220429) (xy 162.205545 -313.183592) (xy 162.179242 -313.141996)
			(xy 162.159951 -313.09672) (xy 162.148174 -313.048936) (xy 162.144214 -312.999882) (xy 161.805366 -312.999882)
			(xy 161.804871 -313.024489) (xy 161.796976 -313.073066) (xy 161.781392 -313.119747) (xy 161.758521 -313.163324)
			(xy 161.728956 -313.202668) (xy 161.693463 -313.23676) (xy 161.65296 -313.264716) (xy 161.608498 -313.285814)
			(xy 161.561227 -313.299506) (xy 161.512372 -313.305438) (xy 161.463197 -313.303457) (xy 161.414978 -313.293613)
			(xy 161.368962 -313.276161) (xy 161.326341 -313.251554) (xy 161.28822 -313.220429) (xy 161.255585 -313.183592)
			(xy 161.229282 -313.141996) (xy 161.209991 -313.09672) (xy 161.198214 -313.048936) (xy 161.194254 -312.999882)
			(xy 160.855152 -312.999882) (xy 160.854657 -313.024489) (xy 160.846762 -313.073066) (xy 160.831178 -313.119747)
			(xy 160.808307 -313.163324) (xy 160.778742 -313.202668) (xy 160.743249 -313.23676) (xy 160.702746 -313.264716)
			(xy 160.658284 -313.285814) (xy 160.611013 -313.299506) (xy 160.562158 -313.305438) (xy 160.512983 -313.303457)
			(xy 160.464764 -313.293613) (xy 160.418748 -313.276161) (xy 160.376127 -313.251554) (xy 160.338006 -313.220429)
			(xy 160.305371 -313.183592) (xy 160.279068 -313.141996) (xy 160.259777 -313.09672) (xy 160.248 -313.048936)
			(xy 160.24404 -312.999882) (xy 159.905192 -312.999882) (xy 159.904697 -313.024489) (xy 159.896802 -313.073066)
			(xy 159.881218 -313.119747) (xy 159.858347 -313.163324) (xy 159.828782 -313.202668) (xy 159.793289 -313.23676)
			(xy 159.752786 -313.264716) (xy 159.708324 -313.285814) (xy 159.661053 -313.299506) (xy 159.612198 -313.305438)
			(xy 159.563023 -313.303457) (xy 159.514804 -313.293613) (xy 159.468788 -313.276161) (xy 159.426167 -313.251554)
			(xy 159.388046 -313.220429) (xy 159.355411 -313.183592) (xy 159.329108 -313.141996) (xy 159.309817 -313.09672)
			(xy 159.29804 -313.048936) (xy 159.29408 -312.999882) (xy 158.955232 -312.999882) (xy 158.954737 -313.024489)
			(xy 158.946842 -313.073066) (xy 158.931258 -313.119747) (xy 158.908387 -313.163324) (xy 158.878822 -313.202668)
			(xy 158.843329 -313.23676) (xy 158.802826 -313.264716) (xy 158.758364 -313.285814) (xy 158.711093 -313.299506)
			(xy 158.662238 -313.305438) (xy 158.613063 -313.303457) (xy 158.564844 -313.293613) (xy 158.518828 -313.276161)
			(xy 158.476207 -313.251554) (xy 158.438086 -313.220429) (xy 158.405451 -313.183592) (xy 158.379148 -313.141996)
			(xy 158.359857 -313.09672) (xy 158.34808 -313.048936) (xy 158.34412 -312.999882) (xy 158.005272 -312.999882)
			(xy 158.004777 -313.024489) (xy 157.996882 -313.073066) (xy 157.981298 -313.119747) (xy 157.958427 -313.163324)
			(xy 157.928862 -313.202668) (xy 157.893369 -313.23676) (xy 157.852866 -313.264716) (xy 157.808404 -313.285814)
			(xy 157.761133 -313.299506) (xy 157.712278 -313.305438) (xy 157.663103 -313.303457) (xy 157.614884 -313.293613)
			(xy 157.568868 -313.276161) (xy 157.526247 -313.251554) (xy 157.488126 -313.220429) (xy 157.455491 -313.183592)
			(xy 157.429188 -313.141996) (xy 157.409897 -313.09672) (xy 157.39812 -313.048936) (xy 157.39416 -312.999882)
			(xy 157.055312 -312.999882) (xy 157.054817 -313.024489) (xy 157.046922 -313.073066) (xy 157.031338 -313.119747)
			(xy 157.008467 -313.163324) (xy 156.978902 -313.202668) (xy 156.943409 -313.23676) (xy 156.902906 -313.264716)
			(xy 156.858444 -313.285814) (xy 156.811173 -313.299506) (xy 156.762318 -313.305438) (xy 156.713143 -313.303457)
			(xy 156.664924 -313.293613) (xy 156.618908 -313.276161) (xy 156.576287 -313.251554) (xy 156.538166 -313.220429)
			(xy 156.505531 -313.183592) (xy 156.479228 -313.141996) (xy 156.459937 -313.09672) (xy 156.44816 -313.048936)
			(xy 156.4442 -312.999882) (xy 156.105352 -312.999882) (xy 156.104857 -313.024489) (xy 156.096962 -313.073066)
			(xy 156.081378 -313.119747) (xy 156.058507 -313.163324) (xy 156.028942 -313.202668) (xy 155.993449 -313.23676)
			(xy 155.952946 -313.264716) (xy 155.908484 -313.285814) (xy 155.861213 -313.299506) (xy 155.812358 -313.305438)
			(xy 155.763183 -313.303457) (xy 155.714964 -313.293613) (xy 155.668948 -313.276161) (xy 155.626327 -313.251554)
			(xy 155.588206 -313.220429) (xy 155.555571 -313.183592) (xy 155.529268 -313.141996) (xy 155.509977 -313.09672)
			(xy 155.4982 -313.048936) (xy 155.49424 -312.999882) (xy 155.155392 -312.999882) (xy 155.154897 -313.024489)
			(xy 155.147002 -313.073066) (xy 155.131418 -313.119747) (xy 155.108547 -313.163324) (xy 155.078982 -313.202668)
			(xy 155.043489 -313.23676) (xy 155.002986 -313.264716) (xy 154.958524 -313.285814) (xy 154.911253 -313.299506)
			(xy 154.862398 -313.305438) (xy 154.813223 -313.303457) (xy 154.765004 -313.293613) (xy 154.718988 -313.276161)
			(xy 154.676367 -313.251554) (xy 154.638246 -313.220429) (xy 154.605611 -313.183592) (xy 154.579308 -313.141996)
			(xy 154.560017 -313.09672) (xy 154.54824 -313.048936) (xy 154.54428 -312.999882) (xy 154.205178 -312.999882)
			(xy 154.204683 -313.024489) (xy 154.196788 -313.073066) (xy 154.181204 -313.119747) (xy 154.158333 -313.163324)
			(xy 154.128768 -313.202668) (xy 154.093275 -313.23676) (xy 154.052772 -313.264716) (xy 154.00831 -313.285814)
			(xy 153.961039 -313.299506) (xy 153.912184 -313.305438) (xy 153.863009 -313.303457) (xy 153.81479 -313.293613)
			(xy 153.768774 -313.276161) (xy 153.726153 -313.251554) (xy 153.688032 -313.220429) (xy 153.655397 -313.183592)
			(xy 153.629094 -313.141996) (xy 153.609803 -313.09672) (xy 153.598026 -313.048936) (xy 153.594066 -312.999882)
			(xy 153.255218 -312.999882) (xy 153.254723 -313.024489) (xy 153.246828 -313.073066) (xy 153.231244 -313.119747)
			(xy 153.208373 -313.163324) (xy 153.178808 -313.202668) (xy 153.143315 -313.23676) (xy 153.102812 -313.264716)
			(xy 153.05835 -313.285814) (xy 153.011079 -313.299506) (xy 152.962224 -313.305438) (xy 152.913049 -313.303457)
			(xy 152.86483 -313.293613) (xy 152.818814 -313.276161) (xy 152.776193 -313.251554) (xy 152.738072 -313.220429)
			(xy 152.705437 -313.183592) (xy 152.679134 -313.141996) (xy 152.659843 -313.09672) (xy 152.648066 -313.048936)
			(xy 152.644106 -312.999882) (xy 119.631206 -312.999882) (xy 119.631206 -313.485276) (xy 125.23673 -313.485276)
			(xy 125.240801 -313.429654) (xy 125.252927 -313.375217) (xy 125.27285 -313.323126) (xy 125.300146 -313.274491)
			(xy 125.334232 -313.230348) (xy 125.374381 -313.191639) (xy 125.419739 -313.159188) (xy 125.469339 -313.133687)
			(xy 125.522123 -313.11568) (xy 125.576966 -313.10555) (xy 125.6327 -313.103513) (xy 125.688137 -313.109613)
			(xy 125.742094 -313.123719) (xy 125.793423 -313.145531) (xy 125.841029 -313.174585) (xy 125.883897 -313.21026)
			(xy 125.921114 -313.251797) (xy 125.951887 -313.29831) (xy 125.975559 -313.348807) (xy 125.991627 -313.402214)
			(xy 125.999747 -313.45739) (xy 126.000256 -313.485276) (xy 126.25273 -313.485276) (xy 126.256801 -313.429654)
			(xy 126.268927 -313.375217) (xy 126.28885 -313.323126) (xy 126.316146 -313.274491) (xy 126.350232 -313.230348)
			(xy 126.390381 -313.191639) (xy 126.435739 -313.159188) (xy 126.485339 -313.133687) (xy 126.538123 -313.11568)
			(xy 126.592966 -313.10555) (xy 126.6487 -313.103513) (xy 126.704137 -313.109613) (xy 126.758094 -313.123719)
			(xy 126.809423 -313.145531) (xy 126.857029 -313.174585) (xy 126.899897 -313.21026) (xy 126.937114 -313.251797)
			(xy 126.967887 -313.29831) (xy 126.991559 -313.348807) (xy 127.007627 -313.402214) (xy 127.015747 -313.45739)
			(xy 127.016256 -313.485276) (xy 127.26873 -313.485276) (xy 127.272801 -313.429654) (xy 127.284927 -313.375217)
			(xy 127.30485 -313.323126) (xy 127.332146 -313.274491) (xy 127.366232 -313.230348) (xy 127.406381 -313.191639)
			(xy 127.451739 -313.159188) (xy 127.501339 -313.133687) (xy 127.554123 -313.11568) (xy 127.608966 -313.10555)
			(xy 127.6647 -313.103513) (xy 127.720137 -313.109613) (xy 127.774094 -313.123719) (xy 127.825423 -313.145531)
			(xy 127.873029 -313.174585) (xy 127.915897 -313.21026) (xy 127.953114 -313.251797) (xy 127.983887 -313.29831)
			(xy 128.007559 -313.348807) (xy 128.023627 -313.402214) (xy 128.031747 -313.45739) (xy 128.032256 -313.485276)
			(xy 128.28473 -313.485276) (xy 128.288801 -313.429654) (xy 128.300927 -313.375217) (xy 128.32085 -313.323126)
			(xy 128.348146 -313.274491) (xy 128.382232 -313.230348) (xy 128.422381 -313.191639) (xy 128.467739 -313.159188)
			(xy 128.517339 -313.133687) (xy 128.570123 -313.11568) (xy 128.624966 -313.10555) (xy 128.6807 -313.103513)
			(xy 128.736137 -313.109613) (xy 128.790094 -313.123719) (xy 128.841423 -313.145531) (xy 128.889029 -313.174585)
			(xy 128.931897 -313.21026) (xy 128.969114 -313.251797) (xy 128.999887 -313.29831) (xy 129.023559 -313.348807)
			(xy 129.039627 -313.402214) (xy 129.047747 -313.45739) (xy 129.048256 -313.485276) (xy 129.30073 -313.485276)
			(xy 129.304801 -313.429654) (xy 129.316927 -313.375217) (xy 129.33685 -313.323126) (xy 129.364146 -313.274491)
			(xy 129.398232 -313.230348) (xy 129.438381 -313.191639) (xy 129.483739 -313.159188) (xy 129.533339 -313.133687)
			(xy 129.586123 -313.11568) (xy 129.640966 -313.10555) (xy 129.6967 -313.103513) (xy 129.752137 -313.109613)
			(xy 129.806094 -313.123719) (xy 129.857423 -313.145531) (xy 129.905029 -313.174585) (xy 129.947897 -313.21026)
			(xy 129.985114 -313.251797) (xy 130.015887 -313.29831) (xy 130.039559 -313.348807) (xy 130.055627 -313.402214)
			(xy 130.063747 -313.45739) (xy 130.064256 -313.485276) (xy 130.31673 -313.485276) (xy 130.320801 -313.429654)
			(xy 130.332927 -313.375217) (xy 130.35285 -313.323126) (xy 130.380146 -313.274491) (xy 130.414232 -313.230348)
			(xy 130.454381 -313.191639) (xy 130.499739 -313.159188) (xy 130.549339 -313.133687) (xy 130.602123 -313.11568)
			(xy 130.656966 -313.10555) (xy 130.7127 -313.103513) (xy 130.768137 -313.109613) (xy 130.822094 -313.123719)
			(xy 130.873423 -313.145531) (xy 130.921029 -313.174585) (xy 130.963897 -313.21026) (xy 131.001114 -313.251797)
			(xy 131.031887 -313.29831) (xy 131.055559 -313.348807) (xy 131.071627 -313.402214) (xy 131.079747 -313.45739)
			(xy 131.080256 -313.485276) (xy 131.33273 -313.485276) (xy 131.336801 -313.429654) (xy 131.348927 -313.375217)
			(xy 131.36885 -313.323126) (xy 131.396146 -313.274491) (xy 131.430232 -313.230348) (xy 131.470381 -313.191639)
			(xy 131.515739 -313.159188) (xy 131.565339 -313.133687) (xy 131.618123 -313.11568) (xy 131.672966 -313.10555)
			(xy 131.7287 -313.103513) (xy 131.784137 -313.109613) (xy 131.838094 -313.123719) (xy 131.889423 -313.145531)
			(xy 131.937029 -313.174585) (xy 131.979897 -313.21026) (xy 132.017114 -313.251797) (xy 132.047887 -313.29831)
			(xy 132.071559 -313.348807) (xy 132.087627 -313.402214) (xy 132.095747 -313.45739) (xy 132.096256 -313.485276)
			(xy 132.095747 -313.513162) (xy 132.087627 -313.568338) (xy 132.071559 -313.621745) (xy 132.048969 -313.669934)
			(xy 150.147018 -313.669934) (xy 150.151089 -313.614312) (xy 150.163215 -313.559875) (xy 150.183138 -313.507784)
			(xy 150.210434 -313.459149) (xy 150.24452 -313.415006) (xy 150.284669 -313.376297) (xy 150.330027 -313.343846)
			(xy 150.379627 -313.318345) (xy 150.432411 -313.300338) (xy 150.487254 -313.290208) (xy 150.542988 -313.288171)
			(xy 150.598425 -313.294271) (xy 150.652382 -313.308377) (xy 150.703711 -313.330189) (xy 150.751317 -313.359243)
			(xy 150.794185 -313.394918) (xy 150.831402 -313.436455) (xy 150.862175 -313.482968) (xy 150.885847 -313.533465)
			(xy 150.901915 -313.586872) (xy 150.910035 -313.642048) (xy 150.910544 -313.669934) (xy 150.910035 -313.69782)
			(xy 150.901915 -313.752996) (xy 150.885847 -313.806403) (xy 150.862175 -313.8569) (xy 150.831402 -313.903413)
			(xy 150.794185 -313.94495) (xy 150.788307 -313.949842) (xy 152.644106 -313.949842) (xy 152.648066 -313.900788)
			(xy 152.659843 -313.853004) (xy 152.679134 -313.807728) (xy 152.705437 -313.766132) (xy 152.738072 -313.729295)
			(xy 152.776193 -313.69817) (xy 152.818814 -313.673563) (xy 152.86483 -313.656111) (xy 152.913049 -313.646267)
			(xy 152.962224 -313.644286) (xy 153.011079 -313.650218) (xy 153.05835 -313.66391) (xy 153.102812 -313.685008)
			(xy 153.143315 -313.712964) (xy 153.178808 -313.747056) (xy 153.208373 -313.7864) (xy 153.231244 -313.829977)
			(xy 153.246828 -313.876658) (xy 153.254723 -313.925235) (xy 153.255218 -313.949842) (xy 153.594066 -313.949842)
			(xy 153.598026 -313.900788) (xy 153.609803 -313.853004) (xy 153.629094 -313.807728) (xy 153.655397 -313.766132)
			(xy 153.688032 -313.729295) (xy 153.726153 -313.69817) (xy 153.768774 -313.673563) (xy 153.81479 -313.656111)
			(xy 153.863009 -313.646267) (xy 153.912184 -313.644286) (xy 153.961039 -313.650218) (xy 154.00831 -313.66391)
			(xy 154.052772 -313.685008) (xy 154.093275 -313.712964) (xy 154.128768 -313.747056) (xy 154.158333 -313.7864)
			(xy 154.181204 -313.829977) (xy 154.196788 -313.876658) (xy 154.204683 -313.925235) (xy 154.205178 -313.949842)
			(xy 154.54428 -313.949842) (xy 154.54824 -313.900788) (xy 154.560017 -313.853004) (xy 154.579308 -313.807728)
			(xy 154.605611 -313.766132) (xy 154.638246 -313.729295) (xy 154.676367 -313.69817) (xy 154.718988 -313.673563)
			(xy 154.765004 -313.656111) (xy 154.813223 -313.646267) (xy 154.862398 -313.644286) (xy 154.911253 -313.650218)
			(xy 154.958524 -313.66391) (xy 155.002986 -313.685008) (xy 155.043489 -313.712964) (xy 155.078982 -313.747056)
			(xy 155.108547 -313.7864) (xy 155.131418 -313.829977) (xy 155.147002 -313.876658) (xy 155.154897 -313.925235)
			(xy 155.155392 -313.949842) (xy 155.49424 -313.949842) (xy 155.4982 -313.900788) (xy 155.509977 -313.853004)
			(xy 155.529268 -313.807728) (xy 155.555571 -313.766132) (xy 155.588206 -313.729295) (xy 155.626327 -313.69817)
			(xy 155.668948 -313.673563) (xy 155.714964 -313.656111) (xy 155.763183 -313.646267) (xy 155.812358 -313.644286)
			(xy 155.861213 -313.650218) (xy 155.908484 -313.66391) (xy 155.952946 -313.685008) (xy 155.993449 -313.712964)
			(xy 156.028942 -313.747056) (xy 156.058507 -313.7864) (xy 156.081378 -313.829977) (xy 156.096962 -313.876658)
			(xy 156.104857 -313.925235) (xy 156.105352 -313.949842) (xy 156.4442 -313.949842) (xy 156.44816 -313.900788)
			(xy 156.459937 -313.853004) (xy 156.479228 -313.807728) (xy 156.505531 -313.766132) (xy 156.538166 -313.729295)
			(xy 156.576287 -313.69817) (xy 156.618908 -313.673563) (xy 156.664924 -313.656111) (xy 156.713143 -313.646267)
			(xy 156.762318 -313.644286) (xy 156.811173 -313.650218) (xy 156.858444 -313.66391) (xy 156.902906 -313.685008)
			(xy 156.943409 -313.712964) (xy 156.978902 -313.747056) (xy 157.008467 -313.7864) (xy 157.031338 -313.829977)
			(xy 157.046922 -313.876658) (xy 157.054817 -313.925235) (xy 157.055312 -313.949842) (xy 157.39416 -313.949842)
			(xy 157.39812 -313.900788) (xy 157.409897 -313.853004) (xy 157.429188 -313.807728) (xy 157.455491 -313.766132)
			(xy 157.488126 -313.729295) (xy 157.526247 -313.69817) (xy 157.568868 -313.673563) (xy 157.614884 -313.656111)
			(xy 157.663103 -313.646267) (xy 157.712278 -313.644286) (xy 157.761133 -313.650218) (xy 157.808404 -313.66391)
			(xy 157.852866 -313.685008) (xy 157.893369 -313.712964) (xy 157.928862 -313.747056) (xy 157.958427 -313.7864)
			(xy 157.981298 -313.829977) (xy 157.996882 -313.876658) (xy 158.004777 -313.925235) (xy 158.005272 -313.949842)
			(xy 158.34412 -313.949842) (xy 158.34808 -313.900788) (xy 158.359857 -313.853004) (xy 158.379148 -313.807728)
			(xy 158.405451 -313.766132) (xy 158.438086 -313.729295) (xy 158.476207 -313.69817) (xy 158.518828 -313.673563)
			(xy 158.564844 -313.656111) (xy 158.613063 -313.646267) (xy 158.662238 -313.644286) (xy 158.711093 -313.650218)
			(xy 158.758364 -313.66391) (xy 158.802826 -313.685008) (xy 158.843329 -313.712964) (xy 158.878822 -313.747056)
			(xy 158.908387 -313.7864) (xy 158.931258 -313.829977) (xy 158.946842 -313.876658) (xy 158.954737 -313.925235)
			(xy 158.955232 -313.949842) (xy 159.29408 -313.949842) (xy 159.29804 -313.900788) (xy 159.309817 -313.853004)
			(xy 159.329108 -313.807728) (xy 159.355411 -313.766132) (xy 159.388046 -313.729295) (xy 159.426167 -313.69817)
			(xy 159.468788 -313.673563) (xy 159.514804 -313.656111) (xy 159.563023 -313.646267) (xy 159.612198 -313.644286)
			(xy 159.661053 -313.650218) (xy 159.708324 -313.66391) (xy 159.752786 -313.685008) (xy 159.793289 -313.712964)
			(xy 159.828782 -313.747056) (xy 159.858347 -313.7864) (xy 159.881218 -313.829977) (xy 159.896802 -313.876658)
			(xy 159.904697 -313.925235) (xy 159.905192 -313.949842) (xy 160.24404 -313.949842) (xy 160.248 -313.900788)
			(xy 160.259777 -313.853004) (xy 160.279068 -313.807728) (xy 160.305371 -313.766132) (xy 160.338006 -313.729295)
			(xy 160.376127 -313.69817) (xy 160.418748 -313.673563) (xy 160.464764 -313.656111) (xy 160.512983 -313.646267)
			(xy 160.562158 -313.644286) (xy 160.611013 -313.650218) (xy 160.658284 -313.66391) (xy 160.702746 -313.685008)
			(xy 160.743249 -313.712964) (xy 160.778742 -313.747056) (xy 160.808307 -313.7864) (xy 160.831178 -313.829977)
			(xy 160.846762 -313.876658) (xy 160.854657 -313.925235) (xy 160.855152 -313.949842) (xy 161.194254 -313.949842)
			(xy 161.198214 -313.900788) (xy 161.209991 -313.853004) (xy 161.229282 -313.807728) (xy 161.255585 -313.766132)
			(xy 161.28822 -313.729295) (xy 161.326341 -313.69817) (xy 161.368962 -313.673563) (xy 161.414978 -313.656111)
			(xy 161.463197 -313.646267) (xy 161.512372 -313.644286) (xy 161.561227 -313.650218) (xy 161.608498 -313.66391)
			(xy 161.65296 -313.685008) (xy 161.693463 -313.712964) (xy 161.728956 -313.747056) (xy 161.758521 -313.7864)
			(xy 161.781392 -313.829977) (xy 161.796976 -313.876658) (xy 161.804871 -313.925235) (xy 161.805366 -313.949842)
			(xy 162.144214 -313.949842) (xy 162.148174 -313.900788) (xy 162.159951 -313.853004) (xy 162.179242 -313.807728)
			(xy 162.205545 -313.766132) (xy 162.23818 -313.729295) (xy 162.276301 -313.69817) (xy 162.318922 -313.673563)
			(xy 162.364938 -313.656111) (xy 162.413157 -313.646267) (xy 162.462332 -313.644286) (xy 162.511187 -313.650218)
			(xy 162.558458 -313.66391) (xy 162.60292 -313.685008) (xy 162.643423 -313.712964) (xy 162.678916 -313.747056)
			(xy 162.708481 -313.7864) (xy 162.731352 -313.829977) (xy 162.746936 -313.876658) (xy 162.754831 -313.925235)
			(xy 162.755326 -313.949842) (xy 162.754831 -313.974449) (xy 162.746936 -314.023026) (xy 162.731352 -314.069707)
			(xy 162.708481 -314.113284) (xy 162.678916 -314.152628) (xy 162.643423 -314.18672) (xy 162.60292 -314.214676)
			(xy 162.558458 -314.235774) (xy 162.511187 -314.249466) (xy 162.462332 -314.255398) (xy 162.413157 -314.253417)
			(xy 162.364938 -314.243573) (xy 162.318922 -314.226121) (xy 162.276301 -314.201514) (xy 162.23818 -314.170389)
			(xy 162.205545 -314.133552) (xy 162.179242 -314.091956) (xy 162.159951 -314.04668) (xy 162.148174 -313.998896)
			(xy 162.144214 -313.949842) (xy 161.805366 -313.949842) (xy 161.804871 -313.974449) (xy 161.796976 -314.023026)
			(xy 161.781392 -314.069707) (xy 161.758521 -314.113284) (xy 161.728956 -314.152628) (xy 161.693463 -314.18672)
			(xy 161.65296 -314.214676) (xy 161.608498 -314.235774) (xy 161.561227 -314.249466) (xy 161.512372 -314.255398)
			(xy 161.463197 -314.253417) (xy 161.414978 -314.243573) (xy 161.368962 -314.226121) (xy 161.326341 -314.201514)
			(xy 161.28822 -314.170389) (xy 161.255585 -314.133552) (xy 161.229282 -314.091956) (xy 161.209991 -314.04668)
			(xy 161.198214 -313.998896) (xy 161.194254 -313.949842) (xy 160.855152 -313.949842) (xy 160.854657 -313.974449)
			(xy 160.846762 -314.023026) (xy 160.831178 -314.069707) (xy 160.808307 -314.113284) (xy 160.778742 -314.152628)
			(xy 160.743249 -314.18672) (xy 160.702746 -314.214676) (xy 160.658284 -314.235774) (xy 160.611013 -314.249466)
			(xy 160.562158 -314.255398) (xy 160.512983 -314.253417) (xy 160.464764 -314.243573) (xy 160.418748 -314.226121)
			(xy 160.376127 -314.201514) (xy 160.338006 -314.170389) (xy 160.305371 -314.133552) (xy 160.279068 -314.091956)
			(xy 160.259777 -314.04668) (xy 160.248 -313.998896) (xy 160.24404 -313.949842) (xy 159.905192 -313.949842)
			(xy 159.904697 -313.974449) (xy 159.896802 -314.023026) (xy 159.881218 -314.069707) (xy 159.858347 -314.113284)
			(xy 159.828782 -314.152628) (xy 159.793289 -314.18672) (xy 159.752786 -314.214676) (xy 159.708324 -314.235774)
			(xy 159.661053 -314.249466) (xy 159.612198 -314.255398) (xy 159.563023 -314.253417) (xy 159.514804 -314.243573)
			(xy 159.468788 -314.226121) (xy 159.426167 -314.201514) (xy 159.388046 -314.170389) (xy 159.355411 -314.133552)
			(xy 159.329108 -314.091956) (xy 159.309817 -314.04668) (xy 159.29804 -313.998896) (xy 159.29408 -313.949842)
			(xy 158.955232 -313.949842) (xy 158.954737 -313.974449) (xy 158.946842 -314.023026) (xy 158.931258 -314.069707)
			(xy 158.908387 -314.113284) (xy 158.878822 -314.152628) (xy 158.843329 -314.18672) (xy 158.802826 -314.214676)
			(xy 158.758364 -314.235774) (xy 158.711093 -314.249466) (xy 158.662238 -314.255398) (xy 158.613063 -314.253417)
			(xy 158.564844 -314.243573) (xy 158.518828 -314.226121) (xy 158.476207 -314.201514) (xy 158.438086 -314.170389)
			(xy 158.405451 -314.133552) (xy 158.379148 -314.091956) (xy 158.359857 -314.04668) (xy 158.34808 -313.998896)
			(xy 158.34412 -313.949842) (xy 158.005272 -313.949842) (xy 158.004777 -313.974449) (xy 157.996882 -314.023026)
			(xy 157.981298 -314.069707) (xy 157.958427 -314.113284) (xy 157.928862 -314.152628) (xy 157.893369 -314.18672)
			(xy 157.852866 -314.214676) (xy 157.808404 -314.235774) (xy 157.761133 -314.249466) (xy 157.712278 -314.255398)
			(xy 157.663103 -314.253417) (xy 157.614884 -314.243573) (xy 157.568868 -314.226121) (xy 157.526247 -314.201514)
			(xy 157.488126 -314.170389) (xy 157.455491 -314.133552) (xy 157.429188 -314.091956) (xy 157.409897 -314.04668)
			(xy 157.39812 -313.998896) (xy 157.39416 -313.949842) (xy 157.055312 -313.949842) (xy 157.054817 -313.974449)
			(xy 157.046922 -314.023026) (xy 157.031338 -314.069707) (xy 157.008467 -314.113284) (xy 156.978902 -314.152628)
			(xy 156.943409 -314.18672) (xy 156.902906 -314.214676) (xy 156.858444 -314.235774) (xy 156.811173 -314.249466)
			(xy 156.762318 -314.255398) (xy 156.713143 -314.253417) (xy 156.664924 -314.243573) (xy 156.618908 -314.226121)
			(xy 156.576287 -314.201514) (xy 156.538166 -314.170389) (xy 156.505531 -314.133552) (xy 156.479228 -314.091956)
			(xy 156.459937 -314.04668) (xy 156.44816 -313.998896) (xy 156.4442 -313.949842) (xy 156.105352 -313.949842)
			(xy 156.104857 -313.974449) (xy 156.096962 -314.023026) (xy 156.081378 -314.069707) (xy 156.058507 -314.113284)
			(xy 156.028942 -314.152628) (xy 155.993449 -314.18672) (xy 155.952946 -314.214676) (xy 155.908484 -314.235774)
			(xy 155.861213 -314.249466) (xy 155.812358 -314.255398) (xy 155.763183 -314.253417) (xy 155.714964 -314.243573)
			(xy 155.668948 -314.226121) (xy 155.626327 -314.201514) (xy 155.588206 -314.170389) (xy 155.555571 -314.133552)
			(xy 155.529268 -314.091956) (xy 155.509977 -314.04668) (xy 155.4982 -313.998896) (xy 155.49424 -313.949842)
			(xy 155.155392 -313.949842) (xy 155.154897 -313.974449) (xy 155.147002 -314.023026) (xy 155.131418 -314.069707)
			(xy 155.108547 -314.113284) (xy 155.078982 -314.152628) (xy 155.043489 -314.18672) (xy 155.002986 -314.214676)
			(xy 154.958524 -314.235774) (xy 154.911253 -314.249466) (xy 154.862398 -314.255398) (xy 154.813223 -314.253417)
			(xy 154.765004 -314.243573) (xy 154.718988 -314.226121) (xy 154.676367 -314.201514) (xy 154.638246 -314.170389)
			(xy 154.605611 -314.133552) (xy 154.579308 -314.091956) (xy 154.560017 -314.04668) (xy 154.54824 -313.998896)
			(xy 154.54428 -313.949842) (xy 154.205178 -313.949842) (xy 154.204683 -313.974449) (xy 154.196788 -314.023026)
			(xy 154.181204 -314.069707) (xy 154.158333 -314.113284) (xy 154.128768 -314.152628) (xy 154.093275 -314.18672)
			(xy 154.052772 -314.214676) (xy 154.00831 -314.235774) (xy 153.961039 -314.249466) (xy 153.912184 -314.255398)
			(xy 153.863009 -314.253417) (xy 153.81479 -314.243573) (xy 153.768774 -314.226121) (xy 153.726153 -314.201514)
			(xy 153.688032 -314.170389) (xy 153.655397 -314.133552) (xy 153.629094 -314.091956) (xy 153.609803 -314.04668)
			(xy 153.598026 -313.998896) (xy 153.594066 -313.949842) (xy 153.255218 -313.949842) (xy 153.254723 -313.974449)
			(xy 153.246828 -314.023026) (xy 153.231244 -314.069707) (xy 153.208373 -314.113284) (xy 153.178808 -314.152628)
			(xy 153.143315 -314.18672) (xy 153.102812 -314.214676) (xy 153.05835 -314.235774) (xy 153.011079 -314.249466)
			(xy 152.962224 -314.255398) (xy 152.913049 -314.253417) (xy 152.86483 -314.243573) (xy 152.818814 -314.226121)
			(xy 152.776193 -314.201514) (xy 152.738072 -314.170389) (xy 152.705437 -314.133552) (xy 152.679134 -314.091956)
			(xy 152.659843 -314.04668) (xy 152.648066 -313.998896) (xy 152.644106 -313.949842) (xy 150.788307 -313.949842)
			(xy 150.751317 -313.980625) (xy 150.703711 -314.009679) (xy 150.652382 -314.031491) (xy 150.598425 -314.045597)
			(xy 150.542988 -314.051697) (xy 150.487254 -314.04966) (xy 150.432411 -314.03953) (xy 150.379627 -314.021523)
			(xy 150.330027 -313.996022) (xy 150.284669 -313.963571) (xy 150.24452 -313.924862) (xy 150.210434 -313.880719)
			(xy 150.183138 -313.832084) (xy 150.163215 -313.779993) (xy 150.151089 -313.725556) (xy 150.147018 -313.669934)
			(xy 132.048969 -313.669934) (xy 132.047887 -313.672242) (xy 132.017114 -313.718755) (xy 131.979897 -313.760292)
			(xy 131.937029 -313.795967) (xy 131.889423 -313.825021) (xy 131.838094 -313.846833) (xy 131.784137 -313.860939)
			(xy 131.7287 -313.867039) (xy 131.672966 -313.865002) (xy 131.618123 -313.854872) (xy 131.565339 -313.836865)
			(xy 131.515739 -313.811364) (xy 131.470381 -313.778913) (xy 131.430232 -313.740204) (xy 131.396146 -313.696061)
			(xy 131.36885 -313.647426) (xy 131.348927 -313.595335) (xy 131.336801 -313.540898) (xy 131.33273 -313.485276)
			(xy 131.080256 -313.485276) (xy 131.079747 -313.513162) (xy 131.071627 -313.568338) (xy 131.055559 -313.621745)
			(xy 131.031887 -313.672242) (xy 131.001114 -313.718755) (xy 130.963897 -313.760292) (xy 130.921029 -313.795967)
			(xy 130.873423 -313.825021) (xy 130.822094 -313.846833) (xy 130.768137 -313.860939) (xy 130.7127 -313.867039)
			(xy 130.656966 -313.865002) (xy 130.602123 -313.854872) (xy 130.549339 -313.836865) (xy 130.499739 -313.811364)
			(xy 130.454381 -313.778913) (xy 130.414232 -313.740204) (xy 130.380146 -313.696061) (xy 130.35285 -313.647426)
			(xy 130.332927 -313.595335) (xy 130.320801 -313.540898) (xy 130.31673 -313.485276) (xy 130.064256 -313.485276)
			(xy 130.063747 -313.513162) (xy 130.055627 -313.568338) (xy 130.039559 -313.621745) (xy 130.015887 -313.672242)
			(xy 129.985114 -313.718755) (xy 129.947897 -313.760292) (xy 129.905029 -313.795967) (xy 129.857423 -313.825021)
			(xy 129.806094 -313.846833) (xy 129.752137 -313.860939) (xy 129.6967 -313.867039) (xy 129.640966 -313.865002)
			(xy 129.586123 -313.854872) (xy 129.533339 -313.836865) (xy 129.483739 -313.811364) (xy 129.438381 -313.778913)
			(xy 129.398232 -313.740204) (xy 129.364146 -313.696061) (xy 129.33685 -313.647426) (xy 129.316927 -313.595335)
			(xy 129.304801 -313.540898) (xy 129.30073 -313.485276) (xy 129.048256 -313.485276) (xy 129.047747 -313.513162)
			(xy 129.039627 -313.568338) (xy 129.023559 -313.621745) (xy 128.999887 -313.672242) (xy 128.969114 -313.718755)
			(xy 128.931897 -313.760292) (xy 128.889029 -313.795967) (xy 128.841423 -313.825021) (xy 128.790094 -313.846833)
			(xy 128.736137 -313.860939) (xy 128.6807 -313.867039) (xy 128.624966 -313.865002) (xy 128.570123 -313.854872)
			(xy 128.517339 -313.836865) (xy 128.467739 -313.811364) (xy 128.422381 -313.778913) (xy 128.382232 -313.740204)
			(xy 128.348146 -313.696061) (xy 128.32085 -313.647426) (xy 128.300927 -313.595335) (xy 128.288801 -313.540898)
			(xy 128.28473 -313.485276) (xy 128.032256 -313.485276) (xy 128.031747 -313.513162) (xy 128.023627 -313.568338)
			(xy 128.007559 -313.621745) (xy 127.983887 -313.672242) (xy 127.953114 -313.718755) (xy 127.915897 -313.760292)
			(xy 127.873029 -313.795967) (xy 127.825423 -313.825021) (xy 127.774094 -313.846833) (xy 127.720137 -313.860939)
			(xy 127.6647 -313.867039) (xy 127.608966 -313.865002) (xy 127.554123 -313.854872) (xy 127.501339 -313.836865)
			(xy 127.451739 -313.811364) (xy 127.406381 -313.778913) (xy 127.366232 -313.740204) (xy 127.332146 -313.696061)
			(xy 127.30485 -313.647426) (xy 127.284927 -313.595335) (xy 127.272801 -313.540898) (xy 127.26873 -313.485276)
			(xy 127.016256 -313.485276) (xy 127.015747 -313.513162) (xy 127.007627 -313.568338) (xy 126.991559 -313.621745)
			(xy 126.967887 -313.672242) (xy 126.937114 -313.718755) (xy 126.899897 -313.760292) (xy 126.857029 -313.795967)
			(xy 126.809423 -313.825021) (xy 126.758094 -313.846833) (xy 126.704137 -313.860939) (xy 126.6487 -313.867039)
			(xy 126.592966 -313.865002) (xy 126.538123 -313.854872) (xy 126.485339 -313.836865) (xy 126.435739 -313.811364)
			(xy 126.390381 -313.778913) (xy 126.350232 -313.740204) (xy 126.316146 -313.696061) (xy 126.28885 -313.647426)
			(xy 126.268927 -313.595335) (xy 126.256801 -313.540898) (xy 126.25273 -313.485276) (xy 126.000256 -313.485276)
			(xy 125.999747 -313.513162) (xy 125.991627 -313.568338) (xy 125.975559 -313.621745) (xy 125.951887 -313.672242)
			(xy 125.921114 -313.718755) (xy 125.883897 -313.760292) (xy 125.841029 -313.795967) (xy 125.793423 -313.825021)
			(xy 125.742094 -313.846833) (xy 125.688137 -313.860939) (xy 125.6327 -313.867039) (xy 125.576966 -313.865002)
			(xy 125.522123 -313.854872) (xy 125.469339 -313.836865) (xy 125.419739 -313.811364) (xy 125.374381 -313.778913)
			(xy 125.334232 -313.740204) (xy 125.300146 -313.696061) (xy 125.27285 -313.647426) (xy 125.252927 -313.595335)
			(xy 125.240801 -313.540898) (xy 125.23673 -313.485276) (xy 119.631206 -313.485276) (xy 119.631206 -314.501276)
			(xy 125.23673 -314.501276) (xy 125.240801 -314.445654) (xy 125.252927 -314.391217) (xy 125.27285 -314.339126)
			(xy 125.300146 -314.290491) (xy 125.334232 -314.246348) (xy 125.374381 -314.207639) (xy 125.419739 -314.175188)
			(xy 125.469339 -314.149687) (xy 125.522123 -314.13168) (xy 125.576966 -314.12155) (xy 125.6327 -314.119513)
			(xy 125.688137 -314.125613) (xy 125.742094 -314.139719) (xy 125.793423 -314.161531) (xy 125.841029 -314.190585)
			(xy 125.883897 -314.22626) (xy 125.921114 -314.267797) (xy 125.951887 -314.31431) (xy 125.975559 -314.364807)
			(xy 125.991627 -314.418214) (xy 125.999747 -314.47339) (xy 126.000256 -314.501276) (xy 126.25273 -314.501276)
			(xy 126.256801 -314.445654) (xy 126.268927 -314.391217) (xy 126.28885 -314.339126) (xy 126.316146 -314.290491)
			(xy 126.350232 -314.246348) (xy 126.390381 -314.207639) (xy 126.435739 -314.175188) (xy 126.485339 -314.149687)
			(xy 126.538123 -314.13168) (xy 126.592966 -314.12155) (xy 126.6487 -314.119513) (xy 126.704137 -314.125613)
			(xy 126.758094 -314.139719) (xy 126.809423 -314.161531) (xy 126.857029 -314.190585) (xy 126.899897 -314.22626)
			(xy 126.937114 -314.267797) (xy 126.967887 -314.31431) (xy 126.991559 -314.364807) (xy 127.007627 -314.418214)
			(xy 127.015747 -314.47339) (xy 127.016256 -314.501276) (xy 127.26873 -314.501276) (xy 127.272801 -314.445654)
			(xy 127.284927 -314.391217) (xy 127.30485 -314.339126) (xy 127.332146 -314.290491) (xy 127.366232 -314.246348)
			(xy 127.406381 -314.207639) (xy 127.451739 -314.175188) (xy 127.501339 -314.149687) (xy 127.554123 -314.13168)
			(xy 127.608966 -314.12155) (xy 127.6647 -314.119513) (xy 127.720137 -314.125613) (xy 127.774094 -314.139719)
			(xy 127.825423 -314.161531) (xy 127.873029 -314.190585) (xy 127.915897 -314.22626) (xy 127.953114 -314.267797)
			(xy 127.983887 -314.31431) (xy 128.007559 -314.364807) (xy 128.023627 -314.418214) (xy 128.031747 -314.47339)
			(xy 128.032256 -314.501276) (xy 128.28473 -314.501276) (xy 128.288801 -314.445654) (xy 128.300927 -314.391217)
			(xy 128.32085 -314.339126) (xy 128.348146 -314.290491) (xy 128.382232 -314.246348) (xy 128.422381 -314.207639)
			(xy 128.467739 -314.175188) (xy 128.517339 -314.149687) (xy 128.570123 -314.13168) (xy 128.624966 -314.12155)
			(xy 128.6807 -314.119513) (xy 128.736137 -314.125613) (xy 128.790094 -314.139719) (xy 128.841423 -314.161531)
			(xy 128.889029 -314.190585) (xy 128.931897 -314.22626) (xy 128.969114 -314.267797) (xy 128.999887 -314.31431)
			(xy 129.023559 -314.364807) (xy 129.039627 -314.418214) (xy 129.047747 -314.47339) (xy 129.048256 -314.501276)
			(xy 129.30073 -314.501276) (xy 129.304801 -314.445654) (xy 129.316927 -314.391217) (xy 129.33685 -314.339126)
			(xy 129.364146 -314.290491) (xy 129.398232 -314.246348) (xy 129.438381 -314.207639) (xy 129.483739 -314.175188)
			(xy 129.533339 -314.149687) (xy 129.586123 -314.13168) (xy 129.640966 -314.12155) (xy 129.6967 -314.119513)
			(xy 129.752137 -314.125613) (xy 129.806094 -314.139719) (xy 129.857423 -314.161531) (xy 129.905029 -314.190585)
			(xy 129.947897 -314.22626) (xy 129.985114 -314.267797) (xy 130.015887 -314.31431) (xy 130.039559 -314.364807)
			(xy 130.055627 -314.418214) (xy 130.063747 -314.47339) (xy 130.064256 -314.501276) (xy 130.31673 -314.501276)
			(xy 130.320801 -314.445654) (xy 130.332927 -314.391217) (xy 130.35285 -314.339126) (xy 130.380146 -314.290491)
			(xy 130.414232 -314.246348) (xy 130.454381 -314.207639) (xy 130.499739 -314.175188) (xy 130.549339 -314.149687)
			(xy 130.602123 -314.13168) (xy 130.656966 -314.12155) (xy 130.7127 -314.119513) (xy 130.768137 -314.125613)
			(xy 130.822094 -314.139719) (xy 130.873423 -314.161531) (xy 130.921029 -314.190585) (xy 130.963897 -314.22626)
			(xy 131.001114 -314.267797) (xy 131.031887 -314.31431) (xy 131.055559 -314.364807) (xy 131.071627 -314.418214)
			(xy 131.079747 -314.47339) (xy 131.080256 -314.501276) (xy 131.079747 -314.529162) (xy 131.071627 -314.584338)
			(xy 131.055559 -314.637745) (xy 131.031887 -314.688242) (xy 131.001114 -314.734755) (xy 130.963897 -314.776292)
			(xy 130.921029 -314.811967) (xy 130.873423 -314.841021) (xy 130.822094 -314.862833) (xy 130.768137 -314.876939)
			(xy 130.7127 -314.883039) (xy 130.656966 -314.881002) (xy 130.602123 -314.870872) (xy 130.549339 -314.852865)
			(xy 130.499739 -314.827364) (xy 130.454381 -314.794913) (xy 130.414232 -314.756204) (xy 130.380146 -314.712061)
			(xy 130.35285 -314.663426) (xy 130.332927 -314.611335) (xy 130.320801 -314.556898) (xy 130.31673 -314.501276)
			(xy 130.064256 -314.501276) (xy 130.063747 -314.529162) (xy 130.055627 -314.584338) (xy 130.039559 -314.637745)
			(xy 130.015887 -314.688242) (xy 129.985114 -314.734755) (xy 129.947897 -314.776292) (xy 129.905029 -314.811967)
			(xy 129.857423 -314.841021) (xy 129.806094 -314.862833) (xy 129.752137 -314.876939) (xy 129.6967 -314.883039)
			(xy 129.640966 -314.881002) (xy 129.586123 -314.870872) (xy 129.533339 -314.852865) (xy 129.483739 -314.827364)
			(xy 129.438381 -314.794913) (xy 129.398232 -314.756204) (xy 129.364146 -314.712061) (xy 129.33685 -314.663426)
			(xy 129.316927 -314.611335) (xy 129.304801 -314.556898) (xy 129.30073 -314.501276) (xy 129.048256 -314.501276)
			(xy 129.047747 -314.529162) (xy 129.039627 -314.584338) (xy 129.023559 -314.637745) (xy 128.999887 -314.688242)
			(xy 128.969114 -314.734755) (xy 128.931897 -314.776292) (xy 128.889029 -314.811967) (xy 128.841423 -314.841021)
			(xy 128.790094 -314.862833) (xy 128.736137 -314.876939) (xy 128.6807 -314.883039) (xy 128.624966 -314.881002)
			(xy 128.570123 -314.870872) (xy 128.517339 -314.852865) (xy 128.467739 -314.827364) (xy 128.422381 -314.794913)
			(xy 128.382232 -314.756204) (xy 128.348146 -314.712061) (xy 128.32085 -314.663426) (xy 128.300927 -314.611335)
			(xy 128.288801 -314.556898) (xy 128.28473 -314.501276) (xy 128.032256 -314.501276) (xy 128.031747 -314.529162)
			(xy 128.023627 -314.584338) (xy 128.007559 -314.637745) (xy 127.983887 -314.688242) (xy 127.953114 -314.734755)
			(xy 127.915897 -314.776292) (xy 127.873029 -314.811967) (xy 127.825423 -314.841021) (xy 127.774094 -314.862833)
			(xy 127.720137 -314.876939) (xy 127.6647 -314.883039) (xy 127.608966 -314.881002) (xy 127.554123 -314.870872)
			(xy 127.501339 -314.852865) (xy 127.451739 -314.827364) (xy 127.406381 -314.794913) (xy 127.366232 -314.756204)
			(xy 127.332146 -314.712061) (xy 127.30485 -314.663426) (xy 127.284927 -314.611335) (xy 127.272801 -314.556898)
			(xy 127.26873 -314.501276) (xy 127.016256 -314.501276) (xy 127.015747 -314.529162) (xy 127.007627 -314.584338)
			(xy 126.991559 -314.637745) (xy 126.967887 -314.688242) (xy 126.937114 -314.734755) (xy 126.899897 -314.776292)
			(xy 126.857029 -314.811967) (xy 126.809423 -314.841021) (xy 126.758094 -314.862833) (xy 126.704137 -314.876939)
			(xy 126.6487 -314.883039) (xy 126.592966 -314.881002) (xy 126.538123 -314.870872) (xy 126.485339 -314.852865)
			(xy 126.435739 -314.827364) (xy 126.390381 -314.794913) (xy 126.350232 -314.756204) (xy 126.316146 -314.712061)
			(xy 126.28885 -314.663426) (xy 126.268927 -314.611335) (xy 126.256801 -314.556898) (xy 126.25273 -314.501276)
			(xy 126.000256 -314.501276) (xy 125.999747 -314.529162) (xy 125.991627 -314.584338) (xy 125.975559 -314.637745)
			(xy 125.951887 -314.688242) (xy 125.921114 -314.734755) (xy 125.883897 -314.776292) (xy 125.841029 -314.811967)
			(xy 125.793423 -314.841021) (xy 125.742094 -314.862833) (xy 125.688137 -314.876939) (xy 125.6327 -314.883039)
			(xy 125.576966 -314.881002) (xy 125.522123 -314.870872) (xy 125.469339 -314.852865) (xy 125.419739 -314.827364)
			(xy 125.374381 -314.794913) (xy 125.334232 -314.756204) (xy 125.300146 -314.712061) (xy 125.27285 -314.663426)
			(xy 125.252927 -314.611335) (xy 125.240801 -314.556898) (xy 125.23673 -314.501276) (xy 119.631206 -314.501276)
			(xy 119.631206 -314.899548) (xy 151.693638 -314.899548) (xy 151.697598 -314.850494) (xy 151.709375 -314.80271)
			(xy 151.728666 -314.757434) (xy 151.754969 -314.715838) (xy 151.787604 -314.679001) (xy 151.825725 -314.647876)
			(xy 151.868346 -314.623269) (xy 151.914362 -314.605817) (xy 151.962581 -314.595973) (xy 152.011756 -314.593992)
			(xy 152.060611 -314.599924) (xy 152.107882 -314.613616) (xy 152.152344 -314.634714) (xy 152.192847 -314.66267)
			(xy 152.22834 -314.696762) (xy 152.257905 -314.736106) (xy 152.280776 -314.779683) (xy 152.29636 -314.826364)
			(xy 152.304255 -314.874941) (xy 152.30475 -314.899548) (xy 152.304745 -314.899802) (xy 152.644106 -314.899802)
			(xy 152.648066 -314.850748) (xy 152.659843 -314.802964) (xy 152.679134 -314.757688) (xy 152.705437 -314.716092)
			(xy 152.738072 -314.679255) (xy 152.776193 -314.64813) (xy 152.818814 -314.623523) (xy 152.86483 -314.606071)
			(xy 152.913049 -314.596227) (xy 152.962224 -314.594246) (xy 153.011079 -314.600178) (xy 153.05835 -314.61387)
			(xy 153.102812 -314.634968) (xy 153.143315 -314.662924) (xy 153.178808 -314.697016) (xy 153.208373 -314.73636)
			(xy 153.231244 -314.779937) (xy 153.246828 -314.826618) (xy 153.254723 -314.875195) (xy 153.255218 -314.899802)
			(xy 153.594066 -314.899802) (xy 153.598026 -314.850748) (xy 153.609803 -314.802964) (xy 153.629094 -314.757688)
			(xy 153.655397 -314.716092) (xy 153.688032 -314.679255) (xy 153.726153 -314.64813) (xy 153.768774 -314.623523)
			(xy 153.81479 -314.606071) (xy 153.863009 -314.596227) (xy 153.912184 -314.594246) (xy 153.961039 -314.600178)
			(xy 154.00831 -314.61387) (xy 154.052772 -314.634968) (xy 154.093275 -314.662924) (xy 154.128768 -314.697016)
			(xy 154.158333 -314.73636) (xy 154.181204 -314.779937) (xy 154.196788 -314.826618) (xy 154.204683 -314.875195)
			(xy 154.205178 -314.899802) (xy 154.54428 -314.899802) (xy 154.54824 -314.850748) (xy 154.560017 -314.802964)
			(xy 154.579308 -314.757688) (xy 154.605611 -314.716092) (xy 154.638246 -314.679255) (xy 154.676367 -314.64813)
			(xy 154.718988 -314.623523) (xy 154.765004 -314.606071) (xy 154.813223 -314.596227) (xy 154.862398 -314.594246)
			(xy 154.911253 -314.600178) (xy 154.958524 -314.61387) (xy 155.002986 -314.634968) (xy 155.043489 -314.662924)
			(xy 155.078982 -314.697016) (xy 155.108547 -314.73636) (xy 155.131418 -314.779937) (xy 155.147002 -314.826618)
			(xy 155.154897 -314.875195) (xy 155.155392 -314.899802) (xy 155.49424 -314.899802) (xy 155.4982 -314.850748)
			(xy 155.509977 -314.802964) (xy 155.529268 -314.757688) (xy 155.555571 -314.716092) (xy 155.588206 -314.679255)
			(xy 155.626327 -314.64813) (xy 155.668948 -314.623523) (xy 155.714964 -314.606071) (xy 155.763183 -314.596227)
			(xy 155.812358 -314.594246) (xy 155.861213 -314.600178) (xy 155.908484 -314.61387) (xy 155.952946 -314.634968)
			(xy 155.993449 -314.662924) (xy 156.028942 -314.697016) (xy 156.058507 -314.73636) (xy 156.081378 -314.779937)
			(xy 156.096962 -314.826618) (xy 156.104857 -314.875195) (xy 156.105352 -314.899802) (xy 156.4442 -314.899802)
			(xy 156.44816 -314.850748) (xy 156.459937 -314.802964) (xy 156.479228 -314.757688) (xy 156.505531 -314.716092)
			(xy 156.538166 -314.679255) (xy 156.576287 -314.64813) (xy 156.618908 -314.623523) (xy 156.664924 -314.606071)
			(xy 156.713143 -314.596227) (xy 156.762318 -314.594246) (xy 156.811173 -314.600178) (xy 156.858444 -314.61387)
			(xy 156.902906 -314.634968) (xy 156.943409 -314.662924) (xy 156.978902 -314.697016) (xy 157.008467 -314.73636)
			(xy 157.031338 -314.779937) (xy 157.046922 -314.826618) (xy 157.054817 -314.875195) (xy 157.055312 -314.899802)
			(xy 157.39416 -314.899802) (xy 157.39812 -314.850748) (xy 157.409897 -314.802964) (xy 157.429188 -314.757688)
			(xy 157.455491 -314.716092) (xy 157.488126 -314.679255) (xy 157.526247 -314.64813) (xy 157.568868 -314.623523)
			(xy 157.614884 -314.606071) (xy 157.663103 -314.596227) (xy 157.712278 -314.594246) (xy 157.761133 -314.600178)
			(xy 157.808404 -314.61387) (xy 157.852866 -314.634968) (xy 157.893369 -314.662924) (xy 157.928862 -314.697016)
			(xy 157.958427 -314.73636) (xy 157.981298 -314.779937) (xy 157.996882 -314.826618) (xy 158.004777 -314.875195)
			(xy 158.005272 -314.899802) (xy 158.34412 -314.899802) (xy 158.34808 -314.850748) (xy 158.359857 -314.802964)
			(xy 158.379148 -314.757688) (xy 158.405451 -314.716092) (xy 158.438086 -314.679255) (xy 158.476207 -314.64813)
			(xy 158.518828 -314.623523) (xy 158.564844 -314.606071) (xy 158.613063 -314.596227) (xy 158.662238 -314.594246)
			(xy 158.711093 -314.600178) (xy 158.758364 -314.61387) (xy 158.802826 -314.634968) (xy 158.843329 -314.662924)
			(xy 158.878822 -314.697016) (xy 158.908387 -314.73636) (xy 158.931258 -314.779937) (xy 158.946842 -314.826618)
			(xy 158.954737 -314.875195) (xy 158.955232 -314.899802) (xy 159.29408 -314.899802) (xy 159.29804 -314.850748)
			(xy 159.309817 -314.802964) (xy 159.329108 -314.757688) (xy 159.355411 -314.716092) (xy 159.388046 -314.679255)
			(xy 159.426167 -314.64813) (xy 159.468788 -314.623523) (xy 159.514804 -314.606071) (xy 159.563023 -314.596227)
			(xy 159.612198 -314.594246) (xy 159.661053 -314.600178) (xy 159.708324 -314.61387) (xy 159.752786 -314.634968)
			(xy 159.793289 -314.662924) (xy 159.828782 -314.697016) (xy 159.858347 -314.73636) (xy 159.881218 -314.779937)
			(xy 159.896802 -314.826618) (xy 159.904697 -314.875195) (xy 159.905192 -314.899802) (xy 160.24404 -314.899802)
			(xy 160.248 -314.850748) (xy 160.259777 -314.802964) (xy 160.279068 -314.757688) (xy 160.305371 -314.716092)
			(xy 160.338006 -314.679255) (xy 160.376127 -314.64813) (xy 160.418748 -314.623523) (xy 160.464764 -314.606071)
			(xy 160.512983 -314.596227) (xy 160.562158 -314.594246) (xy 160.611013 -314.600178) (xy 160.658284 -314.61387)
			(xy 160.702746 -314.634968) (xy 160.743249 -314.662924) (xy 160.778742 -314.697016) (xy 160.808307 -314.73636)
			(xy 160.831178 -314.779937) (xy 160.846762 -314.826618) (xy 160.854657 -314.875195) (xy 160.855152 -314.899802)
			(xy 161.194254 -314.899802) (xy 161.198214 -314.850748) (xy 161.209991 -314.802964) (xy 161.229282 -314.757688)
			(xy 161.255585 -314.716092) (xy 161.28822 -314.679255) (xy 161.326341 -314.64813) (xy 161.368962 -314.623523)
			(xy 161.414978 -314.606071) (xy 161.463197 -314.596227) (xy 161.512372 -314.594246) (xy 161.561227 -314.600178)
			(xy 161.608498 -314.61387) (xy 161.65296 -314.634968) (xy 161.693463 -314.662924) (xy 161.728956 -314.697016)
			(xy 161.758521 -314.73636) (xy 161.781392 -314.779937) (xy 161.796976 -314.826618) (xy 161.804871 -314.875195)
			(xy 161.805366 -314.899802) (xy 161.804871 -314.924409) (xy 161.796976 -314.972986) (xy 161.781392 -315.019667)
			(xy 161.758521 -315.063244) (xy 161.728956 -315.102588) (xy 161.693463 -315.13668) (xy 161.65296 -315.164636)
			(xy 161.608498 -315.185734) (xy 161.561227 -315.199426) (xy 161.512372 -315.205358) (xy 161.463197 -315.203377)
			(xy 161.414978 -315.193533) (xy 161.368962 -315.176081) (xy 161.326341 -315.151474) (xy 161.28822 -315.120349)
			(xy 161.255585 -315.083512) (xy 161.229282 -315.041916) (xy 161.209991 -314.99664) (xy 161.198214 -314.948856)
			(xy 161.194254 -314.899802) (xy 160.855152 -314.899802) (xy 160.854657 -314.924409) (xy 160.846762 -314.972986)
			(xy 160.831178 -315.019667) (xy 160.808307 -315.063244) (xy 160.778742 -315.102588) (xy 160.743249 -315.13668)
			(xy 160.702746 -315.164636) (xy 160.658284 -315.185734) (xy 160.611013 -315.199426) (xy 160.562158 -315.205358)
			(xy 160.512983 -315.203377) (xy 160.464764 -315.193533) (xy 160.418748 -315.176081) (xy 160.376127 -315.151474)
			(xy 160.338006 -315.120349) (xy 160.305371 -315.083512) (xy 160.279068 -315.041916) (xy 160.259777 -314.99664)
			(xy 160.248 -314.948856) (xy 160.24404 -314.899802) (xy 159.905192 -314.899802) (xy 159.904697 -314.924409)
			(xy 159.896802 -314.972986) (xy 159.881218 -315.019667) (xy 159.858347 -315.063244) (xy 159.828782 -315.102588)
			(xy 159.793289 -315.13668) (xy 159.752786 -315.164636) (xy 159.708324 -315.185734) (xy 159.661053 -315.199426)
			(xy 159.612198 -315.205358) (xy 159.563023 -315.203377) (xy 159.514804 -315.193533) (xy 159.468788 -315.176081)
			(xy 159.426167 -315.151474) (xy 159.388046 -315.120349) (xy 159.355411 -315.083512) (xy 159.329108 -315.041916)
			(xy 159.309817 -314.99664) (xy 159.29804 -314.948856) (xy 159.29408 -314.899802) (xy 158.955232 -314.899802)
			(xy 158.954737 -314.924409) (xy 158.946842 -314.972986) (xy 158.931258 -315.019667) (xy 158.908387 -315.063244)
			(xy 158.878822 -315.102588) (xy 158.843329 -315.13668) (xy 158.802826 -315.164636) (xy 158.758364 -315.185734)
			(xy 158.711093 -315.199426) (xy 158.662238 -315.205358) (xy 158.613063 -315.203377) (xy 158.564844 -315.193533)
			(xy 158.518828 -315.176081) (xy 158.476207 -315.151474) (xy 158.438086 -315.120349) (xy 158.405451 -315.083512)
			(xy 158.379148 -315.041916) (xy 158.359857 -314.99664) (xy 158.34808 -314.948856) (xy 158.34412 -314.899802)
			(xy 158.005272 -314.899802) (xy 158.004777 -314.924409) (xy 157.996882 -314.972986) (xy 157.981298 -315.019667)
			(xy 157.958427 -315.063244) (xy 157.928862 -315.102588) (xy 157.893369 -315.13668) (xy 157.852866 -315.164636)
			(xy 157.808404 -315.185734) (xy 157.761133 -315.199426) (xy 157.712278 -315.205358) (xy 157.663103 -315.203377)
			(xy 157.614884 -315.193533) (xy 157.568868 -315.176081) (xy 157.526247 -315.151474) (xy 157.488126 -315.120349)
			(xy 157.455491 -315.083512) (xy 157.429188 -315.041916) (xy 157.409897 -314.99664) (xy 157.39812 -314.948856)
			(xy 157.39416 -314.899802) (xy 157.055312 -314.899802) (xy 157.054817 -314.924409) (xy 157.046922 -314.972986)
			(xy 157.031338 -315.019667) (xy 157.008467 -315.063244) (xy 156.978902 -315.102588) (xy 156.943409 -315.13668)
			(xy 156.902906 -315.164636) (xy 156.858444 -315.185734) (xy 156.811173 -315.199426) (xy 156.762318 -315.205358)
			(xy 156.713143 -315.203377) (xy 156.664924 -315.193533) (xy 156.618908 -315.176081) (xy 156.576287 -315.151474)
			(xy 156.538166 -315.120349) (xy 156.505531 -315.083512) (xy 156.479228 -315.041916) (xy 156.459937 -314.99664)
			(xy 156.44816 -314.948856) (xy 156.4442 -314.899802) (xy 156.105352 -314.899802) (xy 156.104857 -314.924409)
			(xy 156.096962 -314.972986) (xy 156.081378 -315.019667) (xy 156.058507 -315.063244) (xy 156.028942 -315.102588)
			(xy 155.993449 -315.13668) (xy 155.952946 -315.164636) (xy 155.908484 -315.185734) (xy 155.861213 -315.199426)
			(xy 155.812358 -315.205358) (xy 155.763183 -315.203377) (xy 155.714964 -315.193533) (xy 155.668948 -315.176081)
			(xy 155.626327 -315.151474) (xy 155.588206 -315.120349) (xy 155.555571 -315.083512) (xy 155.529268 -315.041916)
			(xy 155.509977 -314.99664) (xy 155.4982 -314.948856) (xy 155.49424 -314.899802) (xy 155.155392 -314.899802)
			(xy 155.154897 -314.924409) (xy 155.147002 -314.972986) (xy 155.131418 -315.019667) (xy 155.108547 -315.063244)
			(xy 155.078982 -315.102588) (xy 155.043489 -315.13668) (xy 155.002986 -315.164636) (xy 154.958524 -315.185734)
			(xy 154.911253 -315.199426) (xy 154.862398 -315.205358) (xy 154.813223 -315.203377) (xy 154.765004 -315.193533)
			(xy 154.718988 -315.176081) (xy 154.676367 -315.151474) (xy 154.638246 -315.120349) (xy 154.605611 -315.083512)
			(xy 154.579308 -315.041916) (xy 154.560017 -314.99664) (xy 154.54824 -314.948856) (xy 154.54428 -314.899802)
			(xy 154.205178 -314.899802) (xy 154.204683 -314.924409) (xy 154.196788 -314.972986) (xy 154.181204 -315.019667)
			(xy 154.158333 -315.063244) (xy 154.128768 -315.102588) (xy 154.093275 -315.13668) (xy 154.052772 -315.164636)
			(xy 154.00831 -315.185734) (xy 153.961039 -315.199426) (xy 153.912184 -315.205358) (xy 153.863009 -315.203377)
			(xy 153.81479 -315.193533) (xy 153.768774 -315.176081) (xy 153.726153 -315.151474) (xy 153.688032 -315.120349)
			(xy 153.655397 -315.083512) (xy 153.629094 -315.041916) (xy 153.609803 -314.99664) (xy 153.598026 -314.948856)
			(xy 153.594066 -314.899802) (xy 153.255218 -314.899802) (xy 153.254723 -314.924409) (xy 153.246828 -314.972986)
			(xy 153.231244 -315.019667) (xy 153.208373 -315.063244) (xy 153.178808 -315.102588) (xy 153.143315 -315.13668)
			(xy 153.102812 -315.164636) (xy 153.05835 -315.185734) (xy 153.011079 -315.199426) (xy 152.962224 -315.205358)
			(xy 152.913049 -315.203377) (xy 152.86483 -315.193533) (xy 152.818814 -315.176081) (xy 152.776193 -315.151474)
			(xy 152.738072 -315.120349) (xy 152.705437 -315.083512) (xy 152.679134 -315.041916) (xy 152.659843 -314.99664)
			(xy 152.648066 -314.948856) (xy 152.644106 -314.899802) (xy 152.304745 -314.899802) (xy 152.304255 -314.924155)
			(xy 152.29636 -314.972732) (xy 152.280776 -315.019413) (xy 152.257905 -315.06299) (xy 152.22834 -315.102334)
			(xy 152.192847 -315.136426) (xy 152.152344 -315.164382) (xy 152.107882 -315.18548) (xy 152.060611 -315.199172)
			(xy 152.011756 -315.205104) (xy 151.962581 -315.203123) (xy 151.914362 -315.193279) (xy 151.868346 -315.175827)
			(xy 151.825725 -315.15122) (xy 151.787604 -315.120095) (xy 151.754969 -315.083258) (xy 151.728666 -315.041662)
			(xy 151.709375 -314.996386) (xy 151.697598 -314.948602) (xy 151.693638 -314.899548) (xy 119.631206 -314.899548)
			(xy 119.631206 -315.517276) (xy 125.23673 -315.517276) (xy 125.240801 -315.461654) (xy 125.252927 -315.407217)
			(xy 125.27285 -315.355126) (xy 125.300146 -315.306491) (xy 125.334232 -315.262348) (xy 125.374381 -315.223639)
			(xy 125.419739 -315.191188) (xy 125.469339 -315.165687) (xy 125.522123 -315.14768) (xy 125.576966 -315.13755)
			(xy 125.6327 -315.135513) (xy 125.688137 -315.141613) (xy 125.742094 -315.155719) (xy 125.793423 -315.177531)
			(xy 125.841029 -315.206585) (xy 125.883897 -315.24226) (xy 125.921114 -315.283797) (xy 125.951887 -315.33031)
			(xy 125.975559 -315.380807) (xy 125.991627 -315.434214) (xy 125.999747 -315.48939) (xy 126.000256 -315.517276)
			(xy 126.25273 -315.517276) (xy 126.256801 -315.461654) (xy 126.268927 -315.407217) (xy 126.28885 -315.355126)
			(xy 126.316146 -315.306491) (xy 126.350232 -315.262348) (xy 126.390381 -315.223639) (xy 126.435739 -315.191188)
			(xy 126.485339 -315.165687) (xy 126.538123 -315.14768) (xy 126.592966 -315.13755) (xy 126.6487 -315.135513)
			(xy 126.704137 -315.141613) (xy 126.758094 -315.155719) (xy 126.809423 -315.177531) (xy 126.857029 -315.206585)
			(xy 126.899897 -315.24226) (xy 126.937114 -315.283797) (xy 126.967887 -315.33031) (xy 126.991559 -315.380807)
			(xy 127.007627 -315.434214) (xy 127.015747 -315.48939) (xy 127.016256 -315.517276) (xy 127.26873 -315.517276)
			(xy 127.272801 -315.461654) (xy 127.284927 -315.407217) (xy 127.30485 -315.355126) (xy 127.332146 -315.306491)
			(xy 127.366232 -315.262348) (xy 127.406381 -315.223639) (xy 127.451739 -315.191188) (xy 127.501339 -315.165687)
			(xy 127.554123 -315.14768) (xy 127.608966 -315.13755) (xy 127.6647 -315.135513) (xy 127.720137 -315.141613)
			(xy 127.774094 -315.155719) (xy 127.825423 -315.177531) (xy 127.873029 -315.206585) (xy 127.915897 -315.24226)
			(xy 127.953114 -315.283797) (xy 127.983887 -315.33031) (xy 128.007559 -315.380807) (xy 128.023627 -315.434214)
			(xy 128.031747 -315.48939) (xy 128.032256 -315.517276) (xy 128.28473 -315.517276) (xy 128.288801 -315.461654)
			(xy 128.300927 -315.407217) (xy 128.32085 -315.355126) (xy 128.348146 -315.306491) (xy 128.382232 -315.262348)
			(xy 128.422381 -315.223639) (xy 128.467739 -315.191188) (xy 128.517339 -315.165687) (xy 128.570123 -315.14768)
			(xy 128.624966 -315.13755) (xy 128.6807 -315.135513) (xy 128.736137 -315.141613) (xy 128.790094 -315.155719)
			(xy 128.841423 -315.177531) (xy 128.889029 -315.206585) (xy 128.931897 -315.24226) (xy 128.969114 -315.283797)
			(xy 128.999887 -315.33031) (xy 129.023559 -315.380807) (xy 129.039627 -315.434214) (xy 129.047747 -315.48939)
			(xy 129.048256 -315.517276) (xy 129.30073 -315.517276) (xy 129.304801 -315.461654) (xy 129.316927 -315.407217)
			(xy 129.33685 -315.355126) (xy 129.364146 -315.306491) (xy 129.398232 -315.262348) (xy 129.438381 -315.223639)
			(xy 129.483739 -315.191188) (xy 129.533339 -315.165687) (xy 129.586123 -315.14768) (xy 129.640966 -315.13755)
			(xy 129.6967 -315.135513) (xy 129.752137 -315.141613) (xy 129.806094 -315.155719) (xy 129.857423 -315.177531)
			(xy 129.905029 -315.206585) (xy 129.947897 -315.24226) (xy 129.985114 -315.283797) (xy 130.015887 -315.33031)
			(xy 130.039559 -315.380807) (xy 130.055627 -315.434214) (xy 130.063747 -315.48939) (xy 130.064256 -315.517276)
			(xy 130.31673 -315.517276) (xy 130.320801 -315.461654) (xy 130.332927 -315.407217) (xy 130.35285 -315.355126)
			(xy 130.380146 -315.306491) (xy 130.414232 -315.262348) (xy 130.454381 -315.223639) (xy 130.499739 -315.191188)
			(xy 130.549339 -315.165687) (xy 130.602123 -315.14768) (xy 130.656966 -315.13755) (xy 130.7127 -315.135513)
			(xy 130.768137 -315.141613) (xy 130.822094 -315.155719) (xy 130.873423 -315.177531) (xy 130.921029 -315.206585)
			(xy 130.963897 -315.24226) (xy 131.001114 -315.283797) (xy 131.031887 -315.33031) (xy 131.055559 -315.380807)
			(xy 131.071627 -315.434214) (xy 131.079747 -315.48939) (xy 131.080256 -315.517276) (xy 131.079747 -315.545162)
			(xy 131.071627 -315.600338) (xy 131.055559 -315.653745) (xy 131.031887 -315.704242) (xy 131.001114 -315.750755)
			(xy 130.963897 -315.792292) (xy 130.921029 -315.827967) (xy 130.885317 -315.849762) (xy 152.644106 -315.849762)
			(xy 152.648066 -315.800708) (xy 152.659843 -315.752924) (xy 152.679134 -315.707648) (xy 152.705437 -315.666052)
			(xy 152.738072 -315.629215) (xy 152.776193 -315.59809) (xy 152.818814 -315.573483) (xy 152.86483 -315.556031)
			(xy 152.913049 -315.546187) (xy 152.962224 -315.544206) (xy 153.011079 -315.550138) (xy 153.05835 -315.56383)
			(xy 153.102812 -315.584928) (xy 153.143315 -315.612884) (xy 153.178808 -315.646976) (xy 153.208373 -315.68632)
			(xy 153.231244 -315.729897) (xy 153.246828 -315.776578) (xy 153.254723 -315.825155) (xy 153.255218 -315.849762)
			(xy 153.594066 -315.849762) (xy 153.598026 -315.800708) (xy 153.609803 -315.752924) (xy 153.629094 -315.707648)
			(xy 153.655397 -315.666052) (xy 153.688032 -315.629215) (xy 153.726153 -315.59809) (xy 153.768774 -315.573483)
			(xy 153.81479 -315.556031) (xy 153.863009 -315.546187) (xy 153.912184 -315.544206) (xy 153.961039 -315.550138)
			(xy 154.00831 -315.56383) (xy 154.052772 -315.584928) (xy 154.093275 -315.612884) (xy 154.128768 -315.646976)
			(xy 154.158333 -315.68632) (xy 154.181204 -315.729897) (xy 154.196788 -315.776578) (xy 154.204683 -315.825155)
			(xy 154.205178 -315.849762) (xy 154.54428 -315.849762) (xy 154.54824 -315.800708) (xy 154.560017 -315.752924)
			(xy 154.579308 -315.707648) (xy 154.605611 -315.666052) (xy 154.638246 -315.629215) (xy 154.676367 -315.59809)
			(xy 154.718988 -315.573483) (xy 154.765004 -315.556031) (xy 154.813223 -315.546187) (xy 154.862398 -315.544206)
			(xy 154.911253 -315.550138) (xy 154.958524 -315.56383) (xy 155.002986 -315.584928) (xy 155.043489 -315.612884)
			(xy 155.078982 -315.646976) (xy 155.108547 -315.68632) (xy 155.131418 -315.729897) (xy 155.147002 -315.776578)
			(xy 155.154897 -315.825155) (xy 155.155392 -315.849762) (xy 155.49424 -315.849762) (xy 155.4982 -315.800708)
			(xy 155.509977 -315.752924) (xy 155.529268 -315.707648) (xy 155.555571 -315.666052) (xy 155.588206 -315.629215)
			(xy 155.626327 -315.59809) (xy 155.668948 -315.573483) (xy 155.714964 -315.556031) (xy 155.763183 -315.546187)
			(xy 155.812358 -315.544206) (xy 155.861213 -315.550138) (xy 155.908484 -315.56383) (xy 155.952946 -315.584928)
			(xy 155.993449 -315.612884) (xy 156.028942 -315.646976) (xy 156.058507 -315.68632) (xy 156.081378 -315.729897)
			(xy 156.096962 -315.776578) (xy 156.104857 -315.825155) (xy 156.105352 -315.849762) (xy 156.4442 -315.849762)
			(xy 156.44816 -315.800708) (xy 156.459937 -315.752924) (xy 156.479228 -315.707648) (xy 156.505531 -315.666052)
			(xy 156.538166 -315.629215) (xy 156.576287 -315.59809) (xy 156.618908 -315.573483) (xy 156.664924 -315.556031)
			(xy 156.713143 -315.546187) (xy 156.762318 -315.544206) (xy 156.811173 -315.550138) (xy 156.858444 -315.56383)
			(xy 156.902906 -315.584928) (xy 156.943409 -315.612884) (xy 156.978902 -315.646976) (xy 157.008467 -315.68632)
			(xy 157.031338 -315.729897) (xy 157.046922 -315.776578) (xy 157.054817 -315.825155) (xy 157.055312 -315.849762)
			(xy 157.39416 -315.849762) (xy 157.39812 -315.800708) (xy 157.409897 -315.752924) (xy 157.429188 -315.707648)
			(xy 157.455491 -315.666052) (xy 157.488126 -315.629215) (xy 157.526247 -315.59809) (xy 157.568868 -315.573483)
			(xy 157.614884 -315.556031) (xy 157.663103 -315.546187) (xy 157.712278 -315.544206) (xy 157.761133 -315.550138)
			(xy 157.808404 -315.56383) (xy 157.852866 -315.584928) (xy 157.893369 -315.612884) (xy 157.928862 -315.646976)
			(xy 157.958427 -315.68632) (xy 157.981298 -315.729897) (xy 157.996882 -315.776578) (xy 158.004777 -315.825155)
			(xy 158.005272 -315.849762) (xy 158.34412 -315.849762) (xy 158.34808 -315.800708) (xy 158.359857 -315.752924)
			(xy 158.379148 -315.707648) (xy 158.405451 -315.666052) (xy 158.438086 -315.629215) (xy 158.476207 -315.59809)
			(xy 158.518828 -315.573483) (xy 158.564844 -315.556031) (xy 158.613063 -315.546187) (xy 158.662238 -315.544206)
			(xy 158.711093 -315.550138) (xy 158.758364 -315.56383) (xy 158.802826 -315.584928) (xy 158.843329 -315.612884)
			(xy 158.878822 -315.646976) (xy 158.908387 -315.68632) (xy 158.931258 -315.729897) (xy 158.946842 -315.776578)
			(xy 158.954737 -315.825155) (xy 158.955232 -315.849762) (xy 159.29408 -315.849762) (xy 159.29804 -315.800708)
			(xy 159.309817 -315.752924) (xy 159.329108 -315.707648) (xy 159.355411 -315.666052) (xy 159.388046 -315.629215)
			(xy 159.426167 -315.59809) (xy 159.468788 -315.573483) (xy 159.514804 -315.556031) (xy 159.563023 -315.546187)
			(xy 159.612198 -315.544206) (xy 159.661053 -315.550138) (xy 159.708324 -315.56383) (xy 159.752786 -315.584928)
			(xy 159.793289 -315.612884) (xy 159.828782 -315.646976) (xy 159.858347 -315.68632) (xy 159.881218 -315.729897)
			(xy 159.896802 -315.776578) (xy 159.904697 -315.825155) (xy 159.905192 -315.849762) (xy 160.24404 -315.849762)
			(xy 160.248 -315.800708) (xy 160.259777 -315.752924) (xy 160.279068 -315.707648) (xy 160.305371 -315.666052)
			(xy 160.338006 -315.629215) (xy 160.376127 -315.59809) (xy 160.418748 -315.573483) (xy 160.464764 -315.556031)
			(xy 160.512983 -315.546187) (xy 160.562158 -315.544206) (xy 160.611013 -315.550138) (xy 160.658284 -315.56383)
			(xy 160.702746 -315.584928) (xy 160.743249 -315.612884) (xy 160.778742 -315.646976) (xy 160.808307 -315.68632)
			(xy 160.831178 -315.729897) (xy 160.846762 -315.776578) (xy 160.854657 -315.825155) (xy 160.855152 -315.849762)
			(xy 161.194254 -315.849762) (xy 161.198214 -315.800708) (xy 161.209991 -315.752924) (xy 161.229282 -315.707648)
			(xy 161.255585 -315.666052) (xy 161.28822 -315.629215) (xy 161.326341 -315.59809) (xy 161.368962 -315.573483)
			(xy 161.414978 -315.556031) (xy 161.463197 -315.546187) (xy 161.512372 -315.544206) (xy 161.561227 -315.550138)
			(xy 161.608498 -315.56383) (xy 161.65296 -315.584928) (xy 161.693463 -315.612884) (xy 161.728956 -315.646976)
			(xy 161.758521 -315.68632) (xy 161.781392 -315.729897) (xy 161.796976 -315.776578) (xy 161.804871 -315.825155)
			(xy 161.805366 -315.849762) (xy 161.804871 -315.874369) (xy 161.796976 -315.922946) (xy 161.781392 -315.969627)
			(xy 161.758521 -316.013204) (xy 161.728956 -316.052548) (xy 161.693463 -316.08664) (xy 161.65296 -316.114596)
			(xy 161.608498 -316.135694) (xy 161.561227 -316.149386) (xy 161.512372 -316.155318) (xy 161.463197 -316.153337)
			(xy 161.414978 -316.143493) (xy 161.368962 -316.126041) (xy 161.326341 -316.101434) (xy 161.28822 -316.070309)
			(xy 161.255585 -316.033472) (xy 161.229282 -315.991876) (xy 161.209991 -315.9466) (xy 161.198214 -315.898816)
			(xy 161.194254 -315.849762) (xy 160.855152 -315.849762) (xy 160.854657 -315.874369) (xy 160.846762 -315.922946)
			(xy 160.831178 -315.969627) (xy 160.808307 -316.013204) (xy 160.778742 -316.052548) (xy 160.743249 -316.08664)
			(xy 160.702746 -316.114596) (xy 160.658284 -316.135694) (xy 160.611013 -316.149386) (xy 160.562158 -316.155318)
			(xy 160.512983 -316.153337) (xy 160.464764 -316.143493) (xy 160.418748 -316.126041) (xy 160.376127 -316.101434)
			(xy 160.338006 -316.070309) (xy 160.305371 -316.033472) (xy 160.279068 -315.991876) (xy 160.259777 -315.9466)
			(xy 160.248 -315.898816) (xy 160.24404 -315.849762) (xy 159.905192 -315.849762) (xy 159.904697 -315.874369)
			(xy 159.896802 -315.922946) (xy 159.881218 -315.969627) (xy 159.858347 -316.013204) (xy 159.828782 -316.052548)
			(xy 159.793289 -316.08664) (xy 159.752786 -316.114596) (xy 159.708324 -316.135694) (xy 159.661053 -316.149386)
			(xy 159.612198 -316.155318) (xy 159.563023 -316.153337) (xy 159.514804 -316.143493) (xy 159.468788 -316.126041)
			(xy 159.426167 -316.101434) (xy 159.388046 -316.070309) (xy 159.355411 -316.033472) (xy 159.329108 -315.991876)
			(xy 159.309817 -315.9466) (xy 159.29804 -315.898816) (xy 159.29408 -315.849762) (xy 158.955232 -315.849762)
			(xy 158.954737 -315.874369) (xy 158.946842 -315.922946) (xy 158.931258 -315.969627) (xy 158.908387 -316.013204)
			(xy 158.878822 -316.052548) (xy 158.843329 -316.08664) (xy 158.802826 -316.114596) (xy 158.758364 -316.135694)
			(xy 158.711093 -316.149386) (xy 158.662238 -316.155318) (xy 158.613063 -316.153337) (xy 158.564844 -316.143493)
			(xy 158.518828 -316.126041) (xy 158.476207 -316.101434) (xy 158.438086 -316.070309) (xy 158.405451 -316.033472)
			(xy 158.379148 -315.991876) (xy 158.359857 -315.9466) (xy 158.34808 -315.898816) (xy 158.34412 -315.849762)
			(xy 158.005272 -315.849762) (xy 158.004777 -315.874369) (xy 157.996882 -315.922946) (xy 157.981298 -315.969627)
			(xy 157.958427 -316.013204) (xy 157.928862 -316.052548) (xy 157.893369 -316.08664) (xy 157.852866 -316.114596)
			(xy 157.808404 -316.135694) (xy 157.761133 -316.149386) (xy 157.712278 -316.155318) (xy 157.663103 -316.153337)
			(xy 157.614884 -316.143493) (xy 157.568868 -316.126041) (xy 157.526247 -316.101434) (xy 157.488126 -316.070309)
			(xy 157.455491 -316.033472) (xy 157.429188 -315.991876) (xy 157.409897 -315.9466) (xy 157.39812 -315.898816)
			(xy 157.39416 -315.849762) (xy 157.055312 -315.849762) (xy 157.054817 -315.874369) (xy 157.046922 -315.922946)
			(xy 157.031338 -315.969627) (xy 157.008467 -316.013204) (xy 156.978902 -316.052548) (xy 156.943409 -316.08664)
			(xy 156.902906 -316.114596) (xy 156.858444 -316.135694) (xy 156.811173 -316.149386) (xy 156.762318 -316.155318)
			(xy 156.713143 -316.153337) (xy 156.664924 -316.143493) (xy 156.618908 -316.126041) (xy 156.576287 -316.101434)
			(xy 156.538166 -316.070309) (xy 156.505531 -316.033472) (xy 156.479228 -315.991876) (xy 156.459937 -315.9466)
			(xy 156.44816 -315.898816) (xy 156.4442 -315.849762) (xy 156.105352 -315.849762) (xy 156.104857 -315.874369)
			(xy 156.096962 -315.922946) (xy 156.081378 -315.969627) (xy 156.058507 -316.013204) (xy 156.028942 -316.052548)
			(xy 155.993449 -316.08664) (xy 155.952946 -316.114596) (xy 155.908484 -316.135694) (xy 155.861213 -316.149386)
			(xy 155.812358 -316.155318) (xy 155.763183 -316.153337) (xy 155.714964 -316.143493) (xy 155.668948 -316.126041)
			(xy 155.626327 -316.101434) (xy 155.588206 -316.070309) (xy 155.555571 -316.033472) (xy 155.529268 -315.991876)
			(xy 155.509977 -315.9466) (xy 155.4982 -315.898816) (xy 155.49424 -315.849762) (xy 155.155392 -315.849762)
			(xy 155.154897 -315.874369) (xy 155.147002 -315.922946) (xy 155.131418 -315.969627) (xy 155.108547 -316.013204)
			(xy 155.078982 -316.052548) (xy 155.043489 -316.08664) (xy 155.002986 -316.114596) (xy 154.958524 -316.135694)
			(xy 154.911253 -316.149386) (xy 154.862398 -316.155318) (xy 154.813223 -316.153337) (xy 154.765004 -316.143493)
			(xy 154.718988 -316.126041) (xy 154.676367 -316.101434) (xy 154.638246 -316.070309) (xy 154.605611 -316.033472)
			(xy 154.579308 -315.991876) (xy 154.560017 -315.9466) (xy 154.54824 -315.898816) (xy 154.54428 -315.849762)
			(xy 154.205178 -315.849762) (xy 154.204683 -315.874369) (xy 154.196788 -315.922946) (xy 154.181204 -315.969627)
			(xy 154.158333 -316.013204) (xy 154.128768 -316.052548) (xy 154.093275 -316.08664) (xy 154.052772 -316.114596)
			(xy 154.00831 -316.135694) (xy 153.961039 -316.149386) (xy 153.912184 -316.155318) (xy 153.863009 -316.153337)
			(xy 153.81479 -316.143493) (xy 153.768774 -316.126041) (xy 153.726153 -316.101434) (xy 153.688032 -316.070309)
			(xy 153.655397 -316.033472) (xy 153.629094 -315.991876) (xy 153.609803 -315.9466) (xy 153.598026 -315.898816)
			(xy 153.594066 -315.849762) (xy 153.255218 -315.849762) (xy 153.254723 -315.874369) (xy 153.246828 -315.922946)
			(xy 153.231244 -315.969627) (xy 153.208373 -316.013204) (xy 153.178808 -316.052548) (xy 153.143315 -316.08664)
			(xy 153.102812 -316.114596) (xy 153.05835 -316.135694) (xy 153.011079 -316.149386) (xy 152.962224 -316.155318)
			(xy 152.913049 -316.153337) (xy 152.86483 -316.143493) (xy 152.818814 -316.126041) (xy 152.776193 -316.101434)
			(xy 152.738072 -316.070309) (xy 152.705437 -316.033472) (xy 152.679134 -315.991876) (xy 152.659843 -315.9466)
			(xy 152.648066 -315.898816) (xy 152.644106 -315.849762) (xy 130.885317 -315.849762) (xy 130.873423 -315.857021)
			(xy 130.822094 -315.878833) (xy 130.768137 -315.892939) (xy 130.7127 -315.899039) (xy 130.656966 -315.897002)
			(xy 130.602123 -315.886872) (xy 130.549339 -315.868865) (xy 130.499739 -315.843364) (xy 130.454381 -315.810913)
			(xy 130.414232 -315.772204) (xy 130.380146 -315.728061) (xy 130.35285 -315.679426) (xy 130.332927 -315.627335)
			(xy 130.320801 -315.572898) (xy 130.31673 -315.517276) (xy 130.064256 -315.517276) (xy 130.063747 -315.545162)
			(xy 130.055627 -315.600338) (xy 130.039559 -315.653745) (xy 130.015887 -315.704242) (xy 129.985114 -315.750755)
			(xy 129.947897 -315.792292) (xy 129.905029 -315.827967) (xy 129.857423 -315.857021) (xy 129.806094 -315.878833)
			(xy 129.752137 -315.892939) (xy 129.6967 -315.899039) (xy 129.640966 -315.897002) (xy 129.586123 -315.886872)
			(xy 129.533339 -315.868865) (xy 129.483739 -315.843364) (xy 129.438381 -315.810913) (xy 129.398232 -315.772204)
			(xy 129.364146 -315.728061) (xy 129.33685 -315.679426) (xy 129.316927 -315.627335) (xy 129.304801 -315.572898)
			(xy 129.30073 -315.517276) (xy 129.048256 -315.517276) (xy 129.047747 -315.545162) (xy 129.039627 -315.600338)
			(xy 129.023559 -315.653745) (xy 128.999887 -315.704242) (xy 128.969114 -315.750755) (xy 128.931897 -315.792292)
			(xy 128.889029 -315.827967) (xy 128.841423 -315.857021) (xy 128.790094 -315.878833) (xy 128.736137 -315.892939)
			(xy 128.6807 -315.899039) (xy 128.624966 -315.897002) (xy 128.570123 -315.886872) (xy 128.517339 -315.868865)
			(xy 128.467739 -315.843364) (xy 128.422381 -315.810913) (xy 128.382232 -315.772204) (xy 128.348146 -315.728061)
			(xy 128.32085 -315.679426) (xy 128.300927 -315.627335) (xy 128.288801 -315.572898) (xy 128.28473 -315.517276)
			(xy 128.032256 -315.517276) (xy 128.031747 -315.545162) (xy 128.023627 -315.600338) (xy 128.007559 -315.653745)
			(xy 127.983887 -315.704242) (xy 127.953114 -315.750755) (xy 127.915897 -315.792292) (xy 127.873029 -315.827967)
			(xy 127.825423 -315.857021) (xy 127.774094 -315.878833) (xy 127.720137 -315.892939) (xy 127.6647 -315.899039)
			(xy 127.608966 -315.897002) (xy 127.554123 -315.886872) (xy 127.501339 -315.868865) (xy 127.451739 -315.843364)
			(xy 127.406381 -315.810913) (xy 127.366232 -315.772204) (xy 127.332146 -315.728061) (xy 127.30485 -315.679426)
			(xy 127.284927 -315.627335) (xy 127.272801 -315.572898) (xy 127.26873 -315.517276) (xy 127.016256 -315.517276)
			(xy 127.015747 -315.545162) (xy 127.007627 -315.600338) (xy 126.991559 -315.653745) (xy 126.967887 -315.704242)
			(xy 126.937114 -315.750755) (xy 126.899897 -315.792292) (xy 126.857029 -315.827967) (xy 126.809423 -315.857021)
			(xy 126.758094 -315.878833) (xy 126.704137 -315.892939) (xy 126.6487 -315.899039) (xy 126.592966 -315.897002)
			(xy 126.538123 -315.886872) (xy 126.485339 -315.868865) (xy 126.435739 -315.843364) (xy 126.390381 -315.810913)
			(xy 126.350232 -315.772204) (xy 126.316146 -315.728061) (xy 126.28885 -315.679426) (xy 126.268927 -315.627335)
			(xy 126.256801 -315.572898) (xy 126.25273 -315.517276) (xy 126.000256 -315.517276) (xy 125.999747 -315.545162)
			(xy 125.991627 -315.600338) (xy 125.975559 -315.653745) (xy 125.951887 -315.704242) (xy 125.921114 -315.750755)
			(xy 125.883897 -315.792292) (xy 125.841029 -315.827967) (xy 125.793423 -315.857021) (xy 125.742094 -315.878833)
			(xy 125.688137 -315.892939) (xy 125.6327 -315.899039) (xy 125.576966 -315.897002) (xy 125.522123 -315.886872)
			(xy 125.469339 -315.868865) (xy 125.419739 -315.843364) (xy 125.374381 -315.810913) (xy 125.334232 -315.772204)
			(xy 125.300146 -315.728061) (xy 125.27285 -315.679426) (xy 125.252927 -315.627335) (xy 125.240801 -315.572898)
			(xy 125.23673 -315.517276) (xy 119.631206 -315.517276) (xy 119.631206 -316.533276) (xy 125.23673 -316.533276)
			(xy 125.240801 -316.477654) (xy 125.252927 -316.423217) (xy 125.27285 -316.371126) (xy 125.300146 -316.322491)
			(xy 125.334232 -316.278348) (xy 125.374381 -316.239639) (xy 125.419739 -316.207188) (xy 125.469339 -316.181687)
			(xy 125.522123 -316.16368) (xy 125.576966 -316.15355) (xy 125.6327 -316.151513) (xy 125.688137 -316.157613)
			(xy 125.742094 -316.171719) (xy 125.793423 -316.193531) (xy 125.841029 -316.222585) (xy 125.883897 -316.25826)
			(xy 125.921114 -316.299797) (xy 125.951887 -316.34631) (xy 125.975559 -316.396807) (xy 125.991627 -316.450214)
			(xy 125.999747 -316.50539) (xy 126.000256 -316.533276) (xy 126.25273 -316.533276) (xy 126.256801 -316.477654)
			(xy 126.268927 -316.423217) (xy 126.28885 -316.371126) (xy 126.316146 -316.322491) (xy 126.350232 -316.278348)
			(xy 126.390381 -316.239639) (xy 126.435739 -316.207188) (xy 126.485339 -316.181687) (xy 126.538123 -316.16368)
			(xy 126.592966 -316.15355) (xy 126.6487 -316.151513) (xy 126.704137 -316.157613) (xy 126.758094 -316.171719)
			(xy 126.809423 -316.193531) (xy 126.857029 -316.222585) (xy 126.899897 -316.25826) (xy 126.937114 -316.299797)
			(xy 126.967887 -316.34631) (xy 126.991559 -316.396807) (xy 127.007627 -316.450214) (xy 127.015747 -316.50539)
			(xy 127.016256 -316.533276) (xy 127.26873 -316.533276) (xy 127.272801 -316.477654) (xy 127.284927 -316.423217)
			(xy 127.30485 -316.371126) (xy 127.332146 -316.322491) (xy 127.366232 -316.278348) (xy 127.406381 -316.239639)
			(xy 127.451739 -316.207188) (xy 127.501339 -316.181687) (xy 127.554123 -316.16368) (xy 127.608966 -316.15355)
			(xy 127.6647 -316.151513) (xy 127.720137 -316.157613) (xy 127.774094 -316.171719) (xy 127.825423 -316.193531)
			(xy 127.873029 -316.222585) (xy 127.915897 -316.25826) (xy 127.953114 -316.299797) (xy 127.983887 -316.34631)
			(xy 128.007559 -316.396807) (xy 128.023627 -316.450214) (xy 128.031747 -316.50539) (xy 128.032256 -316.533276)
			(xy 128.28473 -316.533276) (xy 128.288801 -316.477654) (xy 128.300927 -316.423217) (xy 128.32085 -316.371126)
			(xy 128.348146 -316.322491) (xy 128.382232 -316.278348) (xy 128.422381 -316.239639) (xy 128.467739 -316.207188)
			(xy 128.517339 -316.181687) (xy 128.570123 -316.16368) (xy 128.624966 -316.15355) (xy 128.6807 -316.151513)
			(xy 128.736137 -316.157613) (xy 128.790094 -316.171719) (xy 128.841423 -316.193531) (xy 128.889029 -316.222585)
			(xy 128.931897 -316.25826) (xy 128.969114 -316.299797) (xy 128.999887 -316.34631) (xy 129.023559 -316.396807)
			(xy 129.039627 -316.450214) (xy 129.047747 -316.50539) (xy 129.048256 -316.533276) (xy 129.30073 -316.533276)
			(xy 129.304801 -316.477654) (xy 129.316927 -316.423217) (xy 129.33685 -316.371126) (xy 129.364146 -316.322491)
			(xy 129.398232 -316.278348) (xy 129.438381 -316.239639) (xy 129.483739 -316.207188) (xy 129.533339 -316.181687)
			(xy 129.586123 -316.16368) (xy 129.640966 -316.15355) (xy 129.6967 -316.151513) (xy 129.752137 -316.157613)
			(xy 129.806094 -316.171719) (xy 129.857423 -316.193531) (xy 129.905029 -316.222585) (xy 129.947897 -316.25826)
			(xy 129.985114 -316.299797) (xy 130.015887 -316.34631) (xy 130.039559 -316.396807) (xy 130.055627 -316.450214)
			(xy 130.063747 -316.50539) (xy 130.064256 -316.533276) (xy 130.31673 -316.533276) (xy 130.320801 -316.477654)
			(xy 130.332927 -316.423217) (xy 130.35285 -316.371126) (xy 130.380146 -316.322491) (xy 130.414232 -316.278348)
			(xy 130.454381 -316.239639) (xy 130.499739 -316.207188) (xy 130.549339 -316.181687) (xy 130.602123 -316.16368)
			(xy 130.656966 -316.15355) (xy 130.7127 -316.151513) (xy 130.768137 -316.157613) (xy 130.822094 -316.171719)
			(xy 130.873423 -316.193531) (xy 130.921029 -316.222585) (xy 130.963897 -316.25826) (xy 131.001114 -316.299797)
			(xy 131.031887 -316.34631) (xy 131.055559 -316.396807) (xy 131.071627 -316.450214) (xy 131.079747 -316.50539)
			(xy 131.080256 -316.533276) (xy 131.079747 -316.561162) (xy 131.071627 -316.616338) (xy 131.055559 -316.669745)
			(xy 131.031887 -316.720242) (xy 131.001114 -316.766755) (xy 130.963897 -316.808292) (xy 130.921029 -316.843967)
			(xy 130.873423 -316.873021) (xy 130.822094 -316.894833) (xy 130.768137 -316.908939) (xy 130.7127 -316.915039)
			(xy 130.656966 -316.913002) (xy 130.602123 -316.902872) (xy 130.549339 -316.884865) (xy 130.499739 -316.859364)
			(xy 130.454381 -316.826913) (xy 130.414232 -316.788204) (xy 130.380146 -316.744061) (xy 130.35285 -316.695426)
			(xy 130.332927 -316.643335) (xy 130.320801 -316.588898) (xy 130.31673 -316.533276) (xy 130.064256 -316.533276)
			(xy 130.063747 -316.561162) (xy 130.055627 -316.616338) (xy 130.039559 -316.669745) (xy 130.015887 -316.720242)
			(xy 129.985114 -316.766755) (xy 129.947897 -316.808292) (xy 129.905029 -316.843967) (xy 129.857423 -316.873021)
			(xy 129.806094 -316.894833) (xy 129.752137 -316.908939) (xy 129.6967 -316.915039) (xy 129.640966 -316.913002)
			(xy 129.586123 -316.902872) (xy 129.533339 -316.884865) (xy 129.483739 -316.859364) (xy 129.438381 -316.826913)
			(xy 129.398232 -316.788204) (xy 129.364146 -316.744061) (xy 129.33685 -316.695426) (xy 129.316927 -316.643335)
			(xy 129.304801 -316.588898) (xy 129.30073 -316.533276) (xy 129.048256 -316.533276) (xy 129.047747 -316.561162)
			(xy 129.039627 -316.616338) (xy 129.023559 -316.669745) (xy 128.999887 -316.720242) (xy 128.969114 -316.766755)
			(xy 128.931897 -316.808292) (xy 128.889029 -316.843967) (xy 128.841423 -316.873021) (xy 128.790094 -316.894833)
			(xy 128.736137 -316.908939) (xy 128.6807 -316.915039) (xy 128.624966 -316.913002) (xy 128.570123 -316.902872)
			(xy 128.517339 -316.884865) (xy 128.467739 -316.859364) (xy 128.422381 -316.826913) (xy 128.382232 -316.788204)
			(xy 128.348146 -316.744061) (xy 128.32085 -316.695426) (xy 128.300927 -316.643335) (xy 128.288801 -316.588898)
			(xy 128.28473 -316.533276) (xy 128.032256 -316.533276) (xy 128.031747 -316.561162) (xy 128.023627 -316.616338)
			(xy 128.007559 -316.669745) (xy 127.983887 -316.720242) (xy 127.953114 -316.766755) (xy 127.915897 -316.808292)
			(xy 127.873029 -316.843967) (xy 127.825423 -316.873021) (xy 127.774094 -316.894833) (xy 127.720137 -316.908939)
			(xy 127.6647 -316.915039) (xy 127.608966 -316.913002) (xy 127.554123 -316.902872) (xy 127.501339 -316.884865)
			(xy 127.451739 -316.859364) (xy 127.406381 -316.826913) (xy 127.366232 -316.788204) (xy 127.332146 -316.744061)
			(xy 127.30485 -316.695426) (xy 127.284927 -316.643335) (xy 127.272801 -316.588898) (xy 127.26873 -316.533276)
			(xy 127.016256 -316.533276) (xy 127.015747 -316.561162) (xy 127.007627 -316.616338) (xy 126.991559 -316.669745)
			(xy 126.967887 -316.720242) (xy 126.937114 -316.766755) (xy 126.899897 -316.808292) (xy 126.857029 -316.843967)
			(xy 126.809423 -316.873021) (xy 126.758094 -316.894833) (xy 126.704137 -316.908939) (xy 126.6487 -316.915039)
			(xy 126.592966 -316.913002) (xy 126.538123 -316.902872) (xy 126.485339 -316.884865) (xy 126.435739 -316.859364)
			(xy 126.390381 -316.826913) (xy 126.350232 -316.788204) (xy 126.316146 -316.744061) (xy 126.28885 -316.695426)
			(xy 126.268927 -316.643335) (xy 126.256801 -316.588898) (xy 126.25273 -316.533276) (xy 126.000256 -316.533276)
			(xy 125.999747 -316.561162) (xy 125.991627 -316.616338) (xy 125.975559 -316.669745) (xy 125.951887 -316.720242)
			(xy 125.921114 -316.766755) (xy 125.883897 -316.808292) (xy 125.841029 -316.843967) (xy 125.793423 -316.873021)
			(xy 125.742094 -316.894833) (xy 125.688137 -316.908939) (xy 125.6327 -316.915039) (xy 125.576966 -316.913002)
			(xy 125.522123 -316.902872) (xy 125.469339 -316.884865) (xy 125.419739 -316.859364) (xy 125.374381 -316.826913)
			(xy 125.334232 -316.788204) (xy 125.300146 -316.744061) (xy 125.27285 -316.695426) (xy 125.252927 -316.643335)
			(xy 125.240801 -316.588898) (xy 125.23673 -316.533276) (xy 119.631206 -316.533276) (xy 119.631206 -320.900044)
			(xy 140.998709 -320.900044) (xy 141.002715 -320.704989) (xy 141.014725 -320.510263) (xy 141.03472 -320.316194)
			(xy 141.062665 -320.12311) (xy 141.098514 -319.931335) (xy 141.142206 -319.741195) (xy 141.193667 -319.553008)
			(xy 141.252811 -319.367093) (xy 141.319538 -319.183762) (xy 141.393735 -319.003326) (xy 141.475277 -318.826088)
			(xy 141.564028 -318.652347) (xy 141.659836 -318.482396) (xy 141.762541 -318.316522) (xy 141.871969 -318.155004)
			(xy 141.987936 -317.998115) (xy 142.110247 -317.84612) (xy 142.238694 -317.699274) (xy 142.373062 -317.557825)
			(xy 142.513124 -317.422012) (xy 142.658643 -317.292063) (xy 142.809375 -317.168199) (xy 142.965065 -317.050627)
			(xy 143.125451 -316.939547) (xy 143.290262 -316.835144) (xy 143.45922 -316.737596) (xy 143.632041 -316.647067)
			(xy 143.808433 -316.563709) (xy 143.988098 -316.487663) (xy 144.170733 -316.419058) (xy 144.356032 -316.358008)
			(xy 144.54368 -316.304618) (xy 144.733362 -316.258976) (xy 144.924759 -316.22116) (xy 145.117546 -316.191234)
			(xy 145.311399 -316.169248) (xy 145.505992 -316.155239) (xy 145.700995 -316.149231) (xy 145.896081 -316.151234)
			(xy 146.09092 -316.161245) (xy 146.285184 -316.179246) (xy 146.478545 -316.205208) (xy 146.670678 -316.239086)
			(xy 146.861257 -316.280823) (xy 147.049962 -316.33035) (xy 147.236475 -316.387582) (xy 147.420481 -316.452423)
			(xy 147.601669 -316.524764) (xy 147.779735 -316.604482) (xy 147.954378 -316.691444) (xy 148.125304 -316.785503)
			(xy 148.148384 -316.799468) (xy 151.693638 -316.799468) (xy 151.697598 -316.750414) (xy 151.709375 -316.70263)
			(xy 151.728666 -316.657354) (xy 151.754969 -316.615758) (xy 151.787604 -316.578921) (xy 151.825725 -316.547796)
			(xy 151.868346 -316.523189) (xy 151.914362 -316.505737) (xy 151.962581 -316.495893) (xy 152.011756 -316.493912)
			(xy 152.060611 -316.499844) (xy 152.107882 -316.513536) (xy 152.152344 -316.534634) (xy 152.192847 -316.56259)
			(xy 152.22834 -316.596682) (xy 152.257905 -316.636026) (xy 152.280776 -316.679603) (xy 152.29636 -316.726284)
			(xy 152.304255 -316.774861) (xy 152.30475 -316.799468) (xy 152.304745 -316.799722) (xy 152.644106 -316.799722)
			(xy 152.648066 -316.750668) (xy 152.659843 -316.702884) (xy 152.679134 -316.657608) (xy 152.705437 -316.616012)
			(xy 152.738072 -316.579175) (xy 152.776193 -316.54805) (xy 152.818814 -316.523443) (xy 152.86483 -316.505991)
			(xy 152.913049 -316.496147) (xy 152.962224 -316.494166) (xy 153.011079 -316.500098) (xy 153.05835 -316.51379)
			(xy 153.102812 -316.534888) (xy 153.143315 -316.562844) (xy 153.178808 -316.596936) (xy 153.208373 -316.63628)
			(xy 153.231244 -316.679857) (xy 153.246828 -316.726538) (xy 153.254723 -316.775115) (xy 153.255218 -316.799722)
			(xy 153.594066 -316.799722) (xy 153.598026 -316.750668) (xy 153.609803 -316.702884) (xy 153.629094 -316.657608)
			(xy 153.655397 -316.616012) (xy 153.688032 -316.579175) (xy 153.726153 -316.54805) (xy 153.768774 -316.523443)
			(xy 153.81479 -316.505991) (xy 153.863009 -316.496147) (xy 153.912184 -316.494166) (xy 153.961039 -316.500098)
			(xy 154.00831 -316.51379) (xy 154.052772 -316.534888) (xy 154.093275 -316.562844) (xy 154.128768 -316.596936)
			(xy 154.158333 -316.63628) (xy 154.181204 -316.679857) (xy 154.196788 -316.726538) (xy 154.204683 -316.775115)
			(xy 154.205178 -316.799722) (xy 154.54428 -316.799722) (xy 154.54824 -316.750668) (xy 154.560017 -316.702884)
			(xy 154.579308 -316.657608) (xy 154.605611 -316.616012) (xy 154.638246 -316.579175) (xy 154.676367 -316.54805)
			(xy 154.718988 -316.523443) (xy 154.765004 -316.505991) (xy 154.813223 -316.496147) (xy 154.862398 -316.494166)
			(xy 154.911253 -316.500098) (xy 154.958524 -316.51379) (xy 155.002986 -316.534888) (xy 155.043489 -316.562844)
			(xy 155.078982 -316.596936) (xy 155.108547 -316.63628) (xy 155.131418 -316.679857) (xy 155.147002 -316.726538)
			(xy 155.154897 -316.775115) (xy 155.155392 -316.799722) (xy 155.49424 -316.799722) (xy 155.4982 -316.750668)
			(xy 155.509977 -316.702884) (xy 155.529268 -316.657608) (xy 155.555571 -316.616012) (xy 155.588206 -316.579175)
			(xy 155.626327 -316.54805) (xy 155.668948 -316.523443) (xy 155.714964 -316.505991) (xy 155.763183 -316.496147)
			(xy 155.812358 -316.494166) (xy 155.861213 -316.500098) (xy 155.908484 -316.51379) (xy 155.952946 -316.534888)
			(xy 155.993449 -316.562844) (xy 156.028942 -316.596936) (xy 156.058507 -316.63628) (xy 156.081378 -316.679857)
			(xy 156.096962 -316.726538) (xy 156.104857 -316.775115) (xy 156.105352 -316.799722) (xy 156.4442 -316.799722)
			(xy 156.44816 -316.750668) (xy 156.459937 -316.702884) (xy 156.479228 -316.657608) (xy 156.505531 -316.616012)
			(xy 156.538166 -316.579175) (xy 156.576287 -316.54805) (xy 156.618908 -316.523443) (xy 156.664924 -316.505991)
			(xy 156.713143 -316.496147) (xy 156.762318 -316.494166) (xy 156.811173 -316.500098) (xy 156.858444 -316.51379)
			(xy 156.902906 -316.534888) (xy 156.943409 -316.562844) (xy 156.978902 -316.596936) (xy 157.008467 -316.63628)
			(xy 157.031338 -316.679857) (xy 157.046922 -316.726538) (xy 157.054817 -316.775115) (xy 157.055312 -316.799722)
			(xy 157.39416 -316.799722) (xy 157.39812 -316.750668) (xy 157.409897 -316.702884) (xy 157.429188 -316.657608)
			(xy 157.455491 -316.616012) (xy 157.488126 -316.579175) (xy 157.526247 -316.54805) (xy 157.568868 -316.523443)
			(xy 157.614884 -316.505991) (xy 157.663103 -316.496147) (xy 157.712278 -316.494166) (xy 157.761133 -316.500098)
			(xy 157.808404 -316.51379) (xy 157.852866 -316.534888) (xy 157.893369 -316.562844) (xy 157.928862 -316.596936)
			(xy 157.958427 -316.63628) (xy 157.981298 -316.679857) (xy 157.996882 -316.726538) (xy 158.004777 -316.775115)
			(xy 158.005272 -316.799722) (xy 158.34412 -316.799722) (xy 158.34808 -316.750668) (xy 158.359857 -316.702884)
			(xy 158.379148 -316.657608) (xy 158.405451 -316.616012) (xy 158.438086 -316.579175) (xy 158.476207 -316.54805)
			(xy 158.518828 -316.523443) (xy 158.564844 -316.505991) (xy 158.613063 -316.496147) (xy 158.662238 -316.494166)
			(xy 158.711093 -316.500098) (xy 158.758364 -316.51379) (xy 158.802826 -316.534888) (xy 158.843329 -316.562844)
			(xy 158.878822 -316.596936) (xy 158.908387 -316.63628) (xy 158.931258 -316.679857) (xy 158.946842 -316.726538)
			(xy 158.954737 -316.775115) (xy 158.955232 -316.799722) (xy 159.29408 -316.799722) (xy 159.29804 -316.750668)
			(xy 159.309817 -316.702884) (xy 159.329108 -316.657608) (xy 159.355411 -316.616012) (xy 159.388046 -316.579175)
			(xy 159.426167 -316.54805) (xy 159.468788 -316.523443) (xy 159.514804 -316.505991) (xy 159.563023 -316.496147)
			(xy 159.612198 -316.494166) (xy 159.661053 -316.500098) (xy 159.708324 -316.51379) (xy 159.752786 -316.534888)
			(xy 159.793289 -316.562844) (xy 159.828782 -316.596936) (xy 159.858347 -316.63628) (xy 159.881218 -316.679857)
			(xy 159.896802 -316.726538) (xy 159.904697 -316.775115) (xy 159.905192 -316.799722) (xy 160.24404 -316.799722)
			(xy 160.248 -316.750668) (xy 160.259777 -316.702884) (xy 160.279068 -316.657608) (xy 160.305371 -316.616012)
			(xy 160.338006 -316.579175) (xy 160.376127 -316.54805) (xy 160.418748 -316.523443) (xy 160.464764 -316.505991)
			(xy 160.512983 -316.496147) (xy 160.562158 -316.494166) (xy 160.611013 -316.500098) (xy 160.658284 -316.51379)
			(xy 160.702746 -316.534888) (xy 160.743249 -316.562844) (xy 160.778742 -316.596936) (xy 160.808307 -316.63628)
			(xy 160.831178 -316.679857) (xy 160.846762 -316.726538) (xy 160.854657 -316.775115) (xy 160.855152 -316.799722)
			(xy 161.194254 -316.799722) (xy 161.198214 -316.750668) (xy 161.209991 -316.702884) (xy 161.229282 -316.657608)
			(xy 161.255585 -316.616012) (xy 161.28822 -316.579175) (xy 161.326341 -316.54805) (xy 161.368962 -316.523443)
			(xy 161.414978 -316.505991) (xy 161.463197 -316.496147) (xy 161.512372 -316.494166) (xy 161.561227 -316.500098)
			(xy 161.608498 -316.51379) (xy 161.65296 -316.534888) (xy 161.693463 -316.562844) (xy 161.728956 -316.596936)
			(xy 161.758521 -316.63628) (xy 161.781392 -316.679857) (xy 161.796976 -316.726538) (xy 161.804871 -316.775115)
			(xy 161.805366 -316.799722) (xy 161.804871 -316.824329) (xy 161.796976 -316.872906) (xy 161.781392 -316.919587)
			(xy 161.758521 -316.963164) (xy 161.728956 -317.002508) (xy 161.693463 -317.0366) (xy 161.65296 -317.064556)
			(xy 161.608498 -317.085654) (xy 161.561227 -317.099346) (xy 161.512372 -317.105278) (xy 161.463197 -317.103297)
			(xy 161.414978 -317.093453) (xy 161.368962 -317.076001) (xy 161.326341 -317.051394) (xy 161.28822 -317.020269)
			(xy 161.255585 -316.983432) (xy 161.229282 -316.941836) (xy 161.209991 -316.89656) (xy 161.198214 -316.848776)
			(xy 161.194254 -316.799722) (xy 160.855152 -316.799722) (xy 160.854657 -316.824329) (xy 160.846762 -316.872906)
			(xy 160.831178 -316.919587) (xy 160.808307 -316.963164) (xy 160.778742 -317.002508) (xy 160.743249 -317.0366)
			(xy 160.702746 -317.064556) (xy 160.658284 -317.085654) (xy 160.611013 -317.099346) (xy 160.562158 -317.105278)
			(xy 160.512983 -317.103297) (xy 160.464764 -317.093453) (xy 160.418748 -317.076001) (xy 160.376127 -317.051394)
			(xy 160.338006 -317.020269) (xy 160.305371 -316.983432) (xy 160.279068 -316.941836) (xy 160.259777 -316.89656)
			(xy 160.248 -316.848776) (xy 160.24404 -316.799722) (xy 159.905192 -316.799722) (xy 159.904697 -316.824329)
			(xy 159.896802 -316.872906) (xy 159.881218 -316.919587) (xy 159.858347 -316.963164) (xy 159.828782 -317.002508)
			(xy 159.793289 -317.0366) (xy 159.752786 -317.064556) (xy 159.708324 -317.085654) (xy 159.661053 -317.099346)
			(xy 159.612198 -317.105278) (xy 159.563023 -317.103297) (xy 159.514804 -317.093453) (xy 159.468788 -317.076001)
			(xy 159.426167 -317.051394) (xy 159.388046 -317.020269) (xy 159.355411 -316.983432) (xy 159.329108 -316.941836)
			(xy 159.309817 -316.89656) (xy 159.29804 -316.848776) (xy 159.29408 -316.799722) (xy 158.955232 -316.799722)
			(xy 158.954737 -316.824329) (xy 158.946842 -316.872906) (xy 158.931258 -316.919587) (xy 158.908387 -316.963164)
			(xy 158.878822 -317.002508) (xy 158.843329 -317.0366) (xy 158.802826 -317.064556) (xy 158.758364 -317.085654)
			(xy 158.711093 -317.099346) (xy 158.662238 -317.105278) (xy 158.613063 -317.103297) (xy 158.564844 -317.093453)
			(xy 158.518828 -317.076001) (xy 158.476207 -317.051394) (xy 158.438086 -317.020269) (xy 158.405451 -316.983432)
			(xy 158.379148 -316.941836) (xy 158.359857 -316.89656) (xy 158.34808 -316.848776) (xy 158.34412 -316.799722)
			(xy 158.005272 -316.799722) (xy 158.004777 -316.824329) (xy 157.996882 -316.872906) (xy 157.981298 -316.919587)
			(xy 157.958427 -316.963164) (xy 157.928862 -317.002508) (xy 157.893369 -317.0366) (xy 157.852866 -317.064556)
			(xy 157.808404 -317.085654) (xy 157.761133 -317.099346) (xy 157.712278 -317.105278) (xy 157.663103 -317.103297)
			(xy 157.614884 -317.093453) (xy 157.568868 -317.076001) (xy 157.526247 -317.051394) (xy 157.488126 -317.020269)
			(xy 157.455491 -316.983432) (xy 157.429188 -316.941836) (xy 157.409897 -316.89656) (xy 157.39812 -316.848776)
			(xy 157.39416 -316.799722) (xy 157.055312 -316.799722) (xy 157.054817 -316.824329) (xy 157.046922 -316.872906)
			(xy 157.031338 -316.919587) (xy 157.008467 -316.963164) (xy 156.978902 -317.002508) (xy 156.943409 -317.0366)
			(xy 156.902906 -317.064556) (xy 156.858444 -317.085654) (xy 156.811173 -317.099346) (xy 156.762318 -317.105278)
			(xy 156.713143 -317.103297) (xy 156.664924 -317.093453) (xy 156.618908 -317.076001) (xy 156.576287 -317.051394)
			(xy 156.538166 -317.020269) (xy 156.505531 -316.983432) (xy 156.479228 -316.941836) (xy 156.459937 -316.89656)
			(xy 156.44816 -316.848776) (xy 156.4442 -316.799722) (xy 156.105352 -316.799722) (xy 156.104857 -316.824329)
			(xy 156.096962 -316.872906) (xy 156.081378 -316.919587) (xy 156.058507 -316.963164) (xy 156.028942 -317.002508)
			(xy 155.993449 -317.0366) (xy 155.952946 -317.064556) (xy 155.908484 -317.085654) (xy 155.861213 -317.099346)
			(xy 155.812358 -317.105278) (xy 155.763183 -317.103297) (xy 155.714964 -317.093453) (xy 155.668948 -317.076001)
			(xy 155.626327 -317.051394) (xy 155.588206 -317.020269) (xy 155.555571 -316.983432) (xy 155.529268 -316.941836)
			(xy 155.509977 -316.89656) (xy 155.4982 -316.848776) (xy 155.49424 -316.799722) (xy 155.155392 -316.799722)
			(xy 155.154897 -316.824329) (xy 155.147002 -316.872906) (xy 155.131418 -316.919587) (xy 155.108547 -316.963164)
			(xy 155.078982 -317.002508) (xy 155.043489 -317.0366) (xy 155.002986 -317.064556) (xy 154.958524 -317.085654)
			(xy 154.911253 -317.099346) (xy 154.862398 -317.105278) (xy 154.813223 -317.103297) (xy 154.765004 -317.093453)
			(xy 154.718988 -317.076001) (xy 154.676367 -317.051394) (xy 154.638246 -317.020269) (xy 154.605611 -316.983432)
			(xy 154.579308 -316.941836) (xy 154.560017 -316.89656) (xy 154.54824 -316.848776) (xy 154.54428 -316.799722)
			(xy 154.205178 -316.799722) (xy 154.204683 -316.824329) (xy 154.196788 -316.872906) (xy 154.181204 -316.919587)
			(xy 154.158333 -316.963164) (xy 154.128768 -317.002508) (xy 154.093275 -317.0366) (xy 154.052772 -317.064556)
			(xy 154.00831 -317.085654) (xy 153.961039 -317.099346) (xy 153.912184 -317.105278) (xy 153.863009 -317.103297)
			(xy 153.81479 -317.093453) (xy 153.768774 -317.076001) (xy 153.726153 -317.051394) (xy 153.688032 -317.020269)
			(xy 153.655397 -316.983432) (xy 153.629094 -316.941836) (xy 153.609803 -316.89656) (xy 153.598026 -316.848776)
			(xy 153.594066 -316.799722) (xy 153.255218 -316.799722) (xy 153.254723 -316.824329) (xy 153.246828 -316.872906)
			(xy 153.231244 -316.919587) (xy 153.208373 -316.963164) (xy 153.178808 -317.002508) (xy 153.143315 -317.0366)
			(xy 153.102812 -317.064556) (xy 153.05835 -317.085654) (xy 153.011079 -317.099346) (xy 152.962224 -317.105278)
			(xy 152.913049 -317.103297) (xy 152.86483 -317.093453) (xy 152.818814 -317.076001) (xy 152.776193 -317.051394)
			(xy 152.738072 -317.020269) (xy 152.705437 -316.983432) (xy 152.679134 -316.941836) (xy 152.659843 -316.89656)
			(xy 152.648066 -316.848776) (xy 152.644106 -316.799722) (xy 152.304745 -316.799722) (xy 152.304255 -316.824075)
			(xy 152.29636 -316.872652) (xy 152.280776 -316.919333) (xy 152.257905 -316.96291) (xy 152.22834 -317.002254)
			(xy 152.192847 -317.036346) (xy 152.152344 -317.064302) (xy 152.107882 -317.0854) (xy 152.060611 -317.099092)
			(xy 152.011756 -317.105024) (xy 151.962581 -317.103043) (xy 151.914362 -317.093199) (xy 151.868346 -317.075747)
			(xy 151.825725 -317.05114) (xy 151.787604 -317.020015) (xy 151.754969 -316.983178) (xy 151.728666 -316.941582)
			(xy 151.709375 -316.896306) (xy 151.697598 -316.848522) (xy 151.693638 -316.799468) (xy 148.148384 -316.799468)
			(xy 148.292223 -316.886499) (xy 148.454856 -316.994264) (xy 148.612927 -317.108614) (xy 148.76617 -317.229357)
			(xy 148.914327 -317.356291) (xy 149.057148 -317.489199) (xy 149.194392 -317.627859) (xy 149.30568 -317.749936)
			(xy 152.644106 -317.749936) (xy 152.648066 -317.700882) (xy 152.659843 -317.653098) (xy 152.679134 -317.607822)
			(xy 152.705437 -317.566226) (xy 152.738072 -317.529389) (xy 152.776193 -317.498264) (xy 152.818814 -317.473657)
			(xy 152.86483 -317.456205) (xy 152.913049 -317.446361) (xy 152.962224 -317.44438) (xy 153.011079 -317.450312)
			(xy 153.05835 -317.464004) (xy 153.102812 -317.485102) (xy 153.143315 -317.513058) (xy 153.178808 -317.54715)
			(xy 153.208373 -317.586494) (xy 153.231244 -317.630071) (xy 153.246828 -317.676752) (xy 153.254723 -317.725329)
			(xy 153.255218 -317.749936) (xy 153.594066 -317.749936) (xy 153.598026 -317.700882) (xy 153.609803 -317.653098)
			(xy 153.629094 -317.607822) (xy 153.655397 -317.566226) (xy 153.688032 -317.529389) (xy 153.726153 -317.498264)
			(xy 153.768774 -317.473657) (xy 153.81479 -317.456205) (xy 153.863009 -317.446361) (xy 153.912184 -317.44438)
			(xy 153.961039 -317.450312) (xy 154.00831 -317.464004) (xy 154.052772 -317.485102) (xy 154.093275 -317.513058)
			(xy 154.128768 -317.54715) (xy 154.158333 -317.586494) (xy 154.181204 -317.630071) (xy 154.196788 -317.676752)
			(xy 154.204683 -317.725329) (xy 154.205178 -317.749936) (xy 154.54428 -317.749936) (xy 154.54824 -317.700882)
			(xy 154.560017 -317.653098) (xy 154.579308 -317.607822) (xy 154.605611 -317.566226) (xy 154.638246 -317.529389)
			(xy 154.676367 -317.498264) (xy 154.718988 -317.473657) (xy 154.765004 -317.456205) (xy 154.813223 -317.446361)
			(xy 154.862398 -317.44438) (xy 154.911253 -317.450312) (xy 154.958524 -317.464004) (xy 155.002986 -317.485102)
			(xy 155.043489 -317.513058) (xy 155.078982 -317.54715) (xy 155.108547 -317.586494) (xy 155.131418 -317.630071)
			(xy 155.147002 -317.676752) (xy 155.154897 -317.725329) (xy 155.155392 -317.749936) (xy 155.49424 -317.749936)
			(xy 155.4982 -317.700882) (xy 155.509977 -317.653098) (xy 155.529268 -317.607822) (xy 155.555571 -317.566226)
			(xy 155.588206 -317.529389) (xy 155.626327 -317.498264) (xy 155.668948 -317.473657) (xy 155.714964 -317.456205)
			(xy 155.763183 -317.446361) (xy 155.812358 -317.44438) (xy 155.861213 -317.450312) (xy 155.908484 -317.464004)
			(xy 155.952946 -317.485102) (xy 155.993449 -317.513058) (xy 156.028942 -317.54715) (xy 156.058507 -317.586494)
			(xy 156.081378 -317.630071) (xy 156.096962 -317.676752) (xy 156.104857 -317.725329) (xy 156.105352 -317.749936)
			(xy 156.4442 -317.749936) (xy 156.44816 -317.700882) (xy 156.459937 -317.653098) (xy 156.479228 -317.607822)
			(xy 156.505531 -317.566226) (xy 156.538166 -317.529389) (xy 156.576287 -317.498264) (xy 156.618908 -317.473657)
			(xy 156.664924 -317.456205) (xy 156.713143 -317.446361) (xy 156.762318 -317.44438) (xy 156.811173 -317.450312)
			(xy 156.858444 -317.464004) (xy 156.902906 -317.485102) (xy 156.943409 -317.513058) (xy 156.978902 -317.54715)
			(xy 157.008467 -317.586494) (xy 157.031338 -317.630071) (xy 157.046922 -317.676752) (xy 157.054817 -317.725329)
			(xy 157.055312 -317.749936) (xy 157.39416 -317.749936) (xy 157.39812 -317.700882) (xy 157.409897 -317.653098)
			(xy 157.429188 -317.607822) (xy 157.455491 -317.566226) (xy 157.488126 -317.529389) (xy 157.526247 -317.498264)
			(xy 157.568868 -317.473657) (xy 157.614884 -317.456205) (xy 157.663103 -317.446361) (xy 157.712278 -317.44438)
			(xy 157.761133 -317.450312) (xy 157.808404 -317.464004) (xy 157.852866 -317.485102) (xy 157.893369 -317.513058)
			(xy 157.928862 -317.54715) (xy 157.958427 -317.586494) (xy 157.981298 -317.630071) (xy 157.996882 -317.676752)
			(xy 158.004777 -317.725329) (xy 158.005272 -317.749936) (xy 158.34412 -317.749936) (xy 158.34808 -317.700882)
			(xy 158.359857 -317.653098) (xy 158.379148 -317.607822) (xy 158.405451 -317.566226) (xy 158.438086 -317.529389)
			(xy 158.476207 -317.498264) (xy 158.518828 -317.473657) (xy 158.564844 -317.456205) (xy 158.613063 -317.446361)
			(xy 158.662238 -317.44438) (xy 158.711093 -317.450312) (xy 158.758364 -317.464004) (xy 158.802826 -317.485102)
			(xy 158.843329 -317.513058) (xy 158.878822 -317.54715) (xy 158.908387 -317.586494) (xy 158.931258 -317.630071)
			(xy 158.946842 -317.676752) (xy 158.954737 -317.725329) (xy 158.955232 -317.749936) (xy 159.29408 -317.749936)
			(xy 159.29804 -317.700882) (xy 159.309817 -317.653098) (xy 159.329108 -317.607822) (xy 159.355411 -317.566226)
			(xy 159.388046 -317.529389) (xy 159.426167 -317.498264) (xy 159.468788 -317.473657) (xy 159.514804 -317.456205)
			(xy 159.563023 -317.446361) (xy 159.612198 -317.44438) (xy 159.661053 -317.450312) (xy 159.708324 -317.464004)
			(xy 159.752786 -317.485102) (xy 159.793289 -317.513058) (xy 159.828782 -317.54715) (xy 159.858347 -317.586494)
			(xy 159.881218 -317.630071) (xy 159.896802 -317.676752) (xy 159.904697 -317.725329) (xy 159.905192 -317.749936)
			(xy 160.24404 -317.749936) (xy 160.248 -317.700882) (xy 160.259777 -317.653098) (xy 160.279068 -317.607822)
			(xy 160.305371 -317.566226) (xy 160.338006 -317.529389) (xy 160.376127 -317.498264) (xy 160.418748 -317.473657)
			(xy 160.464764 -317.456205) (xy 160.512983 -317.446361) (xy 160.562158 -317.44438) (xy 160.611013 -317.450312)
			(xy 160.658284 -317.464004) (xy 160.702746 -317.485102) (xy 160.743249 -317.513058) (xy 160.778742 -317.54715)
			(xy 160.808307 -317.586494) (xy 160.831178 -317.630071) (xy 160.846762 -317.676752) (xy 160.854657 -317.725329)
			(xy 160.855152 -317.749936) (xy 161.194254 -317.749936) (xy 161.198214 -317.700882) (xy 161.209991 -317.653098)
			(xy 161.229282 -317.607822) (xy 161.255585 -317.566226) (xy 161.28822 -317.529389) (xy 161.326341 -317.498264)
			(xy 161.368962 -317.473657) (xy 161.414978 -317.456205) (xy 161.463197 -317.446361) (xy 161.512372 -317.44438)
			(xy 161.561227 -317.450312) (xy 161.608498 -317.464004) (xy 161.65296 -317.485102) (xy 161.693463 -317.513058)
			(xy 161.728956 -317.54715) (xy 161.758521 -317.586494) (xy 161.781392 -317.630071) (xy 161.796976 -317.676752)
			(xy 161.804871 -317.725329) (xy 161.805366 -317.749936) (xy 161.804871 -317.774543) (xy 161.796976 -317.82312)
			(xy 161.781392 -317.869801) (xy 161.758521 -317.913378) (xy 161.728956 -317.952722) (xy 161.693463 -317.986814)
			(xy 161.65296 -318.01477) (xy 161.608498 -318.035868) (xy 161.561227 -318.04956) (xy 161.512372 -318.055492)
			(xy 161.463197 -318.053511) (xy 161.414978 -318.043667) (xy 161.368962 -318.026215) (xy 161.326341 -318.001608)
			(xy 161.28822 -317.970483) (xy 161.255585 -317.933646) (xy 161.229282 -317.89205) (xy 161.209991 -317.846774)
			(xy 161.198214 -317.79899) (xy 161.194254 -317.749936) (xy 160.855152 -317.749936) (xy 160.854657 -317.774543)
			(xy 160.846762 -317.82312) (xy 160.831178 -317.869801) (xy 160.808307 -317.913378) (xy 160.778742 -317.952722)
			(xy 160.743249 -317.986814) (xy 160.702746 -318.01477) (xy 160.658284 -318.035868) (xy 160.611013 -318.04956)
			(xy 160.562158 -318.055492) (xy 160.512983 -318.053511) (xy 160.464764 -318.043667) (xy 160.418748 -318.026215)
			(xy 160.376127 -318.001608) (xy 160.338006 -317.970483) (xy 160.305371 -317.933646) (xy 160.279068 -317.89205)
			(xy 160.259777 -317.846774) (xy 160.248 -317.79899) (xy 160.24404 -317.749936) (xy 159.905192 -317.749936)
			(xy 159.904697 -317.774543) (xy 159.896802 -317.82312) (xy 159.881218 -317.869801) (xy 159.858347 -317.913378)
			(xy 159.828782 -317.952722) (xy 159.793289 -317.986814) (xy 159.752786 -318.01477) (xy 159.708324 -318.035868)
			(xy 159.661053 -318.04956) (xy 159.612198 -318.055492) (xy 159.563023 -318.053511) (xy 159.514804 -318.043667)
			(xy 159.468788 -318.026215) (xy 159.426167 -318.001608) (xy 159.388046 -317.970483) (xy 159.355411 -317.933646)
			(xy 159.329108 -317.89205) (xy 159.309817 -317.846774) (xy 159.29804 -317.79899) (xy 159.29408 -317.749936)
			(xy 158.955232 -317.749936) (xy 158.954737 -317.774543) (xy 158.946842 -317.82312) (xy 158.931258 -317.869801)
			(xy 158.908387 -317.913378) (xy 158.878822 -317.952722) (xy 158.843329 -317.986814) (xy 158.802826 -318.01477)
			(xy 158.758364 -318.035868) (xy 158.711093 -318.04956) (xy 158.662238 -318.055492) (xy 158.613063 -318.053511)
			(xy 158.564844 -318.043667) (xy 158.518828 -318.026215) (xy 158.476207 -318.001608) (xy 158.438086 -317.970483)
			(xy 158.405451 -317.933646) (xy 158.379148 -317.89205) (xy 158.359857 -317.846774) (xy 158.34808 -317.79899)
			(xy 158.34412 -317.749936) (xy 158.005272 -317.749936) (xy 158.004777 -317.774543) (xy 157.996882 -317.82312)
			(xy 157.981298 -317.869801) (xy 157.958427 -317.913378) (xy 157.928862 -317.952722) (xy 157.893369 -317.986814)
			(xy 157.852866 -318.01477) (xy 157.808404 -318.035868) (xy 157.761133 -318.04956) (xy 157.712278 -318.055492)
			(xy 157.663103 -318.053511) (xy 157.614884 -318.043667) (xy 157.568868 -318.026215) (xy 157.526247 -318.001608)
			(xy 157.488126 -317.970483) (xy 157.455491 -317.933646) (xy 157.429188 -317.89205) (xy 157.409897 -317.846774)
			(xy 157.39812 -317.79899) (xy 157.39416 -317.749936) (xy 157.055312 -317.749936) (xy 157.054817 -317.774543)
			(xy 157.046922 -317.82312) (xy 157.031338 -317.869801) (xy 157.008467 -317.913378) (xy 156.978902 -317.952722)
			(xy 156.943409 -317.986814) (xy 156.902906 -318.01477) (xy 156.858444 -318.035868) (xy 156.811173 -318.04956)
			(xy 156.762318 -318.055492) (xy 156.713143 -318.053511) (xy 156.664924 -318.043667) (xy 156.618908 -318.026215)
			(xy 156.576287 -318.001608) (xy 156.538166 -317.970483) (xy 156.505531 -317.933646) (xy 156.479228 -317.89205)
			(xy 156.459937 -317.846774) (xy 156.44816 -317.79899) (xy 156.4442 -317.749936) (xy 156.105352 -317.749936)
			(xy 156.104857 -317.774543) (xy 156.096962 -317.82312) (xy 156.081378 -317.869801) (xy 156.058507 -317.913378)
			(xy 156.028942 -317.952722) (xy 155.993449 -317.986814) (xy 155.952946 -318.01477) (xy 155.908484 -318.035868)
			(xy 155.861213 -318.04956) (xy 155.812358 -318.055492) (xy 155.763183 -318.053511) (xy 155.714964 -318.043667)
			(xy 155.668948 -318.026215) (xy 155.626327 -318.001608) (xy 155.588206 -317.970483) (xy 155.555571 -317.933646)
			(xy 155.529268 -317.89205) (xy 155.509977 -317.846774) (xy 155.4982 -317.79899) (xy 155.49424 -317.749936)
			(xy 155.155392 -317.749936) (xy 155.154897 -317.774543) (xy 155.147002 -317.82312) (xy 155.131418 -317.869801)
			(xy 155.108547 -317.913378) (xy 155.078982 -317.952722) (xy 155.043489 -317.986814) (xy 155.002986 -318.01477)
			(xy 154.958524 -318.035868) (xy 154.911253 -318.04956) (xy 154.862398 -318.055492) (xy 154.813223 -318.053511)
			(xy 154.765004 -318.043667) (xy 154.718988 -318.026215) (xy 154.676367 -318.001608) (xy 154.638246 -317.970483)
			(xy 154.605611 -317.933646) (xy 154.579308 -317.89205) (xy 154.560017 -317.846774) (xy 154.54824 -317.79899)
			(xy 154.54428 -317.749936) (xy 154.205178 -317.749936) (xy 154.204683 -317.774543) (xy 154.196788 -317.82312)
			(xy 154.181204 -317.869801) (xy 154.158333 -317.913378) (xy 154.128768 -317.952722) (xy 154.093275 -317.986814)
			(xy 154.052772 -318.01477) (xy 154.00831 -318.035868) (xy 153.961039 -318.04956) (xy 153.912184 -318.055492)
			(xy 153.863009 -318.053511) (xy 153.81479 -318.043667) (xy 153.768774 -318.026215) (xy 153.726153 -318.001608)
			(xy 153.688032 -317.970483) (xy 153.655397 -317.933646) (xy 153.629094 -317.89205) (xy 153.609803 -317.846774)
			(xy 153.598026 -317.79899) (xy 153.594066 -317.749936) (xy 153.255218 -317.749936) (xy 153.254723 -317.774543)
			(xy 153.246828 -317.82312) (xy 153.231244 -317.869801) (xy 153.208373 -317.913378) (xy 153.178808 -317.952722)
			(xy 153.143315 -317.986814) (xy 153.102812 -318.01477) (xy 153.05835 -318.035868) (xy 153.011079 -318.04956)
			(xy 152.962224 -318.055492) (xy 152.913049 -318.053511) (xy 152.86483 -318.043667) (xy 152.818814 -318.026215)
			(xy 152.776193 -318.001608) (xy 152.738072 -317.970483) (xy 152.705437 -317.933646) (xy 152.679134 -317.89205)
			(xy 152.659843 -317.846774) (xy 152.648066 -317.79899) (xy 152.644106 -317.749936) (xy 149.30568 -317.749936)
			(xy 149.325828 -317.772037) (xy 149.451233 -317.92149) (xy 149.570397 -318.075964) (xy 149.683118 -318.235201)
			(xy 149.789207 -318.398932) (xy 149.888485 -318.566879) (xy 149.959913 -318.699896) (xy 153.594066 -318.699896)
			(xy 153.598026 -318.650842) (xy 153.609803 -318.603058) (xy 153.629094 -318.557782) (xy 153.655397 -318.516186)
			(xy 153.688032 -318.479349) (xy 153.726153 -318.448224) (xy 153.768774 -318.423617) (xy 153.81479 -318.406165)
			(xy 153.863009 -318.396321) (xy 153.912184 -318.39434) (xy 153.961039 -318.400272) (xy 154.00831 -318.413964)
			(xy 154.052772 -318.435062) (xy 154.093275 -318.463018) (xy 154.128768 -318.49711) (xy 154.158333 -318.536454)
			(xy 154.181204 -318.580031) (xy 154.196788 -318.626712) (xy 154.204683 -318.675289) (xy 154.205178 -318.699896)
			(xy 154.54428 -318.699896) (xy 154.54824 -318.650842) (xy 154.560017 -318.603058) (xy 154.579308 -318.557782)
			(xy 154.605611 -318.516186) (xy 154.638246 -318.479349) (xy 154.676367 -318.448224) (xy 154.718988 -318.423617)
			(xy 154.765004 -318.406165) (xy 154.813223 -318.396321) (xy 154.862398 -318.39434) (xy 154.911253 -318.400272)
			(xy 154.958524 -318.413964) (xy 155.002986 -318.435062) (xy 155.043489 -318.463018) (xy 155.078982 -318.49711)
			(xy 155.108547 -318.536454) (xy 155.131418 -318.580031) (xy 155.147002 -318.626712) (xy 155.154897 -318.675289)
			(xy 155.155392 -318.699896) (xy 155.49424 -318.699896) (xy 155.4982 -318.650842) (xy 155.509977 -318.603058)
			(xy 155.529268 -318.557782) (xy 155.555571 -318.516186) (xy 155.588206 -318.479349) (xy 155.626327 -318.448224)
			(xy 155.668948 -318.423617) (xy 155.714964 -318.406165) (xy 155.763183 -318.396321) (xy 155.812358 -318.39434)
			(xy 155.861213 -318.400272) (xy 155.908484 -318.413964) (xy 155.952946 -318.435062) (xy 155.993449 -318.463018)
			(xy 156.028942 -318.49711) (xy 156.058507 -318.536454) (xy 156.081378 -318.580031) (xy 156.096962 -318.626712)
			(xy 156.104857 -318.675289) (xy 156.105352 -318.699896) (xy 156.4442 -318.699896) (xy 156.44816 -318.650842)
			(xy 156.459937 -318.603058) (xy 156.479228 -318.557782) (xy 156.505531 -318.516186) (xy 156.538166 -318.479349)
			(xy 156.576287 -318.448224) (xy 156.618908 -318.423617) (xy 156.664924 -318.406165) (xy 156.713143 -318.396321)
			(xy 156.762318 -318.39434) (xy 156.811173 -318.400272) (xy 156.858444 -318.413964) (xy 156.902906 -318.435062)
			(xy 156.943409 -318.463018) (xy 156.978902 -318.49711) (xy 157.008467 -318.536454) (xy 157.031338 -318.580031)
			(xy 157.046922 -318.626712) (xy 157.054817 -318.675289) (xy 157.055312 -318.699896) (xy 157.39416 -318.699896)
			(xy 157.39812 -318.650842) (xy 157.409897 -318.603058) (xy 157.429188 -318.557782) (xy 157.455491 -318.516186)
			(xy 157.488126 -318.479349) (xy 157.526247 -318.448224) (xy 157.568868 -318.423617) (xy 157.614884 -318.406165)
			(xy 157.663103 -318.396321) (xy 157.712278 -318.39434) (xy 157.761133 -318.400272) (xy 157.808404 -318.413964)
			(xy 157.852866 -318.435062) (xy 157.893369 -318.463018) (xy 157.928862 -318.49711) (xy 157.958427 -318.536454)
			(xy 157.981298 -318.580031) (xy 157.996882 -318.626712) (xy 158.004777 -318.675289) (xy 158.005272 -318.699896)
			(xy 158.34412 -318.699896) (xy 158.34808 -318.650842) (xy 158.359857 -318.603058) (xy 158.379148 -318.557782)
			(xy 158.405451 -318.516186) (xy 158.438086 -318.479349) (xy 158.476207 -318.448224) (xy 158.518828 -318.423617)
			(xy 158.564844 -318.406165) (xy 158.613063 -318.396321) (xy 158.662238 -318.39434) (xy 158.711093 -318.400272)
			(xy 158.758364 -318.413964) (xy 158.802826 -318.435062) (xy 158.843329 -318.463018) (xy 158.878822 -318.49711)
			(xy 158.908387 -318.536454) (xy 158.931258 -318.580031) (xy 158.946842 -318.626712) (xy 158.954737 -318.675289)
			(xy 158.955232 -318.699896) (xy 159.29408 -318.699896) (xy 159.29804 -318.650842) (xy 159.309817 -318.603058)
			(xy 159.329108 -318.557782) (xy 159.355411 -318.516186) (xy 159.388046 -318.479349) (xy 159.426167 -318.448224)
			(xy 159.468788 -318.423617) (xy 159.514804 -318.406165) (xy 159.563023 -318.396321) (xy 159.612198 -318.39434)
			(xy 159.661053 -318.400272) (xy 159.708324 -318.413964) (xy 159.752786 -318.435062) (xy 159.793289 -318.463018)
			(xy 159.828782 -318.49711) (xy 159.858347 -318.536454) (xy 159.881218 -318.580031) (xy 159.896802 -318.626712)
			(xy 159.904697 -318.675289) (xy 159.905192 -318.699896) (xy 160.24404 -318.699896) (xy 160.248 -318.650842)
			(xy 160.259777 -318.603058) (xy 160.279068 -318.557782) (xy 160.305371 -318.516186) (xy 160.338006 -318.479349)
			(xy 160.376127 -318.448224) (xy 160.418748 -318.423617) (xy 160.464764 -318.406165) (xy 160.512983 -318.396321)
			(xy 160.562158 -318.39434) (xy 160.611013 -318.400272) (xy 160.658284 -318.413964) (xy 160.702746 -318.435062)
			(xy 160.743249 -318.463018) (xy 160.778742 -318.49711) (xy 160.808307 -318.536454) (xy 160.831178 -318.580031)
			(xy 160.846762 -318.626712) (xy 160.854657 -318.675289) (xy 160.855152 -318.699896) (xy 161.194254 -318.699896)
			(xy 161.198214 -318.650842) (xy 161.209991 -318.603058) (xy 161.229282 -318.557782) (xy 161.255585 -318.516186)
			(xy 161.28822 -318.479349) (xy 161.326341 -318.448224) (xy 161.368962 -318.423617) (xy 161.414978 -318.406165)
			(xy 161.463197 -318.396321) (xy 161.512372 -318.39434) (xy 161.561227 -318.400272) (xy 161.608498 -318.413964)
			(xy 161.65296 -318.435062) (xy 161.693463 -318.463018) (xy 161.728956 -318.49711) (xy 161.758521 -318.536454)
			(xy 161.781392 -318.580031) (xy 161.796976 -318.626712) (xy 161.804871 -318.675289) (xy 161.805366 -318.699896)
			(xy 161.804871 -318.724503) (xy 161.796976 -318.77308) (xy 161.781392 -318.819761) (xy 161.758521 -318.863338)
			(xy 161.728956 -318.902682) (xy 161.693463 -318.936774) (xy 161.65296 -318.96473) (xy 161.608498 -318.985828)
			(xy 161.561227 -318.99952) (xy 161.512372 -319.005452) (xy 161.463197 -319.003471) (xy 161.414978 -318.993627)
			(xy 161.368962 -318.976175) (xy 161.326341 -318.951568) (xy 161.28822 -318.920443) (xy 161.255585 -318.883606)
			(xy 161.229282 -318.84201) (xy 161.209991 -318.796734) (xy 161.198214 -318.74895) (xy 161.194254 -318.699896)
			(xy 160.855152 -318.699896) (xy 160.854657 -318.724503) (xy 160.846762 -318.77308) (xy 160.831178 -318.819761)
			(xy 160.808307 -318.863338) (xy 160.778742 -318.902682) (xy 160.743249 -318.936774) (xy 160.702746 -318.96473)
			(xy 160.658284 -318.985828) (xy 160.611013 -318.99952) (xy 160.562158 -319.005452) (xy 160.512983 -319.003471)
			(xy 160.464764 -318.993627) (xy 160.418748 -318.976175) (xy 160.376127 -318.951568) (xy 160.338006 -318.920443)
			(xy 160.305371 -318.883606) (xy 160.279068 -318.84201) (xy 160.259777 -318.796734) (xy 160.248 -318.74895)
			(xy 160.24404 -318.699896) (xy 159.905192 -318.699896) (xy 159.904697 -318.724503) (xy 159.896802 -318.77308)
			(xy 159.881218 -318.819761) (xy 159.858347 -318.863338) (xy 159.828782 -318.902682) (xy 159.793289 -318.936774)
			(xy 159.752786 -318.96473) (xy 159.708324 -318.985828) (xy 159.661053 -318.99952) (xy 159.612198 -319.005452)
			(xy 159.563023 -319.003471) (xy 159.514804 -318.993627) (xy 159.468788 -318.976175) (xy 159.426167 -318.951568)
			(xy 159.388046 -318.920443) (xy 159.355411 -318.883606) (xy 159.329108 -318.84201) (xy 159.309817 -318.796734)
			(xy 159.29804 -318.74895) (xy 159.29408 -318.699896) (xy 158.955232 -318.699896) (xy 158.954737 -318.724503)
			(xy 158.946842 -318.77308) (xy 158.931258 -318.819761) (xy 158.908387 -318.863338) (xy 158.878822 -318.902682)
			(xy 158.843329 -318.936774) (xy 158.802826 -318.96473) (xy 158.758364 -318.985828) (xy 158.711093 -318.99952)
			(xy 158.662238 -319.005452) (xy 158.613063 -319.003471) (xy 158.564844 -318.993627) (xy 158.518828 -318.976175)
			(xy 158.476207 -318.951568) (xy 158.438086 -318.920443) (xy 158.405451 -318.883606) (xy 158.379148 -318.84201)
			(xy 158.359857 -318.796734) (xy 158.34808 -318.74895) (xy 158.34412 -318.699896) (xy 158.005272 -318.699896)
			(xy 158.004777 -318.724503) (xy 157.996882 -318.77308) (xy 157.981298 -318.819761) (xy 157.958427 -318.863338)
			(xy 157.928862 -318.902682) (xy 157.893369 -318.936774) (xy 157.852866 -318.96473) (xy 157.808404 -318.985828)
			(xy 157.761133 -318.99952) (xy 157.712278 -319.005452) (xy 157.663103 -319.003471) (xy 157.614884 -318.993627)
			(xy 157.568868 -318.976175) (xy 157.526247 -318.951568) (xy 157.488126 -318.920443) (xy 157.455491 -318.883606)
			(xy 157.429188 -318.84201) (xy 157.409897 -318.796734) (xy 157.39812 -318.74895) (xy 157.39416 -318.699896)
			(xy 157.055312 -318.699896) (xy 157.054817 -318.724503) (xy 157.046922 -318.77308) (xy 157.031338 -318.819761)
			(xy 157.008467 -318.863338) (xy 156.978902 -318.902682) (xy 156.943409 -318.936774) (xy 156.902906 -318.96473)
			(xy 156.858444 -318.985828) (xy 156.811173 -318.99952) (xy 156.762318 -319.005452) (xy 156.713143 -319.003471)
			(xy 156.664924 -318.993627) (xy 156.618908 -318.976175) (xy 156.576287 -318.951568) (xy 156.538166 -318.920443)
			(xy 156.505531 -318.883606) (xy 156.479228 -318.84201) (xy 156.459937 -318.796734) (xy 156.44816 -318.74895)
			(xy 156.4442 -318.699896) (xy 156.105352 -318.699896) (xy 156.104857 -318.724503) (xy 156.096962 -318.77308)
			(xy 156.081378 -318.819761) (xy 156.058507 -318.863338) (xy 156.028942 -318.902682) (xy 155.993449 -318.936774)
			(xy 155.952946 -318.96473) (xy 155.908484 -318.985828) (xy 155.861213 -318.99952) (xy 155.812358 -319.005452)
			(xy 155.763183 -319.003471) (xy 155.714964 -318.993627) (xy 155.668948 -318.976175) (xy 155.626327 -318.951568)
			(xy 155.588206 -318.920443) (xy 155.555571 -318.883606) (xy 155.529268 -318.84201) (xy 155.509977 -318.796734)
			(xy 155.4982 -318.74895) (xy 155.49424 -318.699896) (xy 155.155392 -318.699896) (xy 155.154897 -318.724503)
			(xy 155.147002 -318.77308) (xy 155.131418 -318.819761) (xy 155.108547 -318.863338) (xy 155.078982 -318.902682)
			(xy 155.043489 -318.936774) (xy 155.002986 -318.96473) (xy 154.958524 -318.985828) (xy 154.911253 -318.99952)
			(xy 154.862398 -319.005452) (xy 154.813223 -319.003471) (xy 154.765004 -318.993627) (xy 154.718988 -318.976175)
			(xy 154.676367 -318.951568) (xy 154.638246 -318.920443) (xy 154.605611 -318.883606) (xy 154.579308 -318.84201)
			(xy 154.560017 -318.796734) (xy 154.54824 -318.74895) (xy 154.54428 -318.699896) (xy 154.205178 -318.699896)
			(xy 154.204683 -318.724503) (xy 154.196788 -318.77308) (xy 154.181204 -318.819761) (xy 154.158333 -318.863338)
			(xy 154.128768 -318.902682) (xy 154.093275 -318.936774) (xy 154.052772 -318.96473) (xy 154.00831 -318.985828)
			(xy 153.961039 -318.99952) (xy 153.912184 -319.005452) (xy 153.863009 -319.003471) (xy 153.81479 -318.993627)
			(xy 153.768774 -318.976175) (xy 153.726153 -318.951568) (xy 153.688032 -318.920443) (xy 153.655397 -318.883606)
			(xy 153.629094 -318.84201) (xy 153.609803 -318.796734) (xy 153.598026 -318.74895) (xy 153.594066 -318.699896)
			(xy 149.959913 -318.699896) (xy 149.980783 -318.738762) (xy 150.065948 -318.914288) (xy 150.143834 -319.093163)
			(xy 150.214311 -319.275085) (xy 150.277259 -319.459747) (xy 150.332574 -319.646837) (xy 150.333397 -319.65011)
			(xy 154.54428 -319.65011) (xy 154.54824 -319.601056) (xy 154.560017 -319.553272) (xy 154.579308 -319.507996)
			(xy 154.605611 -319.4664) (xy 154.638246 -319.429563) (xy 154.676367 -319.398438) (xy 154.718988 -319.373831)
			(xy 154.765004 -319.356379) (xy 154.813223 -319.346535) (xy 154.862398 -319.344554) (xy 154.911253 -319.350486)
			(xy 154.958524 -319.364178) (xy 155.002986 -319.385276) (xy 155.043489 -319.413232) (xy 155.078982 -319.447324)
			(xy 155.108547 -319.486668) (xy 155.131418 -319.530245) (xy 155.147002 -319.576926) (xy 155.154897 -319.625503)
			(xy 155.155392 -319.65011) (xy 156.4442 -319.65011) (xy 156.44816 -319.601056) (xy 156.459937 -319.553272)
			(xy 156.479228 -319.507996) (xy 156.505531 -319.4664) (xy 156.538166 -319.429563) (xy 156.576287 -319.398438)
			(xy 156.618908 -319.373831) (xy 156.664924 -319.356379) (xy 156.713143 -319.346535) (xy 156.762318 -319.344554)
			(xy 156.811173 -319.350486) (xy 156.858444 -319.364178) (xy 156.902906 -319.385276) (xy 156.943409 -319.413232)
			(xy 156.978902 -319.447324) (xy 157.008467 -319.486668) (xy 157.031338 -319.530245) (xy 157.046922 -319.576926)
			(xy 157.054817 -319.625503) (xy 157.055312 -319.65011) (xy 158.34412 -319.65011) (xy 158.34808 -319.601056)
			(xy 158.359857 -319.553272) (xy 158.379148 -319.507996) (xy 158.405451 -319.4664) (xy 158.438086 -319.429563)
			(xy 158.476207 -319.398438) (xy 158.518828 -319.373831) (xy 158.564844 -319.356379) (xy 158.613063 -319.346535)
			(xy 158.662238 -319.344554) (xy 158.711093 -319.350486) (xy 158.758364 -319.364178) (xy 158.802826 -319.385276)
			(xy 158.843329 -319.413232) (xy 158.878822 -319.447324) (xy 158.908387 -319.486668) (xy 158.931258 -319.530245)
			(xy 158.946842 -319.576926) (xy 158.954737 -319.625503) (xy 158.955232 -319.65011) (xy 160.244294 -319.65011)
			(xy 160.248254 -319.601056) (xy 160.260031 -319.553272) (xy 160.279322 -319.507996) (xy 160.305625 -319.4664)
			(xy 160.33826 -319.429563) (xy 160.376381 -319.398438) (xy 160.419002 -319.373831) (xy 160.465018 -319.356379)
			(xy 160.513237 -319.346535) (xy 160.562412 -319.344554) (xy 160.611267 -319.350486) (xy 160.658538 -319.364178)
			(xy 160.703 -319.385276) (xy 160.743503 -319.413232) (xy 160.778996 -319.447324) (xy 160.808561 -319.486668)
			(xy 160.831432 -319.530245) (xy 160.847016 -319.576926) (xy 160.854911 -319.625503) (xy 160.855406 -319.65011)
			(xy 160.854911 -319.674717) (xy 160.847016 -319.723294) (xy 160.831432 -319.769975) (xy 160.808561 -319.813552)
			(xy 160.778996 -319.852896) (xy 160.743503 -319.886988) (xy 160.703 -319.914944) (xy 160.658538 -319.936042)
			(xy 160.611267 -319.949734) (xy 160.562412 -319.955666) (xy 160.513237 -319.953685) (xy 160.465018 -319.943841)
			(xy 160.419002 -319.926389) (xy 160.376381 -319.901782) (xy 160.33826 -319.870657) (xy 160.305625 -319.83382)
			(xy 160.279322 -319.792224) (xy 160.260031 -319.746948) (xy 160.248254 -319.699164) (xy 160.244294 -319.65011)
			(xy 158.955232 -319.65011) (xy 158.954737 -319.674717) (xy 158.946842 -319.723294) (xy 158.931258 -319.769975)
			(xy 158.908387 -319.813552) (xy 158.878822 -319.852896) (xy 158.843329 -319.886988) (xy 158.802826 -319.914944)
			(xy 158.758364 -319.936042) (xy 158.711093 -319.949734) (xy 158.662238 -319.955666) (xy 158.613063 -319.953685)
			(xy 158.564844 -319.943841) (xy 158.518828 -319.926389) (xy 158.476207 -319.901782) (xy 158.438086 -319.870657)
			(xy 158.405451 -319.83382) (xy 158.379148 -319.792224) (xy 158.359857 -319.746948) (xy 158.34808 -319.699164)
			(xy 158.34412 -319.65011) (xy 157.055312 -319.65011) (xy 157.054817 -319.674717) (xy 157.046922 -319.723294)
			(xy 157.031338 -319.769975) (xy 157.008467 -319.813552) (xy 156.978902 -319.852896) (xy 156.943409 -319.886988)
			(xy 156.902906 -319.914944) (xy 156.858444 -319.936042) (xy 156.811173 -319.949734) (xy 156.762318 -319.955666)
			(xy 156.713143 -319.953685) (xy 156.664924 -319.943841) (xy 156.618908 -319.926389) (xy 156.576287 -319.901782)
			(xy 156.538166 -319.870657) (xy 156.505531 -319.83382) (xy 156.479228 -319.792224) (xy 156.459937 -319.746948)
			(xy 156.44816 -319.699164) (xy 156.4442 -319.65011) (xy 155.155392 -319.65011) (xy 155.154897 -319.674717)
			(xy 155.147002 -319.723294) (xy 155.131418 -319.769975) (xy 155.108547 -319.813552) (xy 155.078982 -319.852896)
			(xy 155.043489 -319.886988) (xy 155.002986 -319.914944) (xy 154.958524 -319.936042) (xy 154.911253 -319.949734)
			(xy 154.862398 -319.955666) (xy 154.813223 -319.953685) (xy 154.765004 -319.943841) (xy 154.718988 -319.926389)
			(xy 154.676367 -319.901782) (xy 154.638246 -319.870657) (xy 154.605611 -319.83382) (xy 154.579308 -319.792224)
			(xy 154.560017 -319.746948) (xy 154.54824 -319.699164) (xy 154.54428 -319.65011) (xy 150.333397 -319.65011)
			(xy 150.38016 -319.836041) (xy 150.419939 -320.027038) (xy 150.451843 -320.219508) (xy 150.475818 -320.413126)
			(xy 150.491824 -320.607564) (xy 150.499833 -320.802496) (xy 150.500334 -320.900044) (xy 150.499833 -320.997592)
			(xy 150.491824 -321.192524) (xy 150.475818 -321.386962) (xy 150.451843 -321.58058) (xy 150.419939 -321.77305)
			(xy 150.38016 -321.964047) (xy 150.332574 -322.153251) (xy 150.277259 -322.340341) (xy 150.214311 -322.525003)
			(xy 150.143834 -322.706925) (xy 150.065948 -322.8858) (xy 149.980783 -323.061326) (xy 149.888485 -323.233209)
			(xy 149.789207 -323.401156) (xy 149.683118 -323.564887) (xy 149.570397 -323.724124) (xy 149.451233 -323.878598)
			(xy 149.325828 -324.028051) (xy 149.194392 -324.172229) (xy 149.057148 -324.310889) (xy 148.914327 -324.443797)
			(xy 148.76617 -324.570731) (xy 148.612927 -324.691474) (xy 148.454856 -324.805824) (xy 148.292223 -324.913589)
			(xy 148.125304 -325.014585) (xy 147.954378 -325.108644) (xy 147.779735 -325.195606) (xy 147.601669 -325.275324)
			(xy 147.420481 -325.347665) (xy 147.236475 -325.412506) (xy 147.049962 -325.469738) (xy 146.861257 -325.519265)
			(xy 146.670678 -325.561002) (xy 146.478545 -325.59488) (xy 146.285184 -325.620842) (xy 146.09092 -325.638843)
			(xy 145.896081 -325.648854) (xy 145.700995 -325.650857) (xy 145.505992 -325.644849) (xy 145.311399 -325.63084)
			(xy 145.117546 -325.608854) (xy 144.924759 -325.578928) (xy 144.733362 -325.541112) (xy 144.54368 -325.49547)
			(xy 144.356032 -325.44208) (xy 144.170733 -325.38103) (xy 143.988098 -325.312425) (xy 143.808433 -325.236379)
			(xy 143.632041 -325.153021) (xy 143.45922 -325.062492) (xy 143.290262 -324.964944) (xy 143.125451 -324.860541)
			(xy 142.965065 -324.749461) (xy 142.809375 -324.631889) (xy 142.658643 -324.508025) (xy 142.513124 -324.378076)
			(xy 142.373062 -324.242263) (xy 142.238694 -324.100814) (xy 142.110247 -323.953968) (xy 141.987936 -323.801973)
			(xy 141.871969 -323.645084) (xy 141.762541 -323.483566) (xy 141.659836 -323.317692) (xy 141.564028 -323.147741)
			(xy 141.475277 -322.974) (xy 141.393735 -322.796762) (xy 141.319538 -322.616326) (xy 141.252811 -322.432995)
			(xy 141.193667 -322.24708) (xy 141.142206 -322.058893) (xy 141.098514 -321.868753) (xy 141.062665 -321.676978)
			(xy 141.03472 -321.483894) (xy 141.014725 -321.289825) (xy 141.002715 -321.095099) (xy 140.998709 -320.900044)
			(xy 119.631206 -320.900044) (xy 119.631206 -327.019254) (xy 130.267135 -327.019254) (xy 130.267135 -326.964746)
			(xy 130.274892 -326.910792) (xy 130.290249 -326.858491) (xy 130.312893 -326.808908) (xy 130.342363 -326.763052)
			(xy 130.378059 -326.721857) (xy 130.419254 -326.686162) (xy 130.46511 -326.656692) (xy 130.514693 -326.634049)
			(xy 130.566994 -326.618692) (xy 130.620948 -326.610935) (xy 130.648202 -326.610472) (xy 130.675749 -326.610902)
			(xy 130.730271 -326.618822) (xy 130.783085 -326.634511) (xy 130.833088 -326.657641) (xy 130.87924 -326.687732)
			(xy 130.920577 -326.724155) (xy 130.938778 -326.744838) (xy 130.94677 -326.75338) (xy 130.968227 -326.762635)
			(xy 130.979926 -326.762618) (xy 131.072382 -326.758046) (xy 131.092702 -326.746616) (xy 131.09956 -326.736964)
			(xy 131.114868 -326.715586) (xy 131.150479 -326.6769) (xy 131.191069 -326.643473) (xy 131.235866 -326.615941)
			(xy 131.284021 -326.594825) (xy 131.334621 -326.580526) (xy 131.386705 -326.573314) (xy 131.412996 -326.57288)
			(xy 131.439561 -326.573317) (xy 131.492178 -326.580685) (xy 131.543265 -326.595277) (xy 131.591834 -326.616813)
			(xy 131.636948 -326.644876) (xy 131.677735 -326.678924) (xy 131.713406 -326.718299) (xy 131.728718 -326.740012)
			(xy 131.73583 -326.75068) (xy 131.758436 -326.762364) (xy 131.868926 -326.761094) (xy 131.891278 -326.748648)
			(xy 131.898136 -326.73798) (xy 131.913211 -326.715247) (xy 131.948898 -326.673993) (xy 131.9901 -326.638245)
			(xy 132.035975 -326.608733) (xy 132.085588 -326.586058) (xy 132.137924 -326.570684) (xy 132.191918 -326.562925)
			(xy 132.219192 -326.562466) (xy 132.246443 -326.562981) (xy 132.300391 -326.570736) (xy 132.352687 -326.586091)
			(xy 132.402264 -326.608731) (xy 132.448115 -326.638197) (xy 132.489306 -326.673888) (xy 132.524998 -326.715078)
			(xy 132.554465 -326.760928) (xy 132.577107 -326.810506) (xy 132.592462 -326.862801) (xy 132.600219 -326.916749)
			(xy 132.600219 -326.971251) (xy 132.592462 -327.025199) (xy 132.577107 -327.077494) (xy 132.554465 -327.127072)
			(xy 132.524998 -327.172922) (xy 132.489306 -327.214112) (xy 132.448115 -327.249803) (xy 132.402264 -327.279269)
			(xy 132.352687 -327.301909) (xy 132.300391 -327.317264) (xy 132.246443 -327.325019) (xy 132.219192 -327.325482)
			(xy 132.192628 -327.325027) (xy 132.140013 -327.317659) (xy 132.088928 -327.303068) (xy 132.040359 -327.281534)
			(xy 131.995245 -327.253475) (xy 131.954457 -327.219431) (xy 131.918784 -327.180061) (xy 131.90347 -327.15835)
			(xy 131.896358 -327.147682) (xy 131.873752 -327.135998) (xy 131.763262 -327.137268) (xy 131.74091 -327.149714)
			(xy 131.734052 -327.160382) (xy 131.718907 -327.183066) (xy 131.683232 -327.224323) (xy 131.642043 -327.260075)
			(xy 131.59618 -327.289594) (xy 131.546579 -327.312277) (xy 131.494252 -327.32766) (xy 131.440267 -327.335431)
			(xy 131.412996 -327.335896) (xy 131.385452 -327.335374) (xy 131.330935 -327.32747) (xy 131.278125 -327.311798)
			(xy 131.228121 -327.288684) (xy 131.181967 -327.258611) (xy 131.140625 -327.222205) (xy 131.12242 -327.20153)
			(xy 131.114419 -327.192998) (xy 131.092969 -327.183734) (xy 131.081272 -327.18375) (xy 130.988816 -327.188322)
			(xy 130.968496 -327.199752) (xy 130.961638 -327.209404) (xy 130.94626 -327.230729) (xy 130.910661 -327.269418)
			(xy 130.870084 -327.30285) (xy 130.825299 -327.330389) (xy 130.777155 -327.351514) (xy 130.726565 -327.365824)
			(xy 130.674489 -327.373047) (xy 130.648202 -327.373488) (xy 130.620948 -327.373065) (xy 130.566994 -327.365308)
			(xy 130.514693 -327.349951) (xy 130.46511 -327.327308) (xy 130.419254 -327.297838) (xy 130.378059 -327.262143)
			(xy 130.342363 -327.220948) (xy 130.312893 -327.175092) (xy 130.290249 -327.125509) (xy 130.274892 -327.073208)
			(xy 130.267135 -327.019254) (xy 119.631206 -327.019254) (xy 119.631206 -329.311508) (xy 119.632222 -329.32116)
			(xy 119.63385 -329.328404) (xy 119.640692 -329.341572) (xy 119.645684 -329.347068) (xy 120.344184 -330.045568)
			(xy 120.349684 -330.050555) (xy 120.36285 -330.0574) (xy 120.370092 -330.05903) (xy 120.379744 -330.060046)
			(xy 124.013722 -330.060046)
		)
		(stroke
			(width 0)
			(type solid)
		)
		(fill yes)
		(layer "In5.Cu")
		(net "P0V8_SERDES_VDDA_PEX1")
	)
	(gr_poly
		(pts
			(xy 379.910086 -330.060046) (xy 379.916754 -330.059853) (xy 379.929631 -330.056384) (xy 379.935486 -330.053188)
			(xy 394.805916 -320.116962) (xy 394.814282 -320.110783) (xy 394.82558 -320.093347) (xy 394.82776 -320.08318)
			(xy 394.82776 -320.082672) (xy 394.828522 -320.074798) (xy 394.828522 -320.049652) (xy 394.827943 -320.038452)
			(xy 394.818462 -320.018156) (xy 394.810234 -320.010536) (xy 394.749782 -319.960498) (xy 394.740689 -319.953791)
			(xy 394.718809 -319.948262) (xy 394.707618 -319.94983) (xy 394.693344 -319.952425) (xy 394.664466 -319.955224)
			(xy 394.64996 -319.955418) (xy 394.624706 -319.954893) (xy 394.574888 -319.946574) (xy 394.527118 -319.930169)
			(xy 394.4827 -319.906126) (xy 394.442844 -319.8751) (xy 394.408638 -319.837938) (xy 394.381015 -319.795653)
			(xy 394.360728 -319.749398) (xy 394.34833 -319.700436) (xy 394.344159 -319.6501) (xy 394.34833 -319.599764)
			(xy 394.360728 -319.550802) (xy 394.381015 -319.504547) (xy 394.408638 -319.462262) (xy 394.442844 -319.4251)
			(xy 394.4827 -319.394074) (xy 394.527118 -319.370031) (xy 394.574888 -319.353626) (xy 394.624706 -319.345307)
			(xy 394.64996 -319.344802) (xy 394.659128 -319.344893) (xy 394.677428 -319.346035) (xy 394.686536 -319.347088)
			(xy 394.69822 -319.348612) (xy 394.72108 -319.340484) (xy 394.793724 -319.26403) (xy 394.800836 -319.241424)
			(xy 394.799566 -319.233804) (xy 394.797076 -319.219199) (xy 394.794405 -319.189691) (xy 394.794232 -319.174876)
			(xy 394.794411 -319.160062) (xy 394.797085 -319.130554) (xy 394.799566 -319.115948) (xy 394.799566 -319.115186)
			(xy 394.800836 -319.108582) (xy 394.793724 -319.085976) (xy 394.729208 -319.018412) (xy 394.720568 -319.0102)
			(xy 394.698175 -319.002121) (xy 394.686282 -319.002918) (xy 394.677238 -319.003965) (xy 394.659064 -319.005107)
			(xy 394.64996 -319.005204) (xy 394.624707 -319.004679) (xy 394.574891 -318.99636) (xy 394.527124 -318.979956)
			(xy 394.482707 -318.955914) (xy 394.442853 -318.92489) (xy 394.408649 -318.88773) (xy 394.381027 -318.845446)
			(xy 394.360741 -318.799194) (xy 394.348343 -318.750233) (xy 394.344173 -318.6999) (xy 394.348343 -318.649567)
			(xy 394.360741 -318.600606) (xy 394.381027 -318.554354) (xy 394.408649 -318.51207) (xy 394.442853 -318.47491)
			(xy 394.482707 -318.443886) (xy 394.527124 -318.419844) (xy 394.574891 -318.40344) (xy 394.624707 -318.395121)
			(xy 394.64996 -318.394588) (xy 394.659064 -318.394686) (xy 394.677237 -318.395831) (xy 394.686282 -318.396874)
			(xy 394.698178 -318.397679) (xy 394.720582 -318.389609) (xy 394.729208 -318.38138) (xy 394.793724 -318.313816)
			(xy 394.800836 -318.29121) (xy 394.799566 -318.284098) (xy 394.797064 -318.269431) (xy 394.794394 -318.239794)
			(xy 394.794232 -318.224916) (xy 394.794409 -318.210102) (xy 394.797079 -318.180593) (xy 394.799566 -318.165988)
			(xy 394.799566 -318.165226) (xy 394.800836 -318.158622) (xy 394.793724 -318.136016) (xy 394.729208 -318.068452)
			(xy 394.72057 -318.060235) (xy 394.698176 -318.05215) (xy 394.686282 -318.052958) (xy 394.677238 -318.054005)
			(xy 394.659064 -318.055146) (xy 394.64996 -318.055244) (xy 394.624704 -318.054719) (xy 394.574881 -318.046399)
			(xy 394.527108 -318.029993) (xy 394.482685 -318.005948) (xy 394.442826 -317.974919) (xy 394.408618 -317.937754)
			(xy 394.380992 -317.895465) (xy 394.360703 -317.849207) (xy 394.348304 -317.80024) (xy 394.344133 -317.7499)
			(xy 394.348304 -317.69956) (xy 394.360703 -317.650593) (xy 394.380992 -317.604335) (xy 394.408618 -317.562046)
			(xy 394.442826 -317.524881) (xy 394.482685 -317.493852) (xy 394.527108 -317.469807) (xy 394.574881 -317.453401)
			(xy 394.624704 -317.445081) (xy 394.64996 -317.444628) (xy 394.675123 -317.445097) (xy 394.724781 -317.45326)
			(xy 394.748766 -317.460884) (xy 394.756132 -317.462916) (xy 394.76934 -317.465202) (xy 394.779342 -317.464707)
			(xy 394.797821 -317.45704) (xy 394.811962 -317.442889) (xy 394.819614 -317.424405) (xy 394.82014 -317.414402)
			(xy 394.817346 -317.400432) (xy 394.81506 -317.391796) (xy 394.809472 -317.376048) (xy 394.802235 -317.352109)
			(xy 394.794204 -317.302748) (xy 394.79347 -317.27775) (xy 394.79347 -317.204344) (xy 394.7929 -317.193656)
			(xy 394.784229 -317.174113) (xy 394.776706 -317.166498) (xy 394.712698 -317.10884) (xy 394.69187 -317.102236)
			(xy 394.681456 -317.103506) (xy 394.64996 -317.10503) (xy 394.624705 -317.104505) (xy 394.574885 -317.096186)
			(xy 394.527113 -317.07978) (xy 394.482693 -317.055736) (xy 394.442836 -317.024709) (xy 394.408629 -316.987545)
			(xy 394.381004 -316.945259) (xy 394.360716 -316.899002) (xy 394.348318 -316.850038) (xy 394.344147 -316.7997)
			(xy 394.348318 -316.749362) (xy 394.360716 -316.700398) (xy 394.381004 -316.654141) (xy 394.408629 -316.611855)
			(xy 394.442836 -316.574691) (xy 394.482693 -316.543664) (xy 394.527113 -316.51962) (xy 394.574885 -316.503214)
			(xy 394.624705 -316.494895) (xy 394.64996 -316.494414) (xy 394.681456 -316.495938) (xy 394.69187 -316.497208)
			(xy 394.712698 -316.490604) (xy 394.776706 -316.432946) (xy 394.784368 -316.425429) (xy 394.793061 -316.405825)
			(xy 394.79347 -316.3951) (xy 394.79347 -316.324742) (xy 394.793657 -316.309667) (xy 394.796452 -316.279647)
			(xy 394.799058 -316.264798) (xy 394.799058 -316.263782) (xy 394.800074 -316.258448) (xy 394.792962 -316.235842)
			(xy 394.720064 -316.159642) (xy 394.697712 -316.151514) (xy 394.685774 -316.153038) (xy 394.676852 -316.153999)
			(xy 394.658934 -316.155013) (xy 394.64996 -316.15507) (xy 394.62471 -316.154545) (xy 394.5749 -316.146228)
			(xy 394.527137 -316.129825) (xy 394.482726 -316.105786) (xy 394.442877 -316.074765) (xy 394.408676 -316.037609)
			(xy 394.381057 -315.99533) (xy 394.360773 -315.949083) (xy 394.348377 -315.900128) (xy 394.344207 -315.8498)
			(xy 394.348377 -315.799472) (xy 394.360773 -315.750517) (xy 394.381057 -315.70427) (xy 394.408676 -315.661991)
			(xy 394.442877 -315.624835) (xy 394.482726 -315.593814) (xy 394.527137 -315.569775) (xy 394.5749 -315.553372)
			(xy 394.62471 -315.545055) (xy 394.64996 -315.544454) (xy 394.659064 -315.544552) (xy 394.677237 -315.545697)
			(xy 394.686282 -315.54674) (xy 394.698177 -315.547544) (xy 394.720578 -315.539471) (xy 394.729208 -315.531246)
			(xy 394.793724 -315.463682) (xy 394.800836 -315.441076) (xy 394.799566 -315.433964) (xy 394.797065 -315.419297)
			(xy 394.794398 -315.38966) (xy 394.794232 -315.374782) (xy 394.794428 -315.359771) (xy 394.797223 -315.329878)
			(xy 394.79982 -315.315092) (xy 394.79982 -315.314076) (xy 394.800836 -315.308488) (xy 394.793724 -315.285882)
			(xy 394.729208 -315.218318) (xy 394.720568 -315.210106) (xy 394.698176 -315.202025) (xy 394.686282 -315.202824)
			(xy 394.677238 -315.203871) (xy 394.659064 -315.205013) (xy 394.64996 -315.20511) (xy 394.62514 -315.204621)
			(xy 394.576154 -315.196584) (xy 394.529114 -315.180728) (xy 394.485258 -315.15747) (xy 394.445743 -315.127425)
			(xy 394.411609 -315.091382) (xy 394.383756 -315.050292) (xy 394.362917 -315.005237) (xy 394.349641 -314.957404)
			(xy 394.344278 -314.908054) (xy 394.34697 -314.858486) (xy 394.357646 -314.810007) (xy 394.376023 -314.763894)
			(xy 394.401619 -314.721361) (xy 394.433758 -314.683529) (xy 394.471595 -314.651394) (xy 394.514131 -314.625805)
			(xy 394.560247 -314.607433) (xy 394.608728 -314.596765) (xy 394.658296 -314.59408) (xy 394.707646 -314.599449)
			(xy 394.755477 -314.612731) (xy 394.800528 -314.633576) (xy 394.841615 -314.661435) (xy 394.877653 -314.695574)
			(xy 394.907693 -314.735094) (xy 394.930944 -314.778952) (xy 394.946794 -314.825995) (xy 394.954824 -314.874982)
			(xy 394.955268 -314.899802) (xy 394.955171 -314.908906) (xy 394.95403 -314.92708) (xy 394.952982 -314.936124)
			(xy 394.952188 -314.948015) (xy 394.960276 -314.9704) (xy 394.968476 -314.97905) (xy 395.03604 -315.043566)
			(xy 395.058646 -315.050678) (xy 395.064742 -315.049662) (xy 395.079657 -315.04707) (xy 395.109803 -315.044276)
			(xy 395.12494 -315.044074) (xy 395.137759 -315.044212) (xy 395.163315 -315.046244) (xy 395.175994 -315.048138)
			(xy 395.188186 -315.049916) (xy 395.199362 -315.04636) (xy 395.205024 -315.044314) (xy 395.215287 -315.038028)
			(xy 395.219682 -315.033914) (xy 395.281658 -314.971938) (xy 395.289211 -314.963477) (xy 395.296739 -314.942114)
			(xy 395.296136 -314.93079) (xy 395.294612 -314.899802) (xy 395.295058 -314.875809) (xy 395.302565 -314.828415)
			(xy 395.317393 -314.782778) (xy 395.339179 -314.740023) (xy 395.367385 -314.701203) (xy 395.401317 -314.667273)
			(xy 395.440139 -314.639069) (xy 395.482895 -314.617286) (xy 395.528532 -314.60246) (xy 395.575927 -314.594957)
			(xy 395.59992 -314.594494) (xy 395.630908 -314.596018) (xy 395.642228 -314.596593) (xy 395.663573 -314.589061)
			(xy 395.672056 -314.58154) (xy 395.678914 -314.574682) (xy 395.681683 -314.57191) (xy 395.687937 -314.567191)
			(xy 395.69136 -314.565284) (xy 395.691614 -314.565284) (xy 395.69898 -314.56122) (xy 395.703806 -314.556648)
			(xy 395.71041 -314.548774) (xy 395.74216 -314.489846) (xy 395.745716 -314.478416) (xy 395.746986 -314.472066)
			(xy 395.74597 -314.463684) (xy 395.74597 -314.46343) (xy 395.744905 -314.453813) (xy 395.743765 -314.434497)
			(xy 395.743684 -314.424822) (xy 395.743684 -314.354464) (xy 395.743118 -314.343774) (xy 395.734454 -314.324224)
			(xy 395.72692 -314.316618) (xy 395.662912 -314.25896) (xy 395.642084 -314.252356) (xy 395.63167 -314.253626)
			(xy 395.59992 -314.25515) (xy 395.574658 -314.254659) (xy 395.524822 -314.246346) (xy 395.477034 -314.229943)
			(xy 395.432598 -314.205898) (xy 395.392726 -314.174867) (xy 395.358506 -314.137696) (xy 395.33087 -314.095399)
			(xy 395.310574 -314.04913) (xy 395.29817 -314.000152) (xy 395.293998 -313.9498) (xy 395.29817 -313.899448)
			(xy 395.310574 -313.85047) (xy 395.33087 -313.804201) (xy 395.358506 -313.761904) (xy 395.392726 -313.724733)
			(xy 395.432598 -313.693702) (xy 395.477034 -313.669657) (xy 395.524822 -313.653254) (xy 395.574658 -313.644941)
			(xy 395.59992 -313.644534) (xy 395.63167 -313.646058) (xy 395.642084 -313.647328) (xy 395.662912 -313.640724)
			(xy 395.72692 -313.583066) (xy 395.734579 -313.575549) (xy 395.743257 -313.555944) (xy 395.743684 -313.54522)
			(xy 395.743684 -313.474862) (xy 395.743874 -313.459788) (xy 395.746677 -313.429769) (xy 395.749272 -313.414918)
			(xy 395.749272 -313.413902) (xy 395.750288 -313.408568) (xy 395.743176 -313.385962) (xy 395.670278 -313.309762)
			(xy 395.647926 -313.301634) (xy 395.635988 -313.303158) (xy 395.627004 -313.304139) (xy 395.608958 -313.305154)
			(xy 395.59992 -313.30519) (xy 395.575101 -313.304706) (xy 395.526115 -313.296678) (xy 395.479074 -313.280832)
			(xy 395.435216 -313.257583) (xy 395.395697 -313.227546) (xy 395.361558 -313.19151) (xy 395.333698 -313.150426)
			(xy 395.312853 -313.105377) (xy 395.29957 -313.057548) (xy 395.2942 -313.008201) (xy 395.296884 -312.958634)
			(xy 395.307552 -312.910155) (xy 395.325922 -312.864041) (xy 395.351511 -312.821506) (xy 395.383644 -312.783671)
			(xy 395.421475 -312.751533) (xy 395.464007 -312.725939) (xy 395.510119 -312.707563) (xy 395.558597 -312.696889)
			(xy 395.608163 -312.694199) (xy 395.657511 -312.699563) (xy 395.705341 -312.712839) (xy 395.750393 -312.73368)
			(xy 395.791481 -312.761534) (xy 395.82752 -312.795668) (xy 395.857563 -312.835184) (xy 395.880817 -312.879039)
			(xy 395.896669 -312.926078) (xy 395.904703 -312.975063) (xy 395.905228 -312.999882) (xy 395.905189 -313.008983)
			(xy 395.904173 -313.027156) (xy 395.903196 -313.036204) (xy 395.901672 -313.048142) (xy 395.9098 -313.070494)
			(xy 395.985746 -313.143392) (xy 396.008352 -313.150504) (xy 396.012924 -313.149742) (xy 396.028208 -313.147007)
			(xy 396.059121 -313.144081) (xy 396.074646 -313.1439) (xy 396.089651 -313.144047) (xy 396.119542 -313.146721)
			(xy 396.134336 -313.149234) (xy 396.134844 -313.149234) (xy 396.141194 -313.15025) (xy 396.1638 -313.143392)
			(xy 396.231364 -313.078622) (xy 396.23945 -313.070134) (xy 396.247543 -313.048159) (xy 396.246858 -313.036458)
			(xy 396.246858 -313.036204) (xy 396.24581 -313.02716) (xy 396.244668 -313.008986) (xy 396.244572 -312.999882)
			(xy 396.245059 -312.97506) (xy 396.253094 -312.926069) (xy 396.268949 -312.879024) (xy 396.292205 -312.835163)
			(xy 396.322252 -312.795643) (xy 396.358296 -312.761504) (xy 396.399388 -312.733646) (xy 396.444446 -312.712804)
			(xy 396.492282 -312.699525) (xy 396.541636 -312.694161) (xy 396.591208 -312.696851) (xy 396.639692 -312.707527)
			(xy 396.68581 -312.725905) (xy 396.728347 -312.751502) (xy 396.766183 -312.783644) (xy 396.79832 -312.821484)
			(xy 396.823912 -312.864024) (xy 396.842285 -312.910144) (xy 396.852954 -312.958629) (xy 396.855638 -313.008202)
			(xy 396.850268 -313.057555) (xy 396.836983 -313.10539) (xy 396.816135 -313.150445) (xy 396.788272 -313.191534)
			(xy 396.754129 -313.227574) (xy 396.714605 -313.257615) (xy 396.670741 -313.280867) (xy 396.623694 -313.296715)
			(xy 396.574703 -313.304744) (xy 396.54988 -313.30519) (xy 396.540839 -313.305084) (xy 396.522794 -313.303939)
			(xy 396.513812 -313.302904) (xy 396.513304 -313.302904) (xy 396.50162 -313.301634) (xy 396.479268 -313.309762)
			(xy 396.40637 -313.385962) (xy 396.399258 -313.408822) (xy 396.40129 -313.420506) (xy 396.403058 -313.431733)
			(xy 396.405221 -313.454359) (xy 396.405608 -313.465718) (xy 396.405608 -313.54522) (xy 396.406171 -313.555912)
			(xy 396.41483 -313.575467) (xy 396.422372 -313.583066) (xy 396.478506 -313.633612) (xy 396.486728 -313.640392)
			(xy 396.506983 -313.646953) (xy 396.517622 -313.646312) (xy 396.517876 -313.646312) (xy 396.54988 -313.644534)
			(xy 396.573873 -313.644979) (xy 396.621268 -313.652483) (xy 396.666906 -313.667311) (xy 396.709662 -313.689096)
			(xy 396.748483 -313.717302) (xy 396.782413 -313.751234) (xy 396.810616 -313.790057) (xy 396.832398 -313.832814)
			(xy 396.847222 -313.878453) (xy 396.854723 -313.925849) (xy 396.855188 -313.949842) (xy 396.855188 -313.95035)
			(xy 396.854654 -313.975522) (xy 396.846361 -314.025179) (xy 396.838678 -314.049156) (xy 396.836646 -314.056776)
			(xy 396.83436 -314.06973) (xy 396.834853 -314.079737) (xy 396.842516 -314.098225) (xy 396.856667 -314.112378)
			(xy 396.875153 -314.120045) (xy 396.88516 -314.12053) (xy 396.899384 -314.117736) (xy 396.907512 -314.11545)
			(xy 396.91706 -314.111946) (xy 396.936505 -314.105972) (xy 396.946374 -314.103512) (xy 396.968137 -314.098559)
			(xy 397.012523 -314.093858) (xy 397.057138 -314.095156) (xy 397.079216 -314.098432) (xy 397.0909 -314.100464)
			(xy 397.11376 -314.093352) (xy 397.181578 -314.028836) (xy 397.18958 -314.02031) (xy 397.197525 -313.998344)
			(xy 397.196818 -313.986672) (xy 397.196818 -313.986164) (xy 397.195769 -313.97712) (xy 397.194622 -313.958946)
			(xy 397.194532 -313.949842) (xy 397.194975 -313.925848) (xy 397.202477 -313.87845) (xy 397.217302 -313.832809)
			(xy 397.239086 -313.79005) (xy 397.267292 -313.751226) (xy 397.301224 -313.717293) (xy 397.340048 -313.689087)
			(xy 397.382807 -313.667303) (xy 397.428448 -313.652477) (xy 397.475846 -313.644975) (xy 397.49984 -313.644534)
			(xy 397.531336 -313.646312) (xy 397.531844 -313.646312) (xy 397.542467 -313.646836) (xy 397.562679 -313.640285)
			(xy 397.57096 -313.633612) (xy 397.627094 -313.583066) (xy 397.634744 -313.575545) (xy 397.643409 -313.555941)
			(xy 397.643858 -313.54522) (xy 397.643858 -313.47537) (xy 397.643858 -313.474862) (xy 397.644112 -313.470798)
			(xy 397.644112 -313.46902) (xy 397.646398 -313.434984) (xy 397.646398 -313.434476) (xy 397.646652 -313.43219)
			(xy 397.646906 -313.43092) (xy 397.647668 -313.425078) (xy 397.647922 -313.423554) (xy 397.64843 -313.420506)
			(xy 397.650462 -313.408568) (xy 397.64335 -313.385708) (xy 397.57858 -313.318144) (xy 397.570052 -313.310149)
			(xy 397.548087 -313.302225) (xy 397.536416 -313.302904) (xy 397.536162 -313.302904) (xy 397.527118 -313.303954)
			(xy 397.508944 -313.3051) (xy 397.49984 -313.30519) (xy 397.47502 -313.304707) (xy 397.426034 -313.296683)
			(xy 397.37899 -313.280839) (xy 397.33513 -313.257593) (xy 397.295609 -313.227557) (xy 397.261468 -313.191523)
			(xy 397.233606 -313.15044) (xy 397.212758 -313.105391) (xy 397.199472 -313.057562) (xy 397.1941 -313.008214)
			(xy 397.196782 -312.958647) (xy 397.207448 -312.910167) (xy 397.225817 -312.864051) (xy 397.251405 -312.821515)
			(xy 397.283537 -312.783678) (xy 397.321367 -312.751539) (xy 397.363899 -312.725943) (xy 397.410011 -312.707565)
			(xy 397.458489 -312.69689) (xy 397.508056 -312.694198) (xy 397.557405 -312.699561) (xy 397.605236 -312.712838)
			(xy 397.650289 -312.733677) (xy 397.691378 -312.761531) (xy 397.727418 -312.795666) (xy 397.757461 -312.835181)
			(xy 397.780716 -312.879037) (xy 397.796569 -312.926077) (xy 397.804603 -312.975062) (xy 397.805148 -312.999882)
			(xy 397.805109 -313.008983) (xy 397.804094 -313.027156) (xy 397.803116 -313.036204) (xy 397.801592 -313.048142)
			(xy 397.80972 -313.070494) (xy 397.88592 -313.143392) (xy 397.908526 -313.150504) (xy 397.914368 -313.149488)
			(xy 397.929345 -313.146879) (xy 397.959619 -313.144079) (xy 397.97482 -313.1439) (xy 397.989831 -313.144096)
			(xy 398.019724 -313.146891) (xy 398.03451 -313.149488) (xy 398.035526 -313.149488) (xy 398.041114 -313.150504)
			(xy 398.06372 -313.143392) (xy 398.13992 -313.070494) (xy 398.148048 -313.048142) (xy 398.146524 -313.036204)
			(xy 398.145536 -313.027157) (xy 398.144522 -313.008983) (xy 398.144492 -312.999882) (xy 398.144979 -312.975061)
			(xy 398.153013 -312.926075) (xy 398.168866 -312.879033) (xy 398.192121 -312.835176) (xy 398.222164 -312.795658)
			(xy 398.258205 -312.761522) (xy 398.299294 -312.733666) (xy 398.344348 -312.712824) (xy 398.39218 -312.699546)
			(xy 398.44153 -312.694181) (xy 398.491099 -312.69687) (xy 398.539579 -312.707543) (xy 398.585693 -312.725919)
			(xy 398.628228 -312.751513) (xy 398.666062 -312.783651) (xy 398.698197 -312.821487) (xy 398.723789 -312.864023)
			(xy 398.742162 -312.910139) (xy 398.752832 -312.958619) (xy 398.755519 -313.008188) (xy 398.750151 -313.057538)
			(xy 398.736869 -313.105369) (xy 398.716025 -313.150422) (xy 398.688167 -313.191509) (xy 398.654028 -313.227548)
			(xy 398.614509 -313.257589) (xy 398.57065 -313.280841) (xy 398.523608 -313.296691) (xy 398.474621 -313.304722)
			(xy 398.4498 -313.30519) (xy 398.440759 -313.305085) (xy 398.422714 -313.303941) (xy 398.413732 -313.302904)
			(xy 398.41297 -313.302904) (xy 398.401299 -313.3022) (xy 398.379335 -313.310145) (xy 398.370806 -313.318144)
			(xy 398.306036 -313.385708) (xy 398.298924 -313.408314) (xy 398.299686 -313.41314) (xy 398.302402 -313.428298)
			(xy 398.305332 -313.458956) (xy 398.305528 -313.474354) (xy 398.305528 -313.54522) (xy 398.306091 -313.555911)
			(xy 398.314753 -313.575464) (xy 398.322292 -313.583066) (xy 398.378426 -313.633612) (xy 398.386644 -313.640406)
			(xy 398.406903 -313.646999) (xy 398.417542 -313.646312) (xy 398.417796 -313.646312) (xy 398.4498 -313.644534)
			(xy 398.473792 -313.64498) (xy 398.521185 -313.652487) (xy 398.56682 -313.667316) (xy 398.609573 -313.689102)
			(xy 398.648391 -313.717309) (xy 398.682319 -313.751241) (xy 398.71052 -313.790063) (xy 398.7323 -313.832819)
			(xy 398.747123 -313.878456) (xy 398.754623 -313.92585) (xy 398.755108 -313.949842) (xy 398.75501 -313.958946)
			(xy 398.753867 -313.977119) (xy 398.752822 -313.986164) (xy 398.752013 -313.998062) (xy 398.760077 -314.020472)
			(xy 398.768316 -314.02909) (xy 398.83588 -314.093606) (xy 398.858486 -314.100718) (xy 398.865598 -314.099448)
			(xy 398.89143 -314.095252) (xy 398.943748 -314.094096) (xy 398.969738 -314.097162) (xy 398.970246 -314.097162)
			(xy 398.985994 -314.099702) (xy 398.986502 -314.099702) (xy 398.991328 -314.100464) (xy 399.013934 -314.093606)
			(xy 399.081498 -314.02909) (xy 399.089705 -314.020448) (xy 399.097774 -313.998057) (xy 399.096992 -313.986164)
			(xy 399.095942 -313.97712) (xy 399.094796 -313.958946) (xy 399.094706 -313.949842) (xy 399.095149 -313.925847)
			(xy 399.102651 -313.878447) (xy 399.117476 -313.832805) (xy 399.139259 -313.790044) (xy 399.167464 -313.751218)
			(xy 399.201396 -313.717282) (xy 399.24022 -313.689074) (xy 399.282979 -313.667286) (xy 399.32862 -313.652457)
			(xy 399.376019 -313.644951) (xy 399.400014 -313.644534) (xy 399.431764 -313.646058) (xy 399.442178 -313.647328)
			(xy 399.463006 -313.64047) (xy 399.527014 -313.582812) (xy 399.534682 -313.575299) (xy 399.543378 -313.555693)
			(xy 399.543778 -313.544966) (xy 399.543778 -313.474862) (xy 399.543968 -313.459788) (xy 399.546771 -313.429769)
			(xy 399.549366 -313.414918) (xy 399.549366 -313.413902) (xy 399.550382 -313.408568) (xy 399.54327 -313.385962)
			(xy 399.470372 -313.309762) (xy 399.44802 -313.301634) (xy 399.436082 -313.303158) (xy 399.427098 -313.304139)
			(xy 399.409052 -313.305153) (xy 399.400014 -313.30519) (xy 399.375195 -313.304705) (xy 399.32621 -313.296677)
			(xy 399.279169 -313.280829) (xy 399.235311 -313.25758) (xy 399.195793 -313.227542) (xy 399.161655 -313.191506)
			(xy 399.133796 -313.150422) (xy 399.112951 -313.105373) (xy 399.099669 -313.057544) (xy 399.0943 -313.008197)
			(xy 399.096984 -312.958631) (xy 399.107653 -312.910152) (xy 399.126024 -312.864038) (xy 399.151613 -312.821503)
			(xy 399.183746 -312.783669) (xy 399.221577 -312.751532) (xy 399.264109 -312.725938) (xy 399.310221 -312.707562)
			(xy 399.358699 -312.696889) (xy 399.408265 -312.694199) (xy 399.457612 -312.699563) (xy 399.505443 -312.71284)
			(xy 399.550495 -312.73368) (xy 399.591581 -312.761534) (xy 399.627621 -312.795669) (xy 399.657663 -312.835184)
			(xy 399.680917 -312.879039) (xy 399.696769 -312.926078) (xy 399.704803 -312.975063) (xy 399.705322 -312.999882)
			(xy 399.705283 -313.008983) (xy 399.704267 -313.027156) (xy 399.70329 -313.036204) (xy 399.701766 -313.048142)
			(xy 399.709894 -313.070494) (xy 399.78584 -313.143392) (xy 399.808446 -313.150504) (xy 399.813018 -313.149742)
			(xy 399.828302 -313.147007) (xy 399.859215 -313.14408) (xy 399.87474 -313.1439) (xy 399.883122 -313.1439)
			(xy 399.887694 -313.144154) (xy 399.887948 -313.144154) (xy 399.893028 -313.144408) (xy 399.903438 -313.145041)
			(xy 399.924154 -313.147453) (xy 399.93443 -313.149234) (xy 399.934938 -313.149234) (xy 399.941288 -313.15025)
			(xy 399.963894 -313.143392) (xy 400.031458 -313.078622) (xy 400.039545 -313.070134) (xy 400.047639 -313.04816)
			(xy 400.046952 -313.036458) (xy 400.046952 -313.036204) (xy 400.045904 -313.02716) (xy 400.044762 -313.008986)
			(xy 400.044666 -312.999882) (xy 400.045153 -312.975059) (xy 400.053188 -312.926067) (xy 400.069043 -312.879021)
			(xy 400.092301 -312.835159) (xy 400.122348 -312.795638) (xy 400.158393 -312.761499) (xy 400.199486 -312.733641)
			(xy 400.244545 -312.712798) (xy 400.292383 -312.699519) (xy 400.341738 -312.694155) (xy 400.391311 -312.696846)
			(xy 400.439796 -312.707522) (xy 400.485915 -312.725901) (xy 400.528453 -312.751499) (xy 400.566289 -312.783642)
			(xy 400.598427 -312.821483) (xy 400.624019 -312.864024) (xy 400.642391 -312.910146) (xy 400.65306 -312.958632)
			(xy 400.655744 -313.008206) (xy 400.650373 -313.057561) (xy 400.637087 -313.105396) (xy 400.616238 -313.150452)
			(xy 400.588374 -313.191542) (xy 400.554229 -313.227582) (xy 400.514704 -313.257623) (xy 400.470839 -313.280874)
			(xy 400.42379 -313.296722) (xy 400.374797 -313.30475) (xy 400.349974 -313.30519) (xy 400.34087 -313.305093)
			(xy 400.322697 -313.30395) (xy 400.313652 -313.302904) (xy 400.313398 -313.302904) (xy 400.301598 -313.302096)
			(xy 400.279356 -313.310053) (xy 400.270726 -313.318144) (xy 400.20621 -313.385708) (xy 400.199098 -313.408314)
			(xy 400.200114 -313.414664) (xy 400.202708 -313.429579) (xy 400.205509 -313.459725) (xy 400.205702 -313.474862)
			(xy 400.205702 -313.485784) (xy 400.205448 -313.487816) (xy 400.205448 -313.54522) (xy 400.206012 -313.555911)
			(xy 400.214676 -313.575462) (xy 400.222212 -313.583066) (xy 400.286728 -313.640724) (xy 400.307048 -313.647328)
			(xy 400.317716 -313.646312) (xy 400.349974 -313.644534) (xy 400.373967 -313.644978) (xy 400.421363 -313.652482)
			(xy 400.467002 -313.667309) (xy 400.509759 -313.689093) (xy 400.54858 -313.717299) (xy 400.582511 -313.751232)
			(xy 400.610715 -313.790055) (xy 400.632497 -313.832813) (xy 400.647322 -313.878452) (xy 400.654823 -313.925849)
			(xy 400.655282 -313.949842) (xy 400.655184 -313.958946) (xy 400.654041 -313.977119) (xy 400.652996 -313.986164)
			(xy 400.652188 -313.99806) (xy 400.66026 -314.020464) (xy 400.66849 -314.02909) (xy 400.736054 -314.093606)
			(xy 400.75866 -314.100464) (xy 400.76374 -314.099702) (xy 400.790002 -314.095346) (xy 400.843217 -314.094078)
			(xy 400.869658 -314.097162) (xy 400.870166 -314.097162) (xy 400.885914 -314.099702) (xy 400.886422 -314.099702)
			(xy 400.891248 -314.100464) (xy 400.913854 -314.093606) (xy 400.981418 -314.02909) (xy 400.989635 -314.020453)
			(xy 400.997718 -313.998058) (xy 400.996912 -313.986164) (xy 400.995863 -313.97712) (xy 400.994717 -313.958946)
			(xy 400.994626 -313.949842) (xy 400.995069 -313.925848) (xy 401.002571 -313.878449) (xy 401.017396 -313.832808)
			(xy 401.03918 -313.790049) (xy 401.067385 -313.751224) (xy 401.101318 -313.71729) (xy 401.140142 -313.689084)
			(xy 401.182901 -313.667299) (xy 401.228541 -313.652473) (xy 401.27594 -313.64497) (xy 401.299934 -313.644534)
			(xy 401.331684 -313.646058) (xy 401.342098 -313.647328) (xy 401.362926 -313.64047) (xy 401.426934 -313.582812)
			(xy 401.434599 -313.575297) (xy 401.443292 -313.555692) (xy 401.443698 -313.544966) (xy 401.443698 -313.474862)
			(xy 401.443888 -313.459788) (xy 401.446691 -313.429769) (xy 401.449286 -313.414918) (xy 401.449286 -313.413902)
			(xy 401.450302 -313.408568) (xy 401.44319 -313.385962) (xy 401.370292 -313.309762) (xy 401.34794 -313.301634)
			(xy 401.336002 -313.303158) (xy 401.327018 -313.30414) (xy 401.308972 -313.305155) (xy 401.299934 -313.30519)
			(xy 401.275114 -313.304707) (xy 401.226128 -313.296682) (xy 401.179085 -313.280837) (xy 401.135226 -313.25759)
			(xy 401.095705 -313.227554) (xy 401.061565 -313.191519) (xy 401.033704 -313.150436) (xy 401.012856 -313.105387)
			(xy 400.999572 -313.057558) (xy 400.9942 -313.00821) (xy 400.996883 -312.958643) (xy 401.007549 -312.910163)
			(xy 401.025919 -312.864048) (xy 401.051507 -312.821512) (xy 401.083639 -312.783676) (xy 401.12147 -312.751537)
			(xy 401.164001 -312.725942) (xy 401.210114 -312.707565) (xy 401.258592 -312.69689) (xy 401.308158 -312.694199)
			(xy 401.357507 -312.699562) (xy 401.405338 -312.712838) (xy 401.450391 -312.733678) (xy 401.491478 -312.761532)
			(xy 401.527519 -312.795667) (xy 401.557562 -312.835182) (xy 401.580816 -312.879038) (xy 401.596669 -312.926077)
			(xy 401.604703 -312.975062) (xy 401.605242 -312.999882) (xy 401.605203 -313.008983) (xy 401.604188 -313.027156)
			(xy 401.60321 -313.036204) (xy 401.601686 -313.048142) (xy 401.609814 -313.070494) (xy 401.68576 -313.143392)
			(xy 401.708366 -313.150504) (xy 401.712938 -313.149742) (xy 401.728222 -313.147007) (xy 401.759135 -313.144082)
			(xy 401.77466 -313.1439) (xy 401.783042 -313.1439) (xy 401.787614 -313.144154) (xy 401.787868 -313.144154)
			(xy 401.792948 -313.144408) (xy 401.803357 -313.145041) (xy 401.824074 -313.147455) (xy 401.83435 -313.149234)
			(xy 401.834858 -313.149234) (xy 401.841208 -313.15025) (xy 401.863814 -313.143392) (xy 401.931378 -313.078622)
			(xy 401.939462 -313.070133) (xy 401.947553 -313.048159) (xy 401.946872 -313.036458) (xy 401.946872 -313.036204)
			(xy 401.945824 -313.02716) (xy 401.944681 -313.008986) (xy 401.944586 -312.999882) (xy 401.945073 -312.975061)
			(xy 401.953107 -312.926073) (xy 401.968961 -312.87903) (xy 401.992216 -312.835172) (xy 402.02226 -312.795654)
			(xy 402.058302 -312.761517) (xy 402.099392 -312.73366) (xy 402.144447 -312.712818) (xy 402.192281 -312.69954)
			(xy 402.241632 -312.694175) (xy 402.291202 -312.696865) (xy 402.339683 -312.707538) (xy 402.385798 -312.725915)
			(xy 402.428334 -312.75151) (xy 402.466168 -312.783649) (xy 402.498304 -312.821486) (xy 402.523896 -312.864023)
			(xy 402.542269 -312.91014) (xy 402.552939 -312.958622) (xy 402.555625 -313.008192) (xy 402.550256 -313.057543)
			(xy 402.536974 -313.105375) (xy 402.516128 -313.150429) (xy 402.488268 -313.191516) (xy 402.454128 -313.227556)
			(xy 402.414608 -313.257597) (xy 402.370748 -313.280849) (xy 402.323704 -313.296698) (xy 402.274715 -313.304729)
			(xy 402.249894 -313.30519) (xy 402.24079 -313.305093) (xy 402.222616 -313.303952) (xy 402.213572 -313.302904)
			(xy 402.213318 -313.302904) (xy 402.201516 -313.302092) (xy 402.179267 -313.310043) (xy 402.170646 -313.318144)
			(xy 402.10613 -313.385708) (xy 402.099018 -313.408314) (xy 402.100034 -313.414664) (xy 402.102627 -313.429579)
			(xy 402.105429 -313.459725) (xy 402.105622 -313.474862) (xy 402.105622 -313.485784) (xy 402.105368 -313.487816)
			(xy 402.105368 -313.54522) (xy 402.105933 -313.55591) (xy 402.114599 -313.575459) (xy 402.122132 -313.583066)
			(xy 402.186648 -313.640724) (xy 402.206968 -313.647328) (xy 402.217636 -313.646312) (xy 402.249894 -313.644534)
			(xy 402.273886 -313.64498) (xy 402.32128 -313.652486) (xy 402.366916 -313.667315) (xy 402.40967 -313.6891)
			(xy 402.448489 -313.717307) (xy 402.482417 -313.751239) (xy 402.510619 -313.790061) (xy 402.532399 -313.832818)
			(xy 402.547222 -313.878455) (xy 402.554723 -313.92585) (xy 402.555202 -313.949842) (xy 402.555104 -313.958946)
			(xy 402.553961 -313.977119) (xy 402.552916 -313.986164) (xy 402.552107 -313.998062) (xy 402.56017 -314.020473)
			(xy 402.56841 -314.02909) (xy 402.635974 -314.093606) (xy 402.65858 -314.100464) (xy 402.66366 -314.099702)
			(xy 402.689922 -314.09534) (xy 402.743138 -314.094059) (xy 402.769578 -314.097162) (xy 402.770086 -314.097162)
			(xy 402.785834 -314.099702) (xy 402.786342 -314.099702) (xy 402.791168 -314.100464) (xy 402.813774 -314.093606)
			(xy 402.881338 -314.02909) (xy 402.889552 -314.020452) (xy 402.897632 -313.998058) (xy 402.896832 -313.986164)
			(xy 402.895782 -313.97712) (xy 402.894636 -313.958946) (xy 402.894546 -313.949842) (xy 402.895013 -313.925847)
			(xy 402.902514 -313.878448) (xy 402.917337 -313.832805) (xy 402.939118 -313.790043) (xy 402.96732 -313.751215)
			(xy 403.001248 -313.717277) (xy 403.040068 -313.689064) (xy 403.082824 -313.667271) (xy 403.128462 -313.652435)
			(xy 403.175859 -313.64492) (xy 403.199854 -313.644534) (xy 403.23135 -313.646312) (xy 403.231858 -313.646312)
			(xy 403.24248 -313.646833) (xy 403.262688 -313.640278) (xy 403.270974 -313.633612) (xy 403.327108 -313.583066)
			(xy 403.334756 -313.575544) (xy 403.343418 -313.55594) (xy 403.343872 -313.54522) (xy 403.343872 -313.474862)
			(xy 403.34565 -313.441588) (xy 403.348444 -313.420506) (xy 403.348444 -313.420252) (xy 403.349737 -313.408513)
			(xy 403.342718 -313.385995) (xy 403.334982 -313.377072) (xy 403.278594 -313.318144) (xy 403.270067 -313.310147)
			(xy 403.248101 -313.302216) (xy 403.23643 -313.302904) (xy 403.236176 -313.302904) (xy 403.227132 -313.303951)
			(xy 403.208958 -313.305092) (xy 403.199854 -313.30519) (xy 403.175036 -313.304701) (xy 403.126054 -313.296663)
			(xy 403.079018 -313.280808) (xy 403.035167 -313.257552) (xy 402.995655 -313.227508) (xy 402.961524 -313.191468)
			(xy 402.933673 -313.150382) (xy 402.912836 -313.105331) (xy 402.899561 -313.057502) (xy 402.894198 -313.008156)
			(xy 402.89689 -312.958593) (xy 402.907563 -312.910117) (xy 402.925939 -312.864007) (xy 402.951532 -312.821477)
			(xy 402.983667 -312.783648) (xy 403.0215 -312.751515) (xy 403.064032 -312.725926) (xy 403.110144 -312.707555)
			(xy 403.15862 -312.696886) (xy 403.208184 -312.694199) (xy 403.25753 -312.699566) (xy 403.305357 -312.712845)
			(xy 403.350406 -312.733687) (xy 403.39149 -312.761542) (xy 403.427527 -312.795676) (xy 403.457567 -312.83519)
			(xy 403.480819 -312.879044) (xy 403.49667 -312.926081) (xy 403.504703 -312.975064) (xy 403.505162 -312.999882)
			(xy 403.505123 -313.008983) (xy 403.504108 -313.027156) (xy 403.50313 -313.036204) (xy 403.501606 -313.048142)
			(xy 403.509734 -313.070494) (xy 403.585934 -313.143392) (xy 403.60854 -313.150504) (xy 403.614382 -313.149488)
			(xy 403.629359 -313.146881) (xy 403.659633 -313.144079) (xy 403.674834 -313.1439) (xy 403.689908 -313.14409)
			(xy 403.719927 -313.146893) (xy 403.734778 -313.149488) (xy 403.735794 -313.149488) (xy 403.741128 -313.150504)
			(xy 403.763734 -313.143392) (xy 403.839934 -313.070494) (xy 403.848062 -313.048142) (xy 403.846538 -313.036204)
			(xy 403.84555 -313.027157) (xy 403.844537 -313.008983) (xy 403.844506 -312.999882) (xy 403.844993 -312.975063)
			(xy 403.853027 -312.926079) (xy 403.868879 -312.87904) (xy 403.892132 -312.835185) (xy 403.922173 -312.795669)
			(xy 403.958212 -312.761535) (xy 403.999298 -312.73368) (xy 404.044349 -312.712839) (xy 404.092179 -312.69956)
			(xy 404.141526 -312.694195) (xy 404.191092 -312.696883) (xy 404.239569 -312.707555) (xy 404.285682 -312.725929)
			(xy 404.328215 -312.751521) (xy 404.366047 -312.783656) (xy 404.398182 -312.821489) (xy 404.423773 -312.864022)
			(xy 404.442146 -312.910135) (xy 404.452817 -312.958612) (xy 404.455505 -313.008178) (xy 404.450139 -313.057525)
			(xy 404.43686 -313.105354) (xy 404.416018 -313.150405) (xy 404.388163 -313.191491) (xy 404.354028 -313.227529)
			(xy 404.314512 -313.25757) (xy 404.270657 -313.280823) (xy 404.223617 -313.296674) (xy 404.174633 -313.304707)
			(xy 404.149814 -313.30519) (xy 404.140713 -313.305151) (xy 404.12254 -313.304135) (xy 404.113492 -313.303158)
			(xy 404.101554 -313.301634) (xy 404.079202 -313.309762) (xy 404.006304 -313.385962) (xy 403.999192 -313.408568)
			(xy 404.000208 -313.41441) (xy 404.002814 -313.429387) (xy 404.005613 -313.459661) (xy 404.005796 -313.474862)
			(xy 404.005796 -313.54522) (xy 404.006359 -313.555912) (xy 404.015016 -313.575469) (xy 404.02256 -313.583066)
			(xy 404.078694 -313.633612) (xy 404.086915 -313.640394) (xy 404.107171 -313.646959) (xy 404.11781 -313.646312)
			(xy 404.118064 -313.646312) (xy 404.149814 -313.644534) (xy 404.173805 -313.644981) (xy 404.221197 -313.65249)
			(xy 404.26683 -313.66732) (xy 404.309581 -313.689107) (xy 404.348397 -313.717314) (xy 404.382323 -313.751246)
			(xy 404.410522 -313.790067) (xy 404.432301 -313.832822) (xy 404.447123 -313.878458) (xy 404.454623 -313.925851)
			(xy 404.455122 -313.949842) (xy 404.455024 -313.958946) (xy 404.45388 -313.977119) (xy 404.452836 -313.986164)
			(xy 404.452028 -313.998062) (xy 404.460093 -314.02047) (xy 404.46833 -314.02909) (xy 404.535894 -314.093606)
			(xy 404.5585 -314.100718) (xy 404.564596 -314.099702) (xy 404.579511 -314.097107) (xy 404.609657 -314.094309)
			(xy 404.624794 -314.094114) (xy 404.639349 -314.094257) (xy 404.668348 -314.096802) (xy 404.682706 -314.099194)
			(xy 404.683214 -314.099194) (xy 404.691342 -314.100464) (xy 404.713948 -314.093606) (xy 404.790402 -314.020962)
			(xy 404.79853 -313.998102) (xy 404.797006 -313.986418) (xy 404.795951 -313.97731) (xy 404.794806 -313.95901)
			(xy 404.79472 -313.949842) (xy 404.795163 -313.925847) (xy 404.802665 -313.878449) (xy 404.81749 -313.832807)
			(xy 404.839274 -313.790047) (xy 404.867479 -313.751222) (xy 404.901411 -313.717288) (xy 404.940235 -313.689081)
			(xy 404.982994 -313.667295) (xy 405.028635 -313.652468) (xy 405.076034 -313.644964) (xy 405.100028 -313.644534)
			(xy 405.131778 -313.646312) (xy 405.132286 -313.646312) (xy 405.142906 -313.646827) (xy 405.163107 -313.640265)
			(xy 405.171402 -313.633612) (xy 405.227536 -313.583066) (xy 405.235193 -313.575548) (xy 405.243868 -313.555943)
			(xy 405.2443 -313.54522) (xy 405.2443 -313.48299) (xy 405.244046 -313.482482) (xy 405.244046 -313.474862)
			(xy 405.246078 -313.438794) (xy 405.246586 -313.434222) (xy 405.246586 -313.433968) (xy 405.249634 -313.414918)
			(xy 405.249634 -313.413902) (xy 405.25065 -313.408568) (xy 405.243538 -313.385962) (xy 405.17064 -313.309762)
			(xy 405.148288 -313.301634) (xy 405.13635 -313.303158) (xy 405.127303 -313.304147) (xy 405.109129 -313.305163)
			(xy 405.100028 -313.30519) (xy 405.075208 -313.304706) (xy 405.026222 -313.29668) (xy 404.97918 -313.280835)
			(xy 404.935322 -313.257587) (xy 404.895802 -313.22755) (xy 404.861662 -313.191515) (xy 404.833801 -313.150432)
			(xy 404.812955 -313.105382) (xy 404.799671 -313.057554) (xy 404.7943 -313.008206) (xy 404.796983 -312.958639)
			(xy 404.80765 -312.91016) (xy 404.82602 -312.864045) (xy 404.851608 -312.821509) (xy 404.883741 -312.783674)
			(xy 404.921572 -312.751535) (xy 404.964104 -312.725941) (xy 405.010216 -312.707564) (xy 405.058694 -312.696889)
			(xy 405.10826 -312.694199) (xy 405.157608 -312.699562) (xy 405.205439 -312.712839) (xy 405.250492 -312.733679)
			(xy 405.291579 -312.761533) (xy 405.327619 -312.795667) (xy 405.357662 -312.835183) (xy 405.380916 -312.879038)
			(xy 405.396769 -312.926078) (xy 405.404803 -312.975062) (xy 405.405336 -312.999882) (xy 405.405289 -313.008919)
			(xy 405.404272 -313.026965) (xy 405.403304 -313.03595) (xy 405.403304 -313.036204) (xy 405.402497 -313.048004)
			(xy 405.410454 -313.070246) (xy 405.418544 -313.078876) (xy 405.486108 -313.143138) (xy 405.508968 -313.15025)
			(xy 405.520652 -313.148218) (xy 405.523954 -313.14771) (xy 405.524462 -313.14771) (xy 405.543838 -313.145038)
			(xy 405.582931 -313.143764) (xy 405.60244 -313.14517) (xy 405.629364 -313.148472) (xy 405.641048 -313.150504)
			(xy 405.663908 -313.143392) (xy 405.731726 -313.078622) (xy 405.73972 -313.070092) (xy 405.747651 -313.048129)
			(xy 405.746966 -313.036458) (xy 405.746966 -313.036204) (xy 405.745918 -313.02716) (xy 405.744776 -313.008986)
			(xy 405.74468 -312.999882) (xy 405.745167 -312.97506) (xy 405.753202 -312.926071) (xy 405.769056 -312.879027)
			(xy 405.792311 -312.835168) (xy 405.822357 -312.795649) (xy 405.858399 -312.761511) (xy 405.89949 -312.733654)
			(xy 405.944547 -312.712812) (xy 405.992381 -312.699534) (xy 406.041734 -312.694169) (xy 406.091305 -312.696859)
			(xy 406.139787 -312.707533) (xy 406.185903 -312.725911) (xy 406.22844 -312.751507) (xy 406.266274 -312.783647)
			(xy 406.298411 -312.821485) (xy 406.324003 -312.864023) (xy 406.342375 -312.910142) (xy 406.353045 -312.958625)
			(xy 406.35528 -312.999882) (xy 406.694144 -312.999882) (xy 406.698104 -312.950828) (xy 406.709881 -312.903044)
			(xy 406.729172 -312.857768) (xy 406.755475 -312.816172) (xy 406.78811 -312.779335) (xy 406.826231 -312.74821)
			(xy 406.868852 -312.723603) (xy 406.914868 -312.706151) (xy 406.963087 -312.696307) (xy 407.012262 -312.694326)
			(xy 407.061117 -312.700258) (xy 407.108388 -312.71395) (xy 407.15285 -312.735048) (xy 407.193353 -312.763004)
			(xy 407.228846 -312.797096) (xy 407.258411 -312.83644) (xy 407.281282 -312.880017) (xy 407.296866 -312.926698)
			(xy 407.304761 -312.975275) (xy 407.305256 -312.999882) (xy 407.304761 -313.024489) (xy 407.296866 -313.073066)
			(xy 407.281282 -313.119747) (xy 407.258411 -313.163324) (xy 407.228846 -313.202668) (xy 407.193353 -313.23676)
			(xy 407.15285 -313.264716) (xy 407.108388 -313.285814) (xy 407.061117 -313.299506) (xy 407.012262 -313.305438)
			(xy 406.963087 -313.303457) (xy 406.914868 -313.293613) (xy 406.868852 -313.276161) (xy 406.826231 -313.251554)
			(xy 406.78811 -313.220429) (xy 406.755475 -313.183592) (xy 406.729172 -313.141996) (xy 406.709881 -313.09672)
			(xy 406.698104 -313.048936) (xy 406.694144 -312.999882) (xy 406.35528 -312.999882) (xy 406.35573 -313.008196)
			(xy 406.350361 -313.057548) (xy 406.337078 -313.105382) (xy 406.316231 -313.150436) (xy 406.28837 -313.191524)
			(xy 406.254229 -313.227563) (xy 406.214707 -313.257605) (xy 406.170845 -313.280856) (xy 406.1238 -313.296706)
			(xy 406.07481 -313.304735) (xy 406.049988 -313.30519) (xy 406.040884 -313.305093) (xy 406.02271 -313.303951)
			(xy 406.013666 -313.302904) (xy 406.013412 -313.302904) (xy 406.001611 -313.302093) (xy 405.979364 -313.310046)
			(xy 405.97074 -313.318144) (xy 405.906224 -313.385708) (xy 405.899112 -313.408314) (xy 405.900128 -313.413902)
			(xy 405.902735 -313.428879) (xy 405.905532 -313.459153) (xy 405.905716 -313.474354) (xy 405.905716 -313.54522)
			(xy 405.906279 -313.555912) (xy 405.914939 -313.575466) (xy 405.92248 -313.583066) (xy 405.978614 -313.633612)
			(xy 405.986832 -313.640408) (xy 406.007091 -313.647005) (xy 406.01773 -313.646312) (xy 406.017984 -313.646312)
			(xy 406.049988 -313.644534) (xy 406.073981 -313.644979) (xy 406.121375 -313.652485) (xy 406.167012 -313.667313)
			(xy 406.209766 -313.689098) (xy 406.248586 -313.717304) (xy 406.282515 -313.751237) (xy 406.310717 -313.790059)
			(xy 406.332499 -313.832816) (xy 406.347322 -313.878454) (xy 406.354823 -313.925849) (xy 406.355296 -313.949842)
			(xy 406.355296 -313.95035) (xy 406.354762 -313.975522) (xy 406.346467 -314.025179) (xy 406.338786 -314.049156)
			(xy 406.336754 -314.056776) (xy 406.334468 -314.06973) (xy 406.334961 -314.079736) (xy 406.342624 -314.098223)
			(xy 406.356775 -314.112374) (xy 406.375262 -314.120039) (xy 406.385268 -314.12053) (xy 406.399492 -314.117736)
			(xy 406.40762 -314.11545) (xy 406.417168 -314.111946) (xy 406.436613 -314.105973) (xy 406.446482 -314.103512)
			(xy 406.468245 -314.098559) (xy 406.512631 -314.09386) (xy 406.557245 -314.095159) (xy 406.579324 -314.098432)
			(xy 406.591008 -314.100464) (xy 406.613868 -314.093352) (xy 406.681686 -314.028836) (xy 406.689687 -314.020309)
			(xy 406.697631 -313.998343) (xy 406.696926 -313.986672) (xy 406.696926 -313.986164) (xy 406.695877 -313.97712)
			(xy 406.69473 -313.958946) (xy 406.69464 -313.949842) (xy 406.695122 -313.925025) (xy 406.703145 -313.876044)
			(xy 406.718987 -313.829006) (xy 406.74223 -313.785151) (xy 406.772261 -313.745634) (xy 406.80829 -313.711496)
			(xy 406.849368 -313.683636) (xy 406.894411 -313.662789) (xy 406.942234 -313.649504) (xy 406.991576 -313.64413)
			(xy 407.041137 -313.64681) (xy 407.089612 -313.657473) (xy 407.135723 -313.675838) (xy 407.178256 -313.70142)
			(xy 407.216089 -313.733547) (xy 407.248227 -313.771371) (xy 407.273822 -313.813896) (xy 407.292201 -313.860002)
			(xy 407.302878 -313.908474) (xy 407.305572 -313.958034) (xy 407.300213 -314.007378) (xy 407.286942 -314.055204)
			(xy 407.266108 -314.100254) (xy 407.238261 -314.14134) (xy 407.204133 -314.177379) (xy 407.164625 -314.207422)
			(xy 407.120776 -314.230677) (xy 407.073743 -314.246533) (xy 407.024765 -314.25457) (xy 406.999948 -314.25515)
			(xy 406.990907 -314.255046) (xy 406.972861 -314.253905) (xy 406.96388 -314.252864) (xy 406.963372 -314.252864)
			(xy 406.951688 -314.251594) (xy 406.929336 -314.259722) (xy 406.856438 -314.335922) (xy 406.849326 -314.358782)
			(xy 406.851358 -314.370466) (xy 406.854914 -314.399168) (xy 406.854914 -314.399676) (xy 406.855422 -314.408566)
			(xy 406.855422 -314.40882) (xy 406.855676 -314.411614) (xy 406.855676 -314.41263) (xy 406.856932 -314.420433)
			(xy 406.863537 -314.43478) (xy 406.86863 -314.440824) (xy 406.893522 -314.465208) (xy 406.893776 -314.465462)
			(xy 406.902158 -314.47359) (xy 406.921462 -314.492132) (xy 406.921716 -314.492386) (xy 406.927321 -314.497395)
			(xy 406.940762 -314.50411) (xy 406.948132 -314.505594) (xy 406.94864 -314.505594) (xy 406.956768 -314.506356)
			(xy 407.993088 -314.506356) (xy 408.001216 -314.505594) (xy 408.001724 -314.505594) (xy 408.00907 -314.504045)
			(xy 408.022487 -314.497327) (xy 408.02814 -314.492386) (xy 408.046936 -314.474352) (xy 408.080718 -314.44184)
			(xy 408.08358 -314.438721) (xy 408.088305 -314.431697) (xy 408.090116 -314.42787) (xy 408.093926 -314.419234)
			(xy 408.09418 -314.414154) (xy 408.09418 -314.354464) (xy 408.093614 -314.343774) (xy 408.084949 -314.324225)
			(xy 408.077416 -314.316618) (xy 408.021282 -314.266072) (xy 408.013064 -314.259278) (xy 407.992805 -314.252684)
			(xy 407.982166 -314.253372) (xy 407.981912 -314.253372) (xy 407.949908 -314.25515) (xy 407.924646 -314.254658)
			(xy 407.874812 -314.246343) (xy 407.827026 -314.229939) (xy 407.782592 -314.205894) (xy 407.742721 -314.174862)
			(xy 407.708502 -314.137692) (xy 407.680868 -314.095395) (xy 407.660573 -314.049128) (xy 407.64817 -314.000151)
			(xy 407.643998 -313.9498) (xy 407.64817 -313.899449) (xy 407.660573 -313.850472) (xy 407.680868 -313.804205)
			(xy 407.708502 -313.761908) (xy 407.742721 -313.724738) (xy 407.782592 -313.693706) (xy 407.827026 -313.669661)
			(xy 407.874812 -313.653257) (xy 407.924646 -313.644942) (xy 407.949908 -313.644534) (xy 407.981658 -313.646312)
			(xy 407.982166 -313.646312) (xy 407.992788 -313.646831) (xy 408.012994 -313.640274) (xy 408.021282 -313.633612)
			(xy 408.077416 -313.583066) (xy 408.085076 -313.57555) (xy 408.093754 -313.555944) (xy 408.09418 -313.54522)
			(xy 408.09418 -313.474862) (xy 408.094398 -313.459978) (xy 408.097193 -313.430341) (xy 408.099768 -313.41568)
			(xy 408.099768 -313.414156) (xy 408.100784 -313.408314) (xy 408.093672 -313.385708) (xy 408.029156 -313.318144)
			(xy 408.020514 -313.310084) (xy 407.998279 -313.302158) (xy 407.986484 -313.302904) (xy 407.98623 -313.302904)
			(xy 407.977186 -313.303953) (xy 407.959012 -313.305097) (xy 407.949908 -313.30519) (xy 407.925089 -313.304705)
			(xy 407.876104 -313.296676) (xy 407.829064 -313.280827) (xy 407.785207 -313.257578) (xy 407.745689 -313.227539)
			(xy 407.711551 -313.191503) (xy 407.683694 -313.150418) (xy 407.662849 -313.105368) (xy 407.649568 -313.05754)
			(xy 407.644199 -313.008193) (xy 407.646885 -312.958627) (xy 407.657554 -312.910148) (xy 407.675925 -312.864035)
			(xy 407.701515 -312.821501) (xy 407.733648 -312.783667) (xy 407.771479 -312.75153) (xy 407.814011 -312.725937)
			(xy 407.860124 -312.707562) (xy 407.908601 -312.696888) (xy 407.958166 -312.694199) (xy 408.007514 -312.699563)
			(xy 408.055344 -312.712841) (xy 408.100396 -312.733681) (xy 408.141482 -312.761535) (xy 408.177521 -312.79567)
			(xy 408.207563 -312.835185) (xy 408.230817 -312.87904) (xy 408.246669 -312.926079) (xy 408.254703 -312.975063)
			(xy 408.255216 -312.999882) (xy 408.255112 -313.008923) (xy 408.253968 -313.026968) (xy 408.25293 -313.03595)
			(xy 408.25293 -313.036458) (xy 408.25166 -313.048142) (xy 408.259788 -313.070494) (xy 408.335988 -313.143392)
			(xy 408.358594 -313.15025) (xy 408.365198 -313.149234) (xy 408.380054 -313.146702) (xy 408.410073 -313.144033)
			(xy 408.425142 -313.1439) (xy 408.440471 -313.144046) (xy 408.471002 -313.146842) (xy 408.486102 -313.149488)
			(xy 408.487626 -313.149742) (xy 408.491436 -313.150504) (xy 408.514042 -313.143392) (xy 408.589988 -313.070494)
			(xy 408.598116 -313.048142) (xy 408.596592 -313.036204) (xy 408.595604 -313.027157) (xy 408.59459 -313.008983)
			(xy 408.59456 -312.999882) (xy 408.595032 -312.975891) (xy 408.60254 -312.928499) (xy 408.617369 -312.882866)
			(xy 408.639153 -312.840113) (xy 408.667356 -312.801294) (xy 408.701284 -312.767365) (xy 408.740101 -312.73916)
			(xy 408.782853 -312.717374) (xy 408.828486 -312.702543) (xy 408.875877 -312.695033) (xy 408.899868 -312.694574)
			(xy 408.908972 -312.694673) (xy 408.927145 -312.695818) (xy 408.93619 -312.69686) (xy 408.948085 -312.697662)
			(xy 408.970485 -312.689589) (xy 408.979116 -312.681366) (xy 409.043632 -312.613802) (xy 409.050744 -312.591196)
			(xy 409.049728 -312.585608) (xy 409.044851 -312.555575) (xy 409.044859 -312.494738) (xy 409.049728 -312.464704)
			(xy 409.049728 -312.463688) (xy 409.050744 -312.458608) (xy 409.043632 -312.436002) (xy 408.979116 -312.368438)
			(xy 408.970478 -312.360222) (xy 408.948084 -312.352135) (xy 408.93619 -312.352944) (xy 408.927146 -312.353991)
			(xy 408.908972 -312.355133) (xy 408.899868 -312.35523) (xy 408.874613 -312.354706) (xy 408.824791 -312.346387)
			(xy 408.777019 -312.329983) (xy 408.732597 -312.305939) (xy 408.692739 -312.274912) (xy 408.658531 -312.237748)
			(xy 408.630905 -312.195461) (xy 408.610617 -312.149204) (xy 408.598218 -312.100238) (xy 408.594047 -312.0499)
			(xy 408.598218 -311.999562) (xy 408.610617 -311.950596) (xy 408.630905 -311.904339) (xy 408.658531 -311.862052)
			(xy 408.692739 -311.824888) (xy 408.732597 -311.793861) (xy 408.777019 -311.769817) (xy 408.824791 -311.753413)
			(xy 408.874613 -311.745094) (xy 408.899868 -311.744614) (xy 408.908972 -311.744713) (xy 408.927145 -311.745858)
			(xy 408.93619 -311.7469) (xy 408.948084 -311.747701) (xy 408.970478 -311.739621) (xy 408.979116 -311.731406)
			(xy 409.043632 -311.663842) (xy 409.050744 -311.641236) (xy 409.049728 -311.63514) (xy 409.047132 -311.620225)
			(xy 409.04433 -311.59008) (xy 409.04414 -311.574942) (xy 409.04414 -311.504584) (xy 409.043576 -311.493893)
			(xy 409.034912 -311.474342) (xy 409.027376 -311.466738) (xy 408.971242 -311.416192) (xy 408.963023 -311.409403)
			(xy 408.942765 -311.402823) (xy 408.932126 -311.403492) (xy 408.931872 -311.403492) (xy 408.899868 -311.40527)
			(xy 408.874618 -311.404746) (xy 408.824806 -311.396429) (xy 408.777043 -311.380028) (xy 408.73263 -311.355989)
			(xy 408.69278 -311.324968) (xy 408.658578 -311.287811) (xy 408.630958 -311.245532) (xy 408.610674 -311.199284)
			(xy 408.598277 -311.150329) (xy 408.594107 -311.1) (xy 408.598277 -311.049671) (xy 408.610674 -311.000716)
			(xy 408.630958 -310.954468) (xy 408.658578 -310.912189) (xy 408.69278 -310.875032) (xy 408.73263 -310.844011)
			(xy 408.777043 -310.819972) (xy 408.824806 -310.803571) (xy 408.874618 -310.795254) (xy 408.899868 -310.794654)
			(xy 408.931618 -310.796432) (xy 408.932126 -310.796432) (xy 408.942744 -310.79694) (xy 408.962935 -310.790367)
			(xy 408.971242 -310.783732) (xy 409.027376 -310.733186) (xy 409.035032 -310.725667) (xy 409.043707 -310.706063)
			(xy 409.04414 -310.69534) (xy 409.04414 -310.624728) (xy 409.044239 -310.612041) (xy 409.046145 -310.58674)
			(xy 409.04795 -310.574182) (xy 409.04795 -310.573674) (xy 409.048458 -310.570372) (xy 409.05049 -310.558688)
			(xy 409.043378 -310.535828) (xy 408.978608 -310.46801) (xy 408.97008 -310.460014) (xy 408.948115 -310.452083)
			(xy 408.936444 -310.45277) (xy 408.93619 -310.45277) (xy 408.927146 -310.453817) (xy 408.908972 -310.454959)
			(xy 408.899868 -310.455056) (xy 408.87461 -310.454532) (xy 408.824785 -310.446213) (xy 408.777008 -310.429807)
			(xy 408.732583 -310.405761) (xy 408.692721 -310.374731) (xy 408.65851 -310.337564) (xy 408.630882 -310.295274)
			(xy 408.610592 -310.249013) (xy 408.598192 -310.200043) (xy 408.59402 -310.1497) (xy 408.598192 -310.099357)
			(xy 408.610592 -310.050387) (xy 408.630882 -310.004126) (xy 408.65851 -309.961836) (xy 408.692721 -309.924669)
			(xy 408.732583 -309.893639) (xy 408.777008 -309.869593) (xy 408.824785 -309.853187) (xy 408.87461 -309.844868)
			(xy 408.899868 -309.84444) (xy 408.909036 -309.844532) (xy 408.927336 -309.845673) (xy 408.936444 -309.846726)
			(xy 408.948128 -309.84825) (xy 408.970988 -309.840122) (xy 409.043632 -309.763668) (xy 409.050744 -309.741062)
			(xy 409.049474 -309.733188) (xy 409.044811 -309.703448) (xy 409.045075 -309.643255) (xy 409.049982 -309.613554)
			(xy 409.049982 -309.61203) (xy 409.050744 -309.60822) (xy 409.043632 -309.585614) (xy 408.978862 -309.51805)
			(xy 408.970338 -309.510039) (xy 408.94837 -309.502079) (xy 408.936698 -309.50281) (xy 408.93619 -309.50281)
			(xy 408.927146 -309.503857) (xy 408.908972 -309.504999) (xy 408.899868 -309.505096) (xy 408.875879 -309.504623)
			(xy 408.828492 -309.497113) (xy 408.782863 -309.482282) (xy 408.740115 -309.460497) (xy 408.701302 -309.432293)
			(xy 408.667379 -309.398364) (xy 408.63918 -309.359547) (xy 408.617401 -309.316797) (xy 408.602577 -309.271166)
			(xy 408.595074 -309.223777) (xy 408.59456 -309.199788) (xy 408.594747 -309.185606) (xy 408.597421 -309.157366)
			(xy 408.599894 -309.1434) (xy 408.60218 -309.130954) (xy 408.594814 -309.107332) (xy 408.517344 -309.029862)
			(xy 408.493722 -309.022496) (xy 408.481276 -309.024782) (xy 408.467311 -309.027267) (xy 408.439071 -309.029938)
			(xy 408.424888 -309.030116) (xy 408.400067 -309.029629) (xy 408.351078 -309.021596) (xy 408.304034 -309.005743)
			(xy 408.260175 -308.982488) (xy 408.220656 -308.952444) (xy 408.186518 -308.916402) (xy 408.158661 -308.875313)
			(xy 408.137818 -308.830257) (xy 408.124538 -308.782423) (xy 408.119173 -308.733071) (xy 408.121862 -308.683501)
			(xy 408.132536 -308.635019) (xy 408.150912 -308.588903) (xy 408.176507 -308.546367) (xy 408.208646 -308.508532)
			(xy 408.246483 -308.476395) (xy 408.289021 -308.450803) (xy 408.335139 -308.43243) (xy 408.383621 -308.421759)
			(xy 408.433191 -308.419073) (xy 408.482543 -308.424442) (xy 408.530376 -308.437725) (xy 408.57543 -308.45857)
			(xy 408.616518 -308.48643) (xy 408.652558 -308.520571) (xy 408.682599 -308.560092) (xy 408.705851 -308.603953)
			(xy 408.721701 -308.650997) (xy 408.729731 -308.699987) (xy 408.730196 -308.724808) (xy 408.730009 -308.73899)
			(xy 408.727335 -308.76723) (xy 408.724862 -308.781196) (xy 408.722576 -308.793642) (xy 408.729942 -308.817264)
			(xy 408.807412 -308.894734) (xy 408.831034 -308.9021) (xy 408.84348 -308.899814) (xy 408.857382 -308.897336)
			(xy 408.885494 -308.894662) (xy 408.899614 -308.89448) (xy 408.900122 -308.89448) (xy 408.909163 -308.894586)
			(xy 408.927208 -308.895732) (xy 408.93619 -308.896766) (xy 408.948085 -308.897568) (xy 408.970486 -308.889496)
			(xy 408.979116 -308.881272) (xy 409.043632 -308.813708) (xy 409.050744 -308.791102) (xy 409.049728 -308.785514)
			(xy 409.045497 -308.760216) (xy 409.043978 -308.70895) (xy 409.050388 -308.658062) (xy 409.064573 -308.608774)
			(xy 409.086194 -308.562264) (xy 409.114732 -308.519648) (xy 409.149504 -308.481945) (xy 409.189677 -308.450059)
			(xy 409.23429 -308.424754) (xy 409.282272 -308.406636) (xy 409.307284 -308.400958) (xy 409.322235 -308.398031)
			(xy 409.352509 -308.3946) (xy 409.367736 -308.3941) (xy 409.368244 -308.3941) (xy 409.375102 -308.393846)
			(xy 409.378658 -308.393846) (xy 409.387294 -308.39029) (xy 409.39847 -308.38394) (xy 409.440888 -308.34076)
			(xy 409.45689 -308.324504) (xy 409.462093 -308.317541) (xy 409.46794 -308.301184) (xy 409.46832 -308.2925)
			(xy 409.46832 -308.20614) (xy 409.467558 -308.197758) (xy 409.465018 -308.188868) (xy 409.4607 -308.178708)
			(xy 409.453588 -308.171342) (xy 409.39847 -308.115716) (xy 409.387294 -308.109366) (xy 409.378404 -308.10581)
			(xy 409.368498 -308.105556) (xy 409.368244 -308.105556) (xy 409.332684 -308.103016) (xy 409.306881 -308.099226)
			(xy 409.256827 -308.084582) (xy 409.209692 -308.062265) (xy 409.166643 -308.032828) (xy 409.128746 -307.997001)
			(xy 409.09694 -307.955671) (xy 409.072014 -307.909863) (xy 409.054584 -307.86071) (xy 409.045084 -307.809431)
			(xy 409.043747 -307.757297) (xy 409.050608 -307.705599) (xy 409.065496 -307.655618) (xy 409.088043 -307.608592)
			(xy 409.117689 -307.565687) (xy 409.153701 -307.527965) (xy 409.195186 -307.496361) (xy 409.241116 -307.471659)
			(xy 409.290353 -307.45447) (xy 409.341677 -307.445219) (xy 409.367736 -307.44414) (xy 409.368244 -307.44414)
			(xy 409.375102 -307.443886) (xy 409.378658 -307.443886) (xy 409.387294 -307.44033) (xy 409.39847 -307.43398)
			(xy 409.440888 -307.3908) (xy 409.45689 -307.374544) (xy 409.462084 -307.367579) (xy 409.467912 -307.351221)
			(xy 409.46832 -307.34254) (xy 409.46832 -307.25618) (xy 409.467558 -307.247798) (xy 409.465018 -307.238908)
			(xy 409.4607 -307.228748) (xy 409.453588 -307.221382) (xy 409.39847 -307.165756) (xy 409.387294 -307.159406)
			(xy 409.378404 -307.15585) (xy 409.368498 -307.155596) (xy 409.368244 -307.155596) (xy 409.342597 -307.154603)
			(xy 409.292057 -307.145669) (xy 409.243504 -307.129033) (xy 409.198105 -307.105096) (xy 409.15695 -307.074431)
			(xy 409.121026 -307.037776) (xy 409.091198 -306.996011) (xy 409.068181 -306.950138) (xy 409.052528 -306.90126)
			(xy 409.044615 -306.85055) (xy 409.04414 -306.824888) (xy 409.044624 -306.798901) (xy 409.052757 -306.747566)
			(xy 409.068821 -306.698137) (xy 409.09242 -306.651829) (xy 409.122973 -306.609783) (xy 409.159728 -306.573034)
			(xy 409.20178 -306.542489) (xy 409.248092 -306.518898) (xy 409.297525 -306.502843) (xy 409.348861 -306.494719)
			(xy 409.374848 -306.49418) (xy 409.384011 -306.494242) (xy 409.40231 -306.495256) (xy 409.411424 -306.496212)
			(xy 409.41371 -306.496466) (xy 409.41752 -306.496466) (xy 409.427536 -306.496042) (xy 409.44604 -306.488368)
			(xy 409.460198 -306.474195) (xy 409.467853 -306.455683) (xy 409.46832 -306.445666) (xy 409.46832 -306.433728)
			(xy 409.470098 -306.39893) (xy 409.470098 -306.398422) (xy 409.470352 -306.39639) (xy 409.470352 -306.395882)
			(xy 409.471114 -306.389024) (xy 409.471114 -306.388262) (xy 409.471622 -306.38496) (xy 409.471622 -306.383944)
			(xy 409.472384 -306.378864) (xy 409.472384 -306.377848) (xy 409.474011 -306.367723) (xy 409.478202 -306.347646)
			(xy 409.480766 -306.337716) (xy 409.482544 -306.331366) (xy 409.482544 -306.331112) (xy 409.488132 -306.311046)
			(xy 409.482798 -306.301648) (xy 409.459684 -306.272184) (xy 409.456128 -306.267612) (xy 409.456128 -306.267104)
			(xy 409.4226 -306.22494) (xy 409.418869 -306.220445) (xy 409.409761 -306.213134) (xy 409.404566 -306.210462)
			(xy 409.393898 -306.205382) (xy 409.381706 -306.205636) (xy 409.374848 -306.205636) (xy 409.348854 -306.205156)
			(xy 409.297505 -306.19703) (xy 409.24806 -306.180971) (xy 409.201736 -306.157374) (xy 409.159675 -306.12682)
			(xy 409.122911 -306.090062) (xy 409.092351 -306.048005) (xy 409.068747 -306.001684) (xy 409.052681 -305.952241)
			(xy 409.044547 -305.900894) (xy 409.044547 -305.848906) (xy 409.052681 -305.797559) (xy 409.068747 -305.748116)
			(xy 409.092351 -305.701795) (xy 409.122911 -305.659738) (xy 409.159675 -305.62298) (xy 409.201736 -305.592426)
			(xy 409.24806 -305.568829) (xy 409.297505 -305.55277) (xy 409.348854 -305.544644) (xy 409.374848 -305.54422)
			(xy 409.387598 -305.544313) (xy 409.413026 -305.546221) (xy 409.425648 -305.54803) (xy 409.450423 -305.552357)
			(xy 409.498375 -305.567516) (xy 409.543482 -305.589756) (xy 409.584703 -305.618567) (xy 409.62109 -305.653283)
			(xy 409.651805 -305.693105) (xy 409.67614 -305.737117) (xy 409.693535 -305.784304) (xy 409.703588 -305.83358)
			(xy 409.705302 -305.858672) (xy 409.705302 -305.858926) (xy 409.706381 -305.870313) (xy 409.717055 -305.890509)
			(xy 409.725876 -305.897788) (xy 409.796488 -305.944524) (xy 409.801585 -305.94775) (xy 409.812879 -305.951979)
			(xy 409.81884 -305.952906) (xy 409.830778 -305.954176) (xy 409.836366 -305.952144) (xy 409.846476 -305.948206)
			(xy 409.867063 -305.941346) (xy 409.877514 -305.938428) (xy 409.887625 -305.935717) (xy 409.908084 -305.931273)
			(xy 409.918408 -305.929538) (xy 409.921964 -305.92903) (xy 409.93568 -305.924712) (xy 409.93822 -305.923442)
			(xy 409.938474 -305.923442) (xy 409.94076 -305.922426) (xy 409.952952 -305.916076) (xy 409.95645 -305.91412)
			(xy 409.962826 -305.909266) (xy 409.965652 -305.906424) (xy 409.976574 -305.894486) (xy 409.981146 -305.889152)
			(xy 409.98648 -305.877214) (xy 409.98648 -305.876706) (xy 409.994354 -305.858672) (xy 409.995116 -305.850036)
			(xy 409.995116 -305.849782) (xy 409.99746 -305.825167) (xy 410.008527 -305.776978) (xy 410.026644 -305.730974)
			(xy 410.051407 -305.688179) (xy 410.082266 -305.649547) (xy 410.118531 -305.61594) (xy 410.159396 -305.588105)
			(xy 410.203948 -305.566664) (xy 410.251196 -305.552094) (xy 410.300086 -305.544721) (xy 410.324808 -305.54422)
			(xy 410.353033 -305.544791) (xy 410.408664 -305.554364) (xy 410.461867 -305.573231) (xy 410.511101 -305.600846)
			(xy 410.554939 -305.636409) (xy 410.573982 -305.65725) (xy 410.574998 -305.65852) (xy 410.580078 -305.6636)
			(xy 410.591762 -305.67122) (xy 410.611066 -305.680364) (xy 410.611828 -305.680618) (xy 410.616775 -305.682733)
			(xy 410.627278 -305.68505) (xy 410.632656 -305.68519) (xy 410.961586 -305.68519) (xy 410.969968 -305.684428)
			(xy 410.98216 -305.681888) (xy 410.992828 -305.678332) (xy 411.00756 -305.671474) (xy 411.007814 -305.67122)
			(xy 411.008068 -305.67122) (xy 411.01518 -305.667156) (xy 411.020514 -305.663092) (xy 411.028388 -305.654202)
			(xy 411.045791 -305.635476) (xy 411.085341 -305.603087) (xy 411.129402 -305.577167) (xy 411.176926 -305.558332)
			(xy 411.226781 -305.54703) (xy 411.27778 -305.54353) (xy 411.328712 -305.547916) (xy 411.378363 -305.560083)
			(xy 411.425551 -305.579741) (xy 411.469155 -305.606424) (xy 411.508136 -305.639495) (xy 411.525212 -305.65852)
			(xy 411.528768 -305.662584) (xy 411.533086 -305.665886) (xy 411.542484 -305.671474) (xy 411.561534 -305.680364)
			(xy 411.562042 -305.680618) (xy 411.571948 -305.68519) (xy 411.911546 -305.68519) (xy 411.919928 -305.684428)
			(xy 411.93212 -305.681888) (xy 411.942788 -305.678332) (xy 411.95752 -305.671474) (xy 411.957774 -305.67122)
			(xy 411.958028 -305.67122) (xy 411.96514 -305.667156) (xy 411.970474 -305.663092) (xy 411.978348 -305.654202)
			(xy 411.995752 -305.635473) (xy 412.035303 -305.603078) (xy 412.079365 -305.577152) (xy 412.126892 -305.558311)
			(xy 412.17675 -305.547004) (xy 412.227754 -305.5435) (xy 412.278691 -305.547882) (xy 412.328347 -305.560046)
			(xy 412.375541 -305.579703) (xy 412.419151 -305.606384) (xy 412.458138 -305.639455) (xy 412.475172 -305.65852)
			(xy 412.478728 -305.662584) (xy 412.483046 -305.665886) (xy 412.492444 -305.671474) (xy 412.511494 -305.680364)
			(xy 412.512002 -305.680618) (xy 412.521908 -305.68519) (xy 412.861506 -305.68519) (xy 412.869888 -305.684428)
			(xy 412.88208 -305.681888) (xy 412.892748 -305.678332) (xy 412.90748 -305.671474) (xy 412.907734 -305.67122)
			(xy 412.907988 -305.67122) (xy 412.9151 -305.667156) (xy 412.920434 -305.663092) (xy 412.928308 -305.654202)
			(xy 412.945711 -305.635478) (xy 412.985261 -305.603092) (xy 413.029321 -305.577175) (xy 413.076843 -305.558342)
			(xy 413.126696 -305.547042) (xy 413.177694 -305.543545) (xy 413.228622 -305.547932) (xy 413.27827 -305.560101)
			(xy 413.325456 -305.57976) (xy 413.369057 -305.606443) (xy 413.408035 -305.639515) (xy 413.425132 -305.65852)
			(xy 413.428688 -305.662584) (xy 413.433006 -305.665886) (xy 413.442404 -305.671474) (xy 413.461454 -305.680364)
			(xy 413.461962 -305.680618) (xy 413.471868 -305.68519) (xy 413.811466 -305.68519) (xy 413.819848 -305.684428)
			(xy 413.83204 -305.681888) (xy 413.842708 -305.678332) (xy 413.85744 -305.671474) (xy 413.857694 -305.67122)
			(xy 413.857948 -305.67122) (xy 413.86506 -305.667156) (xy 413.870394 -305.663092) (xy 413.878268 -305.654202)
			(xy 413.895671 -305.635475) (xy 413.935222 -305.603083) (xy 413.979284 -305.577159) (xy 414.026809 -305.558321)
			(xy 414.076665 -305.547017) (xy 414.127667 -305.543515) (xy 414.178601 -305.547899) (xy 414.228255 -305.560064)
			(xy 414.275446 -305.579722) (xy 414.319053 -305.606404) (xy 414.358037 -305.639475) (xy 414.375092 -305.65852)
			(xy 414.378648 -305.662584) (xy 414.382966 -305.665886) (xy 414.392364 -305.671474) (xy 414.411414 -305.680364)
			(xy 414.411922 -305.680618) (xy 414.421828 -305.68519) (xy 414.761426 -305.68519) (xy 414.769808 -305.684428)
			(xy 414.782 -305.681888) (xy 414.792668 -305.678332) (xy 414.8074 -305.671474) (xy 414.807654 -305.67122)
			(xy 414.807908 -305.67122) (xy 414.81502 -305.667156) (xy 414.820354 -305.663092) (xy 414.828228 -305.654202)
			(xy 414.845631 -305.635479) (xy 414.88518 -305.603097) (xy 414.929239 -305.577182) (xy 414.97676 -305.558352)
			(xy 415.026611 -305.547055) (xy 415.077607 -305.54356) (xy 415.128533 -305.547949) (xy 415.178178 -305.560119)
			(xy 415.225361 -305.57978) (xy 415.268959 -305.606463) (xy 415.307934 -305.639535) (xy 415.325052 -305.65852)
			(xy 415.328608 -305.662584) (xy 415.332926 -305.665886) (xy 415.342324 -305.671474) (xy 415.361374 -305.680364)
			(xy 415.361882 -305.680618) (xy 415.371788 -305.68519) (xy 415.711386 -305.68519) (xy 415.719768 -305.684428)
			(xy 415.73196 -305.681888) (xy 415.742628 -305.678332) (xy 415.75736 -305.671474) (xy 415.757614 -305.67122)
			(xy 415.757868 -305.67122) (xy 415.76498 -305.667156) (xy 415.770314 -305.663092) (xy 415.778188 -305.654202)
			(xy 415.795591 -305.635476) (xy 415.835141 -305.603087) (xy 415.879202 -305.577167) (xy 415.926726 -305.558332)
			(xy 415.976581 -305.54703) (xy 416.02758 -305.54353) (xy 416.078512 -305.547916) (xy 416.128163 -305.560083)
			(xy 416.175351 -305.579741) (xy 416.218955 -305.606424) (xy 416.257936 -305.639495) (xy 416.275012 -305.65852)
			(xy 416.278568 -305.662584) (xy 416.282886 -305.665886) (xy 416.292284 -305.671474) (xy 416.311334 -305.680364)
			(xy 416.311842 -305.680618) (xy 416.321748 -305.68519) (xy 416.672014 -305.68519) (xy 416.683698 -305.682904)
			(xy 416.707828 -305.671474) (xy 416.717734 -305.665124) (xy 416.72129 -305.661314) (xy 416.726116 -305.656488)
			(xy 416.72637 -305.656234) (xy 416.727132 -305.655472) (xy 416.72891 -305.65344) (xy 416.747492 -305.63365)
			(xy 416.789937 -305.599814) (xy 416.837336 -305.57336) (xy 416.888418 -305.554999) (xy 416.941812 -305.545223)
			(xy 416.96894 -305.54422) (xy 416.9791 -305.543966) (xy 416.987736 -305.54041) (xy 416.991929 -305.538497)
			(xy 416.99959 -305.533377) (xy 417.002976 -305.53025) (xy 417.029138 -305.50358) (xy 417.05403 -305.47818)
			(xy 417.05684 -305.475161) (xy 417.061557 -305.468394) (xy 417.063428 -305.464718) (xy 417.065769 -305.459495)
			(xy 417.068329 -305.448341) (xy 417.068508 -305.44262) (xy 417.068508 -305.357022) (xy 417.068357 -305.351298)
			(xy 417.065787 -305.340142) (xy 417.063428 -305.334924) (xy 417.061576 -305.331237) (xy 417.056852 -305.324473)
			(xy 417.05403 -305.321462) (xy 417.029138 -305.296062) (xy 417.002976 -305.269392) (xy 416.999586 -305.266272)
			(xy 416.991918 -305.261167) (xy 416.987736 -305.259232) (xy 416.9791 -305.255676) (xy 416.96894 -305.255422)
			(xy 416.943253 -305.25448) (xy 416.892621 -305.245631) (xy 416.843967 -305.229056) (xy 416.798463 -305.205155)
			(xy 416.757203 -305.174503) (xy 416.721181 -305.137838) (xy 416.691265 -305.096041) (xy 416.668174 -305.050121)
			(xy 416.652464 -305.001181) (xy 416.644513 -304.9504) (xy 416.644513 -304.899) (xy 416.652464 -304.84822)
			(xy 416.668174 -304.79928) (xy 416.691265 -304.753359) (xy 416.721181 -304.711563) (xy 416.757203 -304.674897)
			(xy 416.798462 -304.644245) (xy 416.843967 -304.620344) (xy 416.89262 -304.603769) (xy 416.943252 -304.59492)
			(xy 416.96894 -304.594006) (xy 416.9791 -304.593752) (xy 416.987736 -304.590196) (xy 416.991931 -304.588286)
			(xy 416.999599 -304.583173) (xy 417.002976 -304.580036) (xy 417.029138 -304.553366) (xy 417.05403 -304.527966)
			(xy 417.05684 -304.524946) (xy 417.061555 -304.518179) (xy 417.063428 -304.514504) (xy 417.065767 -304.50928)
			(xy 417.068324 -304.498127) (xy 417.068508 -304.492406) (xy 417.068508 -304.401728) (xy 417.068 -304.395378)
			(xy 417.068 -304.39487) (xy 417.066754 -304.387702) (xy 417.060816 -304.374426) (xy 417.056316 -304.368708)
			(xy 417.037266 -304.34915) (xy 417.021518 -304.332894) (xy 417.005262 -304.31613) (xy 416.99815 -304.308764)
			(xy 416.979608 -304.30089) (xy 416.969956 -304.300382) (xy 416.944497 -304.299145) (xy 416.89439 -304.289812)
			(xy 416.846308 -304.272899) (xy 416.801392 -304.248809) (xy 416.760704 -304.218111) (xy 416.72521 -304.181532)
			(xy 416.695749 -304.13994) (xy 416.67302 -304.094319) (xy 416.657562 -304.045751) (xy 416.64974 -303.995385)
			(xy 416.649739 -303.944416) (xy 416.657561 -303.894051) (xy 416.673019 -303.845482) (xy 416.695748 -303.799862)
			(xy 416.725209 -303.758269) (xy 416.760703 -303.72169) (xy 416.80139 -303.690992) (xy 416.846307 -303.666901)
			(xy 416.894388 -303.649989) (xy 416.944495 -303.640656) (xy 416.969956 -303.639474) (xy 416.979608 -303.638966)
			(xy 416.99815 -303.631092) (xy 417.005262 -303.623726) (xy 417.021518 -303.606962) (xy 417.056824 -303.570132)
			(xy 417.062666 -303.561496) (xy 417.064698 -303.557432) (xy 417.068 -303.544986) (xy 417.068 -303.544478)
			(xy 417.068508 -303.538128) (xy 417.068508 -303.473104) (xy 417.068762 -303.462436) (xy 417.068762 -303.462182)
			(xy 417.069016 -303.448974) (xy 417.06292 -303.435258) (xy 417.057332 -303.426622) (xy 417.045902 -303.414938)
			(xy 417.045902 -303.41443) (xy 417.002976 -303.369218) (xy 416.997372 -303.364354) (xy 416.984078 -303.357778)
			(xy 416.976814 -303.356264) (xy 416.97275 -303.355502) (xy 416.968686 -303.355502) (xy 416.943011 -303.354548)
			(xy 416.892406 -303.34568) (xy 416.843781 -303.329091) (xy 416.798308 -303.305182) (xy 416.757079 -303.274526)
			(xy 416.721089 -303.237863) (xy 416.691202 -303.196074) (xy 416.668138 -303.150166) (xy 416.652452 -303.101243)
			(xy 416.644522 -303.050482) (xy 416.644074 -303.024794) (xy 416.644584 -302.998807) (xy 416.652715 -302.947472)
			(xy 416.668776 -302.898041) (xy 416.692372 -302.851731) (xy 416.722922 -302.809682) (xy 416.759673 -302.77293)
			(xy 416.801721 -302.742379) (xy 416.84803 -302.718781) (xy 416.89746 -302.702718) (xy 416.948795 -302.694585)
			(xy 416.974782 -302.694086) (xy 416.999037 -302.694516) (xy 417.047028 -302.701607) (xy 417.09347 -302.715623)
			(xy 417.137369 -302.736266) (xy 417.177787 -302.763094) (xy 417.213858 -302.795532) (xy 417.24481 -302.832886)
			(xy 417.26998 -302.874356) (xy 417.279836 -302.896524) (xy 417.282122 -302.901858) (xy 417.292536 -302.916336)
			(xy 417.296046 -302.920243) (xy 417.304368 -302.926648) (xy 417.309046 -302.929036) (xy 417.309554 -302.929036)
			(xy 417.317936 -302.932338) (xy 417.377372 -302.94453) (xy 417.403534 -302.949864) (xy 417.41444 -302.951214)
			(xy 417.435647 -302.945549) (xy 417.444428 -302.938942) (xy 417.473384 -302.910494) (xy 417.473384 -302.91024)
			(xy 417.505134 -302.87849) (xy 417.511813 -302.871078) (xy 417.519386 -302.852643) (xy 417.519866 -302.842676)
			(xy 417.519866 -282.05557) (xy 417.519379 -282.046124) (xy 417.512475 -282.028532) (xy 417.506404 -282.02128)
			(xy 417.45281 -281.963114) (xy 417.435792 -281.954986) (xy 417.42614 -281.954224) (xy 417.400928 -281.951747)
			(xy 417.351773 -281.939505) (xy 417.305312 -281.919316) (xy 417.262822 -281.891735) (xy 417.225469 -281.857518)
			(xy 417.194276 -281.817604) (xy 417.1701 -281.773089) (xy 417.153604 -281.725193) (xy 417.145241 -281.675231)
			(xy 417.145241 -281.624574) (xy 417.153603 -281.574612) (xy 417.170098 -281.526716) (xy 417.194273 -281.4822)
			(xy 417.225465 -281.442285) (xy 417.262819 -281.408068) (xy 417.305308 -281.380486) (xy 417.351768 -281.360297)
			(xy 417.400923 -281.348054) (xy 417.42614 -281.34564) (xy 417.435792 -281.344878) (xy 417.45281 -281.33675)
			(xy 417.506404 -281.278584) (xy 417.512557 -281.27138) (xy 417.519478 -281.25376) (xy 417.519866 -281.244294)
			(xy 417.519866 -281.105356) (xy 417.519376 -281.095911) (xy 417.512469 -281.078323) (xy 417.506404 -281.071066)
			(xy 417.45281 -281.0129) (xy 417.435792 -281.004772) (xy 417.42614 -281.00401) (xy 417.400929 -281.001533)
			(xy 417.351776 -280.989291) (xy 417.305318 -280.969104) (xy 417.26283 -280.941524) (xy 417.225478 -280.907308)
			(xy 417.194287 -280.867396) (xy 417.170112 -280.822882) (xy 417.153617 -280.774988) (xy 417.145255 -280.725029)
			(xy 417.145255 -280.674374) (xy 417.153616 -280.624414) (xy 417.170111 -280.576521) (xy 417.194285 -280.532007)
			(xy 417.225476 -280.492094) (xy 417.262828 -280.457878) (xy 417.305316 -280.430298) (xy 417.351773 -280.410109)
			(xy 417.400926 -280.397867) (xy 417.42614 -280.395426) (xy 417.435792 -280.394664) (xy 417.45281 -280.386536)
			(xy 417.506404 -280.32837) (xy 417.512555 -280.321166) (xy 417.519471 -280.303545) (xy 417.519866 -280.29408)
			(xy 417.519866 -280.155396) (xy 417.519383 -280.145948) (xy 417.512486 -280.12835) (xy 417.506404 -280.121106)
			(xy 417.45281 -280.06294) (xy 417.435792 -280.054812) (xy 417.42614 -280.05405) (xy 417.400934 -280.051573)
			(xy 417.351791 -280.039333) (xy 417.305343 -280.019148) (xy 417.262863 -279.991573) (xy 417.225519 -279.957364)
			(xy 417.194335 -279.917459) (xy 417.170165 -279.872953) (xy 417.153674 -279.825069) (xy 417.145315 -279.775119)
			(xy 417.145315 -279.724474) (xy 417.153676 -279.674525) (xy 417.170168 -279.626641) (xy 417.194338 -279.582136)
			(xy 417.225524 -279.542232) (xy 417.262869 -279.508023) (xy 417.305348 -279.480449) (xy 417.351797 -279.460265)
			(xy 417.400941 -279.448026) (xy 417.42614 -279.445466) (xy 417.435792 -279.444704) (xy 417.45281 -279.436576)
			(xy 417.506404 -279.37841) (xy 417.512561 -279.371208) (xy 417.519491 -279.353587) (xy 417.519866 -279.34412)
			(xy 417.519866 -279.205436) (xy 417.519373 -279.195993) (xy 417.512461 -279.178409) (xy 417.506404 -279.171146)
			(xy 417.45281 -279.11298) (xy 417.435792 -279.104852) (xy 417.42614 -279.10409) (xy 417.40092 -279.101628)
			(xy 417.351744 -279.08941) (xy 417.305261 -279.069239) (xy 417.262748 -279.041669) (xy 417.225371 -279.007456)
			(xy 417.194159 -278.96754) (xy 417.169967 -278.923017) (xy 417.15346 -278.87511) (xy 417.145091 -278.825135)
			(xy 417.145092 -278.774464) (xy 417.15346 -278.72449) (xy 417.169967 -278.676583) (xy 417.194159 -278.63206)
			(xy 417.225371 -278.592144) (xy 417.262748 -278.557931) (xy 417.305261 -278.53036) (xy 417.351744 -278.51019)
			(xy 417.40092 -278.497972) (xy 417.42614 -278.495506) (xy 417.435792 -278.494744) (xy 417.45281 -278.486616)
			(xy 417.506404 -278.42845) (xy 417.512552 -278.421245) (xy 417.51946 -278.403624) (xy 417.519866 -278.39416)
			(xy 417.519866 -278.255476) (xy 417.51938 -278.24603) (xy 417.512478 -278.228436) (xy 417.506404 -278.221186)
			(xy 417.45281 -278.16302) (xy 417.435792 -278.154892) (xy 417.42614 -278.15413) (xy 417.400921 -278.151661)
			(xy 417.351748 -278.139434) (xy 417.305268 -278.119257) (xy 417.262757 -278.091685) (xy 417.225379 -278.057474)
			(xy 417.194162 -278.017562) (xy 417.169962 -277.973045) (xy 417.153441 -277.925144) (xy 417.145055 -277.875173)
			(xy 417.144454 -277.849838) (xy 417.144454 -277.84933) (xy 417.14499 -277.824158) (xy 417.153286 -277.774502)
			(xy 417.160964 -277.750524) (xy 417.162996 -277.742904) (xy 417.165282 -277.72995) (xy 417.164785 -277.71995)
			(xy 417.157116 -277.701479) (xy 417.142964 -277.687346) (xy 417.124482 -277.679701) (xy 417.114482 -277.67915)
			(xy 417.100258 -277.681944) (xy 417.09213 -277.68423) (xy 417.079684 -277.688548) (xy 417.054247 -277.696461)
			(xy 417.00167 -277.705011) (xy 416.975036 -277.705566) (xy 416.974782 -277.705566) (xy 416.959707 -277.705377)
			(xy 416.929688 -277.702578) (xy 416.914838 -277.699978) (xy 416.913822 -277.699978) (xy 416.908488 -277.698962)
			(xy 416.885882 -277.706074) (xy 416.818318 -277.77059) (xy 416.810105 -277.77923) (xy 416.802024 -277.801622)
			(xy 416.802824 -277.813516) (xy 416.803871 -277.82256) (xy 416.805013 -277.840734) (xy 416.80511 -277.849838)
			(xy 416.804637 -277.873827) (xy 416.797126 -277.921215) (xy 416.782295 -277.966844) (xy 416.760509 -278.009591)
			(xy 416.732305 -278.048405) (xy 416.698377 -278.082329) (xy 416.65956 -278.110528) (xy 416.61681 -278.132309)
			(xy 416.571179 -278.147134) (xy 416.523791 -278.154639) (xy 416.499802 -278.155146) (xy 416.468306 -278.153368)
			(xy 416.467798 -278.153368) (xy 416.457178 -278.152855) (xy 416.436981 -278.159421) (xy 416.428682 -278.166068)
			(xy 416.372548 -278.216614) (xy 416.364889 -278.224131) (xy 416.35621 -278.243736) (xy 416.355784 -278.25446)
			(xy 416.355784 -278.299672) (xy 416.355784 -278.307546) (xy 416.355784 -278.324818) (xy 416.355594 -278.339893)
			(xy 416.352793 -278.369912) (xy 416.350196 -278.384762) (xy 416.350196 -278.385778) (xy 416.34918 -278.391112)
			(xy 416.356292 -278.413718) (xy 416.42919 -278.489918) (xy 416.451542 -278.498046) (xy 416.46348 -278.496522)
			(xy 416.472527 -278.495534) (xy 416.490701 -278.494519) (xy 416.499802 -278.49449) (xy 416.524623 -278.494976)
			(xy 416.573611 -278.503008) (xy 416.620654 -278.518859) (xy 416.664514 -278.542112) (xy 416.704033 -278.572154)
			(xy 416.738172 -278.608194) (xy 416.76603 -278.649282) (xy 416.786874 -278.694337) (xy 416.800154 -278.742169)
			(xy 416.805521 -278.79152) (xy 416.802833 -278.841089) (xy 416.792161 -278.889571) (xy 416.773786 -278.935687)
			(xy 416.748193 -278.978223) (xy 416.716055 -279.016058) (xy 416.67822 -279.048195) (xy 416.635683 -279.073788)
			(xy 416.589567 -279.092162) (xy 416.541085 -279.102834) (xy 416.491516 -279.105521) (xy 416.442165 -279.100153)
			(xy 416.394333 -279.086872) (xy 416.349279 -279.066028) (xy 416.308191 -279.038169) (xy 416.272151 -279.00403)
			(xy 416.24211 -278.96451) (xy 416.218857 -278.920651) (xy 416.203007 -278.873607) (xy 416.194976 -278.824619)
			(xy 416.194494 -278.799798) (xy 416.194533 -278.790697) (xy 416.19555 -278.772524) (xy 416.196526 -278.763476)
			(xy 416.19805 -278.751538) (xy 416.189922 -278.729186) (xy 416.113722 -278.656288) (xy 416.091116 -278.649176)
			(xy 416.085274 -278.650192) (xy 416.070297 -278.652797) (xy 416.040023 -278.655595) (xy 416.024822 -278.65578)
			(xy 416.02406 -278.65578) (xy 416.009696 -278.655608) (xy 415.98108 -278.65306) (xy 415.96691 -278.6507)
			(xy 415.966402 -278.6507) (xy 415.958274 -278.64943) (xy 415.935668 -278.656288) (xy 415.868104 -278.721058)
			(xy 415.860037 -278.729552) (xy 415.851983 -278.751522) (xy 415.85261 -278.763222) (xy 415.85261 -278.763476)
			(xy 415.853659 -278.77252) (xy 415.854802 -278.790694) (xy 415.854896 -278.799798) (xy 415.85441 -278.824618)
			(xy 415.84638 -278.873603) (xy 415.83053 -278.920644) (xy 415.807279 -278.964502) (xy 415.777239 -279.00402)
			(xy 415.741202 -279.038157) (xy 415.700116 -279.066015) (xy 415.655065 -279.086858) (xy 415.607235 -279.100139)
			(xy 415.557887 -279.105507) (xy 415.50832 -279.10282) (xy 415.459841 -279.09215) (xy 415.413727 -279.073778)
			(xy 415.371192 -279.048187) (xy 415.333358 -279.016052) (xy 415.301222 -278.978219) (xy 415.275629 -278.935686)
			(xy 415.257254 -278.889572) (xy 415.246582 -278.841094) (xy 415.243893 -278.791527) (xy 415.249258 -278.742179)
			(xy 415.262537 -278.694348) (xy 415.283379 -278.649296) (xy 415.311234 -278.608209) (xy 415.34537 -278.57217)
			(xy 415.384887 -278.542128) (xy 415.428743 -278.518875) (xy 415.475783 -278.503023) (xy 415.524768 -278.494991)
			(xy 415.549588 -278.49449) (xy 415.558692 -278.494589) (xy 415.576865 -278.495735) (xy 415.58591 -278.496776)
			(xy 415.586164 -278.496776) (xy 415.597967 -278.497592) (xy 415.62022 -278.489644) (xy 415.628836 -278.481536)
			(xy 415.693352 -278.413972) (xy 415.700464 -278.391366) (xy 415.699448 -278.384762) (xy 415.696865 -278.36991)
			(xy 415.694069 -278.339892) (xy 415.69386 -278.324818) (xy 415.69386 -278.25446) (xy 415.693292 -278.243771)
			(xy 415.684624 -278.224225) (xy 415.677096 -278.216614) (xy 415.620962 -278.166068) (xy 415.612742 -278.159279)
			(xy 415.592485 -278.152693) (xy 415.581846 -278.153368) (xy 415.581592 -278.153368) (xy 415.549588 -278.155146)
			(xy 415.525596 -278.154675) (xy 415.478204 -278.147167) (xy 415.432569 -278.132339) (xy 415.389815 -278.110556)
			(xy 415.350995 -278.082353) (xy 415.317064 -278.048425) (xy 415.288858 -278.009607) (xy 415.267071 -277.966855)
			(xy 415.252239 -277.921221) (xy 415.244728 -277.87383) (xy 415.24428 -277.849838) (xy 415.244384 -277.840797)
			(xy 415.245526 -277.822751) (xy 415.246566 -277.81377) (xy 415.246566 -277.813262) (xy 415.247836 -277.801578)
			(xy 415.239708 -277.779226) (xy 415.163762 -277.706328) (xy 415.140902 -277.699216) (xy 415.128964 -277.701248)
			(xy 415.114716 -277.703419) (xy 415.085973 -277.705583) (xy 415.07156 -277.705566) (xy 415.057059 -277.705272)
			(xy 415.028189 -277.702477) (xy 415.013902 -277.699978) (xy 415.01314 -277.699978) (xy 415.008568 -277.699216)
			(xy 414.985962 -277.706074) (xy 414.918398 -277.77059) (xy 414.910188 -277.779231) (xy 414.90211 -277.801623)
			(xy 414.902904 -277.813516) (xy 414.903951 -277.82256) (xy 414.905093 -277.840734) (xy 414.90519 -277.849838)
			(xy 414.904717 -277.873827) (xy 414.897206 -277.921213) (xy 414.882375 -277.966841) (xy 414.860589 -278.009587)
			(xy 414.832384 -278.048399) (xy 414.798456 -278.082321) (xy 414.759639 -278.110518) (xy 414.716889 -278.132296)
			(xy 414.671258 -278.147119) (xy 414.623871 -278.154621) (xy 414.599882 -278.155146) (xy 414.568386 -278.153368)
			(xy 414.567878 -278.153368) (xy 414.55726 -278.152859) (xy 414.537067 -278.159431) (xy 414.528762 -278.166068)
			(xy 414.472628 -278.216614) (xy 414.464972 -278.224133) (xy 414.456296 -278.243737) (xy 414.455864 -278.25446)
			(xy 414.455864 -278.299418) (xy 414.455356 -278.314912) (xy 414.45561 -278.31796) (xy 414.45561 -278.324818)
			(xy 414.455388 -278.339701) (xy 414.452586 -278.369337) (xy 414.450022 -278.384) (xy 414.450022 -278.385524)
			(xy 414.449006 -278.391366) (xy 414.456118 -278.413972) (xy 414.520634 -278.481536) (xy 414.529275 -278.4896)
			(xy 414.55151 -278.497533) (xy 414.563306 -278.496776) (xy 414.56356 -278.496776) (xy 414.572604 -278.495727)
			(xy 414.590778 -278.494582) (xy 414.599882 -278.49449) (xy 414.624703 -278.494974) (xy 414.673693 -278.503003)
			(xy 414.720738 -278.518851) (xy 414.764599 -278.542102) (xy 414.80412 -278.572143) (xy 414.838261 -278.608181)
			(xy 414.866122 -278.649269) (xy 414.886969 -278.694323) (xy 414.900251 -278.742155) (xy 414.905621 -278.791507)
			(xy 414.902935 -278.841077) (xy 414.892265 -278.889559) (xy 414.873891 -278.935677) (xy 414.848299 -278.978214)
			(xy 414.816162 -279.016051) (xy 414.778327 -279.04819) (xy 414.735791 -279.073784) (xy 414.689675 -279.09216)
			(xy 414.641193 -279.102833) (xy 414.591623 -279.105521) (xy 414.542271 -279.100154) (xy 414.494438 -279.086874)
			(xy 414.449383 -279.06603) (xy 414.408294 -279.038171) (xy 414.372253 -279.004032) (xy 414.342211 -278.964512)
			(xy 414.318958 -278.920652) (xy 414.303107 -278.873608) (xy 414.295076 -278.824619) (xy 414.294574 -278.799798)
			(xy 414.294613 -278.790697) (xy 414.29563 -278.772524) (xy 414.296606 -278.763476) (xy 414.29813 -278.751538)
			(xy 414.290002 -278.729186) (xy 414.213802 -278.656288) (xy 414.191196 -278.64943) (xy 414.184592 -278.650446)
			(xy 414.169862 -278.652956) (xy 414.140098 -278.655627) (xy 414.125156 -278.65578) (xy 414.124648 -278.65578)
			(xy 414.109637 -278.655583) (xy 414.079745 -278.652785) (xy 414.064958 -278.650192) (xy 414.063942 -278.650192)
			(xy 414.058354 -278.649176) (xy 414.035748 -278.656288) (xy 413.959548 -278.729186) (xy 413.95142 -278.751538)
			(xy 413.952944 -278.763476) (xy 413.953932 -278.772523) (xy 413.954947 -278.790697) (xy 413.954976 -278.799798)
			(xy 413.95449 -278.824616) (xy 413.946461 -278.873597) (xy 413.930613 -278.920635) (xy 413.907364 -278.964489)
			(xy 413.877326 -279.004004) (xy 413.841292 -279.038139) (xy 413.80021 -279.065995) (xy 413.755163 -279.086838)
			(xy 413.707337 -279.100118) (xy 413.657993 -279.105487) (xy 413.60843 -279.102801) (xy 413.559954 -279.092133)
			(xy 413.513843 -279.073763) (xy 413.471312 -279.048176) (xy 413.433479 -279.016045) (xy 413.401344 -278.978216)
			(xy 413.375752 -278.935687) (xy 413.357377 -278.889578) (xy 413.346703 -278.841104) (xy 413.344013 -278.791541)
			(xy 413.349375 -278.742196) (xy 413.362651 -278.694369) (xy 413.383488 -278.64932) (xy 413.41134 -278.608234)
			(xy 413.445471 -278.572196) (xy 413.484983 -278.542155) (xy 413.528834 -278.518901) (xy 413.57587 -278.503047)
			(xy 413.62485 -278.495012) (xy 413.649668 -278.49449) (xy 413.658709 -278.494594) (xy 413.676755 -278.495737)
			(xy 413.685736 -278.496776) (xy 413.686498 -278.496776) (xy 413.698172 -278.497487) (xy 413.720144 -278.489549)
			(xy 413.728662 -278.481536) (xy 413.793432 -278.413972) (xy 413.800544 -278.391366) (xy 413.799782 -278.38654)
			(xy 413.797067 -278.371382) (xy 413.794139 -278.340724) (xy 413.79394 -278.325326) (xy 413.79394 -278.25446)
			(xy 413.793372 -278.243771) (xy 413.784702 -278.224228) (xy 413.777176 -278.216614) (xy 413.721042 -278.166068)
			(xy 413.712821 -278.159282) (xy 413.692565 -278.152705) (xy 413.681926 -278.153368) (xy 413.681672 -278.153368)
			(xy 413.649668 -278.155146) (xy 413.625677 -278.154673) (xy 413.578287 -278.147163) (xy 413.532655 -278.132333)
			(xy 413.489904 -278.110549) (xy 413.451087 -278.082346) (xy 413.417158 -278.048418) (xy 413.388954 -278.009601)
			(xy 413.367169 -277.96685) (xy 413.352338 -277.921219) (xy 413.344827 -277.873829) (xy 413.34436 -277.849838)
			(xy 413.344464 -277.840797) (xy 413.345606 -277.822751) (xy 413.346646 -277.81377) (xy 413.346646 -277.813262)
			(xy 413.347916 -277.801578) (xy 413.339788 -277.779226) (xy 413.263842 -277.706328) (xy 413.240982 -277.699216)
			(xy 413.229044 -277.701248) (xy 413.214795 -277.703418) (xy 413.186053 -277.70558) (xy 413.17164 -277.705566)
			(xy 413.157139 -277.705271) (xy 413.128269 -277.702475) (xy 413.113982 -277.699978) (xy 413.11322 -277.699978)
			(xy 413.108648 -277.699216) (xy 413.086042 -277.706074) (xy 413.018478 -277.77059) (xy 413.010258 -277.779227)
			(xy 413.002167 -277.801622) (xy 413.002984 -277.813516) (xy 413.004031 -277.82256) (xy 413.005172 -277.840734)
			(xy 413.00527 -277.849838) (xy 413.004797 -277.873826) (xy 412.997285 -277.921211) (xy 412.982454 -277.966838)
			(xy 412.960668 -278.009582) (xy 412.932463 -278.048392) (xy 412.898535 -278.082313) (xy 412.859717 -278.110508)
			(xy 412.816967 -278.132283) (xy 412.771337 -278.147103) (xy 412.72395 -278.154602) (xy 412.699962 -278.155146)
			(xy 412.668466 -278.153368) (xy 412.667958 -278.153368) (xy 412.657334 -278.152843) (xy 412.63712 -278.159391)
			(xy 412.628842 -278.166068) (xy 412.572708 -278.216614) (xy 412.565054 -278.224134) (xy 412.556382 -278.243738)
			(xy 412.555944 -278.25446) (xy 412.555944 -278.299418) (xy 412.555436 -278.314912) (xy 412.55569 -278.31796)
			(xy 412.55569 -278.324818) (xy 412.555468 -278.339701) (xy 412.552666 -278.369337) (xy 412.550102 -278.384)
			(xy 412.550102 -278.385524) (xy 412.549086 -278.391366) (xy 412.556198 -278.413972) (xy 412.620714 -278.481536)
			(xy 412.629354 -278.489604) (xy 412.65159 -278.497546) (xy 412.663386 -278.496776) (xy 412.66364 -278.496776)
			(xy 412.672684 -278.495726) (xy 412.690858 -278.49458) (xy 412.699962 -278.49449) (xy 412.724784 -278.494973)
			(xy 412.773774 -278.502998) (xy 412.820821 -278.518844) (xy 412.864684 -278.542093) (xy 412.904208 -278.572131)
			(xy 412.938351 -278.608169) (xy 412.966214 -278.649255) (xy 412.987063 -278.694309) (xy 413.000349 -278.742141)
			(xy 413.00572 -278.791493) (xy 413.003036 -278.841064) (xy 412.992368 -278.889548) (xy 412.973997 -278.935667)
			(xy 412.948405 -278.978206) (xy 412.916269 -279.016044) (xy 412.878435 -279.048184) (xy 412.835899 -279.073781)
			(xy 412.789782 -279.092158) (xy 412.7413 -279.102832) (xy 412.691729 -279.105521) (xy 412.642377 -279.100155)
			(xy 412.594542 -279.086876) (xy 412.549487 -279.066032) (xy 412.508397 -279.038174) (xy 412.472355 -279.004035)
			(xy 412.442312 -278.964514) (xy 412.419058 -278.920654) (xy 412.403207 -278.873609) (xy 412.395176 -278.82462)
			(xy 412.394654 -278.799798) (xy 412.394693 -278.790697) (xy 412.39571 -278.772524) (xy 412.396686 -278.763476)
			(xy 412.39821 -278.751538) (xy 412.390082 -278.729186) (xy 412.313882 -278.656288) (xy 412.291276 -278.64943)
			(xy 412.284672 -278.650446) (xy 412.269942 -278.652956) (xy 412.240178 -278.655624) (xy 412.225236 -278.65578)
			(xy 412.224728 -278.65578) (xy 412.209717 -278.655582) (xy 412.179825 -278.652782) (xy 412.165038 -278.650192)
			(xy 412.164022 -278.650192) (xy 412.158434 -278.649176) (xy 412.135828 -278.656288) (xy 412.059628 -278.729186)
			(xy 412.0515 -278.751538) (xy 412.053024 -278.763476) (xy 412.054012 -278.772523) (xy 412.055027 -278.790697)
			(xy 412.055056 -278.799798) (xy 412.054571 -278.824624) (xy 412.046538 -278.873621) (xy 412.030684 -278.920673)
			(xy 412.007426 -278.96454) (xy 411.977378 -279.004067) (xy 411.941331 -279.038211) (xy 411.900234 -279.066074)
			(xy 411.855171 -279.08692) (xy 411.807329 -279.100202) (xy 411.757969 -279.105568) (xy 411.70839 -279.102877)
			(xy 411.6599 -279.092201) (xy 411.613777 -279.07382) (xy 411.571234 -279.048219) (xy 411.533394 -279.016073)
			(xy 411.501254 -278.978228) (xy 411.475659 -278.935682) (xy 411.457286 -278.889556) (xy 411.446617 -278.841064)
			(xy 411.443934 -278.791485) (xy 411.449307 -278.742126) (xy 411.462596 -278.694286) (xy 411.483449 -278.649226)
			(xy 411.511318 -278.608133) (xy 411.545467 -278.572091) (xy 411.584999 -278.542049) (xy 411.628869 -278.518798)
			(xy 411.675924 -278.502951) (xy 411.724922 -278.494926) (xy 411.749748 -278.49449) (xy 411.758789 -278.494593)
			(xy 411.776835 -278.495735) (xy 411.785816 -278.496776) (xy 411.786578 -278.496776) (xy 411.798254 -278.497491)
			(xy 411.820232 -278.48956) (xy 411.828742 -278.481536) (xy 411.893512 -278.413972) (xy 411.900624 -278.391366)
			(xy 411.899862 -278.38654) (xy 411.897148 -278.371382) (xy 411.894219 -278.340724) (xy 411.89402 -278.325326)
			(xy 411.89402 -278.25446) (xy 411.893454 -278.243769) (xy 411.884794 -278.224217) (xy 411.877256 -278.216614)
			(xy 411.821122 -278.166068) (xy 411.812901 -278.159286) (xy 411.792645 -278.152716) (xy 411.782006 -278.153368)
			(xy 411.781752 -278.153368) (xy 411.749748 -278.155146) (xy 411.725751 -278.154703) (xy 411.678348 -278.147203)
			(xy 411.632701 -278.132379) (xy 411.589936 -278.110597) (xy 411.551104 -278.082393) (xy 411.517163 -278.048461)
			(xy 411.488948 -278.009638) (xy 411.467154 -277.966878) (xy 411.452317 -277.921236) (xy 411.444803 -277.873835)
			(xy 411.44444 -277.849838) (xy 411.444544 -277.840797) (xy 411.445686 -277.822751) (xy 411.446726 -277.81377)
			(xy 411.446726 -277.813262) (xy 411.447996 -277.801578) (xy 411.439868 -277.779226) (xy 411.363922 -277.706328)
			(xy 411.341062 -277.699216) (xy 411.329124 -277.701248) (xy 411.311222 -277.703923) (xy 411.275073 -277.705827)
			(xy 411.256988 -277.705058) (xy 411.246642 -277.704423) (xy 411.226052 -277.702009) (xy 411.21584 -277.700232)
			(xy 411.215078 -277.700232) (xy 411.208474 -277.698962) (xy 411.185868 -277.706074) (xy 411.118304 -277.77059)
			(xy 411.110093 -277.779231) (xy 411.102015 -277.801623) (xy 411.10281 -277.813516) (xy 411.103857 -277.82256)
			(xy 411.104999 -277.840734) (xy 411.105096 -277.849838) (xy 411.104623 -277.873827) (xy 411.097112 -277.921213)
			(xy 411.082281 -277.966841) (xy 411.060495 -278.009588) (xy 411.032291 -278.0484) (xy 410.998362 -278.082323)
			(xy 410.959545 -278.110521) (xy 410.916795 -278.1323) (xy 410.871165 -278.147123) (xy 410.823777 -278.154626)
			(xy 410.799788 -278.155146) (xy 410.768038 -278.153622) (xy 410.757624 -278.152352) (xy 410.736796 -278.158956)
			(xy 410.672788 -278.216614) (xy 410.665136 -278.224135) (xy 410.656468 -278.243739) (xy 410.656024 -278.25446)
			(xy 410.656024 -278.300434) (xy 410.656024 -278.300942) (xy 410.65577 -278.317198) (xy 410.65577 -278.317452)
			(xy 410.655516 -278.321262) (xy 410.655516 -278.324818) (xy 410.65532 -278.339829) (xy 410.652526 -278.369722)
			(xy 410.649928 -278.384508) (xy 410.649928 -278.385524) (xy 410.648912 -278.391112) (xy 410.656024 -278.413718)
			(xy 410.72054 -278.481282) (xy 410.729182 -278.489485) (xy 410.751573 -278.497544) (xy 410.763466 -278.496776)
			(xy 410.77251 -278.495727) (xy 410.790684 -278.494583) (xy 410.799788 -278.49449) (xy 410.824609 -278.494975)
			(xy 410.873598 -278.503004) (xy 410.920643 -278.518854) (xy 410.964503 -278.542105) (xy 411.004024 -278.572146)
			(xy 411.038164 -278.608185) (xy 411.066024 -278.649273) (xy 411.08687 -278.694327) (xy 411.100152 -278.742159)
			(xy 411.105521 -278.791511) (xy 411.102834 -278.841081) (xy 411.092164 -278.889563) (xy 411.07379 -278.93568)
			(xy 411.048197 -278.978217) (xy 411.01606 -279.016053) (xy 410.978225 -279.048192) (xy 410.935689 -279.073786)
			(xy 410.889572 -279.092161) (xy 410.841091 -279.102833) (xy 410.791521 -279.105521) (xy 410.742169 -279.100154)
			(xy 410.694336 -279.086874) (xy 410.649282 -279.066029) (xy 410.608193 -279.038171) (xy 410.572153 -279.004032)
			(xy 410.54211 -278.964512) (xy 410.518858 -278.920652) (xy 410.503007 -278.873608) (xy 410.494976 -278.824619)
			(xy 410.49448 -278.799798) (xy 410.494577 -278.790694) (xy 410.495718 -278.77252) (xy 410.496766 -278.763476)
			(xy 410.497561 -278.751584) (xy 410.489478 -278.729195) (xy 410.481272 -278.72055) (xy 410.413708 -278.656034)
			(xy 410.391102 -278.648922) (xy 410.385006 -278.649938) (xy 410.370091 -278.652532) (xy 410.339945 -278.655331)
			(xy 410.324808 -278.655526) (xy 410.324554 -278.655526) (xy 410.310126 -278.655364) (xy 410.281382 -278.652823)
			(xy 410.26715 -278.650446) (xy 410.266642 -278.650446) (xy 410.25826 -278.648922) (xy 410.235654 -278.656034)
			(xy 410.1592 -278.728678) (xy 410.151072 -278.751538) (xy 410.152596 -278.763222) (xy 410.15365 -278.77233)
			(xy 410.154792 -278.79063) (xy 410.154882 -278.799798) (xy 410.154396 -278.824616) (xy 410.146367 -278.873599)
			(xy 410.130518 -278.920638) (xy 410.107268 -278.964493) (xy 410.07723 -279.004009) (xy 410.041195 -279.038144)
			(xy 410.000112 -279.066001) (xy 409.955063 -279.086844) (xy 409.907236 -279.100124) (xy 409.857891 -279.105493)
			(xy 409.808327 -279.102807) (xy 409.75985 -279.092138) (xy 409.713738 -279.073768) (xy 409.671206 -279.048179)
			(xy 409.633373 -279.016047) (xy 409.601237 -278.978217) (xy 409.575645 -278.935687) (xy 409.55727 -278.889576)
			(xy 409.546597 -278.841101) (xy 409.543907 -278.791537) (xy 409.54927 -278.742191) (xy 409.562546 -278.694363)
			(xy 409.583385 -278.649312) (xy 409.611238 -278.608227) (xy 409.645371 -278.572188) (xy 409.684884 -278.542147)
			(xy 409.728737 -278.518893) (xy 409.775774 -278.50304) (xy 409.824756 -278.495006) (xy 409.849574 -278.49449)
			(xy 409.858742 -278.494582) (xy 409.877042 -278.495724) (xy 409.88615 -278.496776) (xy 409.886404 -278.496776)
			(xy 409.898204 -278.497583) (xy 409.920443 -278.489623) (xy 409.929076 -278.481536) (xy 409.993592 -278.413972)
			(xy 410.00045 -278.391366) (xy 409.999434 -278.384508) (xy 409.996915 -278.369715) (xy 409.994244 -278.339823)
			(xy 409.9941 -278.324818) (xy 409.9941 -278.25446) (xy 409.993533 -278.24377) (xy 409.98487 -278.224219)
			(xy 409.977336 -278.216614) (xy 409.91282 -278.158956) (xy 409.8925 -278.152352) (xy 409.881832 -278.153368)
			(xy 409.849574 -278.155146) (xy 409.825583 -278.154673) (xy 409.778192 -278.147164) (xy 409.732559 -278.132335)
			(xy 409.689807 -278.110551) (xy 409.650989 -278.082348) (xy 409.61706 -278.04842) (xy 409.588855 -278.009603)
			(xy 409.567069 -277.966852) (xy 409.552238 -277.921219) (xy 409.544727 -277.873829) (xy 409.544266 -277.849838)
			(xy 409.54437 -277.840797) (xy 409.545512 -277.822751) (xy 409.546552 -277.81377) (xy 409.546552 -277.813262)
			(xy 409.547822 -277.801578) (xy 409.539694 -277.779226) (xy 409.463748 -277.706328) (xy 409.440888 -277.699216)
			(xy 409.42895 -277.701248) (xy 409.414701 -277.703418) (xy 409.385959 -277.705581) (xy 409.371546 -277.705566)
			(xy 409.357045 -277.705271) (xy 409.328175 -277.702476) (xy 409.313888 -277.699978) (xy 409.313126 -277.699978)
			(xy 409.308554 -277.699216) (xy 409.285948 -277.706074) (xy 409.218384 -277.77059) (xy 409.210163 -277.779226)
			(xy 409.202071 -277.801622) (xy 409.20289 -277.813516) (xy 409.203937 -277.82256) (xy 409.205079 -277.840734)
			(xy 409.205176 -277.849838) (xy 409.204703 -277.873826) (xy 409.197191 -277.921212) (xy 409.18236 -277.966838)
			(xy 409.160574 -278.009584) (xy 409.13237 -278.048394) (xy 409.098441 -278.082315) (xy 409.059624 -278.110511)
			(xy 409.016874 -278.132287) (xy 408.971243 -278.147108) (xy 408.923856 -278.154608) (xy 408.899868 -278.155146)
			(xy 408.868118 -278.153368) (xy 408.86761 -278.153368) (xy 408.85699 -278.152853) (xy 408.836789 -278.159415)
			(xy 408.828494 -278.166068) (xy 408.77236 -278.216614) (xy 408.7647 -278.224131) (xy 408.756018 -278.243736)
			(xy 408.755596 -278.25446) (xy 408.755596 -278.324818) (xy 408.755374 -278.339701) (xy 408.752572 -278.369337)
			(xy 408.750008 -278.384) (xy 408.750008 -278.385524) (xy 408.748992 -278.391366) (xy 408.756104 -278.413972)
			(xy 408.82062 -278.481536) (xy 408.82926 -278.489603) (xy 408.851496 -278.497542) (xy 408.863292 -278.496776)
			(xy 408.863546 -278.496776) (xy 408.87259 -278.495727) (xy 408.890764 -278.494581) (xy 408.899868 -278.49449)
			(xy 408.92469 -278.494973) (xy 408.97368 -278.503) (xy 409.020726 -278.518846) (xy 409.064588 -278.542096)
			(xy 409.104112 -278.572135) (xy 409.138254 -278.608173) (xy 409.166117 -278.649259) (xy 409.186965 -278.694313)
			(xy 409.200249 -278.742146) (xy 409.20562 -278.791497) (xy 409.202936 -278.841068) (xy 409.192267 -278.889551)
			(xy 409.173895 -278.93567) (xy 409.148304 -278.978208) (xy 409.116167 -279.016046) (xy 409.078333 -279.048186)
			(xy 409.035797 -279.073782) (xy 408.98968 -279.092158) (xy 408.941198 -279.102832) (xy 408.891627 -279.105521)
			(xy 408.842275 -279.100155) (xy 408.794441 -279.086875) (xy 408.749386 -279.066032) (xy 408.708296 -279.038173)
			(xy 408.672255 -279.004034) (xy 408.642212 -278.964514) (xy 408.618958 -278.920653) (xy 408.603107 -278.873609)
			(xy 408.595076 -278.82462) (xy 408.59456 -278.799798) (xy 408.594665 -278.790757) (xy 408.59581 -278.772712)
			(xy 408.596846 -278.76373) (xy 408.596846 -278.763222) (xy 408.598116 -278.751538) (xy 408.589988 -278.729186)
			(xy 408.513788 -278.656288) (xy 408.491182 -278.64943) (xy 408.484578 -278.650446) (xy 408.469722 -278.652977)
			(xy 408.439703 -278.655644) (xy 408.424634 -278.65578) (xy 408.409559 -278.655593) (xy 408.379539 -278.652796)
			(xy 408.36469 -278.650192) (xy 408.363674 -278.650192) (xy 408.35834 -278.649176) (xy 408.335734 -278.656288)
			(xy 408.259534 -278.729186) (xy 408.251406 -278.751538) (xy 408.25293 -278.763476) (xy 408.253918 -278.772523)
			(xy 408.254933 -278.790697) (xy 408.254962 -278.799798) (xy 408.254476 -278.824614) (xy 408.246447 -278.873593)
			(xy 408.2306 -278.920628) (xy 408.207353 -278.96448) (xy 408.177318 -279.003993) (xy 408.141285 -279.038126)
			(xy 408.100206 -279.065981) (xy 408.055161 -279.086823) (xy 408.007338 -279.100104) (xy 407.957997 -279.105472)
			(xy 407.908437 -279.102788) (xy 407.859964 -279.092122) (xy 407.813855 -279.073754) (xy 407.771325 -279.048168)
			(xy 407.733494 -279.01604) (xy 407.70136 -278.978214) (xy 407.675768 -278.935688) (xy 407.657393 -278.889582)
			(xy 407.646718 -278.841111) (xy 407.644026 -278.791551) (xy 407.649387 -278.742209) (xy 407.66266 -278.694384)
			(xy 407.683495 -278.649336) (xy 407.711343 -278.608252) (xy 407.745471 -278.572215) (xy 407.78498 -278.542173)
			(xy 407.828828 -278.518919) (xy 407.87586 -278.503064) (xy 407.924838 -278.495027) (xy 407.949654 -278.49449)
			(xy 407.958755 -278.494528) (xy 407.976928 -278.495542) (xy 407.985976 -278.496522) (xy 407.997914 -278.498046)
			(xy 408.020266 -278.489918) (xy 408.093164 -278.413718) (xy 408.100276 -278.391112) (xy 408.09926 -278.38527)
			(xy 408.096654 -278.370293) (xy 408.093857 -278.340019) (xy 408.093672 -278.324818) (xy 408.093672 -278.25446)
			(xy 408.093105 -278.24377) (xy 408.084438 -278.224223) (xy 408.076908 -278.216614) (xy 408.020774 -278.166068)
			(xy 408.012555 -278.159276) (xy 407.992297 -278.152686) (xy 407.981658 -278.153368) (xy 407.981404 -278.153368)
			(xy 407.949654 -278.155146) (xy 407.925664 -278.154672) (xy 407.878276 -278.14716) (xy 407.832645 -278.132329)
			(xy 407.789896 -278.110544) (xy 407.751081 -278.082341) (xy 407.717154 -278.048413) (xy 407.688952 -278.009597)
			(xy 407.667168 -277.966847) (xy 407.652338 -277.921217) (xy 407.644827 -277.873828) (xy 407.644346 -277.849838)
			(xy 407.644826 -277.825147) (xy 407.652782 -277.77641) (xy 407.668477 -277.729589) (xy 407.691502 -277.685904)
			(xy 407.721257 -277.646492) (xy 407.756965 -277.612383) (xy 407.797697 -277.584464) (xy 407.842391 -277.563463)
			(xy 407.889882 -277.549929) (xy 407.914348 -277.546562) (xy 407.928826 -277.545038) (xy 407.951686 -277.52675)
			(xy 407.986738 -277.42642) (xy 407.989455 -277.41729) (xy 407.988658 -277.398272) (xy 407.981005 -277.380843)
			(xy 407.974546 -277.373842) (xy 407.475944 -276.87524) (xy 407.468955 -276.868761) (xy 407.451527 -276.861088)
			(xy 407.4325 -276.860325) (xy 407.423366 -276.863048) (xy 407.323036 -276.8981) (xy 407.304748 -276.92096)
			(xy 407.303224 -276.935184) (xy 407.299897 -276.959657) (xy 407.286367 -277.007154) (xy 407.265366 -277.051854)
			(xy 407.237444 -277.09259) (xy 407.203329 -277.1283) (xy 407.16391 -277.158053) (xy 407.120216 -277.181072)
			(xy 407.073386 -277.196757) (xy 407.024642 -277.204699) (xy 406.999948 -277.205186) (xy 406.975953 -277.204743)
			(xy 406.928553 -277.197242) (xy 406.88291 -277.182418) (xy 406.840149 -277.160635) (xy 406.801323 -277.13243)
			(xy 406.767387 -277.098497) (xy 406.739179 -277.059673) (xy 406.717392 -277.016914) (xy 406.702564 -276.971272)
			(xy 406.695059 -276.923873) (xy 406.69464 -276.899878) (xy 406.694737 -276.890774) (xy 406.69588 -276.8726)
			(xy 406.696926 -276.863556) (xy 406.696926 -276.863302) (xy 406.697734 -276.851503) (xy 406.68977 -276.829266)
			(xy 406.681686 -276.82063) (xy 406.614122 -276.756114) (xy 406.591516 -276.749002) (xy 406.585166 -276.750018)
			(xy 406.570251 -276.752608) (xy 406.540105 -276.755404) (xy 406.524968 -276.755606) (xy 406.509957 -276.75541)
			(xy 406.480064 -276.752614) (xy 406.465278 -276.750018) (xy 406.464262 -276.750018) (xy 406.458674 -276.749002)
			(xy 406.436068 -276.756114) (xy 406.368504 -276.82063) (xy 406.360301 -276.829273) (xy 406.35224 -276.851663)
			(xy 406.35301 -276.863556) (xy 406.354059 -276.8726) (xy 406.355204 -276.890774) (xy 406.355296 -276.899878)
			(xy 406.354812 -276.924698) (xy 406.346785 -276.973685) (xy 406.330938 -277.020728) (xy 406.307689 -277.064587)
			(xy 406.277651 -277.104107) (xy 406.241614 -277.138247) (xy 406.20053 -277.166107) (xy 406.155479 -277.186953)
			(xy 406.107649 -277.200236) (xy 406.0583 -277.205606) (xy 406.008733 -277.202922) (xy 405.960252 -277.192254)
			(xy 405.914137 -277.173883) (xy 405.871601 -277.148293) (xy 405.833765 -277.116159) (xy 405.801627 -277.078327)
			(xy 405.776032 -277.035794) (xy 405.757656 -276.98968) (xy 405.746983 -276.941201) (xy 405.744293 -276.891634)
			(xy 405.749657 -276.842285) (xy 405.762935 -276.794453) (xy 405.783776 -276.7494) (xy 405.811632 -276.708312)
			(xy 405.845768 -276.672272) (xy 405.885285 -276.64223) (xy 405.929141 -276.618976) (xy 405.976182 -276.603124)
			(xy 406.025168 -276.595091) (xy 406.049988 -276.59457) (xy 406.059092 -276.594669) (xy 406.077265 -276.595816)
			(xy 406.08631 -276.596856) (xy 406.098203 -276.597654) (xy 406.120596 -276.589574) (xy 406.129236 -276.581362)
			(xy 406.193752 -276.513798) (xy 406.200864 -276.491192) (xy 406.199848 -276.485096) (xy 406.197253 -276.470181)
			(xy 406.194455 -276.440035) (xy 406.19426 -276.424898) (xy 406.19426 -276.424644) (xy 406.194451 -276.40957)
			(xy 406.19725 -276.37955) (xy 406.199848 -276.3647) (xy 406.199848 -276.363684) (xy 406.200864 -276.35835)
			(xy 406.193752 -276.335744) (xy 406.129236 -276.26818) (xy 406.120594 -276.26012) (xy 406.09836 -276.252197)
			(xy 406.086564 -276.25294) (xy 406.08631 -276.25294) (xy 406.077266 -276.253988) (xy 406.059092 -276.255131)
			(xy 406.049988 -276.255226) (xy 406.024732 -276.254703) (xy 405.974909 -276.246388) (xy 405.927134 -276.229985)
			(xy 405.88271 -276.205942) (xy 405.842849 -276.174916) (xy 405.808639 -276.137752) (xy 405.781012 -276.095465)
			(xy 405.760722 -276.049207) (xy 405.748322 -276.00024) (xy 405.744151 -275.9499) (xy 405.748322 -275.89956)
			(xy 405.760722 -275.850593) (xy 405.781012 -275.804335) (xy 405.808639 -275.762048) (xy 405.842849 -275.724884)
			(xy 405.88271 -275.693858) (xy 405.927134 -275.669815) (xy 405.974909 -275.653412) (xy 406.024732 -275.645097)
			(xy 406.049988 -275.64461) (xy 406.059025 -275.644657) (xy 406.077071 -275.645675) (xy 406.086056 -275.646642)
			(xy 406.097994 -275.648166) (xy 406.120346 -275.640038) (xy 406.193244 -275.563838) (xy 406.200356 -275.541232)
			(xy 406.19934 -275.53539) (xy 406.196746 -275.520475) (xy 406.193948 -275.490329) (xy 406.193752 -275.475192)
			(xy 406.193752 -275.40458) (xy 406.193188 -275.393889) (xy 406.184524 -275.374338) (xy 406.176988 -275.366734)
			(xy 406.11298 -275.309076) (xy 406.092152 -275.302472) (xy 406.081738 -275.303742) (xy 406.049988 -275.305266)
			(xy 406.024737 -275.304744) (xy 405.974923 -275.296429) (xy 405.927158 -275.28003) (xy 405.882743 -275.255992)
			(xy 405.84289 -275.224972) (xy 405.808686 -275.187815) (xy 405.781065 -275.145536) (xy 405.760779 -275.099287)
			(xy 405.748381 -275.05033) (xy 405.744211 -275) (xy 405.748381 -274.94967) (xy 405.760779 -274.900713)
			(xy 405.781065 -274.854464) (xy 405.808686 -274.812185) (xy 405.84289 -274.775028) (xy 405.882743 -274.744008)
			(xy 405.927158 -274.71997) (xy 405.974923 -274.703571) (xy 406.024737 -274.695256) (xy 406.049988 -274.69465)
			(xy 406.081738 -274.696174) (xy 406.092152 -274.697444) (xy 406.11298 -274.69084) (xy 406.176988 -274.633182)
			(xy 406.184642 -274.625662) (xy 406.193313 -274.606058) (xy 406.193752 -274.595336) (xy 406.193752 -274.524724)
			(xy 406.193752 -274.524216) (xy 406.193917 -274.509014) (xy 406.196713 -274.478738) (xy 406.19934 -274.463764)
			(xy 406.199594 -274.46224) (xy 406.200356 -274.45843) (xy 406.193244 -274.435824) (xy 406.120346 -274.359624)
			(xy 406.097994 -274.351496) (xy 406.086056 -274.35302) (xy 406.077072 -274.354004) (xy 406.059026 -274.355022)
			(xy 406.049988 -274.355052) (xy 406.02473 -274.35453) (xy 405.974902 -274.346213) (xy 405.927123 -274.329809)
			(xy 405.882696 -274.305765) (xy 405.842832 -274.274736) (xy 405.808618 -274.237569) (xy 405.780989 -274.195277)
			(xy 405.760697 -274.149015) (xy 405.748296 -274.100044) (xy 405.744124 -274.0497) (xy 405.748296 -273.999356)
			(xy 405.760697 -273.950385) (xy 405.780989 -273.904123) (xy 405.808618 -273.861831) (xy 405.842832 -273.824664)
			(xy 405.882696 -273.793635) (xy 405.927123 -273.769591) (xy 405.974902 -273.753187) (xy 406.02473 -273.74487)
			(xy 406.049988 -273.744436) (xy 406.059092 -273.744535) (xy 406.077265 -273.745682) (xy 406.08631 -273.746722)
			(xy 406.086564 -273.746722) (xy 406.098368 -273.747539) (xy 406.120625 -273.739596) (xy 406.129236 -273.731482)
			(xy 406.193752 -273.663918) (xy 406.20061 -273.641312) (xy 406.199848 -273.635978) (xy 406.19721 -273.620813)
			(xy 406.194416 -273.590156) (xy 406.19426 -273.574764) (xy 406.194417 -273.559498) (xy 406.197214 -273.529096)
			(xy 406.199848 -273.514058) (xy 406.199848 -273.513042) (xy 406.20061 -273.508216) (xy 406.193752 -273.48561)
			(xy 406.129236 -273.418046) (xy 406.120593 -273.40999) (xy 406.098359 -273.402072) (xy 406.086564 -273.402806)
			(xy 406.08631 -273.402806) (xy 406.077266 -273.403854) (xy 406.059092 -273.404997) (xy 406.049988 -273.405092)
			(xy 406.024735 -273.40457) (xy 405.974917 -273.396255) (xy 405.927147 -273.379854) (xy 405.882729 -273.355814)
			(xy 405.842872 -273.324791) (xy 405.808666 -273.287631) (xy 405.781042 -273.245349) (xy 405.760754 -273.199096)
			(xy 405.748356 -273.150134) (xy 405.744185 -273.0998) (xy 405.748356 -273.049466) (xy 405.760754 -273.000504)
			(xy 405.781042 -272.954251) (xy 405.808666 -272.911969) (xy 405.842872 -272.874809) (xy 405.882729 -272.843786)
			(xy 405.927147 -272.819746) (xy 405.974917 -272.803345) (xy 406.024735 -272.79503) (xy 406.049988 -272.794476)
			(xy 406.059092 -272.794575) (xy 406.077265 -272.795722) (xy 406.08631 -272.796762) (xy 406.086564 -272.796762)
			(xy 406.098367 -272.797578) (xy 406.120618 -272.789628) (xy 406.129236 -272.781522) (xy 406.193752 -272.713958)
			(xy 406.20061 -272.691352) (xy 406.199848 -272.686018) (xy 406.197209 -272.670853) (xy 406.19441 -272.640196)
			(xy 406.19426 -272.624804) (xy 406.194437 -272.60999) (xy 406.197109 -272.580482) (xy 406.199594 -272.565876)
			(xy 406.199594 -272.56486) (xy 406.200864 -272.558002) (xy 406.193752 -272.535396) (xy 406.129236 -272.467832)
			(xy 406.120592 -272.459778) (xy 406.098359 -272.451862) (xy 406.086564 -272.452592) (xy 406.08631 -272.452592)
			(xy 406.077202 -272.453646) (xy 406.058902 -272.45479) (xy 406.049734 -272.454878) (xy 406.024477 -272.454388)
			(xy 405.974651 -272.446079) (xy 405.926872 -272.429681) (xy 405.882445 -272.405642) (xy 405.84258 -272.374619)
			(xy 405.808366 -272.337456) (xy 405.780736 -272.295168) (xy 405.760443 -272.24891) (xy 405.748042 -272.199942)
			(xy 405.74387 -272.1496) (xy 405.748042 -272.099259) (xy 405.760443 -272.05029) (xy 405.780736 -272.004032)
			(xy 405.808366 -271.961744) (xy 405.84258 -271.924581) (xy 405.882445 -271.893558) (xy 405.926872 -271.869519)
			(xy 405.974651 -271.853121) (xy 406.024477 -271.844812) (xy 406.049734 -271.844262) (xy 406.076393 -271.844845)
			(xy 406.128901 -271.854105) (xy 406.179005 -271.872339) (xy 406.202388 -271.885156) (xy 406.20823 -271.888458)
			(xy 406.22093 -271.892014) (xy 406.227788 -271.892014) (xy 406.237798 -271.891528) (xy 406.256297 -271.883872)
			(xy 406.270457 -271.869719) (xy 406.278123 -271.851224) (xy 406.278588 -271.841214) (xy 406.278588 -271.833594)
			(xy 406.278426 -271.827583) (xy 406.27561 -271.815896) (xy 406.273 -271.81048) (xy 406.27116 -271.807006)
			(xy 406.266567 -271.800627) (xy 406.263856 -271.79778) (xy 406.010364 -271.544288) (xy 406.00751 -271.541586)
			(xy 406.001128 -271.537001) (xy 405.997664 -271.535144) (xy 405.992238 -271.532558) (xy 405.980558 -271.52973)
			(xy 405.97455 -271.529556) (xy 382.728216 -271.529556) (xy 382.720153 -271.529932) (xy 382.704872 -271.535109)
			(xy 382.698244 -271.539716) (xy 382.692656 -271.544542) (xy 382.690072 -271.547099) (xy 382.68561 -271.552839)
			(xy 382.683766 -271.555972) (xy 382.679448 -271.563592) (xy 382.67894 -271.566132) (xy 382.677924 -271.573752)
			(xy 382.664291 -271.666222) (xy 382.630702 -271.850116) (xy 382.589943 -272.032555) (xy 382.558947 -272.14957)
			(xy 392.443728 -272.14957) (xy 392.447688 -272.100516) (xy 392.459465 -272.052732) (xy 392.478756 -272.007456)
			(xy 392.505059 -271.96586) (xy 392.537694 -271.929023) (xy 392.575815 -271.897898) (xy 392.618436 -271.873291)
			(xy 392.664452 -271.855839) (xy 392.712671 -271.845995) (xy 392.761846 -271.844014) (xy 392.810701 -271.849946)
			(xy 392.857972 -271.863638) (xy 392.902434 -271.884736) (xy 392.942937 -271.912692) (xy 392.97843 -271.946784)
			(xy 393.007995 -271.986128) (xy 393.030866 -272.029705) (xy 393.04645 -272.076386) (xy 393.054345 -272.124963)
			(xy 393.05484 -272.14957) (xy 394.343902 -272.14957) (xy 394.347862 -272.100516) (xy 394.359639 -272.052732)
			(xy 394.37893 -272.007456) (xy 394.405233 -271.96586) (xy 394.437868 -271.929023) (xy 394.475989 -271.897898)
			(xy 394.51861 -271.873291) (xy 394.564626 -271.855839) (xy 394.612845 -271.845995) (xy 394.66202 -271.844014)
			(xy 394.710875 -271.849946) (xy 394.758146 -271.863638) (xy 394.802608 -271.884736) (xy 394.843111 -271.912692)
			(xy 394.878604 -271.946784) (xy 394.908169 -271.986128) (xy 394.93104 -272.029705) (xy 394.946624 -272.076386)
			(xy 394.954519 -272.124963) (xy 394.955014 -272.14957) (xy 396.243822 -272.14957) (xy 396.247782 -272.100516)
			(xy 396.259559 -272.052732) (xy 396.27885 -272.007456) (xy 396.305153 -271.96586) (xy 396.337788 -271.929023)
			(xy 396.375909 -271.897898) (xy 396.41853 -271.873291) (xy 396.464546 -271.855839) (xy 396.512765 -271.845995)
			(xy 396.56194 -271.844014) (xy 396.610795 -271.849946) (xy 396.658066 -271.863638) (xy 396.702528 -271.884736)
			(xy 396.743031 -271.912692) (xy 396.778524 -271.946784) (xy 396.808089 -271.986128) (xy 396.83096 -272.029705)
			(xy 396.846544 -272.076386) (xy 396.854439 -272.124963) (xy 396.854934 -272.14957) (xy 398.143742 -272.14957)
			(xy 398.147702 -272.100516) (xy 398.159479 -272.052732) (xy 398.17877 -272.007456) (xy 398.205073 -271.96586)
			(xy 398.237708 -271.929023) (xy 398.275829 -271.897898) (xy 398.31845 -271.873291) (xy 398.364466 -271.855839)
			(xy 398.412685 -271.845995) (xy 398.46186 -271.844014) (xy 398.510715 -271.849946) (xy 398.557986 -271.863638)
			(xy 398.602448 -271.884736) (xy 398.642951 -271.912692) (xy 398.678444 -271.946784) (xy 398.708009 -271.986128)
			(xy 398.73088 -272.029705) (xy 398.746464 -272.076386) (xy 398.754359 -272.124963) (xy 398.754854 -272.14957)
			(xy 400.043916 -272.14957) (xy 400.047876 -272.100516) (xy 400.059653 -272.052732) (xy 400.078944 -272.007456)
			(xy 400.105247 -271.96586) (xy 400.137882 -271.929023) (xy 400.176003 -271.897898) (xy 400.218624 -271.873291)
			(xy 400.26464 -271.855839) (xy 400.312859 -271.845995) (xy 400.362034 -271.844014) (xy 400.410889 -271.849946)
			(xy 400.45816 -271.863638) (xy 400.502622 -271.884736) (xy 400.543125 -271.912692) (xy 400.578618 -271.946784)
			(xy 400.608183 -271.986128) (xy 400.631054 -272.029705) (xy 400.646638 -272.076386) (xy 400.654533 -272.124963)
			(xy 400.655028 -272.14957) (xy 401.943836 -272.14957) (xy 401.947796 -272.100516) (xy 401.959573 -272.052732)
			(xy 401.978864 -272.007456) (xy 402.005167 -271.96586) (xy 402.037802 -271.929023) (xy 402.075923 -271.897898)
			(xy 402.118544 -271.873291) (xy 402.16456 -271.855839) (xy 402.212779 -271.845995) (xy 402.261954 -271.844014)
			(xy 402.310809 -271.849946) (xy 402.35808 -271.863638) (xy 402.402542 -271.884736) (xy 402.443045 -271.912692)
			(xy 402.478538 -271.946784) (xy 402.508103 -271.986128) (xy 402.530974 -272.029705) (xy 402.546558 -272.076386)
			(xy 402.554453 -272.124963) (xy 402.554948 -272.14957) (xy 403.843756 -272.14957) (xy 403.847716 -272.100516)
			(xy 403.859493 -272.052732) (xy 403.878784 -272.007456) (xy 403.905087 -271.96586) (xy 403.937722 -271.929023)
			(xy 403.975843 -271.897898) (xy 404.018464 -271.873291) (xy 404.06448 -271.855839) (xy 404.112699 -271.845995)
			(xy 404.161874 -271.844014) (xy 404.210729 -271.849946) (xy 404.258 -271.863638) (xy 404.302462 -271.884736)
			(xy 404.342965 -271.912692) (xy 404.378458 -271.946784) (xy 404.408023 -271.986128) (xy 404.430894 -272.029705)
			(xy 404.446478 -272.076386) (xy 404.454373 -272.124963) (xy 404.454868 -272.14957) (xy 404.454373 -272.174177)
			(xy 404.446478 -272.222754) (xy 404.430894 -272.269435) (xy 404.408023 -272.313012) (xy 404.378458 -272.352356)
			(xy 404.342965 -272.386448) (xy 404.302462 -272.414404) (xy 404.258 -272.435502) (xy 404.210729 -272.449194)
			(xy 404.161874 -272.455126) (xy 404.112699 -272.453145) (xy 404.06448 -272.443301) (xy 404.018464 -272.425849)
			(xy 403.975843 -272.401242) (xy 403.937722 -272.370117) (xy 403.905087 -272.33328) (xy 403.878784 -272.291684)
			(xy 403.859493 -272.246408) (xy 403.847716 -272.198624) (xy 403.843756 -272.14957) (xy 402.554948 -272.14957)
			(xy 402.554453 -272.174177) (xy 402.546558 -272.222754) (xy 402.530974 -272.269435) (xy 402.508103 -272.313012)
			(xy 402.478538 -272.352356) (xy 402.443045 -272.386448) (xy 402.402542 -272.414404) (xy 402.35808 -272.435502)
			(xy 402.310809 -272.449194) (xy 402.261954 -272.455126) (xy 402.212779 -272.453145) (xy 402.16456 -272.443301)
			(xy 402.118544 -272.425849) (xy 402.075923 -272.401242) (xy 402.037802 -272.370117) (xy 402.005167 -272.33328)
			(xy 401.978864 -272.291684) (xy 401.959573 -272.246408) (xy 401.947796 -272.198624) (xy 401.943836 -272.14957)
			(xy 400.655028 -272.14957) (xy 400.654533 -272.174177) (xy 400.646638 -272.222754) (xy 400.631054 -272.269435)
			(xy 400.608183 -272.313012) (xy 400.578618 -272.352356) (xy 400.543125 -272.386448) (xy 400.502622 -272.414404)
			(xy 400.45816 -272.435502) (xy 400.410889 -272.449194) (xy 400.362034 -272.455126) (xy 400.312859 -272.453145)
			(xy 400.26464 -272.443301) (xy 400.218624 -272.425849) (xy 400.176003 -272.401242) (xy 400.137882 -272.370117)
			(xy 400.105247 -272.33328) (xy 400.078944 -272.291684) (xy 400.059653 -272.246408) (xy 400.047876 -272.198624)
			(xy 400.043916 -272.14957) (xy 398.754854 -272.14957) (xy 398.754359 -272.174177) (xy 398.746464 -272.222754)
			(xy 398.73088 -272.269435) (xy 398.708009 -272.313012) (xy 398.678444 -272.352356) (xy 398.642951 -272.386448)
			(xy 398.602448 -272.414404) (xy 398.557986 -272.435502) (xy 398.510715 -272.449194) (xy 398.46186 -272.455126)
			(xy 398.412685 -272.453145) (xy 398.364466 -272.443301) (xy 398.31845 -272.425849) (xy 398.275829 -272.401242)
			(xy 398.237708 -272.370117) (xy 398.205073 -272.33328) (xy 398.17877 -272.291684) (xy 398.159479 -272.246408)
			(xy 398.147702 -272.198624) (xy 398.143742 -272.14957) (xy 396.854934 -272.14957) (xy 396.854439 -272.174177)
			(xy 396.846544 -272.222754) (xy 396.83096 -272.269435) (xy 396.808089 -272.313012) (xy 396.778524 -272.352356)
			(xy 396.743031 -272.386448) (xy 396.702528 -272.414404) (xy 396.658066 -272.435502) (xy 396.610795 -272.449194)
			(xy 396.56194 -272.455126) (xy 396.512765 -272.453145) (xy 396.464546 -272.443301) (xy 396.41853 -272.425849)
			(xy 396.375909 -272.401242) (xy 396.337788 -272.370117) (xy 396.305153 -272.33328) (xy 396.27885 -272.291684)
			(xy 396.259559 -272.246408) (xy 396.247782 -272.198624) (xy 396.243822 -272.14957) (xy 394.955014 -272.14957)
			(xy 394.954519 -272.174177) (xy 394.946624 -272.222754) (xy 394.93104 -272.269435) (xy 394.908169 -272.313012)
			(xy 394.878604 -272.352356) (xy 394.843111 -272.386448) (xy 394.802608 -272.414404) (xy 394.758146 -272.435502)
			(xy 394.710875 -272.449194) (xy 394.66202 -272.455126) (xy 394.612845 -272.453145) (xy 394.564626 -272.443301)
			(xy 394.51861 -272.425849) (xy 394.475989 -272.401242) (xy 394.437868 -272.370117) (xy 394.405233 -272.33328)
			(xy 394.37893 -272.291684) (xy 394.359639 -272.246408) (xy 394.347862 -272.198624) (xy 394.343902 -272.14957)
			(xy 393.05484 -272.14957) (xy 393.054345 -272.174177) (xy 393.04645 -272.222754) (xy 393.030866 -272.269435)
			(xy 393.007995 -272.313012) (xy 392.97843 -272.352356) (xy 392.942937 -272.386448) (xy 392.902434 -272.414404)
			(xy 392.857972 -272.435502) (xy 392.810701 -272.449194) (xy 392.761846 -272.455126) (xy 392.712671 -272.453145)
			(xy 392.664452 -272.443301) (xy 392.618436 -272.425849) (xy 392.575815 -272.401242) (xy 392.537694 -272.370117)
			(xy 392.505059 -272.33328) (xy 392.478756 -272.291684) (xy 392.459465 -272.246408) (xy 392.447688 -272.198624)
			(xy 392.443728 -272.14957) (xy 382.558947 -272.14957) (xy 382.542076 -272.213259) (xy 382.487176 -272.391952)
			(xy 382.425325 -272.56836) (xy 382.403018 -272.624804) (xy 386.269242 -272.624804) (xy 386.273202 -272.57575)
			(xy 386.284979 -272.527966) (xy 386.30427 -272.48269) (xy 386.330573 -272.441094) (xy 386.363208 -272.404257)
			(xy 386.401329 -272.373132) (xy 386.44395 -272.348525) (xy 386.489966 -272.331073) (xy 386.538185 -272.321229)
			(xy 386.58736 -272.319248) (xy 386.636215 -272.32518) (xy 386.683486 -272.338872) (xy 386.727948 -272.35997)
			(xy 386.768451 -272.387926) (xy 386.803944 -272.422018) (xy 386.833509 -272.461362) (xy 386.85638 -272.504939)
			(xy 386.871964 -272.55162) (xy 386.879859 -272.600197) (xy 386.880354 -272.624804) (xy 387.219202 -272.624804)
			(xy 387.223162 -272.57575) (xy 387.234939 -272.527966) (xy 387.25423 -272.48269) (xy 387.280533 -272.441094)
			(xy 387.313168 -272.404257) (xy 387.351289 -272.373132) (xy 387.39391 -272.348525) (xy 387.439926 -272.331073)
			(xy 387.488145 -272.321229) (xy 387.53732 -272.319248) (xy 387.586175 -272.32518) (xy 387.633446 -272.338872)
			(xy 387.677908 -272.35997) (xy 387.718411 -272.387926) (xy 387.753904 -272.422018) (xy 387.783469 -272.461362)
			(xy 387.80634 -272.504939) (xy 387.821924 -272.55162) (xy 387.829819 -272.600197) (xy 387.830314 -272.624804)
			(xy 388.169162 -272.624804) (xy 388.173122 -272.57575) (xy 388.184899 -272.527966) (xy 388.20419 -272.48269)
			(xy 388.230493 -272.441094) (xy 388.263128 -272.404257) (xy 388.301249 -272.373132) (xy 388.34387 -272.348525)
			(xy 388.389886 -272.331073) (xy 388.438105 -272.321229) (xy 388.48728 -272.319248) (xy 388.536135 -272.32518)
			(xy 388.583406 -272.338872) (xy 388.627868 -272.35997) (xy 388.668371 -272.387926) (xy 388.703864 -272.422018)
			(xy 388.733429 -272.461362) (xy 388.7563 -272.504939) (xy 388.771884 -272.55162) (xy 388.779779 -272.600197)
			(xy 388.780274 -272.624804) (xy 389.119122 -272.624804) (xy 389.123082 -272.57575) (xy 389.134859 -272.527966)
			(xy 389.15415 -272.48269) (xy 389.180453 -272.441094) (xy 389.213088 -272.404257) (xy 389.251209 -272.373132)
			(xy 389.29383 -272.348525) (xy 389.339846 -272.331073) (xy 389.388065 -272.321229) (xy 389.43724 -272.319248)
			(xy 389.486095 -272.32518) (xy 389.533366 -272.338872) (xy 389.577828 -272.35997) (xy 389.618331 -272.387926)
			(xy 389.653824 -272.422018) (xy 389.683389 -272.461362) (xy 389.70626 -272.504939) (xy 389.721844 -272.55162)
			(xy 389.729739 -272.600197) (xy 389.730234 -272.624804) (xy 390.069082 -272.624804) (xy 390.073042 -272.57575)
			(xy 390.084819 -272.527966) (xy 390.10411 -272.48269) (xy 390.130413 -272.441094) (xy 390.163048 -272.404257)
			(xy 390.201169 -272.373132) (xy 390.24379 -272.348525) (xy 390.289806 -272.331073) (xy 390.338025 -272.321229)
			(xy 390.3872 -272.319248) (xy 390.436055 -272.32518) (xy 390.483326 -272.338872) (xy 390.527788 -272.35997)
			(xy 390.568291 -272.387926) (xy 390.603784 -272.422018) (xy 390.633349 -272.461362) (xy 390.65622 -272.504939)
			(xy 390.671804 -272.55162) (xy 390.679699 -272.600197) (xy 390.680194 -272.624804) (xy 391.019042 -272.624804)
			(xy 391.023002 -272.57575) (xy 391.034779 -272.527966) (xy 391.05407 -272.48269) (xy 391.080373 -272.441094)
			(xy 391.113008 -272.404257) (xy 391.151129 -272.373132) (xy 391.19375 -272.348525) (xy 391.239766 -272.331073)
			(xy 391.287985 -272.321229) (xy 391.33716 -272.319248) (xy 391.386015 -272.32518) (xy 391.433286 -272.338872)
			(xy 391.477748 -272.35997) (xy 391.518251 -272.387926) (xy 391.553744 -272.422018) (xy 391.583309 -272.461362)
			(xy 391.60618 -272.504939) (xy 391.621764 -272.55162) (xy 391.629659 -272.600197) (xy 391.630154 -272.624804)
			(xy 391.629659 -272.649411) (xy 391.621764 -272.697988) (xy 391.60618 -272.744669) (xy 391.583309 -272.788246)
			(xy 391.553744 -272.82759) (xy 391.518251 -272.861682) (xy 391.477748 -272.889638) (xy 391.433286 -272.910736)
			(xy 391.386015 -272.924428) (xy 391.33716 -272.93036) (xy 391.287985 -272.928379) (xy 391.239766 -272.918535)
			(xy 391.19375 -272.901083) (xy 391.151129 -272.876476) (xy 391.113008 -272.845351) (xy 391.080373 -272.808514)
			(xy 391.05407 -272.766918) (xy 391.034779 -272.721642) (xy 391.023002 -272.673858) (xy 391.019042 -272.624804)
			(xy 390.680194 -272.624804) (xy 390.679699 -272.649411) (xy 390.671804 -272.697988) (xy 390.65622 -272.744669)
			(xy 390.633349 -272.788246) (xy 390.603784 -272.82759) (xy 390.568291 -272.861682) (xy 390.527788 -272.889638)
			(xy 390.483326 -272.910736) (xy 390.436055 -272.924428) (xy 390.3872 -272.93036) (xy 390.338025 -272.928379)
			(xy 390.289806 -272.918535) (xy 390.24379 -272.901083) (xy 390.201169 -272.876476) (xy 390.163048 -272.845351)
			(xy 390.130413 -272.808514) (xy 390.10411 -272.766918) (xy 390.084819 -272.721642) (xy 390.073042 -272.673858)
			(xy 390.069082 -272.624804) (xy 389.730234 -272.624804) (xy 389.729739 -272.649411) (xy 389.721844 -272.697988)
			(xy 389.70626 -272.744669) (xy 389.683389 -272.788246) (xy 389.653824 -272.82759) (xy 389.618331 -272.861682)
			(xy 389.577828 -272.889638) (xy 389.533366 -272.910736) (xy 389.486095 -272.924428) (xy 389.43724 -272.93036)
			(xy 389.388065 -272.928379) (xy 389.339846 -272.918535) (xy 389.29383 -272.901083) (xy 389.251209 -272.876476)
			(xy 389.213088 -272.845351) (xy 389.180453 -272.808514) (xy 389.15415 -272.766918) (xy 389.134859 -272.721642)
			(xy 389.123082 -272.673858) (xy 389.119122 -272.624804) (xy 388.780274 -272.624804) (xy 388.779779 -272.649411)
			(xy 388.771884 -272.697988) (xy 388.7563 -272.744669) (xy 388.733429 -272.788246) (xy 388.703864 -272.82759)
			(xy 388.668371 -272.861682) (xy 388.627868 -272.889638) (xy 388.583406 -272.910736) (xy 388.536135 -272.924428)
			(xy 388.48728 -272.93036) (xy 388.438105 -272.928379) (xy 388.389886 -272.918535) (xy 388.34387 -272.901083)
			(xy 388.301249 -272.876476) (xy 388.263128 -272.845351) (xy 388.230493 -272.808514) (xy 388.20419 -272.766918)
			(xy 388.184899 -272.721642) (xy 388.173122 -272.673858) (xy 388.169162 -272.624804) (xy 387.830314 -272.624804)
			(xy 387.829819 -272.649411) (xy 387.821924 -272.697988) (xy 387.80634 -272.744669) (xy 387.783469 -272.788246)
			(xy 387.753904 -272.82759) (xy 387.718411 -272.861682) (xy 387.677908 -272.889638) (xy 387.633446 -272.910736)
			(xy 387.586175 -272.924428) (xy 387.53732 -272.93036) (xy 387.488145 -272.928379) (xy 387.439926 -272.918535)
			(xy 387.39391 -272.901083) (xy 387.351289 -272.876476) (xy 387.313168 -272.845351) (xy 387.280533 -272.808514)
			(xy 387.25423 -272.766918) (xy 387.234939 -272.721642) (xy 387.223162 -272.673858) (xy 387.219202 -272.624804)
			(xy 386.880354 -272.624804) (xy 386.879859 -272.649411) (xy 386.871964 -272.697988) (xy 386.85638 -272.744669)
			(xy 386.833509 -272.788246) (xy 386.803944 -272.82759) (xy 386.768451 -272.861682) (xy 386.727948 -272.889638)
			(xy 386.683486 -272.910736) (xy 386.636215 -272.924428) (xy 386.58736 -272.93036) (xy 386.538185 -272.928379)
			(xy 386.489966 -272.918535) (xy 386.44395 -272.901083) (xy 386.401329 -272.876476) (xy 386.363208 -272.845351)
			(xy 386.330573 -272.808514) (xy 386.30427 -272.766918) (xy 386.284979 -272.721642) (xy 386.273202 -272.673858)
			(xy 386.269242 -272.624804) (xy 382.403018 -272.624804) (xy 382.356618 -272.742212) (xy 382.281162 -272.913243)
			(xy 382.240536 -272.997422) (xy 382.19703 -273.085288) (xy 382.189192 -273.099784) (xy 392.443982 -273.099784)
			(xy 392.447942 -273.05073) (xy 392.459719 -273.002946) (xy 392.47901 -272.95767) (xy 392.505313 -272.916074)
			(xy 392.537948 -272.879237) (xy 392.576069 -272.848112) (xy 392.61869 -272.823505) (xy 392.664706 -272.806053)
			(xy 392.712925 -272.796209) (xy 392.7621 -272.794228) (xy 392.810955 -272.80016) (xy 392.858226 -272.813852)
			(xy 392.902688 -272.83495) (xy 392.943191 -272.862906) (xy 392.978684 -272.896998) (xy 393.008249 -272.936342)
			(xy 393.03112 -272.979919) (xy 393.046704 -273.0266) (xy 393.054599 -273.075177) (xy 393.055094 -273.099784)
			(xy 393.394196 -273.099784) (xy 393.398156 -273.05073) (xy 393.409933 -273.002946) (xy 393.429224 -272.95767)
			(xy 393.455527 -272.916074) (xy 393.488162 -272.879237) (xy 393.526283 -272.848112) (xy 393.568904 -272.823505)
			(xy 393.61492 -272.806053) (xy 393.663139 -272.796209) (xy 393.712314 -272.794228) (xy 393.761169 -272.80016)
			(xy 393.80844 -272.813852) (xy 393.852902 -272.83495) (xy 393.893405 -272.862906) (xy 393.928898 -272.896998)
			(xy 393.958463 -272.936342) (xy 393.981334 -272.979919) (xy 393.996918 -273.0266) (xy 394.004813 -273.075177)
			(xy 394.005308 -273.099784) (xy 394.344156 -273.099784) (xy 394.348116 -273.05073) (xy 394.359893 -273.002946)
			(xy 394.379184 -272.95767) (xy 394.405487 -272.916074) (xy 394.438122 -272.879237) (xy 394.476243 -272.848112)
			(xy 394.518864 -272.823505) (xy 394.56488 -272.806053) (xy 394.613099 -272.796209) (xy 394.662274 -272.794228)
			(xy 394.711129 -272.80016) (xy 394.7584 -272.813852) (xy 394.802862 -272.83495) (xy 394.843365 -272.862906)
			(xy 394.878858 -272.896998) (xy 394.908423 -272.936342) (xy 394.931294 -272.979919) (xy 394.946878 -273.0266)
			(xy 394.954773 -273.075177) (xy 394.955268 -273.099784) (xy 395.294116 -273.099784) (xy 395.298076 -273.05073)
			(xy 395.309853 -273.002946) (xy 395.329144 -272.95767) (xy 395.355447 -272.916074) (xy 395.388082 -272.879237)
			(xy 395.426203 -272.848112) (xy 395.468824 -272.823505) (xy 395.51484 -272.806053) (xy 395.563059 -272.796209)
			(xy 395.612234 -272.794228) (xy 395.661089 -272.80016) (xy 395.70836 -272.813852) (xy 395.752822 -272.83495)
			(xy 395.793325 -272.862906) (xy 395.828818 -272.896998) (xy 395.858383 -272.936342) (xy 395.881254 -272.979919)
			(xy 395.896838 -273.0266) (xy 395.904733 -273.075177) (xy 395.905228 -273.099784) (xy 396.244076 -273.099784)
			(xy 396.248036 -273.05073) (xy 396.259813 -273.002946) (xy 396.279104 -272.95767) (xy 396.305407 -272.916074)
			(xy 396.338042 -272.879237) (xy 396.376163 -272.848112) (xy 396.418784 -272.823505) (xy 396.4648 -272.806053)
			(xy 396.513019 -272.796209) (xy 396.562194 -272.794228) (xy 396.611049 -272.80016) (xy 396.65832 -272.813852)
			(xy 396.702782 -272.83495) (xy 396.743285 -272.862906) (xy 396.778778 -272.896998) (xy 396.808343 -272.936342)
			(xy 396.831214 -272.979919) (xy 396.846798 -273.0266) (xy 396.854693 -273.075177) (xy 396.855188 -273.099784)
			(xy 397.194036 -273.099784) (xy 397.197996 -273.05073) (xy 397.209773 -273.002946) (xy 397.229064 -272.95767)
			(xy 397.255367 -272.916074) (xy 397.288002 -272.879237) (xy 397.326123 -272.848112) (xy 397.368744 -272.823505)
			(xy 397.41476 -272.806053) (xy 397.462979 -272.796209) (xy 397.512154 -272.794228) (xy 397.561009 -272.80016)
			(xy 397.60828 -272.813852) (xy 397.652742 -272.83495) (xy 397.693245 -272.862906) (xy 397.728738 -272.896998)
			(xy 397.758303 -272.936342) (xy 397.781174 -272.979919) (xy 397.796758 -273.0266) (xy 397.804653 -273.075177)
			(xy 397.805148 -273.099784) (xy 398.143996 -273.099784) (xy 398.147956 -273.05073) (xy 398.159733 -273.002946)
			(xy 398.179024 -272.95767) (xy 398.205327 -272.916074) (xy 398.237962 -272.879237) (xy 398.276083 -272.848112)
			(xy 398.318704 -272.823505) (xy 398.36472 -272.806053) (xy 398.412939 -272.796209) (xy 398.462114 -272.794228)
			(xy 398.510969 -272.80016) (xy 398.55824 -272.813852) (xy 398.602702 -272.83495) (xy 398.643205 -272.862906)
			(xy 398.678698 -272.896998) (xy 398.708263 -272.936342) (xy 398.731134 -272.979919) (xy 398.746718 -273.0266)
			(xy 398.754613 -273.075177) (xy 398.755108 -273.099784) (xy 399.09421 -273.099784) (xy 399.09817 -273.05073)
			(xy 399.109947 -273.002946) (xy 399.129238 -272.95767) (xy 399.155541 -272.916074) (xy 399.188176 -272.879237)
			(xy 399.226297 -272.848112) (xy 399.268918 -272.823505) (xy 399.314934 -272.806053) (xy 399.363153 -272.796209)
			(xy 399.412328 -272.794228) (xy 399.461183 -272.80016) (xy 399.508454 -272.813852) (xy 399.552916 -272.83495)
			(xy 399.593419 -272.862906) (xy 399.628912 -272.896998) (xy 399.658477 -272.936342) (xy 399.681348 -272.979919)
			(xy 399.696932 -273.0266) (xy 399.704827 -273.075177) (xy 399.705322 -273.099784) (xy 400.04417 -273.099784)
			(xy 400.04813 -273.05073) (xy 400.059907 -273.002946) (xy 400.079198 -272.95767) (xy 400.105501 -272.916074)
			(xy 400.138136 -272.879237) (xy 400.176257 -272.848112) (xy 400.218878 -272.823505) (xy 400.264894 -272.806053)
			(xy 400.313113 -272.796209) (xy 400.362288 -272.794228) (xy 400.411143 -272.80016) (xy 400.458414 -272.813852)
			(xy 400.502876 -272.83495) (xy 400.543379 -272.862906) (xy 400.578872 -272.896998) (xy 400.608437 -272.936342)
			(xy 400.631308 -272.979919) (xy 400.646892 -273.0266) (xy 400.654787 -273.075177) (xy 400.655282 -273.099784)
			(xy 400.99413 -273.099784) (xy 400.99809 -273.05073) (xy 401.009867 -273.002946) (xy 401.029158 -272.95767)
			(xy 401.055461 -272.916074) (xy 401.088096 -272.879237) (xy 401.126217 -272.848112) (xy 401.168838 -272.823505)
			(xy 401.214854 -272.806053) (xy 401.263073 -272.796209) (xy 401.312248 -272.794228) (xy 401.361103 -272.80016)
			(xy 401.408374 -272.813852) (xy 401.452836 -272.83495) (xy 401.493339 -272.862906) (xy 401.528832 -272.896998)
			(xy 401.558397 -272.936342) (xy 401.581268 -272.979919) (xy 401.596852 -273.0266) (xy 401.604747 -273.075177)
			(xy 401.605242 -273.099784) (xy 401.94409 -273.099784) (xy 401.94805 -273.05073) (xy 401.959827 -273.002946)
			(xy 401.979118 -272.95767) (xy 402.005421 -272.916074) (xy 402.038056 -272.879237) (xy 402.076177 -272.848112)
			(xy 402.118798 -272.823505) (xy 402.164814 -272.806053) (xy 402.213033 -272.796209) (xy 402.262208 -272.794228)
			(xy 402.311063 -272.80016) (xy 402.358334 -272.813852) (xy 402.402796 -272.83495) (xy 402.443299 -272.862906)
			(xy 402.478792 -272.896998) (xy 402.508357 -272.936342) (xy 402.531228 -272.979919) (xy 402.546812 -273.0266)
			(xy 402.554707 -273.075177) (xy 402.555202 -273.099784) (xy 402.89405 -273.099784) (xy 402.89801 -273.05073)
			(xy 402.909787 -273.002946) (xy 402.929078 -272.95767) (xy 402.955381 -272.916074) (xy 402.988016 -272.879237)
			(xy 403.026137 -272.848112) (xy 403.068758 -272.823505) (xy 403.114774 -272.806053) (xy 403.162993 -272.796209)
			(xy 403.212168 -272.794228) (xy 403.261023 -272.80016) (xy 403.308294 -272.813852) (xy 403.352756 -272.83495)
			(xy 403.393259 -272.862906) (xy 403.428752 -272.896998) (xy 403.458317 -272.936342) (xy 403.481188 -272.979919)
			(xy 403.496772 -273.0266) (xy 403.504667 -273.075177) (xy 403.505162 -273.099784) (xy 403.84401 -273.099784)
			(xy 403.84797 -273.05073) (xy 403.859747 -273.002946) (xy 403.879038 -272.95767) (xy 403.905341 -272.916074)
			(xy 403.937976 -272.879237) (xy 403.976097 -272.848112) (xy 404.018718 -272.823505) (xy 404.064734 -272.806053)
			(xy 404.112953 -272.796209) (xy 404.162128 -272.794228) (xy 404.210983 -272.80016) (xy 404.258254 -272.813852)
			(xy 404.302716 -272.83495) (xy 404.343219 -272.862906) (xy 404.378712 -272.896998) (xy 404.408277 -272.936342)
			(xy 404.431148 -272.979919) (xy 404.446732 -273.0266) (xy 404.454627 -273.075177) (xy 404.455122 -273.099784)
			(xy 404.794224 -273.099784) (xy 404.798184 -273.05073) (xy 404.809961 -273.002946) (xy 404.829252 -272.95767)
			(xy 404.855555 -272.916074) (xy 404.88819 -272.879237) (xy 404.926311 -272.848112) (xy 404.968932 -272.823505)
			(xy 405.014948 -272.806053) (xy 405.063167 -272.796209) (xy 405.112342 -272.794228) (xy 405.161197 -272.80016)
			(xy 405.208468 -272.813852) (xy 405.25293 -272.83495) (xy 405.293433 -272.862906) (xy 405.328926 -272.896998)
			(xy 405.358491 -272.936342) (xy 405.381362 -272.979919) (xy 405.396946 -273.0266) (xy 405.404841 -273.075177)
			(xy 405.405336 -273.099784) (xy 405.404841 -273.124391) (xy 405.396946 -273.172968) (xy 405.381362 -273.219649)
			(xy 405.358491 -273.263226) (xy 405.328926 -273.30257) (xy 405.293433 -273.336662) (xy 405.25293 -273.364618)
			(xy 405.208468 -273.385716) (xy 405.161197 -273.399408) (xy 405.112342 -273.40534) (xy 405.063167 -273.403359)
			(xy 405.014948 -273.393515) (xy 404.968932 -273.376063) (xy 404.926311 -273.351456) (xy 404.88819 -273.320331)
			(xy 404.855555 -273.283494) (xy 404.829252 -273.241898) (xy 404.809961 -273.196622) (xy 404.798184 -273.148838)
			(xy 404.794224 -273.099784) (xy 404.455122 -273.099784) (xy 404.454627 -273.124391) (xy 404.446732 -273.172968)
			(xy 404.431148 -273.219649) (xy 404.408277 -273.263226) (xy 404.378712 -273.30257) (xy 404.343219 -273.336662)
			(xy 404.302716 -273.364618) (xy 404.258254 -273.385716) (xy 404.210983 -273.399408) (xy 404.162128 -273.40534)
			(xy 404.112953 -273.403359) (xy 404.064734 -273.393515) (xy 404.018718 -273.376063) (xy 403.976097 -273.351456)
			(xy 403.937976 -273.320331) (xy 403.905341 -273.283494) (xy 403.879038 -273.241898) (xy 403.859747 -273.196622)
			(xy 403.84797 -273.148838) (xy 403.84401 -273.099784) (xy 403.505162 -273.099784) (xy 403.504667 -273.124391)
			(xy 403.496772 -273.172968) (xy 403.481188 -273.219649) (xy 403.458317 -273.263226) (xy 403.428752 -273.30257)
			(xy 403.393259 -273.336662) (xy 403.352756 -273.364618) (xy 403.308294 -273.385716) (xy 403.261023 -273.399408)
			(xy 403.212168 -273.40534) (xy 403.162993 -273.403359) (xy 403.114774 -273.393515) (xy 403.068758 -273.376063)
			(xy 403.026137 -273.351456) (xy 402.988016 -273.320331) (xy 402.955381 -273.283494) (xy 402.929078 -273.241898)
			(xy 402.909787 -273.196622) (xy 402.89801 -273.148838) (xy 402.89405 -273.099784) (xy 402.555202 -273.099784)
			(xy 402.554707 -273.124391) (xy 402.546812 -273.172968) (xy 402.531228 -273.219649) (xy 402.508357 -273.263226)
			(xy 402.478792 -273.30257) (xy 402.443299 -273.336662) (xy 402.402796 -273.364618) (xy 402.358334 -273.385716)
			(xy 402.311063 -273.399408) (xy 402.262208 -273.40534) (xy 402.213033 -273.403359) (xy 402.164814 -273.393515)
			(xy 402.118798 -273.376063) (xy 402.076177 -273.351456) (xy 402.038056 -273.320331) (xy 402.005421 -273.283494)
			(xy 401.979118 -273.241898) (xy 401.959827 -273.196622) (xy 401.94805 -273.148838) (xy 401.94409 -273.099784)
			(xy 401.605242 -273.099784) (xy 401.604747 -273.124391) (xy 401.596852 -273.172968) (xy 401.581268 -273.219649)
			(xy 401.558397 -273.263226) (xy 401.528832 -273.30257) (xy 401.493339 -273.336662) (xy 401.452836 -273.364618)
			(xy 401.408374 -273.385716) (xy 401.361103 -273.399408) (xy 401.312248 -273.40534) (xy 401.263073 -273.403359)
			(xy 401.214854 -273.393515) (xy 401.168838 -273.376063) (xy 401.126217 -273.351456) (xy 401.088096 -273.320331)
			(xy 401.055461 -273.283494) (xy 401.029158 -273.241898) (xy 401.009867 -273.196622) (xy 400.99809 -273.148838)
			(xy 400.99413 -273.099784) (xy 400.655282 -273.099784) (xy 400.654787 -273.124391) (xy 400.646892 -273.172968)
			(xy 400.631308 -273.219649) (xy 400.608437 -273.263226) (xy 400.578872 -273.30257) (xy 400.543379 -273.336662)
			(xy 400.502876 -273.364618) (xy 400.458414 -273.385716) (xy 400.411143 -273.399408) (xy 400.362288 -273.40534)
			(xy 400.313113 -273.403359) (xy 400.264894 -273.393515) (xy 400.218878 -273.376063) (xy 400.176257 -273.351456)
			(xy 400.138136 -273.320331) (xy 400.105501 -273.283494) (xy 400.079198 -273.241898) (xy 400.059907 -273.196622)
			(xy 400.04813 -273.148838) (xy 400.04417 -273.099784) (xy 399.705322 -273.099784) (xy 399.704827 -273.124391)
			(xy 399.696932 -273.172968) (xy 399.681348 -273.219649) (xy 399.658477 -273.263226) (xy 399.628912 -273.30257)
			(xy 399.593419 -273.336662) (xy 399.552916 -273.364618) (xy 399.508454 -273.385716) (xy 399.461183 -273.399408)
			(xy 399.412328 -273.40534) (xy 399.363153 -273.403359) (xy 399.314934 -273.393515) (xy 399.268918 -273.376063)
			(xy 399.226297 -273.351456) (xy 399.188176 -273.320331) (xy 399.155541 -273.283494) (xy 399.129238 -273.241898)
			(xy 399.109947 -273.196622) (xy 399.09817 -273.148838) (xy 399.09421 -273.099784) (xy 398.755108 -273.099784)
			(xy 398.754613 -273.124391) (xy 398.746718 -273.172968) (xy 398.731134 -273.219649) (xy 398.708263 -273.263226)
			(xy 398.678698 -273.30257) (xy 398.643205 -273.336662) (xy 398.602702 -273.364618) (xy 398.55824 -273.385716)
			(xy 398.510969 -273.399408) (xy 398.462114 -273.40534) (xy 398.412939 -273.403359) (xy 398.36472 -273.393515)
			(xy 398.318704 -273.376063) (xy 398.276083 -273.351456) (xy 398.237962 -273.320331) (xy 398.205327 -273.283494)
			(xy 398.179024 -273.241898) (xy 398.159733 -273.196622) (xy 398.147956 -273.148838) (xy 398.143996 -273.099784)
			(xy 397.805148 -273.099784) (xy 397.804653 -273.124391) (xy 397.796758 -273.172968) (xy 397.781174 -273.219649)
			(xy 397.758303 -273.263226) (xy 397.728738 -273.30257) (xy 397.693245 -273.336662) (xy 397.652742 -273.364618)
			(xy 397.60828 -273.385716) (xy 397.561009 -273.399408) (xy 397.512154 -273.40534) (xy 397.462979 -273.403359)
			(xy 397.41476 -273.393515) (xy 397.368744 -273.376063) (xy 397.326123 -273.351456) (xy 397.288002 -273.320331)
			(xy 397.255367 -273.283494) (xy 397.229064 -273.241898) (xy 397.209773 -273.196622) (xy 397.197996 -273.148838)
			(xy 397.194036 -273.099784) (xy 396.855188 -273.099784) (xy 396.854693 -273.124391) (xy 396.846798 -273.172968)
			(xy 396.831214 -273.219649) (xy 396.808343 -273.263226) (xy 396.778778 -273.30257) (xy 396.743285 -273.336662)
			(xy 396.702782 -273.364618) (xy 396.65832 -273.385716) (xy 396.611049 -273.399408) (xy 396.562194 -273.40534)
			(xy 396.513019 -273.403359) (xy 396.4648 -273.393515) (xy 396.418784 -273.376063) (xy 396.376163 -273.351456)
			(xy 396.338042 -273.320331) (xy 396.305407 -273.283494) (xy 396.279104 -273.241898) (xy 396.259813 -273.196622)
			(xy 396.248036 -273.148838) (xy 396.244076 -273.099784) (xy 395.905228 -273.099784) (xy 395.904733 -273.124391)
			(xy 395.896838 -273.172968) (xy 395.881254 -273.219649) (xy 395.858383 -273.263226) (xy 395.828818 -273.30257)
			(xy 395.793325 -273.336662) (xy 395.752822 -273.364618) (xy 395.70836 -273.385716) (xy 395.661089 -273.399408)
			(xy 395.612234 -273.40534) (xy 395.563059 -273.403359) (xy 395.51484 -273.393515) (xy 395.468824 -273.376063)
			(xy 395.426203 -273.351456) (xy 395.388082 -273.320331) (xy 395.355447 -273.283494) (xy 395.329144 -273.241898)
			(xy 395.309853 -273.196622) (xy 395.298076 -273.148838) (xy 395.294116 -273.099784) (xy 394.955268 -273.099784)
			(xy 394.954773 -273.124391) (xy 394.946878 -273.172968) (xy 394.931294 -273.219649) (xy 394.908423 -273.263226)
			(xy 394.878858 -273.30257) (xy 394.843365 -273.336662) (xy 394.802862 -273.364618) (xy 394.7584 -273.385716)
			(xy 394.711129 -273.399408) (xy 394.662274 -273.40534) (xy 394.613099 -273.403359) (xy 394.56488 -273.393515)
			(xy 394.518864 -273.376063) (xy 394.476243 -273.351456) (xy 394.438122 -273.320331) (xy 394.405487 -273.283494)
			(xy 394.379184 -273.241898) (xy 394.359893 -273.196622) (xy 394.348116 -273.148838) (xy 394.344156 -273.099784)
			(xy 394.005308 -273.099784) (xy 394.004813 -273.124391) (xy 393.996918 -273.172968) (xy 393.981334 -273.219649)
			(xy 393.958463 -273.263226) (xy 393.928898 -273.30257) (xy 393.893405 -273.336662) (xy 393.852902 -273.364618)
			(xy 393.80844 -273.385716) (xy 393.761169 -273.399408) (xy 393.712314 -273.40534) (xy 393.663139 -273.403359)
			(xy 393.61492 -273.393515) (xy 393.568904 -273.376063) (xy 393.526283 -273.351456) (xy 393.488162 -273.320331)
			(xy 393.455527 -273.283494) (xy 393.429224 -273.241898) (xy 393.409933 -273.196622) (xy 393.398156 -273.148838)
			(xy 393.394196 -273.099784) (xy 393.055094 -273.099784) (xy 393.054599 -273.124391) (xy 393.046704 -273.172968)
			(xy 393.03112 -273.219649) (xy 393.008249 -273.263226) (xy 392.978684 -273.30257) (xy 392.943191 -273.336662)
			(xy 392.902688 -273.364618) (xy 392.858226 -273.385716) (xy 392.810955 -273.399408) (xy 392.7621 -273.40534)
			(xy 392.712925 -273.403359) (xy 392.664706 -273.393515) (xy 392.61869 -273.376063) (xy 392.576069 -273.351456)
			(xy 392.537948 -273.320331) (xy 392.505313 -273.283494) (xy 392.47901 -273.241898) (xy 392.459719 -273.196622)
			(xy 392.447942 -273.148838) (xy 392.443982 -273.099784) (xy 382.189192 -273.099784) (xy 382.103763 -273.25778)
			(xy 382.003495 -273.426298) (xy 381.906693 -273.574764) (xy 385.319028 -273.574764) (xy 385.322988 -273.52571)
			(xy 385.334765 -273.477926) (xy 385.354056 -273.43265) (xy 385.380359 -273.391054) (xy 385.412994 -273.354217)
			(xy 385.451115 -273.323092) (xy 385.493736 -273.298485) (xy 385.539752 -273.281033) (xy 385.587971 -273.271189)
			(xy 385.637146 -273.269208) (xy 385.686001 -273.27514) (xy 385.733272 -273.288832) (xy 385.777734 -273.30993)
			(xy 385.818237 -273.337886) (xy 385.85373 -273.371978) (xy 385.883295 -273.411322) (xy 385.906166 -273.454899)
			(xy 385.92175 -273.50158) (xy 385.929645 -273.550157) (xy 385.93014 -273.574764) (xy 386.268988 -273.574764)
			(xy 386.272948 -273.52571) (xy 386.284725 -273.477926) (xy 386.304016 -273.43265) (xy 386.330319 -273.391054)
			(xy 386.362954 -273.354217) (xy 386.401075 -273.323092) (xy 386.443696 -273.298485) (xy 386.489712 -273.281033)
			(xy 386.537931 -273.271189) (xy 386.587106 -273.269208) (xy 386.635961 -273.27514) (xy 386.683232 -273.288832)
			(xy 386.727694 -273.30993) (xy 386.768197 -273.337886) (xy 386.80369 -273.371978) (xy 386.833255 -273.411322)
			(xy 386.856126 -273.454899) (xy 386.87171 -273.50158) (xy 386.879605 -273.550157) (xy 386.8801 -273.574764)
			(xy 387.219202 -273.574764) (xy 387.223162 -273.52571) (xy 387.234939 -273.477926) (xy 387.25423 -273.43265)
			(xy 387.280533 -273.391054) (xy 387.313168 -273.354217) (xy 387.351289 -273.323092) (xy 387.39391 -273.298485)
			(xy 387.439926 -273.281033) (xy 387.488145 -273.271189) (xy 387.53732 -273.269208) (xy 387.586175 -273.27514)
			(xy 387.633446 -273.288832) (xy 387.677908 -273.30993) (xy 387.718411 -273.337886) (xy 387.753904 -273.371978)
			(xy 387.783469 -273.411322) (xy 387.80634 -273.454899) (xy 387.821924 -273.50158) (xy 387.829819 -273.550157)
			(xy 387.830314 -273.574764) (xy 388.169162 -273.574764) (xy 388.173122 -273.52571) (xy 388.184899 -273.477926)
			(xy 388.20419 -273.43265) (xy 388.230493 -273.391054) (xy 388.263128 -273.354217) (xy 388.301249 -273.323092)
			(xy 388.34387 -273.298485) (xy 388.389886 -273.281033) (xy 388.438105 -273.271189) (xy 388.48728 -273.269208)
			(xy 388.536135 -273.27514) (xy 388.583406 -273.288832) (xy 388.627868 -273.30993) (xy 388.668371 -273.337886)
			(xy 388.703864 -273.371978) (xy 388.733429 -273.411322) (xy 388.7563 -273.454899) (xy 388.771884 -273.50158)
			(xy 388.779779 -273.550157) (xy 388.780274 -273.574764) (xy 389.119122 -273.574764) (xy 389.123082 -273.52571)
			(xy 389.134859 -273.477926) (xy 389.15415 -273.43265) (xy 389.180453 -273.391054) (xy 389.213088 -273.354217)
			(xy 389.251209 -273.323092) (xy 389.29383 -273.298485) (xy 389.339846 -273.281033) (xy 389.388065 -273.271189)
			(xy 389.43724 -273.269208) (xy 389.486095 -273.27514) (xy 389.533366 -273.288832) (xy 389.577828 -273.30993)
			(xy 389.618331 -273.337886) (xy 389.653824 -273.371978) (xy 389.683389 -273.411322) (xy 389.70626 -273.454899)
			(xy 389.721844 -273.50158) (xy 389.729739 -273.550157) (xy 389.730234 -273.574764) (xy 390.069082 -273.574764)
			(xy 390.073042 -273.52571) (xy 390.084819 -273.477926) (xy 390.10411 -273.43265) (xy 390.130413 -273.391054)
			(xy 390.163048 -273.354217) (xy 390.201169 -273.323092) (xy 390.24379 -273.298485) (xy 390.289806 -273.281033)
			(xy 390.338025 -273.271189) (xy 390.3872 -273.269208) (xy 390.436055 -273.27514) (xy 390.483326 -273.288832)
			(xy 390.527788 -273.30993) (xy 390.568291 -273.337886) (xy 390.603784 -273.371978) (xy 390.633349 -273.411322)
			(xy 390.65622 -273.454899) (xy 390.671804 -273.50158) (xy 390.679699 -273.550157) (xy 390.680194 -273.574764)
			(xy 391.019042 -273.574764) (xy 391.023002 -273.52571) (xy 391.034779 -273.477926) (xy 391.05407 -273.43265)
			(xy 391.080373 -273.391054) (xy 391.113008 -273.354217) (xy 391.151129 -273.323092) (xy 391.19375 -273.298485)
			(xy 391.239766 -273.281033) (xy 391.287985 -273.271189) (xy 391.33716 -273.269208) (xy 391.386015 -273.27514)
			(xy 391.433286 -273.288832) (xy 391.477748 -273.30993) (xy 391.518251 -273.337886) (xy 391.553744 -273.371978)
			(xy 391.583309 -273.411322) (xy 391.60618 -273.454899) (xy 391.621764 -273.50158) (xy 391.629659 -273.550157)
			(xy 391.630154 -273.574764) (xy 391.629659 -273.599371) (xy 391.621764 -273.647948) (xy 391.60618 -273.694629)
			(xy 391.583309 -273.738206) (xy 391.553744 -273.77755) (xy 391.518251 -273.811642) (xy 391.477748 -273.839598)
			(xy 391.433286 -273.860696) (xy 391.386015 -273.874388) (xy 391.33716 -273.88032) (xy 391.287985 -273.878339)
			(xy 391.239766 -273.868495) (xy 391.19375 -273.851043) (xy 391.151129 -273.826436) (xy 391.113008 -273.795311)
			(xy 391.080373 -273.758474) (xy 391.05407 -273.716878) (xy 391.034779 -273.671602) (xy 391.023002 -273.623818)
			(xy 391.019042 -273.574764) (xy 390.680194 -273.574764) (xy 390.679699 -273.599371) (xy 390.671804 -273.647948)
			(xy 390.65622 -273.694629) (xy 390.633349 -273.738206) (xy 390.603784 -273.77755) (xy 390.568291 -273.811642)
			(xy 390.527788 -273.839598) (xy 390.483326 -273.860696) (xy 390.436055 -273.874388) (xy 390.3872 -273.88032)
			(xy 390.338025 -273.878339) (xy 390.289806 -273.868495) (xy 390.24379 -273.851043) (xy 390.201169 -273.826436)
			(xy 390.163048 -273.795311) (xy 390.130413 -273.758474) (xy 390.10411 -273.716878) (xy 390.084819 -273.671602)
			(xy 390.073042 -273.623818) (xy 390.069082 -273.574764) (xy 389.730234 -273.574764) (xy 389.729739 -273.599371)
			(xy 389.721844 -273.647948) (xy 389.70626 -273.694629) (xy 389.683389 -273.738206) (xy 389.653824 -273.77755)
			(xy 389.618331 -273.811642) (xy 389.577828 -273.839598) (xy 389.533366 -273.860696) (xy 389.486095 -273.874388)
			(xy 389.43724 -273.88032) (xy 389.388065 -273.878339) (xy 389.339846 -273.868495) (xy 389.29383 -273.851043)
			(xy 389.251209 -273.826436) (xy 389.213088 -273.795311) (xy 389.180453 -273.758474) (xy 389.15415 -273.716878)
			(xy 389.134859 -273.671602) (xy 389.123082 -273.623818) (xy 389.119122 -273.574764) (xy 388.780274 -273.574764)
			(xy 388.779779 -273.599371) (xy 388.771884 -273.647948) (xy 388.7563 -273.694629) (xy 388.733429 -273.738206)
			(xy 388.703864 -273.77755) (xy 388.668371 -273.811642) (xy 388.627868 -273.839598) (xy 388.583406 -273.860696)
			(xy 388.536135 -273.874388) (xy 388.48728 -273.88032) (xy 388.438105 -273.878339) (xy 388.389886 -273.868495)
			(xy 388.34387 -273.851043) (xy 388.301249 -273.826436) (xy 388.263128 -273.795311) (xy 388.230493 -273.758474)
			(xy 388.20419 -273.716878) (xy 388.184899 -273.671602) (xy 388.173122 -273.623818) (xy 388.169162 -273.574764)
			(xy 387.830314 -273.574764) (xy 387.829819 -273.599371) (xy 387.821924 -273.647948) (xy 387.80634 -273.694629)
			(xy 387.783469 -273.738206) (xy 387.753904 -273.77755) (xy 387.718411 -273.811642) (xy 387.677908 -273.839598)
			(xy 387.633446 -273.860696) (xy 387.586175 -273.874388) (xy 387.53732 -273.88032) (xy 387.488145 -273.878339)
			(xy 387.439926 -273.868495) (xy 387.39391 -273.851043) (xy 387.351289 -273.826436) (xy 387.313168 -273.795311)
			(xy 387.280533 -273.758474) (xy 387.25423 -273.716878) (xy 387.234939 -273.671602) (xy 387.223162 -273.623818)
			(xy 387.219202 -273.574764) (xy 386.8801 -273.574764) (xy 386.879605 -273.599371) (xy 386.87171 -273.647948)
			(xy 386.856126 -273.694629) (xy 386.833255 -273.738206) (xy 386.80369 -273.77755) (xy 386.768197 -273.811642)
			(xy 386.727694 -273.839598) (xy 386.683232 -273.860696) (xy 386.635961 -273.874388) (xy 386.587106 -273.88032)
			(xy 386.537931 -273.878339) (xy 386.489712 -273.868495) (xy 386.443696 -273.851043) (xy 386.401075 -273.826436)
			(xy 386.362954 -273.795311) (xy 386.330319 -273.758474) (xy 386.304016 -273.716878) (xy 386.284725 -273.671602)
			(xy 386.272948 -273.623818) (xy 386.268988 -273.574764) (xy 385.93014 -273.574764) (xy 385.929645 -273.599371)
			(xy 385.92175 -273.647948) (xy 385.906166 -273.694629) (xy 385.883295 -273.738206) (xy 385.85373 -273.77755)
			(xy 385.818237 -273.811642) (xy 385.777734 -273.839598) (xy 385.733272 -273.860696) (xy 385.686001 -273.874388)
			(xy 385.637146 -273.88032) (xy 385.587971 -273.878339) (xy 385.539752 -273.868495) (xy 385.493736 -273.851043)
			(xy 385.451115 -273.826436) (xy 385.412994 -273.795311) (xy 385.380359 -273.758474) (xy 385.354056 -273.716878)
			(xy 385.334765 -273.671602) (xy 385.322988 -273.623818) (xy 385.319028 -273.574764) (xy 381.906693 -273.574764)
			(xy 381.896395 -273.590558) (xy 381.782642 -273.750284) (xy 381.66243 -273.905206) (xy 381.54045 -274.049744)
			(xy 392.443982 -274.049744) (xy 392.447942 -274.00069) (xy 392.459719 -273.952906) (xy 392.47901 -273.90763)
			(xy 392.505313 -273.866034) (xy 392.537948 -273.829197) (xy 392.576069 -273.798072) (xy 392.61869 -273.773465)
			(xy 392.664706 -273.756013) (xy 392.712925 -273.746169) (xy 392.7621 -273.744188) (xy 392.810955 -273.75012)
			(xy 392.858226 -273.763812) (xy 392.902688 -273.78491) (xy 392.943191 -273.812866) (xy 392.978684 -273.846958)
			(xy 393.008249 -273.886302) (xy 393.03112 -273.929879) (xy 393.046704 -273.97656) (xy 393.054599 -274.025137)
			(xy 393.055094 -274.049744) (xy 393.394196 -274.049744) (xy 393.398156 -274.00069) (xy 393.409933 -273.952906)
			(xy 393.429224 -273.90763) (xy 393.455527 -273.866034) (xy 393.488162 -273.829197) (xy 393.526283 -273.798072)
			(xy 393.568904 -273.773465) (xy 393.61492 -273.756013) (xy 393.663139 -273.746169) (xy 393.712314 -273.744188)
			(xy 393.761169 -273.75012) (xy 393.80844 -273.763812) (xy 393.852902 -273.78491) (xy 393.893405 -273.812866)
			(xy 393.928898 -273.846958) (xy 393.958463 -273.886302) (xy 393.981334 -273.929879) (xy 393.996918 -273.97656)
			(xy 394.004813 -274.025137) (xy 394.005308 -274.049744) (xy 394.344156 -274.049744) (xy 394.348116 -274.00069)
			(xy 394.359893 -273.952906) (xy 394.379184 -273.90763) (xy 394.405487 -273.866034) (xy 394.438122 -273.829197)
			(xy 394.476243 -273.798072) (xy 394.518864 -273.773465) (xy 394.56488 -273.756013) (xy 394.613099 -273.746169)
			(xy 394.662274 -273.744188) (xy 394.711129 -273.75012) (xy 394.7584 -273.763812) (xy 394.802862 -273.78491)
			(xy 394.843365 -273.812866) (xy 394.878858 -273.846958) (xy 394.908423 -273.886302) (xy 394.931294 -273.929879)
			(xy 394.946878 -273.97656) (xy 394.954773 -274.025137) (xy 394.955268 -274.049744) (xy 395.294116 -274.049744)
			(xy 395.298076 -274.00069) (xy 395.309853 -273.952906) (xy 395.329144 -273.90763) (xy 395.355447 -273.866034)
			(xy 395.388082 -273.829197) (xy 395.426203 -273.798072) (xy 395.468824 -273.773465) (xy 395.51484 -273.756013)
			(xy 395.563059 -273.746169) (xy 395.612234 -273.744188) (xy 395.661089 -273.75012) (xy 395.70836 -273.763812)
			(xy 395.752822 -273.78491) (xy 395.793325 -273.812866) (xy 395.828818 -273.846958) (xy 395.858383 -273.886302)
			(xy 395.881254 -273.929879) (xy 395.896838 -273.97656) (xy 395.904733 -274.025137) (xy 395.905228 -274.049744)
			(xy 396.244076 -274.049744) (xy 396.248036 -274.00069) (xy 396.259813 -273.952906) (xy 396.279104 -273.90763)
			(xy 396.305407 -273.866034) (xy 396.338042 -273.829197) (xy 396.376163 -273.798072) (xy 396.418784 -273.773465)
			(xy 396.4648 -273.756013) (xy 396.513019 -273.746169) (xy 396.562194 -273.744188) (xy 396.611049 -273.75012)
			(xy 396.65832 -273.763812) (xy 396.702782 -273.78491) (xy 396.743285 -273.812866) (xy 396.778778 -273.846958)
			(xy 396.808343 -273.886302) (xy 396.831214 -273.929879) (xy 396.846798 -273.97656) (xy 396.854693 -274.025137)
			(xy 396.855188 -274.049744) (xy 397.194036 -274.049744) (xy 397.197996 -274.00069) (xy 397.209773 -273.952906)
			(xy 397.229064 -273.90763) (xy 397.255367 -273.866034) (xy 397.288002 -273.829197) (xy 397.326123 -273.798072)
			(xy 397.368744 -273.773465) (xy 397.41476 -273.756013) (xy 397.462979 -273.746169) (xy 397.512154 -273.744188)
			(xy 397.561009 -273.75012) (xy 397.60828 -273.763812) (xy 397.652742 -273.78491) (xy 397.693245 -273.812866)
			(xy 397.728738 -273.846958) (xy 397.758303 -273.886302) (xy 397.781174 -273.929879) (xy 397.796758 -273.97656)
			(xy 397.804653 -274.025137) (xy 397.805148 -274.049744) (xy 398.143996 -274.049744) (xy 398.147956 -274.00069)
			(xy 398.159733 -273.952906) (xy 398.179024 -273.90763) (xy 398.205327 -273.866034) (xy 398.237962 -273.829197)
			(xy 398.276083 -273.798072) (xy 398.318704 -273.773465) (xy 398.36472 -273.756013) (xy 398.412939 -273.746169)
			(xy 398.462114 -273.744188) (xy 398.510969 -273.75012) (xy 398.55824 -273.763812) (xy 398.602702 -273.78491)
			(xy 398.643205 -273.812866) (xy 398.678698 -273.846958) (xy 398.708263 -273.886302) (xy 398.731134 -273.929879)
			(xy 398.746718 -273.97656) (xy 398.754613 -274.025137) (xy 398.755108 -274.049744) (xy 399.09421 -274.049744)
			(xy 399.09817 -274.00069) (xy 399.109947 -273.952906) (xy 399.129238 -273.90763) (xy 399.155541 -273.866034)
			(xy 399.188176 -273.829197) (xy 399.226297 -273.798072) (xy 399.268918 -273.773465) (xy 399.314934 -273.756013)
			(xy 399.363153 -273.746169) (xy 399.412328 -273.744188) (xy 399.461183 -273.75012) (xy 399.508454 -273.763812)
			(xy 399.552916 -273.78491) (xy 399.593419 -273.812866) (xy 399.628912 -273.846958) (xy 399.658477 -273.886302)
			(xy 399.681348 -273.929879) (xy 399.696932 -273.97656) (xy 399.704827 -274.025137) (xy 399.705322 -274.049744)
			(xy 400.04417 -274.049744) (xy 400.04813 -274.00069) (xy 400.059907 -273.952906) (xy 400.079198 -273.90763)
			(xy 400.105501 -273.866034) (xy 400.138136 -273.829197) (xy 400.176257 -273.798072) (xy 400.218878 -273.773465)
			(xy 400.264894 -273.756013) (xy 400.313113 -273.746169) (xy 400.362288 -273.744188) (xy 400.411143 -273.75012)
			(xy 400.458414 -273.763812) (xy 400.502876 -273.78491) (xy 400.543379 -273.812866) (xy 400.578872 -273.846958)
			(xy 400.608437 -273.886302) (xy 400.631308 -273.929879) (xy 400.646892 -273.97656) (xy 400.654787 -274.025137)
			(xy 400.655282 -274.049744) (xy 400.99413 -274.049744) (xy 400.99809 -274.00069) (xy 401.009867 -273.952906)
			(xy 401.029158 -273.90763) (xy 401.055461 -273.866034) (xy 401.088096 -273.829197) (xy 401.126217 -273.798072)
			(xy 401.168838 -273.773465) (xy 401.214854 -273.756013) (xy 401.263073 -273.746169) (xy 401.312248 -273.744188)
			(xy 401.361103 -273.75012) (xy 401.408374 -273.763812) (xy 401.452836 -273.78491) (xy 401.493339 -273.812866)
			(xy 401.528832 -273.846958) (xy 401.558397 -273.886302) (xy 401.581268 -273.929879) (xy 401.596852 -273.97656)
			(xy 401.604747 -274.025137) (xy 401.605242 -274.049744) (xy 401.94409 -274.049744) (xy 401.94805 -274.00069)
			(xy 401.959827 -273.952906) (xy 401.979118 -273.90763) (xy 402.005421 -273.866034) (xy 402.038056 -273.829197)
			(xy 402.076177 -273.798072) (xy 402.118798 -273.773465) (xy 402.164814 -273.756013) (xy 402.213033 -273.746169)
			(xy 402.262208 -273.744188) (xy 402.311063 -273.75012) (xy 402.358334 -273.763812) (xy 402.402796 -273.78491)
			(xy 402.443299 -273.812866) (xy 402.478792 -273.846958) (xy 402.508357 -273.886302) (xy 402.531228 -273.929879)
			(xy 402.546812 -273.97656) (xy 402.554707 -274.025137) (xy 402.555202 -274.049744) (xy 402.89405 -274.049744)
			(xy 402.89801 -274.00069) (xy 402.909787 -273.952906) (xy 402.929078 -273.90763) (xy 402.955381 -273.866034)
			(xy 402.988016 -273.829197) (xy 403.026137 -273.798072) (xy 403.068758 -273.773465) (xy 403.114774 -273.756013)
			(xy 403.162993 -273.746169) (xy 403.212168 -273.744188) (xy 403.261023 -273.75012) (xy 403.308294 -273.763812)
			(xy 403.352756 -273.78491) (xy 403.393259 -273.812866) (xy 403.428752 -273.846958) (xy 403.458317 -273.886302)
			(xy 403.481188 -273.929879) (xy 403.496772 -273.97656) (xy 403.504667 -274.025137) (xy 403.505162 -274.049744)
			(xy 403.84401 -274.049744) (xy 403.84797 -274.00069) (xy 403.859747 -273.952906) (xy 403.879038 -273.90763)
			(xy 403.905341 -273.866034) (xy 403.937976 -273.829197) (xy 403.976097 -273.798072) (xy 404.018718 -273.773465)
			(xy 404.064734 -273.756013) (xy 404.112953 -273.746169) (xy 404.162128 -273.744188) (xy 404.210983 -273.75012)
			(xy 404.258254 -273.763812) (xy 404.302716 -273.78491) (xy 404.343219 -273.812866) (xy 404.378712 -273.846958)
			(xy 404.408277 -273.886302) (xy 404.431148 -273.929879) (xy 404.446732 -273.97656) (xy 404.454627 -274.025137)
			(xy 404.455122 -274.049744) (xy 404.794224 -274.049744) (xy 404.798184 -274.00069) (xy 404.809961 -273.952906)
			(xy 404.829252 -273.90763) (xy 404.855555 -273.866034) (xy 404.88819 -273.829197) (xy 404.926311 -273.798072)
			(xy 404.968932 -273.773465) (xy 405.014948 -273.756013) (xy 405.063167 -273.746169) (xy 405.112342 -273.744188)
			(xy 405.161197 -273.75012) (xy 405.208468 -273.763812) (xy 405.25293 -273.78491) (xy 405.293433 -273.812866)
			(xy 405.328926 -273.846958) (xy 405.358491 -273.886302) (xy 405.381362 -273.929879) (xy 405.396946 -273.97656)
			(xy 405.404841 -274.025137) (xy 405.405336 -274.049744) (xy 405.404841 -274.074351) (xy 405.396946 -274.122928)
			(xy 405.381362 -274.169609) (xy 405.358491 -274.213186) (xy 405.328926 -274.25253) (xy 405.293433 -274.286622)
			(xy 405.25293 -274.314578) (xy 405.208468 -274.335676) (xy 405.161197 -274.349368) (xy 405.112342 -274.3553)
			(xy 405.063167 -274.353319) (xy 405.014948 -274.343475) (xy 404.968932 -274.326023) (xy 404.926311 -274.301416)
			(xy 404.88819 -274.270291) (xy 404.855555 -274.233454) (xy 404.829252 -274.191858) (xy 404.809961 -274.146582)
			(xy 404.798184 -274.098798) (xy 404.794224 -274.049744) (xy 404.455122 -274.049744) (xy 404.454627 -274.074351)
			(xy 404.446732 -274.122928) (xy 404.431148 -274.169609) (xy 404.408277 -274.213186) (xy 404.378712 -274.25253)
			(xy 404.343219 -274.286622) (xy 404.302716 -274.314578) (xy 404.258254 -274.335676) (xy 404.210983 -274.349368)
			(xy 404.162128 -274.3553) (xy 404.112953 -274.353319) (xy 404.064734 -274.343475) (xy 404.018718 -274.326023)
			(xy 403.976097 -274.301416) (xy 403.937976 -274.270291) (xy 403.905341 -274.233454) (xy 403.879038 -274.191858)
			(xy 403.859747 -274.146582) (xy 403.84797 -274.098798) (xy 403.84401 -274.049744) (xy 403.505162 -274.049744)
			(xy 403.504667 -274.074351) (xy 403.496772 -274.122928) (xy 403.481188 -274.169609) (xy 403.458317 -274.213186)
			(xy 403.428752 -274.25253) (xy 403.393259 -274.286622) (xy 403.352756 -274.314578) (xy 403.308294 -274.335676)
			(xy 403.261023 -274.349368) (xy 403.212168 -274.3553) (xy 403.162993 -274.353319) (xy 403.114774 -274.343475)
			(xy 403.068758 -274.326023) (xy 403.026137 -274.301416) (xy 402.988016 -274.270291) (xy 402.955381 -274.233454)
			(xy 402.929078 -274.191858) (xy 402.909787 -274.146582) (xy 402.89801 -274.098798) (xy 402.89405 -274.049744)
			(xy 402.555202 -274.049744) (xy 402.554707 -274.074351) (xy 402.546812 -274.122928) (xy 402.531228 -274.169609)
			(xy 402.508357 -274.213186) (xy 402.478792 -274.25253) (xy 402.443299 -274.286622) (xy 402.402796 -274.314578)
			(xy 402.358334 -274.335676) (xy 402.311063 -274.349368) (xy 402.262208 -274.3553) (xy 402.213033 -274.353319)
			(xy 402.164814 -274.343475) (xy 402.118798 -274.326023) (xy 402.076177 -274.301416) (xy 402.038056 -274.270291)
			(xy 402.005421 -274.233454) (xy 401.979118 -274.191858) (xy 401.959827 -274.146582) (xy 401.94805 -274.098798)
			(xy 401.94409 -274.049744) (xy 401.605242 -274.049744) (xy 401.604747 -274.074351) (xy 401.596852 -274.122928)
			(xy 401.581268 -274.169609) (xy 401.558397 -274.213186) (xy 401.528832 -274.25253) (xy 401.493339 -274.286622)
			(xy 401.452836 -274.314578) (xy 401.408374 -274.335676) (xy 401.361103 -274.349368) (xy 401.312248 -274.3553)
			(xy 401.263073 -274.353319) (xy 401.214854 -274.343475) (xy 401.168838 -274.326023) (xy 401.126217 -274.301416)
			(xy 401.088096 -274.270291) (xy 401.055461 -274.233454) (xy 401.029158 -274.191858) (xy 401.009867 -274.146582)
			(xy 400.99809 -274.098798) (xy 400.99413 -274.049744) (xy 400.655282 -274.049744) (xy 400.654787 -274.074351)
			(xy 400.646892 -274.122928) (xy 400.631308 -274.169609) (xy 400.608437 -274.213186) (xy 400.578872 -274.25253)
			(xy 400.543379 -274.286622) (xy 400.502876 -274.314578) (xy 400.458414 -274.335676) (xy 400.411143 -274.349368)
			(xy 400.362288 -274.3553) (xy 400.313113 -274.353319) (xy 400.264894 -274.343475) (xy 400.218878 -274.326023)
			(xy 400.176257 -274.301416) (xy 400.138136 -274.270291) (xy 400.105501 -274.233454) (xy 400.079198 -274.191858)
			(xy 400.059907 -274.146582) (xy 400.04813 -274.098798) (xy 400.04417 -274.049744) (xy 399.705322 -274.049744)
			(xy 399.704827 -274.074351) (xy 399.696932 -274.122928) (xy 399.681348 -274.169609) (xy 399.658477 -274.213186)
			(xy 399.628912 -274.25253) (xy 399.593419 -274.286622) (xy 399.552916 -274.314578) (xy 399.508454 -274.335676)
			(xy 399.461183 -274.349368) (xy 399.412328 -274.3553) (xy 399.363153 -274.353319) (xy 399.314934 -274.343475)
			(xy 399.268918 -274.326023) (xy 399.226297 -274.301416) (xy 399.188176 -274.270291) (xy 399.155541 -274.233454)
			(xy 399.129238 -274.191858) (xy 399.109947 -274.146582) (xy 399.09817 -274.098798) (xy 399.09421 -274.049744)
			(xy 398.755108 -274.049744) (xy 398.754613 -274.074351) (xy 398.746718 -274.122928) (xy 398.731134 -274.169609)
			(xy 398.708263 -274.213186) (xy 398.678698 -274.25253) (xy 398.643205 -274.286622) (xy 398.602702 -274.314578)
			(xy 398.55824 -274.335676) (xy 398.510969 -274.349368) (xy 398.462114 -274.3553) (xy 398.412939 -274.353319)
			(xy 398.36472 -274.343475) (xy 398.318704 -274.326023) (xy 398.276083 -274.301416) (xy 398.237962 -274.270291)
			(xy 398.205327 -274.233454) (xy 398.179024 -274.191858) (xy 398.159733 -274.146582) (xy 398.147956 -274.098798)
			(xy 398.143996 -274.049744) (xy 397.805148 -274.049744) (xy 397.804653 -274.074351) (xy 397.796758 -274.122928)
			(xy 397.781174 -274.169609) (xy 397.758303 -274.213186) (xy 397.728738 -274.25253) (xy 397.693245 -274.286622)
			(xy 397.652742 -274.314578) (xy 397.60828 -274.335676) (xy 397.561009 -274.349368) (xy 397.512154 -274.3553)
			(xy 397.462979 -274.353319) (xy 397.41476 -274.343475) (xy 397.368744 -274.326023) (xy 397.326123 -274.301416)
			(xy 397.288002 -274.270291) (xy 397.255367 -274.233454) (xy 397.229064 -274.191858) (xy 397.209773 -274.146582)
			(xy 397.197996 -274.098798) (xy 397.194036 -274.049744) (xy 396.855188 -274.049744) (xy 396.854693 -274.074351)
			(xy 396.846798 -274.122928) (xy 396.831214 -274.169609) (xy 396.808343 -274.213186) (xy 396.778778 -274.25253)
			(xy 396.743285 -274.286622) (xy 396.702782 -274.314578) (xy 396.65832 -274.335676) (xy 396.611049 -274.349368)
			(xy 396.562194 -274.3553) (xy 396.513019 -274.353319) (xy 396.4648 -274.343475) (xy 396.418784 -274.326023)
			(xy 396.376163 -274.301416) (xy 396.338042 -274.270291) (xy 396.305407 -274.233454) (xy 396.279104 -274.191858)
			(xy 396.259813 -274.146582) (xy 396.248036 -274.098798) (xy 396.244076 -274.049744) (xy 395.905228 -274.049744)
			(xy 395.904733 -274.074351) (xy 395.896838 -274.122928) (xy 395.881254 -274.169609) (xy 395.858383 -274.213186)
			(xy 395.828818 -274.25253) (xy 395.793325 -274.286622) (xy 395.752822 -274.314578) (xy 395.70836 -274.335676)
			(xy 395.661089 -274.349368) (xy 395.612234 -274.3553) (xy 395.563059 -274.353319) (xy 395.51484 -274.343475)
			(xy 395.468824 -274.326023) (xy 395.426203 -274.301416) (xy 395.388082 -274.270291) (xy 395.355447 -274.233454)
			(xy 395.329144 -274.191858) (xy 395.309853 -274.146582) (xy 395.298076 -274.098798) (xy 395.294116 -274.049744)
			(xy 394.955268 -274.049744) (xy 394.954773 -274.074351) (xy 394.946878 -274.122928) (xy 394.931294 -274.169609)
			(xy 394.908423 -274.213186) (xy 394.878858 -274.25253) (xy 394.843365 -274.286622) (xy 394.802862 -274.314578)
			(xy 394.7584 -274.335676) (xy 394.711129 -274.349368) (xy 394.662274 -274.3553) (xy 394.613099 -274.353319)
			(xy 394.56488 -274.343475) (xy 394.518864 -274.326023) (xy 394.476243 -274.301416) (xy 394.438122 -274.270291)
			(xy 394.405487 -274.233454) (xy 394.379184 -274.191858) (xy 394.359893 -274.146582) (xy 394.348116 -274.098798)
			(xy 394.344156 -274.049744) (xy 394.005308 -274.049744) (xy 394.004813 -274.074351) (xy 393.996918 -274.122928)
			(xy 393.981334 -274.169609) (xy 393.958463 -274.213186) (xy 393.928898 -274.25253) (xy 393.893405 -274.286622)
			(xy 393.852902 -274.314578) (xy 393.80844 -274.335676) (xy 393.761169 -274.349368) (xy 393.712314 -274.3553)
			(xy 393.663139 -274.353319) (xy 393.61492 -274.343475) (xy 393.568904 -274.326023) (xy 393.526283 -274.301416)
			(xy 393.488162 -274.270291) (xy 393.455527 -274.233454) (xy 393.429224 -274.191858) (xy 393.409933 -274.146582)
			(xy 393.398156 -274.098798) (xy 393.394196 -274.049744) (xy 393.055094 -274.049744) (xy 393.054599 -274.074351)
			(xy 393.046704 -274.122928) (xy 393.03112 -274.169609) (xy 393.008249 -274.213186) (xy 392.978684 -274.25253)
			(xy 392.943191 -274.286622) (xy 392.902688 -274.314578) (xy 392.858226 -274.335676) (xy 392.810955 -274.349368)
			(xy 392.7621 -274.3553) (xy 392.712925 -274.353319) (xy 392.664706 -274.343475) (xy 392.61869 -274.326023)
			(xy 392.576069 -274.301416) (xy 392.537948 -274.270291) (xy 392.505313 -274.233454) (xy 392.47901 -274.191858)
			(xy 392.459719 -274.146582) (xy 392.447942 -274.098798) (xy 392.443982 -274.049744) (xy 381.54045 -274.049744)
			(xy 381.53596 -274.055064) (xy 381.403445 -274.199604) (xy 381.26511 -274.338584) (xy 381.121186 -274.471768)
			(xy 381.059026 -274.524724) (xy 385.319028 -274.524724) (xy 385.322988 -274.47567) (xy 385.334765 -274.427886)
			(xy 385.354056 -274.38261) (xy 385.380359 -274.341014) (xy 385.412994 -274.304177) (xy 385.451115 -274.273052)
			(xy 385.493736 -274.248445) (xy 385.539752 -274.230993) (xy 385.587971 -274.221149) (xy 385.637146 -274.219168)
			(xy 385.686001 -274.2251) (xy 385.733272 -274.238792) (xy 385.777734 -274.25989) (xy 385.818237 -274.287846)
			(xy 385.85373 -274.321938) (xy 385.883295 -274.361282) (xy 385.906166 -274.404859) (xy 385.92175 -274.45154)
			(xy 385.929645 -274.500117) (xy 385.93014 -274.524724) (xy 385.930135 -274.524978) (xy 386.269242 -274.524978)
			(xy 386.273202 -274.475924) (xy 386.284979 -274.42814) (xy 386.30427 -274.382864) (xy 386.330573 -274.341268)
			(xy 386.363208 -274.304431) (xy 386.401329 -274.273306) (xy 386.44395 -274.248699) (xy 386.489966 -274.231247)
			(xy 386.538185 -274.221403) (xy 386.58736 -274.219422) (xy 386.636215 -274.225354) (xy 386.683486 -274.239046)
			(xy 386.727948 -274.260144) (xy 386.768451 -274.2881) (xy 386.803944 -274.322192) (xy 386.833509 -274.361536)
			(xy 386.85638 -274.405113) (xy 386.871964 -274.451794) (xy 386.879859 -274.500371) (xy 386.880354 -274.524978)
			(xy 387.219202 -274.524978) (xy 387.223162 -274.475924) (xy 387.234939 -274.42814) (xy 387.25423 -274.382864)
			(xy 387.280533 -274.341268) (xy 387.313168 -274.304431) (xy 387.351289 -274.273306) (xy 387.39391 -274.248699)
			(xy 387.439926 -274.231247) (xy 387.488145 -274.221403) (xy 387.53732 -274.219422) (xy 387.586175 -274.225354)
			(xy 387.633446 -274.239046) (xy 387.677908 -274.260144) (xy 387.718411 -274.2881) (xy 387.753904 -274.322192)
			(xy 387.783469 -274.361536) (xy 387.80634 -274.405113) (xy 387.821924 -274.451794) (xy 387.829819 -274.500371)
			(xy 387.830314 -274.524978) (xy 388.169162 -274.524978) (xy 388.173122 -274.475924) (xy 388.184899 -274.42814)
			(xy 388.20419 -274.382864) (xy 388.230493 -274.341268) (xy 388.263128 -274.304431) (xy 388.301249 -274.273306)
			(xy 388.34387 -274.248699) (xy 388.389886 -274.231247) (xy 388.438105 -274.221403) (xy 388.48728 -274.219422)
			(xy 388.536135 -274.225354) (xy 388.583406 -274.239046) (xy 388.627868 -274.260144) (xy 388.668371 -274.2881)
			(xy 388.703864 -274.322192) (xy 388.733429 -274.361536) (xy 388.7563 -274.405113) (xy 388.771884 -274.451794)
			(xy 388.779779 -274.500371) (xy 388.780274 -274.524978) (xy 389.119122 -274.524978) (xy 389.123082 -274.475924)
			(xy 389.134859 -274.42814) (xy 389.15415 -274.382864) (xy 389.180453 -274.341268) (xy 389.213088 -274.304431)
			(xy 389.251209 -274.273306) (xy 389.29383 -274.248699) (xy 389.339846 -274.231247) (xy 389.388065 -274.221403)
			(xy 389.43724 -274.219422) (xy 389.486095 -274.225354) (xy 389.533366 -274.239046) (xy 389.577828 -274.260144)
			(xy 389.618331 -274.2881) (xy 389.653824 -274.322192) (xy 389.683389 -274.361536) (xy 389.70626 -274.405113)
			(xy 389.721844 -274.451794) (xy 389.729739 -274.500371) (xy 389.730234 -274.524978) (xy 390.069082 -274.524978)
			(xy 390.073042 -274.475924) (xy 390.084819 -274.42814) (xy 390.10411 -274.382864) (xy 390.130413 -274.341268)
			(xy 390.163048 -274.304431) (xy 390.201169 -274.273306) (xy 390.24379 -274.248699) (xy 390.289806 -274.231247)
			(xy 390.338025 -274.221403) (xy 390.3872 -274.219422) (xy 390.436055 -274.225354) (xy 390.483326 -274.239046)
			(xy 390.527788 -274.260144) (xy 390.568291 -274.2881) (xy 390.603784 -274.322192) (xy 390.633349 -274.361536)
			(xy 390.65622 -274.405113) (xy 390.671804 -274.451794) (xy 390.679699 -274.500371) (xy 390.680194 -274.524978)
			(xy 391.019042 -274.524978) (xy 391.023002 -274.475924) (xy 391.034779 -274.42814) (xy 391.05407 -274.382864)
			(xy 391.080373 -274.341268) (xy 391.113008 -274.304431) (xy 391.151129 -274.273306) (xy 391.19375 -274.248699)
			(xy 391.239766 -274.231247) (xy 391.287985 -274.221403) (xy 391.33716 -274.219422) (xy 391.386015 -274.225354)
			(xy 391.433286 -274.239046) (xy 391.477748 -274.260144) (xy 391.518251 -274.2881) (xy 391.553744 -274.322192)
			(xy 391.583309 -274.361536) (xy 391.60618 -274.405113) (xy 391.621764 -274.451794) (xy 391.629659 -274.500371)
			(xy 391.630154 -274.524978) (xy 391.629659 -274.549585) (xy 391.621764 -274.598162) (xy 391.60618 -274.644843)
			(xy 391.583309 -274.68842) (xy 391.553744 -274.727764) (xy 391.518251 -274.761856) (xy 391.477748 -274.789812)
			(xy 391.433286 -274.81091) (xy 391.386015 -274.824602) (xy 391.33716 -274.830534) (xy 391.287985 -274.828553)
			(xy 391.239766 -274.818709) (xy 391.19375 -274.801257) (xy 391.151129 -274.77665) (xy 391.113008 -274.745525)
			(xy 391.080373 -274.708688) (xy 391.05407 -274.667092) (xy 391.034779 -274.621816) (xy 391.023002 -274.574032)
			(xy 391.019042 -274.524978) (xy 390.680194 -274.524978) (xy 390.679699 -274.549585) (xy 390.671804 -274.598162)
			(xy 390.65622 -274.644843) (xy 390.633349 -274.68842) (xy 390.603784 -274.727764) (xy 390.568291 -274.761856)
			(xy 390.527788 -274.789812) (xy 390.483326 -274.81091) (xy 390.436055 -274.824602) (xy 390.3872 -274.830534)
			(xy 390.338025 -274.828553) (xy 390.289806 -274.818709) (xy 390.24379 -274.801257) (xy 390.201169 -274.77665)
			(xy 390.163048 -274.745525) (xy 390.130413 -274.708688) (xy 390.10411 -274.667092) (xy 390.084819 -274.621816)
			(xy 390.073042 -274.574032) (xy 390.069082 -274.524978) (xy 389.730234 -274.524978) (xy 389.729739 -274.549585)
			(xy 389.721844 -274.598162) (xy 389.70626 -274.644843) (xy 389.683389 -274.68842) (xy 389.653824 -274.727764)
			(xy 389.618331 -274.761856) (xy 389.577828 -274.789812) (xy 389.533366 -274.81091) (xy 389.486095 -274.824602)
			(xy 389.43724 -274.830534) (xy 389.388065 -274.828553) (xy 389.339846 -274.818709) (xy 389.29383 -274.801257)
			(xy 389.251209 -274.77665) (xy 389.213088 -274.745525) (xy 389.180453 -274.708688) (xy 389.15415 -274.667092)
			(xy 389.134859 -274.621816) (xy 389.123082 -274.574032) (xy 389.119122 -274.524978) (xy 388.780274 -274.524978)
			(xy 388.779779 -274.549585) (xy 388.771884 -274.598162) (xy 388.7563 -274.644843) (xy 388.733429 -274.68842)
			(xy 388.703864 -274.727764) (xy 388.668371 -274.761856) (xy 388.627868 -274.789812) (xy 388.583406 -274.81091)
			(xy 388.536135 -274.824602) (xy 388.48728 -274.830534) (xy 388.438105 -274.828553) (xy 388.389886 -274.818709)
			(xy 388.34387 -274.801257) (xy 388.301249 -274.77665) (xy 388.263128 -274.745525) (xy 388.230493 -274.708688)
			(xy 388.20419 -274.667092) (xy 388.184899 -274.621816) (xy 388.173122 -274.574032) (xy 388.169162 -274.524978)
			(xy 387.830314 -274.524978) (xy 387.829819 -274.549585) (xy 387.821924 -274.598162) (xy 387.80634 -274.644843)
			(xy 387.783469 -274.68842) (xy 387.753904 -274.727764) (xy 387.718411 -274.761856) (xy 387.677908 -274.789812)
			(xy 387.633446 -274.81091) (xy 387.586175 -274.824602) (xy 387.53732 -274.830534) (xy 387.488145 -274.828553)
			(xy 387.439926 -274.818709) (xy 387.39391 -274.801257) (xy 387.351289 -274.77665) (xy 387.313168 -274.745525)
			(xy 387.280533 -274.708688) (xy 387.25423 -274.667092) (xy 387.234939 -274.621816) (xy 387.223162 -274.574032)
			(xy 387.219202 -274.524978) (xy 386.880354 -274.524978) (xy 386.879859 -274.549585) (xy 386.871964 -274.598162)
			(xy 386.85638 -274.644843) (xy 386.833509 -274.68842) (xy 386.803944 -274.727764) (xy 386.768451 -274.761856)
			(xy 386.727948 -274.789812) (xy 386.683486 -274.81091) (xy 386.636215 -274.824602) (xy 386.58736 -274.830534)
			(xy 386.538185 -274.828553) (xy 386.489966 -274.818709) (xy 386.44395 -274.801257) (xy 386.401329 -274.77665)
			(xy 386.363208 -274.745525) (xy 386.330573 -274.708688) (xy 386.30427 -274.667092) (xy 386.284979 -274.621816)
			(xy 386.273202 -274.574032) (xy 386.269242 -274.524978) (xy 385.930135 -274.524978) (xy 385.929645 -274.549331)
			(xy 385.92175 -274.597908) (xy 385.906166 -274.644589) (xy 385.883295 -274.688166) (xy 385.85373 -274.72751)
			(xy 385.818237 -274.761602) (xy 385.777734 -274.789558) (xy 385.733272 -274.810656) (xy 385.686001 -274.824348)
			(xy 385.637146 -274.83028) (xy 385.587971 -274.828299) (xy 385.539752 -274.818455) (xy 385.493736 -274.801003)
			(xy 385.451115 -274.776396) (xy 385.412994 -274.745271) (xy 385.380359 -274.708434) (xy 385.354056 -274.666838)
			(xy 385.334765 -274.621562) (xy 385.322988 -274.573778) (xy 385.319028 -274.524724) (xy 381.059026 -274.524724)
			(xy 380.971918 -274.598933) (xy 380.817556 -274.719863) (xy 380.65836 -274.834356) (xy 380.494599 -274.942219)
			(xy 380.398575 -274.999958) (xy 392.443982 -274.999958) (xy 392.447942 -274.950904) (xy 392.459719 -274.90312)
			(xy 392.47901 -274.857844) (xy 392.505313 -274.816248) (xy 392.537948 -274.779411) (xy 392.576069 -274.748286)
			(xy 392.61869 -274.723679) (xy 392.664706 -274.706227) (xy 392.712925 -274.696383) (xy 392.7621 -274.694402)
			(xy 392.810955 -274.700334) (xy 392.858226 -274.714026) (xy 392.902688 -274.735124) (xy 392.943191 -274.76308)
			(xy 392.978684 -274.797172) (xy 393.008249 -274.836516) (xy 393.03112 -274.880093) (xy 393.046704 -274.926774)
			(xy 393.054599 -274.975351) (xy 393.055094 -274.999958) (xy 393.394196 -274.999958) (xy 393.398156 -274.950904)
			(xy 393.409933 -274.90312) (xy 393.429224 -274.857844) (xy 393.455527 -274.816248) (xy 393.488162 -274.779411)
			(xy 393.526283 -274.748286) (xy 393.568904 -274.723679) (xy 393.61492 -274.706227) (xy 393.663139 -274.696383)
			(xy 393.712314 -274.694402) (xy 393.761169 -274.700334) (xy 393.80844 -274.714026) (xy 393.852902 -274.735124)
			(xy 393.893405 -274.76308) (xy 393.928898 -274.797172) (xy 393.958463 -274.836516) (xy 393.981334 -274.880093)
			(xy 393.996918 -274.926774) (xy 394.004813 -274.975351) (xy 394.005308 -274.999958) (xy 394.344156 -274.999958)
			(xy 394.348116 -274.950904) (xy 394.359893 -274.90312) (xy 394.379184 -274.857844) (xy 394.405487 -274.816248)
			(xy 394.438122 -274.779411) (xy 394.476243 -274.748286) (xy 394.518864 -274.723679) (xy 394.56488 -274.706227)
			(xy 394.613099 -274.696383) (xy 394.662274 -274.694402) (xy 394.711129 -274.700334) (xy 394.7584 -274.714026)
			(xy 394.802862 -274.735124) (xy 394.843365 -274.76308) (xy 394.878858 -274.797172) (xy 394.908423 -274.836516)
			(xy 394.931294 -274.880093) (xy 394.946878 -274.926774) (xy 394.954773 -274.975351) (xy 394.955268 -274.999958)
			(xy 395.294116 -274.999958) (xy 395.298076 -274.950904) (xy 395.309853 -274.90312) (xy 395.329144 -274.857844)
			(xy 395.355447 -274.816248) (xy 395.388082 -274.779411) (xy 395.426203 -274.748286) (xy 395.468824 -274.723679)
			(xy 395.51484 -274.706227) (xy 395.563059 -274.696383) (xy 395.612234 -274.694402) (xy 395.661089 -274.700334)
			(xy 395.70836 -274.714026) (xy 395.752822 -274.735124) (xy 395.793325 -274.76308) (xy 395.828818 -274.797172)
			(xy 395.858383 -274.836516) (xy 395.881254 -274.880093) (xy 395.896838 -274.926774) (xy 395.904733 -274.975351)
			(xy 395.905228 -274.999958) (xy 396.244076 -274.999958) (xy 396.248036 -274.950904) (xy 396.259813 -274.90312)
			(xy 396.279104 -274.857844) (xy 396.305407 -274.816248) (xy 396.338042 -274.779411) (xy 396.376163 -274.748286)
			(xy 396.418784 -274.723679) (xy 396.4648 -274.706227) (xy 396.513019 -274.696383) (xy 396.562194 -274.694402)
			(xy 396.611049 -274.700334) (xy 396.65832 -274.714026) (xy 396.702782 -274.735124) (xy 396.743285 -274.76308)
			(xy 396.778778 -274.797172) (xy 396.808343 -274.836516) (xy 396.831214 -274.880093) (xy 396.846798 -274.926774)
			(xy 396.854693 -274.975351) (xy 396.855188 -274.999958) (xy 397.194036 -274.999958) (xy 397.197996 -274.950904)
			(xy 397.209773 -274.90312) (xy 397.229064 -274.857844) (xy 397.255367 -274.816248) (xy 397.288002 -274.779411)
			(xy 397.326123 -274.748286) (xy 397.368744 -274.723679) (xy 397.41476 -274.706227) (xy 397.462979 -274.696383)
			(xy 397.512154 -274.694402) (xy 397.561009 -274.700334) (xy 397.60828 -274.714026) (xy 397.652742 -274.735124)
			(xy 397.693245 -274.76308) (xy 397.728738 -274.797172) (xy 397.758303 -274.836516) (xy 397.781174 -274.880093)
			(xy 397.796758 -274.926774) (xy 397.804653 -274.975351) (xy 397.805148 -274.999958) (xy 398.143996 -274.999958)
			(xy 398.147956 -274.950904) (xy 398.159733 -274.90312) (xy 398.179024 -274.857844) (xy 398.205327 -274.816248)
			(xy 398.237962 -274.779411) (xy 398.276083 -274.748286) (xy 398.318704 -274.723679) (xy 398.36472 -274.706227)
			(xy 398.412939 -274.696383) (xy 398.462114 -274.694402) (xy 398.510969 -274.700334) (xy 398.55824 -274.714026)
			(xy 398.602702 -274.735124) (xy 398.643205 -274.76308) (xy 398.678698 -274.797172) (xy 398.708263 -274.836516)
			(xy 398.731134 -274.880093) (xy 398.746718 -274.926774) (xy 398.754613 -274.975351) (xy 398.755108 -274.999958)
			(xy 399.09421 -274.999958) (xy 399.09817 -274.950904) (xy 399.109947 -274.90312) (xy 399.129238 -274.857844)
			(xy 399.155541 -274.816248) (xy 399.188176 -274.779411) (xy 399.226297 -274.748286) (xy 399.268918 -274.723679)
			(xy 399.314934 -274.706227) (xy 399.363153 -274.696383) (xy 399.412328 -274.694402) (xy 399.461183 -274.700334)
			(xy 399.508454 -274.714026) (xy 399.552916 -274.735124) (xy 399.593419 -274.76308) (xy 399.628912 -274.797172)
			(xy 399.658477 -274.836516) (xy 399.681348 -274.880093) (xy 399.696932 -274.926774) (xy 399.704827 -274.975351)
			(xy 399.705322 -274.999958) (xy 400.04417 -274.999958) (xy 400.04813 -274.950904) (xy 400.059907 -274.90312)
			(xy 400.079198 -274.857844) (xy 400.105501 -274.816248) (xy 400.138136 -274.779411) (xy 400.176257 -274.748286)
			(xy 400.218878 -274.723679) (xy 400.264894 -274.706227) (xy 400.313113 -274.696383) (xy 400.362288 -274.694402)
			(xy 400.411143 -274.700334) (xy 400.458414 -274.714026) (xy 400.502876 -274.735124) (xy 400.543379 -274.76308)
			(xy 400.578872 -274.797172) (xy 400.608437 -274.836516) (xy 400.631308 -274.880093) (xy 400.646892 -274.926774)
			(xy 400.654787 -274.975351) (xy 400.655282 -274.999958) (xy 400.99413 -274.999958) (xy 400.99809 -274.950904)
			(xy 401.009867 -274.90312) (xy 401.029158 -274.857844) (xy 401.055461 -274.816248) (xy 401.088096 -274.779411)
			(xy 401.126217 -274.748286) (xy 401.168838 -274.723679) (xy 401.214854 -274.706227) (xy 401.263073 -274.696383)
			(xy 401.312248 -274.694402) (xy 401.361103 -274.700334) (xy 401.408374 -274.714026) (xy 401.452836 -274.735124)
			(xy 401.493339 -274.76308) (xy 401.528832 -274.797172) (xy 401.558397 -274.836516) (xy 401.581268 -274.880093)
			(xy 401.596852 -274.926774) (xy 401.604747 -274.975351) (xy 401.605242 -274.999958) (xy 401.94409 -274.999958)
			(xy 401.94805 -274.950904) (xy 401.959827 -274.90312) (xy 401.979118 -274.857844) (xy 402.005421 -274.816248)
			(xy 402.038056 -274.779411) (xy 402.076177 -274.748286) (xy 402.118798 -274.723679) (xy 402.164814 -274.706227)
			(xy 402.213033 -274.696383) (xy 402.262208 -274.694402) (xy 402.311063 -274.700334) (xy 402.358334 -274.714026)
			(xy 402.402796 -274.735124) (xy 402.443299 -274.76308) (xy 402.478792 -274.797172) (xy 402.508357 -274.836516)
			(xy 402.531228 -274.880093) (xy 402.546812 -274.926774) (xy 402.554707 -274.975351) (xy 402.555202 -274.999958)
			(xy 402.89405 -274.999958) (xy 402.89801 -274.950904) (xy 402.909787 -274.90312) (xy 402.929078 -274.857844)
			(xy 402.955381 -274.816248) (xy 402.988016 -274.779411) (xy 403.026137 -274.748286) (xy 403.068758 -274.723679)
			(xy 403.114774 -274.706227) (xy 403.162993 -274.696383) (xy 403.212168 -274.694402) (xy 403.261023 -274.700334)
			(xy 403.308294 -274.714026) (xy 403.352756 -274.735124) (xy 403.393259 -274.76308) (xy 403.428752 -274.797172)
			(xy 403.458317 -274.836516) (xy 403.481188 -274.880093) (xy 403.496772 -274.926774) (xy 403.504667 -274.975351)
			(xy 403.505162 -274.999958) (xy 403.84401 -274.999958) (xy 403.84797 -274.950904) (xy 403.859747 -274.90312)
			(xy 403.879038 -274.857844) (xy 403.905341 -274.816248) (xy 403.937976 -274.779411) (xy 403.976097 -274.748286)
			(xy 404.018718 -274.723679) (xy 404.064734 -274.706227) (xy 404.112953 -274.696383) (xy 404.162128 -274.694402)
			(xy 404.210983 -274.700334) (xy 404.258254 -274.714026) (xy 404.302716 -274.735124) (xy 404.343219 -274.76308)
			(xy 404.378712 -274.797172) (xy 404.408277 -274.836516) (xy 404.431148 -274.880093) (xy 404.446732 -274.926774)
			(xy 404.454627 -274.975351) (xy 404.455122 -274.999958) (xy 404.794224 -274.999958) (xy 404.798184 -274.950904)
			(xy 404.809961 -274.90312) (xy 404.829252 -274.857844) (xy 404.855555 -274.816248) (xy 404.88819 -274.779411)
			(xy 404.926311 -274.748286) (xy 404.968932 -274.723679) (xy 405.014948 -274.706227) (xy 405.063167 -274.696383)
			(xy 405.112342 -274.694402) (xy 405.161197 -274.700334) (xy 405.208468 -274.714026) (xy 405.25293 -274.735124)
			(xy 405.293433 -274.76308) (xy 405.328926 -274.797172) (xy 405.358491 -274.836516) (xy 405.381362 -274.880093)
			(xy 405.396946 -274.926774) (xy 405.404841 -274.975351) (xy 405.405336 -274.999958) (xy 405.404841 -275.024565)
			(xy 405.396946 -275.073142) (xy 405.381362 -275.119823) (xy 405.358491 -275.1634) (xy 405.328926 -275.202744)
			(xy 405.293433 -275.236836) (xy 405.25293 -275.264792) (xy 405.208468 -275.28589) (xy 405.161197 -275.299582)
			(xy 405.112342 -275.305514) (xy 405.063167 -275.303533) (xy 405.014948 -275.293689) (xy 404.968932 -275.276237)
			(xy 404.926311 -275.25163) (xy 404.88819 -275.220505) (xy 404.855555 -275.183668) (xy 404.829252 -275.142072)
			(xy 404.809961 -275.096796) (xy 404.798184 -275.049012) (xy 404.794224 -274.999958) (xy 404.455122 -274.999958)
			(xy 404.454627 -275.024565) (xy 404.446732 -275.073142) (xy 404.431148 -275.119823) (xy 404.408277 -275.1634)
			(xy 404.378712 -275.202744) (xy 404.343219 -275.236836) (xy 404.302716 -275.264792) (xy 404.258254 -275.28589)
			(xy 404.210983 -275.299582) (xy 404.162128 -275.305514) (xy 404.112953 -275.303533) (xy 404.064734 -275.293689)
			(xy 404.018718 -275.276237) (xy 403.976097 -275.25163) (xy 403.937976 -275.220505) (xy 403.905341 -275.183668)
			(xy 403.879038 -275.142072) (xy 403.859747 -275.096796) (xy 403.84797 -275.049012) (xy 403.84401 -274.999958)
			(xy 403.505162 -274.999958) (xy 403.504667 -275.024565) (xy 403.496772 -275.073142) (xy 403.481188 -275.119823)
			(xy 403.458317 -275.1634) (xy 403.428752 -275.202744) (xy 403.393259 -275.236836) (xy 403.352756 -275.264792)
			(xy 403.308294 -275.28589) (xy 403.261023 -275.299582) (xy 403.212168 -275.305514) (xy 403.162993 -275.303533)
			(xy 403.114774 -275.293689) (xy 403.068758 -275.276237) (xy 403.026137 -275.25163) (xy 402.988016 -275.220505)
			(xy 402.955381 -275.183668) (xy 402.929078 -275.142072) (xy 402.909787 -275.096796) (xy 402.89801 -275.049012)
			(xy 402.89405 -274.999958) (xy 402.555202 -274.999958) (xy 402.554707 -275.024565) (xy 402.546812 -275.073142)
			(xy 402.531228 -275.119823) (xy 402.508357 -275.1634) (xy 402.478792 -275.202744) (xy 402.443299 -275.236836)
			(xy 402.402796 -275.264792) (xy 402.358334 -275.28589) (xy 402.311063 -275.299582) (xy 402.262208 -275.305514)
			(xy 402.213033 -275.303533) (xy 402.164814 -275.293689) (xy 402.118798 -275.276237) (xy 402.076177 -275.25163)
			(xy 402.038056 -275.220505) (xy 402.005421 -275.183668) (xy 401.979118 -275.142072) (xy 401.959827 -275.096796)
			(xy 401.94805 -275.049012) (xy 401.94409 -274.999958) (xy 401.605242 -274.999958) (xy 401.604747 -275.024565)
			(xy 401.596852 -275.073142) (xy 401.581268 -275.119823) (xy 401.558397 -275.1634) (xy 401.528832 -275.202744)
			(xy 401.493339 -275.236836) (xy 401.452836 -275.264792) (xy 401.408374 -275.28589) (xy 401.361103 -275.299582)
			(xy 401.312248 -275.305514) (xy 401.263073 -275.303533) (xy 401.214854 -275.293689) (xy 401.168838 -275.276237)
			(xy 401.126217 -275.25163) (xy 401.088096 -275.220505) (xy 401.055461 -275.183668) (xy 401.029158 -275.142072)
			(xy 401.009867 -275.096796) (xy 400.99809 -275.049012) (xy 400.99413 -274.999958) (xy 400.655282 -274.999958)
			(xy 400.654787 -275.024565) (xy 400.646892 -275.073142) (xy 400.631308 -275.119823) (xy 400.608437 -275.1634)
			(xy 400.578872 -275.202744) (xy 400.543379 -275.236836) (xy 400.502876 -275.264792) (xy 400.458414 -275.28589)
			(xy 400.411143 -275.299582) (xy 400.362288 -275.305514) (xy 400.313113 -275.303533) (xy 400.264894 -275.293689)
			(xy 400.218878 -275.276237) (xy 400.176257 -275.25163) (xy 400.138136 -275.220505) (xy 400.105501 -275.183668)
			(xy 400.079198 -275.142072) (xy 400.059907 -275.096796) (xy 400.04813 -275.049012) (xy 400.04417 -274.999958)
			(xy 399.705322 -274.999958) (xy 399.704827 -275.024565) (xy 399.696932 -275.073142) (xy 399.681348 -275.119823)
			(xy 399.658477 -275.1634) (xy 399.628912 -275.202744) (xy 399.593419 -275.236836) (xy 399.552916 -275.264792)
			(xy 399.508454 -275.28589) (xy 399.461183 -275.299582) (xy 399.412328 -275.305514) (xy 399.363153 -275.303533)
			(xy 399.314934 -275.293689) (xy 399.268918 -275.276237) (xy 399.226297 -275.25163) (xy 399.188176 -275.220505)
			(xy 399.155541 -275.183668) (xy 399.129238 -275.142072) (xy 399.109947 -275.096796) (xy 399.09817 -275.049012)
			(xy 399.09421 -274.999958) (xy 398.755108 -274.999958) (xy 398.754613 -275.024565) (xy 398.746718 -275.073142)
			(xy 398.731134 -275.119823) (xy 398.708263 -275.1634) (xy 398.678698 -275.202744) (xy 398.643205 -275.236836)
			(xy 398.602702 -275.264792) (xy 398.55824 -275.28589) (xy 398.510969 -275.299582) (xy 398.462114 -275.305514)
			(xy 398.412939 -275.303533) (xy 398.36472 -275.293689) (xy 398.318704 -275.276237) (xy 398.276083 -275.25163)
			(xy 398.237962 -275.220505) (xy 398.205327 -275.183668) (xy 398.179024 -275.142072) (xy 398.159733 -275.096796)
			(xy 398.147956 -275.049012) (xy 398.143996 -274.999958) (xy 397.805148 -274.999958) (xy 397.804653 -275.024565)
			(xy 397.796758 -275.073142) (xy 397.781174 -275.119823) (xy 397.758303 -275.1634) (xy 397.728738 -275.202744)
			(xy 397.693245 -275.236836) (xy 397.652742 -275.264792) (xy 397.60828 -275.28589) (xy 397.561009 -275.299582)
			(xy 397.512154 -275.305514) (xy 397.462979 -275.303533) (xy 397.41476 -275.293689) (xy 397.368744 -275.276237)
			(xy 397.326123 -275.25163) (xy 397.288002 -275.220505) (xy 397.255367 -275.183668) (xy 397.229064 -275.142072)
			(xy 397.209773 -275.096796) (xy 397.197996 -275.049012) (xy 397.194036 -274.999958) (xy 396.855188 -274.999958)
			(xy 396.854693 -275.024565) (xy 396.846798 -275.073142) (xy 396.831214 -275.119823) (xy 396.808343 -275.1634)
			(xy 396.778778 -275.202744) (xy 396.743285 -275.236836) (xy 396.702782 -275.264792) (xy 396.65832 -275.28589)
			(xy 396.611049 -275.299582) (xy 396.562194 -275.305514) (xy 396.513019 -275.303533) (xy 396.4648 -275.293689)
			(xy 396.418784 -275.276237) (xy 396.376163 -275.25163) (xy 396.338042 -275.220505) (xy 396.305407 -275.183668)
			(xy 396.279104 -275.142072) (xy 396.259813 -275.096796) (xy 396.248036 -275.049012) (xy 396.244076 -274.999958)
			(xy 395.905228 -274.999958) (xy 395.904733 -275.024565) (xy 395.896838 -275.073142) (xy 395.881254 -275.119823)
			(xy 395.858383 -275.1634) (xy 395.828818 -275.202744) (xy 395.793325 -275.236836) (xy 395.752822 -275.264792)
			(xy 395.70836 -275.28589) (xy 395.661089 -275.299582) (xy 395.612234 -275.305514) (xy 395.563059 -275.303533)
			(xy 395.51484 -275.293689) (xy 395.468824 -275.276237) (xy 395.426203 -275.25163) (xy 395.388082 -275.220505)
			(xy 395.355447 -275.183668) (xy 395.329144 -275.142072) (xy 395.309853 -275.096796) (xy 395.298076 -275.049012)
			(xy 395.294116 -274.999958) (xy 394.955268 -274.999958) (xy 394.954773 -275.024565) (xy 394.946878 -275.073142)
			(xy 394.931294 -275.119823) (xy 394.908423 -275.1634) (xy 394.878858 -275.202744) (xy 394.843365 -275.236836)
			(xy 394.802862 -275.264792) (xy 394.7584 -275.28589) (xy 394.711129 -275.299582) (xy 394.662274 -275.305514)
			(xy 394.613099 -275.303533) (xy 394.56488 -275.293689) (xy 394.518864 -275.276237) (xy 394.476243 -275.25163)
			(xy 394.438122 -275.220505) (xy 394.405487 -275.183668) (xy 394.379184 -275.142072) (xy 394.359893 -275.096796)
			(xy 394.348116 -275.049012) (xy 394.344156 -274.999958) (xy 394.005308 -274.999958) (xy 394.004813 -275.024565)
			(xy 393.996918 -275.073142) (xy 393.981334 -275.119823) (xy 393.958463 -275.1634) (xy 393.928898 -275.202744)
			(xy 393.893405 -275.236836) (xy 393.852902 -275.264792) (xy 393.80844 -275.28589) (xy 393.761169 -275.299582)
			(xy 393.712314 -275.305514) (xy 393.663139 -275.303533) (xy 393.61492 -275.293689) (xy 393.568904 -275.276237)
			(xy 393.526283 -275.25163) (xy 393.488162 -275.220505) (xy 393.455527 -275.183668) (xy 393.429224 -275.142072)
			(xy 393.409933 -275.096796) (xy 393.398156 -275.049012) (xy 393.394196 -274.999958) (xy 393.055094 -274.999958)
			(xy 393.054599 -275.024565) (xy 393.046704 -275.073142) (xy 393.03112 -275.119823) (xy 393.008249 -275.1634)
			(xy 392.978684 -275.202744) (xy 392.943191 -275.236836) (xy 392.902688 -275.264792) (xy 392.858226 -275.28589)
			(xy 392.810955 -275.299582) (xy 392.7621 -275.305514) (xy 392.712925 -275.303533) (xy 392.664706 -275.293689)
			(xy 392.61869 -275.276237) (xy 392.576069 -275.25163) (xy 392.537948 -275.220505) (xy 392.505313 -275.183668)
			(xy 392.47901 -275.142072) (xy 392.459719 -275.096796) (xy 392.447942 -275.049012) (xy 392.443982 -274.999958)
			(xy 380.398575 -274.999958) (xy 380.326548 -275.043268) (xy 380.154492 -275.137335) (xy 379.97872 -275.224261)
			(xy 379.799527 -275.303899) (xy 379.617218 -275.376114) (xy 379.432097 -275.440786) (xy 379.319721 -275.474938)
			(xy 384.369068 -275.474938) (xy 384.373028 -275.425884) (xy 384.384805 -275.3781) (xy 384.404096 -275.332824)
			(xy 384.430399 -275.291228) (xy 384.463034 -275.254391) (xy 384.501155 -275.223266) (xy 384.543776 -275.198659)
			(xy 384.589792 -275.181207) (xy 384.638011 -275.171363) (xy 384.687186 -275.169382) (xy 384.736041 -275.175314)
			(xy 384.783312 -275.189006) (xy 384.827774 -275.210104) (xy 384.868277 -275.23806) (xy 384.90377 -275.272152)
			(xy 384.933335 -275.311496) (xy 384.956206 -275.355073) (xy 384.97179 -275.401754) (xy 384.979685 -275.450331)
			(xy 384.98018 -275.474938) (xy 385.319028 -275.474938) (xy 385.322988 -275.425884) (xy 385.334765 -275.3781)
			(xy 385.354056 -275.332824) (xy 385.380359 -275.291228) (xy 385.412994 -275.254391) (xy 385.451115 -275.223266)
			(xy 385.493736 -275.198659) (xy 385.539752 -275.181207) (xy 385.587971 -275.171363) (xy 385.637146 -275.169382)
			(xy 385.686001 -275.175314) (xy 385.733272 -275.189006) (xy 385.777734 -275.210104) (xy 385.818237 -275.23806)
			(xy 385.85373 -275.272152) (xy 385.883295 -275.311496) (xy 385.906166 -275.355073) (xy 385.92175 -275.401754)
			(xy 385.929645 -275.450331) (xy 385.93014 -275.474938) (xy 386.269242 -275.474938) (xy 386.273202 -275.425884)
			(xy 386.284979 -275.3781) (xy 386.30427 -275.332824) (xy 386.330573 -275.291228) (xy 386.363208 -275.254391)
			(xy 386.401329 -275.223266) (xy 386.44395 -275.198659) (xy 386.489966 -275.181207) (xy 386.538185 -275.171363)
			(xy 386.58736 -275.169382) (xy 386.636215 -275.175314) (xy 386.683486 -275.189006) (xy 386.727948 -275.210104)
			(xy 386.768451 -275.23806) (xy 386.803944 -275.272152) (xy 386.833509 -275.311496) (xy 386.85638 -275.355073)
			(xy 386.871964 -275.401754) (xy 386.879859 -275.450331) (xy 386.880354 -275.474938) (xy 387.219202 -275.474938)
			(xy 387.223162 -275.425884) (xy 387.234939 -275.3781) (xy 387.25423 -275.332824) (xy 387.280533 -275.291228)
			(xy 387.313168 -275.254391) (xy 387.351289 -275.223266) (xy 387.39391 -275.198659) (xy 387.439926 -275.181207)
			(xy 387.488145 -275.171363) (xy 387.53732 -275.169382) (xy 387.586175 -275.175314) (xy 387.633446 -275.189006)
			(xy 387.677908 -275.210104) (xy 387.718411 -275.23806) (xy 387.753904 -275.272152) (xy 387.783469 -275.311496)
			(xy 387.80634 -275.355073) (xy 387.821924 -275.401754) (xy 387.829819 -275.450331) (xy 387.830314 -275.474938)
			(xy 388.169162 -275.474938) (xy 388.173122 -275.425884) (xy 388.184899 -275.3781) (xy 388.20419 -275.332824)
			(xy 388.230493 -275.291228) (xy 388.263128 -275.254391) (xy 388.301249 -275.223266) (xy 388.34387 -275.198659)
			(xy 388.389886 -275.181207) (xy 388.438105 -275.171363) (xy 388.48728 -275.169382) (xy 388.536135 -275.175314)
			(xy 388.583406 -275.189006) (xy 388.627868 -275.210104) (xy 388.668371 -275.23806) (xy 388.703864 -275.272152)
			(xy 388.733429 -275.311496) (xy 388.7563 -275.355073) (xy 388.771884 -275.401754) (xy 388.779779 -275.450331)
			(xy 388.780274 -275.474938) (xy 389.119122 -275.474938) (xy 389.123082 -275.425884) (xy 389.134859 -275.3781)
			(xy 389.15415 -275.332824) (xy 389.180453 -275.291228) (xy 389.213088 -275.254391) (xy 389.251209 -275.223266)
			(xy 389.29383 -275.198659) (xy 389.339846 -275.181207) (xy 389.388065 -275.171363) (xy 389.43724 -275.169382)
			(xy 389.486095 -275.175314) (xy 389.533366 -275.189006) (xy 389.577828 -275.210104) (xy 389.618331 -275.23806)
			(xy 389.653824 -275.272152) (xy 389.683389 -275.311496) (xy 389.70626 -275.355073) (xy 389.721844 -275.401754)
			(xy 389.729739 -275.450331) (xy 389.730234 -275.474938) (xy 390.069082 -275.474938) (xy 390.073042 -275.425884)
			(xy 390.084819 -275.3781) (xy 390.10411 -275.332824) (xy 390.130413 -275.291228) (xy 390.163048 -275.254391)
			(xy 390.201169 -275.223266) (xy 390.24379 -275.198659) (xy 390.289806 -275.181207) (xy 390.338025 -275.171363)
			(xy 390.3872 -275.169382) (xy 390.436055 -275.175314) (xy 390.483326 -275.189006) (xy 390.527788 -275.210104)
			(xy 390.568291 -275.23806) (xy 390.603784 -275.272152) (xy 390.633349 -275.311496) (xy 390.65622 -275.355073)
			(xy 390.671804 -275.401754) (xy 390.679699 -275.450331) (xy 390.680194 -275.474938) (xy 391.019042 -275.474938)
			(xy 391.023002 -275.425884) (xy 391.034779 -275.3781) (xy 391.05407 -275.332824) (xy 391.080373 -275.291228)
			(xy 391.113008 -275.254391) (xy 391.151129 -275.223266) (xy 391.19375 -275.198659) (xy 391.239766 -275.181207)
			(xy 391.287985 -275.171363) (xy 391.33716 -275.169382) (xy 391.386015 -275.175314) (xy 391.433286 -275.189006)
			(xy 391.477748 -275.210104) (xy 391.518251 -275.23806) (xy 391.553744 -275.272152) (xy 391.583309 -275.311496)
			(xy 391.60618 -275.355073) (xy 391.621764 -275.401754) (xy 391.629659 -275.450331) (xy 391.630154 -275.474938)
			(xy 391.629659 -275.499545) (xy 391.621764 -275.548122) (xy 391.60618 -275.594803) (xy 391.583309 -275.63838)
			(xy 391.553744 -275.677724) (xy 391.518251 -275.711816) (xy 391.477748 -275.739772) (xy 391.433286 -275.76087)
			(xy 391.386015 -275.774562) (xy 391.33716 -275.780494) (xy 391.287985 -275.778513) (xy 391.239766 -275.768669)
			(xy 391.19375 -275.751217) (xy 391.151129 -275.72661) (xy 391.113008 -275.695485) (xy 391.080373 -275.658648)
			(xy 391.05407 -275.617052) (xy 391.034779 -275.571776) (xy 391.023002 -275.523992) (xy 391.019042 -275.474938)
			(xy 390.680194 -275.474938) (xy 390.679699 -275.499545) (xy 390.671804 -275.548122) (xy 390.65622 -275.594803)
			(xy 390.633349 -275.63838) (xy 390.603784 -275.677724) (xy 390.568291 -275.711816) (xy 390.527788 -275.739772)
			(xy 390.483326 -275.76087) (xy 390.436055 -275.774562) (xy 390.3872 -275.780494) (xy 390.338025 -275.778513)
			(xy 390.289806 -275.768669) (xy 390.24379 -275.751217) (xy 390.201169 -275.72661) (xy 390.163048 -275.695485)
			(xy 390.130413 -275.658648) (xy 390.10411 -275.617052) (xy 390.084819 -275.571776) (xy 390.073042 -275.523992)
			(xy 390.069082 -275.474938) (xy 389.730234 -275.474938) (xy 389.729739 -275.499545) (xy 389.721844 -275.548122)
			(xy 389.70626 -275.594803) (xy 389.683389 -275.63838) (xy 389.653824 -275.677724) (xy 389.618331 -275.711816)
			(xy 389.577828 -275.739772) (xy 389.533366 -275.76087) (xy 389.486095 -275.774562) (xy 389.43724 -275.780494)
			(xy 389.388065 -275.778513) (xy 389.339846 -275.768669) (xy 389.29383 -275.751217) (xy 389.251209 -275.72661)
			(xy 389.213088 -275.695485) (xy 389.180453 -275.658648) (xy 389.15415 -275.617052) (xy 389.134859 -275.571776)
			(xy 389.123082 -275.523992) (xy 389.119122 -275.474938) (xy 388.780274 -275.474938) (xy 388.779779 -275.499545)
			(xy 388.771884 -275.548122) (xy 388.7563 -275.594803) (xy 388.733429 -275.63838) (xy 388.703864 -275.677724)
			(xy 388.668371 -275.711816) (xy 388.627868 -275.739772) (xy 388.583406 -275.76087) (xy 388.536135 -275.774562)
			(xy 388.48728 -275.780494) (xy 388.438105 -275.778513) (xy 388.389886 -275.768669) (xy 388.34387 -275.751217)
			(xy 388.301249 -275.72661) (xy 388.263128 -275.695485) (xy 388.230493 -275.658648) (xy 388.20419 -275.617052)
			(xy 388.184899 -275.571776) (xy 388.173122 -275.523992) (xy 388.169162 -275.474938) (xy 387.830314 -275.474938)
			(xy 387.829819 -275.499545) (xy 387.821924 -275.548122) (xy 387.80634 -275.594803) (xy 387.783469 -275.63838)
			(xy 387.753904 -275.677724) (xy 387.718411 -275.711816) (xy 387.677908 -275.739772) (xy 387.633446 -275.76087)
			(xy 387.586175 -275.774562) (xy 387.53732 -275.780494) (xy 387.488145 -275.778513) (xy 387.439926 -275.768669)
			(xy 387.39391 -275.751217) (xy 387.351289 -275.72661) (xy 387.313168 -275.695485) (xy 387.280533 -275.658648)
			(xy 387.25423 -275.617052) (xy 387.234939 -275.571776) (xy 387.223162 -275.523992) (xy 387.219202 -275.474938)
			(xy 386.880354 -275.474938) (xy 386.879859 -275.499545) (xy 386.871964 -275.548122) (xy 386.85638 -275.594803)
			(xy 386.833509 -275.63838) (xy 386.803944 -275.677724) (xy 386.768451 -275.711816) (xy 386.727948 -275.739772)
			(xy 386.683486 -275.76087) (xy 386.636215 -275.774562) (xy 386.58736 -275.780494) (xy 386.538185 -275.778513)
			(xy 386.489966 -275.768669) (xy 386.44395 -275.751217) (xy 386.401329 -275.72661) (xy 386.363208 -275.695485)
			(xy 386.330573 -275.658648) (xy 386.30427 -275.617052) (xy 386.284979 -275.571776) (xy 386.273202 -275.523992)
			(xy 386.269242 -275.474938) (xy 385.93014 -275.474938) (xy 385.929645 -275.499545) (xy 385.92175 -275.548122)
			(xy 385.906166 -275.594803) (xy 385.883295 -275.63838) (xy 385.85373 -275.677724) (xy 385.818237 -275.711816)
			(xy 385.777734 -275.739772) (xy 385.733272 -275.76087) (xy 385.686001 -275.774562) (xy 385.637146 -275.780494)
			(xy 385.587971 -275.778513) (xy 385.539752 -275.768669) (xy 385.493736 -275.751217) (xy 385.451115 -275.72661)
			(xy 385.412994 -275.695485) (xy 385.380359 -275.658648) (xy 385.354056 -275.617052) (xy 385.334765 -275.571776)
			(xy 385.322988 -275.523992) (xy 385.319028 -275.474938) (xy 384.98018 -275.474938) (xy 384.979685 -275.499545)
			(xy 384.97179 -275.548122) (xy 384.956206 -275.594803) (xy 384.933335 -275.63838) (xy 384.90377 -275.677724)
			(xy 384.868277 -275.711816) (xy 384.827774 -275.739772) (xy 384.783312 -275.76087) (xy 384.736041 -275.774562)
			(xy 384.687186 -275.780494) (xy 384.638011 -275.778513) (xy 384.589792 -275.768669) (xy 384.543776 -275.751217)
			(xy 384.501155 -275.72661) (xy 384.463034 -275.695485) (xy 384.430399 -275.658648) (xy 384.404096 -275.617052)
			(xy 384.384805 -275.571776) (xy 384.373028 -275.523992) (xy 384.369068 -275.474938) (xy 379.319721 -275.474938)
			(xy 379.244478 -275.497805) (xy 379.054677 -275.547075) (xy 378.863014 -275.588513) (xy 378.669811 -275.62205)
			(xy 378.475395 -275.647628) (xy 378.280092 -275.665204) (xy 378.084233 -275.67475) (xy 377.888147 -275.676248)
			(xy 377.692165 -275.669697) (xy 377.496617 -275.655107) (xy 377.301832 -275.632503) (xy 377.108139 -275.601923)
			(xy 376.915865 -275.563419) (xy 376.725333 -275.517055) (xy 376.536865 -275.46291) (xy 376.350778 -275.401075)
			(xy 376.167386 -275.331653) (xy 375.986998 -275.254763) (xy 375.809917 -275.170534) (xy 375.636444 -275.079108)
			(xy 375.466869 -274.980638) (xy 375.301478 -274.875291) (xy 375.140551 -274.763244) (xy 374.984359 -274.644686)
			(xy 374.833164 -274.519817) (xy 374.687223 -274.388848) (xy 374.54678 -274.251999) (xy 374.412072 -274.1095)
			(xy 374.283326 -273.961593) (xy 374.16076 -273.808526) (xy 374.04458 -273.650557) (xy 373.934982 -273.487953)
			(xy 373.83215 -273.320987) (xy 373.736258 -273.149941) (xy 373.647468 -272.975103) (xy 373.565929 -272.796768)
			(xy 373.491778 -272.615237) (xy 373.42514 -272.430815) (xy 373.366129 -272.243813) (xy 373.314842 -272.054547)
			(xy 373.271368 -271.863335) (xy 373.235778 -271.6705) (xy 373.221504 -271.573498) (xy 373.221504 -271.573244)
			(xy 373.220742 -271.568418) (xy 373.218588 -271.560755) (xy 373.210318 -271.547164) (xy 373.204486 -271.541748)
			(xy 373.197628 -271.535906) (xy 373.189246 -271.532858) (xy 373.184959 -271.531335) (xy 373.176014 -271.529682)
			(xy 373.171466 -271.529556) (xy 370.811552 -271.529556) (xy 370.805542 -271.529723) (xy 370.793859 -271.532544)
			(xy 370.788438 -271.535144) (xy 370.784963 -271.536982) (xy 370.778581 -271.541573) (xy 370.775738 -271.544288)
			(xy 369.629436 -272.69059) (xy 369.621565 -272.699383) (xy 369.614161 -272.721761) (xy 369.615212 -272.733516)
			(xy 369.632992 -272.81886) (xy 369.6335 -272.820638) (xy 369.635532 -272.827496) (xy 369.637098 -272.831613)
			(xy 369.641438 -272.839278) (xy 369.644168 -272.842736) (xy 369.648232 -272.847562) (xy 369.658138 -272.854674)
			(xy 369.664996 -272.857214) (xy 369.740679 -272.886903) (xy 369.889406 -272.952607) (xy 370.0348 -273.025389)
			(xy 370.176525 -273.105079) (xy 370.314254 -273.191494) (xy 370.447666 -273.284433) (xy 370.576454 -273.383682)
			(xy 370.700319 -273.489011) (xy 370.818974 -273.600175) (xy 370.932146 -273.716918) (xy 371.039571 -273.838969)
			(xy 371.141002 -273.966045) (xy 371.236203 -274.097853) (xy 371.324954 -274.234088) (xy 371.407049 -274.374434)
			(xy 371.482299 -274.518566) (xy 371.55053 -274.66615) (xy 371.611583 -274.816846) (xy 371.665317 -274.970304)
			(xy 371.711608 -275.126168) (xy 371.750348 -275.284079) (xy 371.781449 -275.44367) (xy 371.804837 -275.604573)
			(xy 371.820459 -275.766414) (xy 371.828279 -275.928819) (xy 371.82842 -275.949918) (xy 392.443982 -275.949918)
			(xy 392.447942 -275.900864) (xy 392.459719 -275.85308) (xy 392.47901 -275.807804) (xy 392.505313 -275.766208)
			(xy 392.537948 -275.729371) (xy 392.576069 -275.698246) (xy 392.61869 -275.673639) (xy 392.664706 -275.656187)
			(xy 392.712925 -275.646343) (xy 392.7621 -275.644362) (xy 392.810955 -275.650294) (xy 392.858226 -275.663986)
			(xy 392.902688 -275.685084) (xy 392.943191 -275.71304) (xy 392.978684 -275.747132) (xy 393.008249 -275.786476)
			(xy 393.03112 -275.830053) (xy 393.046704 -275.876734) (xy 393.054599 -275.925311) (xy 393.055094 -275.949918)
			(xy 393.394196 -275.949918) (xy 393.398156 -275.900864) (xy 393.409933 -275.85308) (xy 393.429224 -275.807804)
			(xy 393.455527 -275.766208) (xy 393.488162 -275.729371) (xy 393.526283 -275.698246) (xy 393.568904 -275.673639)
			(xy 393.61492 -275.656187) (xy 393.663139 -275.646343) (xy 393.712314 -275.644362) (xy 393.761169 -275.650294)
			(xy 393.80844 -275.663986) (xy 393.852902 -275.685084) (xy 393.893405 -275.71304) (xy 393.928898 -275.747132)
			(xy 393.958463 -275.786476) (xy 393.981334 -275.830053) (xy 393.996918 -275.876734) (xy 394.004813 -275.925311)
			(xy 394.005308 -275.949918) (xy 394.344156 -275.949918) (xy 394.348116 -275.900864) (xy 394.359893 -275.85308)
			(xy 394.379184 -275.807804) (xy 394.405487 -275.766208) (xy 394.438122 -275.729371) (xy 394.476243 -275.698246)
			(xy 394.518864 -275.673639) (xy 394.56488 -275.656187) (xy 394.613099 -275.646343) (xy 394.662274 -275.644362)
			(xy 394.711129 -275.650294) (xy 394.7584 -275.663986) (xy 394.802862 -275.685084) (xy 394.843365 -275.71304)
			(xy 394.878858 -275.747132) (xy 394.908423 -275.786476) (xy 394.931294 -275.830053) (xy 394.946878 -275.876734)
			(xy 394.954773 -275.925311) (xy 394.955268 -275.949918) (xy 395.294116 -275.949918) (xy 395.298076 -275.900864)
			(xy 395.309853 -275.85308) (xy 395.329144 -275.807804) (xy 395.355447 -275.766208) (xy 395.388082 -275.729371)
			(xy 395.426203 -275.698246) (xy 395.468824 -275.673639) (xy 395.51484 -275.656187) (xy 395.563059 -275.646343)
			(xy 395.612234 -275.644362) (xy 395.661089 -275.650294) (xy 395.70836 -275.663986) (xy 395.752822 -275.685084)
			(xy 395.793325 -275.71304) (xy 395.828818 -275.747132) (xy 395.858383 -275.786476) (xy 395.881254 -275.830053)
			(xy 395.896838 -275.876734) (xy 395.904733 -275.925311) (xy 395.905228 -275.949918) (xy 396.244076 -275.949918)
			(xy 396.248036 -275.900864) (xy 396.259813 -275.85308) (xy 396.279104 -275.807804) (xy 396.305407 -275.766208)
			(xy 396.338042 -275.729371) (xy 396.376163 -275.698246) (xy 396.418784 -275.673639) (xy 396.4648 -275.656187)
			(xy 396.513019 -275.646343) (xy 396.562194 -275.644362) (xy 396.611049 -275.650294) (xy 396.65832 -275.663986)
			(xy 396.702782 -275.685084) (xy 396.743285 -275.71304) (xy 396.778778 -275.747132) (xy 396.808343 -275.786476)
			(xy 396.831214 -275.830053) (xy 396.846798 -275.876734) (xy 396.854693 -275.925311) (xy 396.855188 -275.949918)
			(xy 397.194036 -275.949918) (xy 397.197996 -275.900864) (xy 397.209773 -275.85308) (xy 397.229064 -275.807804)
			(xy 397.255367 -275.766208) (xy 397.288002 -275.729371) (xy 397.326123 -275.698246) (xy 397.368744 -275.673639)
			(xy 397.41476 -275.656187) (xy 397.462979 -275.646343) (xy 397.512154 -275.644362) (xy 397.561009 -275.650294)
			(xy 397.60828 -275.663986) (xy 397.652742 -275.685084) (xy 397.693245 -275.71304) (xy 397.728738 -275.747132)
			(xy 397.758303 -275.786476) (xy 397.781174 -275.830053) (xy 397.796758 -275.876734) (xy 397.804653 -275.925311)
			(xy 397.805148 -275.949918) (xy 398.143996 -275.949918) (xy 398.147956 -275.900864) (xy 398.159733 -275.85308)
			(xy 398.179024 -275.807804) (xy 398.205327 -275.766208) (xy 398.237962 -275.729371) (xy 398.276083 -275.698246)
			(xy 398.318704 -275.673639) (xy 398.36472 -275.656187) (xy 398.412939 -275.646343) (xy 398.462114 -275.644362)
			(xy 398.510969 -275.650294) (xy 398.55824 -275.663986) (xy 398.602702 -275.685084) (xy 398.643205 -275.71304)
			(xy 398.678698 -275.747132) (xy 398.708263 -275.786476) (xy 398.731134 -275.830053) (xy 398.746718 -275.876734)
			(xy 398.754613 -275.925311) (xy 398.755108 -275.949918) (xy 399.09421 -275.949918) (xy 399.09817 -275.900864)
			(xy 399.109947 -275.85308) (xy 399.129238 -275.807804) (xy 399.155541 -275.766208) (xy 399.188176 -275.729371)
			(xy 399.226297 -275.698246) (xy 399.268918 -275.673639) (xy 399.314934 -275.656187) (xy 399.363153 -275.646343)
			(xy 399.412328 -275.644362) (xy 399.461183 -275.650294) (xy 399.508454 -275.663986) (xy 399.552916 -275.685084)
			(xy 399.593419 -275.71304) (xy 399.628912 -275.747132) (xy 399.658477 -275.786476) (xy 399.681348 -275.830053)
			(xy 399.696932 -275.876734) (xy 399.704827 -275.925311) (xy 399.705322 -275.949918) (xy 400.04417 -275.949918)
			(xy 400.04813 -275.900864) (xy 400.059907 -275.85308) (xy 400.079198 -275.807804) (xy 400.105501 -275.766208)
			(xy 400.138136 -275.729371) (xy 400.176257 -275.698246) (xy 400.218878 -275.673639) (xy 400.264894 -275.656187)
			(xy 400.313113 -275.646343) (xy 400.362288 -275.644362) (xy 400.411143 -275.650294) (xy 400.458414 -275.663986)
			(xy 400.502876 -275.685084) (xy 400.543379 -275.71304) (xy 400.578872 -275.747132) (xy 400.608437 -275.786476)
			(xy 400.631308 -275.830053) (xy 400.646892 -275.876734) (xy 400.654787 -275.925311) (xy 400.655282 -275.949918)
			(xy 400.99413 -275.949918) (xy 400.99809 -275.900864) (xy 401.009867 -275.85308) (xy 401.029158 -275.807804)
			(xy 401.055461 -275.766208) (xy 401.088096 -275.729371) (xy 401.126217 -275.698246) (xy 401.168838 -275.673639)
			(xy 401.214854 -275.656187) (xy 401.263073 -275.646343) (xy 401.312248 -275.644362) (xy 401.361103 -275.650294)
			(xy 401.408374 -275.663986) (xy 401.452836 -275.685084) (xy 401.493339 -275.71304) (xy 401.528832 -275.747132)
			(xy 401.558397 -275.786476) (xy 401.581268 -275.830053) (xy 401.596852 -275.876734) (xy 401.604747 -275.925311)
			(xy 401.605242 -275.949918) (xy 401.94409 -275.949918) (xy 401.94805 -275.900864) (xy 401.959827 -275.85308)
			(xy 401.979118 -275.807804) (xy 402.005421 -275.766208) (xy 402.038056 -275.729371) (xy 402.076177 -275.698246)
			(xy 402.118798 -275.673639) (xy 402.164814 -275.656187) (xy 402.213033 -275.646343) (xy 402.262208 -275.644362)
			(xy 402.311063 -275.650294) (xy 402.358334 -275.663986) (xy 402.402796 -275.685084) (xy 402.443299 -275.71304)
			(xy 402.478792 -275.747132) (xy 402.508357 -275.786476) (xy 402.531228 -275.830053) (xy 402.546812 -275.876734)
			(xy 402.554707 -275.925311) (xy 402.555202 -275.949918) (xy 402.89405 -275.949918) (xy 402.89801 -275.900864)
			(xy 402.909787 -275.85308) (xy 402.929078 -275.807804) (xy 402.955381 -275.766208) (xy 402.988016 -275.729371)
			(xy 403.026137 -275.698246) (xy 403.068758 -275.673639) (xy 403.114774 -275.656187) (xy 403.162993 -275.646343)
			(xy 403.212168 -275.644362) (xy 403.261023 -275.650294) (xy 403.308294 -275.663986) (xy 403.352756 -275.685084)
			(xy 403.393259 -275.71304) (xy 403.428752 -275.747132) (xy 403.458317 -275.786476) (xy 403.481188 -275.830053)
			(xy 403.496772 -275.876734) (xy 403.504667 -275.925311) (xy 403.505162 -275.949918) (xy 403.84401 -275.949918)
			(xy 403.84797 -275.900864) (xy 403.859747 -275.85308) (xy 403.879038 -275.807804) (xy 403.905341 -275.766208)
			(xy 403.937976 -275.729371) (xy 403.976097 -275.698246) (xy 404.018718 -275.673639) (xy 404.064734 -275.656187)
			(xy 404.112953 -275.646343) (xy 404.162128 -275.644362) (xy 404.210983 -275.650294) (xy 404.258254 -275.663986)
			(xy 404.302716 -275.685084) (xy 404.343219 -275.71304) (xy 404.378712 -275.747132) (xy 404.408277 -275.786476)
			(xy 404.431148 -275.830053) (xy 404.446732 -275.876734) (xy 404.454627 -275.925311) (xy 404.455122 -275.949918)
			(xy 404.794224 -275.949918) (xy 404.798184 -275.900864) (xy 404.809961 -275.85308) (xy 404.829252 -275.807804)
			(xy 404.855555 -275.766208) (xy 404.88819 -275.729371) (xy 404.926311 -275.698246) (xy 404.968932 -275.673639)
			(xy 405.014948 -275.656187) (xy 405.063167 -275.646343) (xy 405.112342 -275.644362) (xy 405.161197 -275.650294)
			(xy 405.208468 -275.663986) (xy 405.25293 -275.685084) (xy 405.293433 -275.71304) (xy 405.328926 -275.747132)
			(xy 405.358491 -275.786476) (xy 405.381362 -275.830053) (xy 405.396946 -275.876734) (xy 405.404841 -275.925311)
			(xy 405.405336 -275.949918) (xy 405.404841 -275.974525) (xy 405.396946 -276.023102) (xy 405.381362 -276.069783)
			(xy 405.358491 -276.11336) (xy 405.328926 -276.152704) (xy 405.293433 -276.186796) (xy 405.25293 -276.214752)
			(xy 405.208468 -276.23585) (xy 405.161197 -276.249542) (xy 405.112342 -276.255474) (xy 405.063167 -276.253493)
			(xy 405.014948 -276.243649) (xy 404.968932 -276.226197) (xy 404.926311 -276.20159) (xy 404.88819 -276.170465)
			(xy 404.855555 -276.133628) (xy 404.829252 -276.092032) (xy 404.809961 -276.046756) (xy 404.798184 -275.998972)
			(xy 404.794224 -275.949918) (xy 404.455122 -275.949918) (xy 404.454627 -275.974525) (xy 404.446732 -276.023102)
			(xy 404.431148 -276.069783) (xy 404.408277 -276.11336) (xy 404.378712 -276.152704) (xy 404.343219 -276.186796)
			(xy 404.302716 -276.214752) (xy 404.258254 -276.23585) (xy 404.210983 -276.249542) (xy 404.162128 -276.255474)
			(xy 404.112953 -276.253493) (xy 404.064734 -276.243649) (xy 404.018718 -276.226197) (xy 403.976097 -276.20159)
			(xy 403.937976 -276.170465) (xy 403.905341 -276.133628) (xy 403.879038 -276.092032) (xy 403.859747 -276.046756)
			(xy 403.84797 -275.998972) (xy 403.84401 -275.949918) (xy 403.505162 -275.949918) (xy 403.504667 -275.974525)
			(xy 403.496772 -276.023102) (xy 403.481188 -276.069783) (xy 403.458317 -276.11336) (xy 403.428752 -276.152704)
			(xy 403.393259 -276.186796) (xy 403.352756 -276.214752) (xy 403.308294 -276.23585) (xy 403.261023 -276.249542)
			(xy 403.212168 -276.255474) (xy 403.162993 -276.253493) (xy 403.114774 -276.243649) (xy 403.068758 -276.226197)
			(xy 403.026137 -276.20159) (xy 402.988016 -276.170465) (xy 402.955381 -276.133628) (xy 402.929078 -276.092032)
			(xy 402.909787 -276.046756) (xy 402.89801 -275.998972) (xy 402.89405 -275.949918) (xy 402.555202 -275.949918)
			(xy 402.554707 -275.974525) (xy 402.546812 -276.023102) (xy 402.531228 -276.069783) (xy 402.508357 -276.11336)
			(xy 402.478792 -276.152704) (xy 402.443299 -276.186796) (xy 402.402796 -276.214752) (xy 402.358334 -276.23585)
			(xy 402.311063 -276.249542) (xy 402.262208 -276.255474) (xy 402.213033 -276.253493) (xy 402.164814 -276.243649)
			(xy 402.118798 -276.226197) (xy 402.076177 -276.20159) (xy 402.038056 -276.170465) (xy 402.005421 -276.133628)
			(xy 401.979118 -276.092032) (xy 401.959827 -276.046756) (xy 401.94805 -275.998972) (xy 401.94409 -275.949918)
			(xy 401.605242 -275.949918) (xy 401.604747 -275.974525) (xy 401.596852 -276.023102) (xy 401.581268 -276.069783)
			(xy 401.558397 -276.11336) (xy 401.528832 -276.152704) (xy 401.493339 -276.186796) (xy 401.452836 -276.214752)
			(xy 401.408374 -276.23585) (xy 401.361103 -276.249542) (xy 401.312248 -276.255474) (xy 401.263073 -276.253493)
			(xy 401.214854 -276.243649) (xy 401.168838 -276.226197) (xy 401.126217 -276.20159) (xy 401.088096 -276.170465)
			(xy 401.055461 -276.133628) (xy 401.029158 -276.092032) (xy 401.009867 -276.046756) (xy 400.99809 -275.998972)
			(xy 400.99413 -275.949918) (xy 400.655282 -275.949918) (xy 400.654787 -275.974525) (xy 400.646892 -276.023102)
			(xy 400.631308 -276.069783) (xy 400.608437 -276.11336) (xy 400.578872 -276.152704) (xy 400.543379 -276.186796)
			(xy 400.502876 -276.214752) (xy 400.458414 -276.23585) (xy 400.411143 -276.249542) (xy 400.362288 -276.255474)
			(xy 400.313113 -276.253493) (xy 400.264894 -276.243649) (xy 400.218878 -276.226197) (xy 400.176257 -276.20159)
			(xy 400.138136 -276.170465) (xy 400.105501 -276.133628) (xy 400.079198 -276.092032) (xy 400.059907 -276.046756)
			(xy 400.04813 -275.998972) (xy 400.04417 -275.949918) (xy 399.705322 -275.949918) (xy 399.704827 -275.974525)
			(xy 399.696932 -276.023102) (xy 399.681348 -276.069783) (xy 399.658477 -276.11336) (xy 399.628912 -276.152704)
			(xy 399.593419 -276.186796) (xy 399.552916 -276.214752) (xy 399.508454 -276.23585) (xy 399.461183 -276.249542)
			(xy 399.412328 -276.255474) (xy 399.363153 -276.253493) (xy 399.314934 -276.243649) (xy 399.268918 -276.226197)
			(xy 399.226297 -276.20159) (xy 399.188176 -276.170465) (xy 399.155541 -276.133628) (xy 399.129238 -276.092032)
			(xy 399.109947 -276.046756) (xy 399.09817 -275.998972) (xy 399.09421 -275.949918) (xy 398.755108 -275.949918)
			(xy 398.754613 -275.974525) (xy 398.746718 -276.023102) (xy 398.731134 -276.069783) (xy 398.708263 -276.11336)
			(xy 398.678698 -276.152704) (xy 398.643205 -276.186796) (xy 398.602702 -276.214752) (xy 398.55824 -276.23585)
			(xy 398.510969 -276.249542) (xy 398.462114 -276.255474) (xy 398.412939 -276.253493) (xy 398.36472 -276.243649)
			(xy 398.318704 -276.226197) (xy 398.276083 -276.20159) (xy 398.237962 -276.170465) (xy 398.205327 -276.133628)
			(xy 398.179024 -276.092032) (xy 398.159733 -276.046756) (xy 398.147956 -275.998972) (xy 398.143996 -275.949918)
			(xy 397.805148 -275.949918) (xy 397.804653 -275.974525) (xy 397.796758 -276.023102) (xy 397.781174 -276.069783)
			(xy 397.758303 -276.11336) (xy 397.728738 -276.152704) (xy 397.693245 -276.186796) (xy 397.652742 -276.214752)
			(xy 397.60828 -276.23585) (xy 397.561009 -276.249542) (xy 397.512154 -276.255474) (xy 397.462979 -276.253493)
			(xy 397.41476 -276.243649) (xy 397.368744 -276.226197) (xy 397.326123 -276.20159) (xy 397.288002 -276.170465)
			(xy 397.255367 -276.133628) (xy 397.229064 -276.092032) (xy 397.209773 -276.046756) (xy 397.197996 -275.998972)
			(xy 397.194036 -275.949918) (xy 396.855188 -275.949918) (xy 396.854693 -275.974525) (xy 396.846798 -276.023102)
			(xy 396.831214 -276.069783) (xy 396.808343 -276.11336) (xy 396.778778 -276.152704) (xy 396.743285 -276.186796)
			(xy 396.702782 -276.214752) (xy 396.65832 -276.23585) (xy 396.611049 -276.249542) (xy 396.562194 -276.255474)
			(xy 396.513019 -276.253493) (xy 396.4648 -276.243649) (xy 396.418784 -276.226197) (xy 396.376163 -276.20159)
			(xy 396.338042 -276.170465) (xy 396.305407 -276.133628) (xy 396.279104 -276.092032) (xy 396.259813 -276.046756)
			(xy 396.248036 -275.998972) (xy 396.244076 -275.949918) (xy 395.905228 -275.949918) (xy 395.904733 -275.974525)
			(xy 395.896838 -276.023102) (xy 395.881254 -276.069783) (xy 395.858383 -276.11336) (xy 395.828818 -276.152704)
			(xy 395.793325 -276.186796) (xy 395.752822 -276.214752) (xy 395.70836 -276.23585) (xy 395.661089 -276.249542)
			(xy 395.612234 -276.255474) (xy 395.563059 -276.253493) (xy 395.51484 -276.243649) (xy 395.468824 -276.226197)
			(xy 395.426203 -276.20159) (xy 395.388082 -276.170465) (xy 395.355447 -276.133628) (xy 395.329144 -276.092032)
			(xy 395.309853 -276.046756) (xy 395.298076 -275.998972) (xy 395.294116 -275.949918) (xy 394.955268 -275.949918)
			(xy 394.954773 -275.974525) (xy 394.946878 -276.023102) (xy 394.931294 -276.069783) (xy 394.908423 -276.11336)
			(xy 394.878858 -276.152704) (xy 394.843365 -276.186796) (xy 394.802862 -276.214752) (xy 394.7584 -276.23585)
			(xy 394.711129 -276.249542) (xy 394.662274 -276.255474) (xy 394.613099 -276.253493) (xy 394.56488 -276.243649)
			(xy 394.518864 -276.226197) (xy 394.476243 -276.20159) (xy 394.438122 -276.170465) (xy 394.405487 -276.133628)
			(xy 394.379184 -276.092032) (xy 394.359893 -276.046756) (xy 394.348116 -275.998972) (xy 394.344156 -275.949918)
			(xy 394.005308 -275.949918) (xy 394.004813 -275.974525) (xy 393.996918 -276.023102) (xy 393.981334 -276.069783)
			(xy 393.958463 -276.11336) (xy 393.928898 -276.152704) (xy 393.893405 -276.186796) (xy 393.852902 -276.214752)
			(xy 393.80844 -276.23585) (xy 393.761169 -276.249542) (xy 393.712314 -276.255474) (xy 393.663139 -276.253493)
			(xy 393.61492 -276.243649) (xy 393.568904 -276.226197) (xy 393.526283 -276.20159) (xy 393.488162 -276.170465)
			(xy 393.455527 -276.133628) (xy 393.429224 -276.092032) (xy 393.409933 -276.046756) (xy 393.398156 -275.998972)
			(xy 393.394196 -275.949918) (xy 393.055094 -275.949918) (xy 393.054599 -275.974525) (xy 393.046704 -276.023102)
			(xy 393.03112 -276.069783) (xy 393.008249 -276.11336) (xy 392.978684 -276.152704) (xy 392.943191 -276.186796)
			(xy 392.902688 -276.214752) (xy 392.858226 -276.23585) (xy 392.810955 -276.249542) (xy 392.7621 -276.255474)
			(xy 392.712925 -276.253493) (xy 392.664706 -276.243649) (xy 392.61869 -276.226197) (xy 392.576069 -276.20159)
			(xy 392.537948 -276.170465) (xy 392.505313 -276.133628) (xy 392.47901 -276.092032) (xy 392.459719 -276.046756)
			(xy 392.447942 -275.998972) (xy 392.443982 -275.949918) (xy 371.82842 -275.949918) (xy 371.828822 -276.010116)
			(xy 371.828313 -276.093046) (xy 371.820174 -276.258706) (xy 371.803916 -276.423768) (xy 371.803748 -276.424898)
			(xy 384.369068 -276.424898) (xy 384.373028 -276.375844) (xy 384.384805 -276.32806) (xy 384.404096 -276.282784)
			(xy 384.430399 -276.241188) (xy 384.463034 -276.204351) (xy 384.501155 -276.173226) (xy 384.543776 -276.148619)
			(xy 384.589792 -276.131167) (xy 384.638011 -276.121323) (xy 384.687186 -276.119342) (xy 384.736041 -276.125274)
			(xy 384.783312 -276.138966) (xy 384.827774 -276.160064) (xy 384.868277 -276.18802) (xy 384.90377 -276.222112)
			(xy 384.933335 -276.261456) (xy 384.956206 -276.305033) (xy 384.97179 -276.351714) (xy 384.979685 -276.400291)
			(xy 384.98018 -276.424898) (xy 385.319028 -276.424898) (xy 385.322988 -276.375844) (xy 385.334765 -276.32806)
			(xy 385.354056 -276.282784) (xy 385.380359 -276.241188) (xy 385.412994 -276.204351) (xy 385.451115 -276.173226)
			(xy 385.493736 -276.148619) (xy 385.539752 -276.131167) (xy 385.587971 -276.121323) (xy 385.637146 -276.119342)
			(xy 385.686001 -276.125274) (xy 385.733272 -276.138966) (xy 385.777734 -276.160064) (xy 385.818237 -276.18802)
			(xy 385.85373 -276.222112) (xy 385.883295 -276.261456) (xy 385.906166 -276.305033) (xy 385.92175 -276.351714)
			(xy 385.929645 -276.400291) (xy 385.93014 -276.424898) (xy 386.269242 -276.424898) (xy 386.273202 -276.375844)
			(xy 386.284979 -276.32806) (xy 386.30427 -276.282784) (xy 386.330573 -276.241188) (xy 386.363208 -276.204351)
			(xy 386.401329 -276.173226) (xy 386.44395 -276.148619) (xy 386.489966 -276.131167) (xy 386.538185 -276.121323)
			(xy 386.58736 -276.119342) (xy 386.636215 -276.125274) (xy 386.683486 -276.138966) (xy 386.727948 -276.160064)
			(xy 386.768451 -276.18802) (xy 386.803944 -276.222112) (xy 386.833509 -276.261456) (xy 386.85638 -276.305033)
			(xy 386.871964 -276.351714) (xy 386.879859 -276.400291) (xy 386.880354 -276.424898) (xy 387.219202 -276.424898)
			(xy 387.223162 -276.375844) (xy 387.234939 -276.32806) (xy 387.25423 -276.282784) (xy 387.280533 -276.241188)
			(xy 387.313168 -276.204351) (xy 387.351289 -276.173226) (xy 387.39391 -276.148619) (xy 387.439926 -276.131167)
			(xy 387.488145 -276.121323) (xy 387.53732 -276.119342) (xy 387.586175 -276.125274) (xy 387.633446 -276.138966)
			(xy 387.677908 -276.160064) (xy 387.718411 -276.18802) (xy 387.753904 -276.222112) (xy 387.783469 -276.261456)
			(xy 387.80634 -276.305033) (xy 387.821924 -276.351714) (xy 387.829819 -276.400291) (xy 387.830314 -276.424898)
			(xy 388.169162 -276.424898) (xy 388.173122 -276.375844) (xy 388.184899 -276.32806) (xy 388.20419 -276.282784)
			(xy 388.230493 -276.241188) (xy 388.263128 -276.204351) (xy 388.301249 -276.173226) (xy 388.34387 -276.148619)
			(xy 388.389886 -276.131167) (xy 388.438105 -276.121323) (xy 388.48728 -276.119342) (xy 388.536135 -276.125274)
			(xy 388.583406 -276.138966) (xy 388.627868 -276.160064) (xy 388.668371 -276.18802) (xy 388.703864 -276.222112)
			(xy 388.733429 -276.261456) (xy 388.7563 -276.305033) (xy 388.771884 -276.351714) (xy 388.779779 -276.400291)
			(xy 388.780274 -276.424898) (xy 389.119122 -276.424898) (xy 389.123082 -276.375844) (xy 389.134859 -276.32806)
			(xy 389.15415 -276.282784) (xy 389.180453 -276.241188) (xy 389.213088 -276.204351) (xy 389.251209 -276.173226)
			(xy 389.29383 -276.148619) (xy 389.339846 -276.131167) (xy 389.388065 -276.121323) (xy 389.43724 -276.119342)
			(xy 389.486095 -276.125274) (xy 389.533366 -276.138966) (xy 389.577828 -276.160064) (xy 389.618331 -276.18802)
			(xy 389.653824 -276.222112) (xy 389.683389 -276.261456) (xy 389.70626 -276.305033) (xy 389.721844 -276.351714)
			(xy 389.729739 -276.400291) (xy 389.730234 -276.424898) (xy 390.069082 -276.424898) (xy 390.073042 -276.375844)
			(xy 390.084819 -276.32806) (xy 390.10411 -276.282784) (xy 390.130413 -276.241188) (xy 390.163048 -276.204351)
			(xy 390.201169 -276.173226) (xy 390.24379 -276.148619) (xy 390.289806 -276.131167) (xy 390.338025 -276.121323)
			(xy 390.3872 -276.119342) (xy 390.436055 -276.125274) (xy 390.483326 -276.138966) (xy 390.527788 -276.160064)
			(xy 390.568291 -276.18802) (xy 390.603784 -276.222112) (xy 390.633349 -276.261456) (xy 390.65622 -276.305033)
			(xy 390.671804 -276.351714) (xy 390.679699 -276.400291) (xy 390.680194 -276.424898) (xy 391.019042 -276.424898)
			(xy 391.023002 -276.375844) (xy 391.034779 -276.32806) (xy 391.05407 -276.282784) (xy 391.080373 -276.241188)
			(xy 391.113008 -276.204351) (xy 391.151129 -276.173226) (xy 391.19375 -276.148619) (xy 391.239766 -276.131167)
			(xy 391.287985 -276.121323) (xy 391.33716 -276.119342) (xy 391.386015 -276.125274) (xy 391.433286 -276.138966)
			(xy 391.477748 -276.160064) (xy 391.518251 -276.18802) (xy 391.553744 -276.222112) (xy 391.583309 -276.261456)
			(xy 391.60618 -276.305033) (xy 391.621764 -276.351714) (xy 391.629659 -276.400291) (xy 391.630154 -276.424898)
			(xy 391.629659 -276.449505) (xy 391.621764 -276.498082) (xy 391.60618 -276.544763) (xy 391.583309 -276.58834)
			(xy 391.553744 -276.627684) (xy 391.518251 -276.661776) (xy 391.477748 -276.689732) (xy 391.433286 -276.71083)
			(xy 391.386015 -276.724522) (xy 391.33716 -276.730454) (xy 391.287985 -276.728473) (xy 391.239766 -276.718629)
			(xy 391.19375 -276.701177) (xy 391.151129 -276.67657) (xy 391.113008 -276.645445) (xy 391.080373 -276.608608)
			(xy 391.05407 -276.567012) (xy 391.034779 -276.521736) (xy 391.023002 -276.473952) (xy 391.019042 -276.424898)
			(xy 390.680194 -276.424898) (xy 390.679699 -276.449505) (xy 390.671804 -276.498082) (xy 390.65622 -276.544763)
			(xy 390.633349 -276.58834) (xy 390.603784 -276.627684) (xy 390.568291 -276.661776) (xy 390.527788 -276.689732)
			(xy 390.483326 -276.71083) (xy 390.436055 -276.724522) (xy 390.3872 -276.730454) (xy 390.338025 -276.728473)
			(xy 390.289806 -276.718629) (xy 390.24379 -276.701177) (xy 390.201169 -276.67657) (xy 390.163048 -276.645445)
			(xy 390.130413 -276.608608) (xy 390.10411 -276.567012) (xy 390.084819 -276.521736) (xy 390.073042 -276.473952)
			(xy 390.069082 -276.424898) (xy 389.730234 -276.424898) (xy 389.729739 -276.449505) (xy 389.721844 -276.498082)
			(xy 389.70626 -276.544763) (xy 389.683389 -276.58834) (xy 389.653824 -276.627684) (xy 389.618331 -276.661776)
			(xy 389.577828 -276.689732) (xy 389.533366 -276.71083) (xy 389.486095 -276.724522) (xy 389.43724 -276.730454)
			(xy 389.388065 -276.728473) (xy 389.339846 -276.718629) (xy 389.29383 -276.701177) (xy 389.251209 -276.67657)
			(xy 389.213088 -276.645445) (xy 389.180453 -276.608608) (xy 389.15415 -276.567012) (xy 389.134859 -276.521736)
			(xy 389.123082 -276.473952) (xy 389.119122 -276.424898) (xy 388.780274 -276.424898) (xy 388.779779 -276.449505)
			(xy 388.771884 -276.498082) (xy 388.7563 -276.544763) (xy 388.733429 -276.58834) (xy 388.703864 -276.627684)
			(xy 388.668371 -276.661776) (xy 388.627868 -276.689732) (xy 388.583406 -276.71083) (xy 388.536135 -276.724522)
			(xy 388.48728 -276.730454) (xy 388.438105 -276.728473) (xy 388.389886 -276.718629) (xy 388.34387 -276.701177)
			(xy 388.301249 -276.67657) (xy 388.263128 -276.645445) (xy 388.230493 -276.608608) (xy 388.20419 -276.567012)
			(xy 388.184899 -276.521736) (xy 388.173122 -276.473952) (xy 388.169162 -276.424898) (xy 387.830314 -276.424898)
			(xy 387.829819 -276.449505) (xy 387.821924 -276.498082) (xy 387.80634 -276.544763) (xy 387.783469 -276.58834)
			(xy 387.753904 -276.627684) (xy 387.718411 -276.661776) (xy 387.677908 -276.689732) (xy 387.633446 -276.71083)
			(xy 387.586175 -276.724522) (xy 387.53732 -276.730454) (xy 387.488145 -276.728473) (xy 387.439926 -276.718629)
			(xy 387.39391 -276.701177) (xy 387.351289 -276.67657) (xy 387.313168 -276.645445) (xy 387.280533 -276.608608)
			(xy 387.25423 -276.567012) (xy 387.234939 -276.521736) (xy 387.223162 -276.473952) (xy 387.219202 -276.424898)
			(xy 386.880354 -276.424898) (xy 386.879859 -276.449505) (xy 386.871964 -276.498082) (xy 386.85638 -276.544763)
			(xy 386.833509 -276.58834) (xy 386.803944 -276.627684) (xy 386.768451 -276.661776) (xy 386.727948 -276.689732)
			(xy 386.683486 -276.71083) (xy 386.636215 -276.724522) (xy 386.58736 -276.730454) (xy 386.538185 -276.728473)
			(xy 386.489966 -276.718629) (xy 386.44395 -276.701177) (xy 386.401329 -276.67657) (xy 386.363208 -276.645445)
			(xy 386.330573 -276.608608) (xy 386.30427 -276.567012) (xy 386.284979 -276.521736) (xy 386.273202 -276.473952)
			(xy 386.269242 -276.424898) (xy 385.93014 -276.424898) (xy 385.929645 -276.449505) (xy 385.92175 -276.498082)
			(xy 385.906166 -276.544763) (xy 385.883295 -276.58834) (xy 385.85373 -276.627684) (xy 385.818237 -276.661776)
			(xy 385.777734 -276.689732) (xy 385.733272 -276.71083) (xy 385.686001 -276.724522) (xy 385.637146 -276.730454)
			(xy 385.587971 -276.728473) (xy 385.539752 -276.718629) (xy 385.493736 -276.701177) (xy 385.451115 -276.67657)
			(xy 385.412994 -276.645445) (xy 385.380359 -276.608608) (xy 385.354056 -276.567012) (xy 385.334765 -276.521736)
			(xy 385.322988 -276.473952) (xy 385.319028 -276.424898) (xy 384.98018 -276.424898) (xy 384.979685 -276.449505)
			(xy 384.97179 -276.498082) (xy 384.956206 -276.544763) (xy 384.933335 -276.58834) (xy 384.90377 -276.627684)
			(xy 384.868277 -276.661776) (xy 384.827774 -276.689732) (xy 384.783312 -276.71083) (xy 384.736041 -276.724522)
			(xy 384.687186 -276.730454) (xy 384.638011 -276.728473) (xy 384.589792 -276.718629) (xy 384.543776 -276.701177)
			(xy 384.501155 -276.67657) (xy 384.463034 -276.645445) (xy 384.430399 -276.608608) (xy 384.404096 -276.567012)
			(xy 384.384805 -276.521736) (xy 384.373028 -276.473952) (xy 384.369068 -276.424898) (xy 371.803748 -276.424898)
			(xy 371.779579 -276.587832) (xy 371.74722 -276.750505) (xy 371.709804 -276.899878) (xy 392.443982 -276.899878)
			(xy 392.447942 -276.850824) (xy 392.459719 -276.80304) (xy 392.47901 -276.757764) (xy 392.505313 -276.716168)
			(xy 392.537948 -276.679331) (xy 392.576069 -276.648206) (xy 392.61869 -276.623599) (xy 392.664706 -276.606147)
			(xy 392.712925 -276.596303) (xy 392.7621 -276.594322) (xy 392.810955 -276.600254) (xy 392.858226 -276.613946)
			(xy 392.902688 -276.635044) (xy 392.943191 -276.663) (xy 392.978684 -276.697092) (xy 393.008249 -276.736436)
			(xy 393.03112 -276.780013) (xy 393.046704 -276.826694) (xy 393.054599 -276.875271) (xy 393.055094 -276.899878)
			(xy 393.394196 -276.899878) (xy 393.398156 -276.850824) (xy 393.409933 -276.80304) (xy 393.429224 -276.757764)
			(xy 393.455527 -276.716168) (xy 393.488162 -276.679331) (xy 393.526283 -276.648206) (xy 393.568904 -276.623599)
			(xy 393.61492 -276.606147) (xy 393.663139 -276.596303) (xy 393.712314 -276.594322) (xy 393.761169 -276.600254)
			(xy 393.80844 -276.613946) (xy 393.852902 -276.635044) (xy 393.893405 -276.663) (xy 393.928898 -276.697092)
			(xy 393.958463 -276.736436) (xy 393.981334 -276.780013) (xy 393.996918 -276.826694) (xy 394.004813 -276.875271)
			(xy 394.005308 -276.899878) (xy 394.344156 -276.899878) (xy 394.348116 -276.850824) (xy 394.359893 -276.80304)
			(xy 394.379184 -276.757764) (xy 394.405487 -276.716168) (xy 394.438122 -276.679331) (xy 394.476243 -276.648206)
			(xy 394.518864 -276.623599) (xy 394.56488 -276.606147) (xy 394.613099 -276.596303) (xy 394.662274 -276.594322)
			(xy 394.711129 -276.600254) (xy 394.7584 -276.613946) (xy 394.802862 -276.635044) (xy 394.843365 -276.663)
			(xy 394.878858 -276.697092) (xy 394.908423 -276.736436) (xy 394.931294 -276.780013) (xy 394.946878 -276.826694)
			(xy 394.954773 -276.875271) (xy 394.955268 -276.899878) (xy 395.294116 -276.899878) (xy 395.298076 -276.850824)
			(xy 395.309853 -276.80304) (xy 395.329144 -276.757764) (xy 395.355447 -276.716168) (xy 395.388082 -276.679331)
			(xy 395.426203 -276.648206) (xy 395.468824 -276.623599) (xy 395.51484 -276.606147) (xy 395.563059 -276.596303)
			(xy 395.612234 -276.594322) (xy 395.661089 -276.600254) (xy 395.70836 -276.613946) (xy 395.752822 -276.635044)
			(xy 395.793325 -276.663) (xy 395.828818 -276.697092) (xy 395.858383 -276.736436) (xy 395.881254 -276.780013)
			(xy 395.896838 -276.826694) (xy 395.904733 -276.875271) (xy 395.905228 -276.899878) (xy 396.244076 -276.899878)
			(xy 396.248036 -276.850824) (xy 396.259813 -276.80304) (xy 396.279104 -276.757764) (xy 396.305407 -276.716168)
			(xy 396.338042 -276.679331) (xy 396.376163 -276.648206) (xy 396.418784 -276.623599) (xy 396.4648 -276.606147)
			(xy 396.513019 -276.596303) (xy 396.562194 -276.594322) (xy 396.611049 -276.600254) (xy 396.65832 -276.613946)
			(xy 396.702782 -276.635044) (xy 396.743285 -276.663) (xy 396.778778 -276.697092) (xy 396.808343 -276.736436)
			(xy 396.831214 -276.780013) (xy 396.846798 -276.826694) (xy 396.854693 -276.875271) (xy 396.855188 -276.899878)
			(xy 397.194036 -276.899878) (xy 397.197996 -276.850824) (xy 397.209773 -276.80304) (xy 397.229064 -276.757764)
			(xy 397.255367 -276.716168) (xy 397.288002 -276.679331) (xy 397.326123 -276.648206) (xy 397.368744 -276.623599)
			(xy 397.41476 -276.606147) (xy 397.462979 -276.596303) (xy 397.512154 -276.594322) (xy 397.561009 -276.600254)
			(xy 397.60828 -276.613946) (xy 397.652742 -276.635044) (xy 397.693245 -276.663) (xy 397.728738 -276.697092)
			(xy 397.758303 -276.736436) (xy 397.781174 -276.780013) (xy 397.796758 -276.826694) (xy 397.804653 -276.875271)
			(xy 397.805148 -276.899878) (xy 398.143996 -276.899878) (xy 398.147956 -276.850824) (xy 398.159733 -276.80304)
			(xy 398.179024 -276.757764) (xy 398.205327 -276.716168) (xy 398.237962 -276.679331) (xy 398.276083 -276.648206)
			(xy 398.318704 -276.623599) (xy 398.36472 -276.606147) (xy 398.412939 -276.596303) (xy 398.462114 -276.594322)
			(xy 398.510969 -276.600254) (xy 398.55824 -276.613946) (xy 398.602702 -276.635044) (xy 398.643205 -276.663)
			(xy 398.678698 -276.697092) (xy 398.708263 -276.736436) (xy 398.731134 -276.780013) (xy 398.746718 -276.826694)
			(xy 398.754613 -276.875271) (xy 398.755108 -276.899878) (xy 399.09421 -276.899878) (xy 399.09817 -276.850824)
			(xy 399.109947 -276.80304) (xy 399.129238 -276.757764) (xy 399.155541 -276.716168) (xy 399.188176 -276.679331)
			(xy 399.226297 -276.648206) (xy 399.268918 -276.623599) (xy 399.314934 -276.606147) (xy 399.363153 -276.596303)
			(xy 399.412328 -276.594322) (xy 399.461183 -276.600254) (xy 399.508454 -276.613946) (xy 399.552916 -276.635044)
			(xy 399.593419 -276.663) (xy 399.628912 -276.697092) (xy 399.658477 -276.736436) (xy 399.681348 -276.780013)
			(xy 399.696932 -276.826694) (xy 399.704827 -276.875271) (xy 399.705322 -276.899878) (xy 400.04417 -276.899878)
			(xy 400.04813 -276.850824) (xy 400.059907 -276.80304) (xy 400.079198 -276.757764) (xy 400.105501 -276.716168)
			(xy 400.138136 -276.679331) (xy 400.176257 -276.648206) (xy 400.218878 -276.623599) (xy 400.264894 -276.606147)
			(xy 400.313113 -276.596303) (xy 400.362288 -276.594322) (xy 400.411143 -276.600254) (xy 400.458414 -276.613946)
			(xy 400.502876 -276.635044) (xy 400.543379 -276.663) (xy 400.578872 -276.697092) (xy 400.608437 -276.736436)
			(xy 400.631308 -276.780013) (xy 400.646892 -276.826694) (xy 400.654787 -276.875271) (xy 400.655282 -276.899878)
			(xy 400.99413 -276.899878) (xy 400.99809 -276.850824) (xy 401.009867 -276.80304) (xy 401.029158 -276.757764)
			(xy 401.055461 -276.716168) (xy 401.088096 -276.679331) (xy 401.126217 -276.648206) (xy 401.168838 -276.623599)
			(xy 401.214854 -276.606147) (xy 401.263073 -276.596303) (xy 401.312248 -276.594322) (xy 401.361103 -276.600254)
			(xy 401.408374 -276.613946) (xy 401.452836 -276.635044) (xy 401.493339 -276.663) (xy 401.528832 -276.697092)
			(xy 401.558397 -276.736436) (xy 401.581268 -276.780013) (xy 401.596852 -276.826694) (xy 401.604747 -276.875271)
			(xy 401.605242 -276.899878) (xy 401.94409 -276.899878) (xy 401.94805 -276.850824) (xy 401.959827 -276.80304)
			(xy 401.979118 -276.757764) (xy 402.005421 -276.716168) (xy 402.038056 -276.679331) (xy 402.076177 -276.648206)
			(xy 402.118798 -276.623599) (xy 402.164814 -276.606147) (xy 402.213033 -276.596303) (xy 402.262208 -276.594322)
			(xy 402.311063 -276.600254) (xy 402.358334 -276.613946) (xy 402.402796 -276.635044) (xy 402.443299 -276.663)
			(xy 402.478792 -276.697092) (xy 402.508357 -276.736436) (xy 402.531228 -276.780013) (xy 402.546812 -276.826694)
			(xy 402.554707 -276.875271) (xy 402.555202 -276.899878) (xy 402.89405 -276.899878) (xy 402.89801 -276.850824)
			(xy 402.909787 -276.80304) (xy 402.929078 -276.757764) (xy 402.955381 -276.716168) (xy 402.988016 -276.679331)
			(xy 403.026137 -276.648206) (xy 403.068758 -276.623599) (xy 403.114774 -276.606147) (xy 403.162993 -276.596303)
			(xy 403.212168 -276.594322) (xy 403.261023 -276.600254) (xy 403.308294 -276.613946) (xy 403.352756 -276.635044)
			(xy 403.393259 -276.663) (xy 403.428752 -276.697092) (xy 403.458317 -276.736436) (xy 403.481188 -276.780013)
			(xy 403.496772 -276.826694) (xy 403.504667 -276.875271) (xy 403.505162 -276.899878) (xy 403.84401 -276.899878)
			(xy 403.84797 -276.850824) (xy 403.859747 -276.80304) (xy 403.879038 -276.757764) (xy 403.905341 -276.716168)
			(xy 403.937976 -276.679331) (xy 403.976097 -276.648206) (xy 404.018718 -276.623599) (xy 404.064734 -276.606147)
			(xy 404.112953 -276.596303) (xy 404.162128 -276.594322) (xy 404.210983 -276.600254) (xy 404.258254 -276.613946)
			(xy 404.302716 -276.635044) (xy 404.343219 -276.663) (xy 404.378712 -276.697092) (xy 404.408277 -276.736436)
			(xy 404.431148 -276.780013) (xy 404.446732 -276.826694) (xy 404.454627 -276.875271) (xy 404.455122 -276.899878)
			(xy 404.794224 -276.899878) (xy 404.798184 -276.850824) (xy 404.809961 -276.80304) (xy 404.829252 -276.757764)
			(xy 404.855555 -276.716168) (xy 404.88819 -276.679331) (xy 404.926311 -276.648206) (xy 404.968932 -276.623599)
			(xy 405.014948 -276.606147) (xy 405.063167 -276.596303) (xy 405.112342 -276.594322) (xy 405.161197 -276.600254)
			(xy 405.208468 -276.613946) (xy 405.25293 -276.635044) (xy 405.293433 -276.663) (xy 405.328926 -276.697092)
			(xy 405.358491 -276.736436) (xy 405.381362 -276.780013) (xy 405.396946 -276.826694) (xy 405.404841 -276.875271)
			(xy 405.405336 -276.899878) (xy 405.404841 -276.924485) (xy 405.396946 -276.973062) (xy 405.381362 -277.019743)
			(xy 405.358491 -277.06332) (xy 405.328926 -277.102664) (xy 405.293433 -277.136756) (xy 405.25293 -277.164712)
			(xy 405.208468 -277.18581) (xy 405.161197 -277.199502) (xy 405.112342 -277.205434) (xy 405.063167 -277.203453)
			(xy 405.014948 -277.193609) (xy 404.968932 -277.176157) (xy 404.926311 -277.15155) (xy 404.88819 -277.120425)
			(xy 404.855555 -277.083588) (xy 404.829252 -277.041992) (xy 404.809961 -276.996716) (xy 404.798184 -276.948932)
			(xy 404.794224 -276.899878) (xy 404.455122 -276.899878) (xy 404.454627 -276.924485) (xy 404.446732 -276.973062)
			(xy 404.431148 -277.019743) (xy 404.408277 -277.06332) (xy 404.378712 -277.102664) (xy 404.343219 -277.136756)
			(xy 404.302716 -277.164712) (xy 404.258254 -277.18581) (xy 404.210983 -277.199502) (xy 404.162128 -277.205434)
			(xy 404.112953 -277.203453) (xy 404.064734 -277.193609) (xy 404.018718 -277.176157) (xy 403.976097 -277.15155)
			(xy 403.937976 -277.120425) (xy 403.905341 -277.083588) (xy 403.879038 -277.041992) (xy 403.859747 -276.996716)
			(xy 403.84797 -276.948932) (xy 403.84401 -276.899878) (xy 403.505162 -276.899878) (xy 403.504667 -276.924485)
			(xy 403.496772 -276.973062) (xy 403.481188 -277.019743) (xy 403.458317 -277.06332) (xy 403.428752 -277.102664)
			(xy 403.393259 -277.136756) (xy 403.352756 -277.164712) (xy 403.308294 -277.18581) (xy 403.261023 -277.199502)
			(xy 403.212168 -277.205434) (xy 403.162993 -277.203453) (xy 403.114774 -277.193609) (xy 403.068758 -277.176157)
			(xy 403.026137 -277.15155) (xy 402.988016 -277.120425) (xy 402.955381 -277.083588) (xy 402.929078 -277.041992)
			(xy 402.909787 -276.996716) (xy 402.89801 -276.948932) (xy 402.89405 -276.899878) (xy 402.555202 -276.899878)
			(xy 402.554707 -276.924485) (xy 402.546812 -276.973062) (xy 402.531228 -277.019743) (xy 402.508357 -277.06332)
			(xy 402.478792 -277.102664) (xy 402.443299 -277.136756) (xy 402.402796 -277.164712) (xy 402.358334 -277.18581)
			(xy 402.311063 -277.199502) (xy 402.262208 -277.205434) (xy 402.213033 -277.203453) (xy 402.164814 -277.193609)
			(xy 402.118798 -277.176157) (xy 402.076177 -277.15155) (xy 402.038056 -277.120425) (xy 402.005421 -277.083588)
			(xy 401.979118 -277.041992) (xy 401.959827 -276.996716) (xy 401.94805 -276.948932) (xy 401.94409 -276.899878)
			(xy 401.605242 -276.899878) (xy 401.604747 -276.924485) (xy 401.596852 -276.973062) (xy 401.581268 -277.019743)
			(xy 401.558397 -277.06332) (xy 401.528832 -277.102664) (xy 401.493339 -277.136756) (xy 401.452836 -277.164712)
			(xy 401.408374 -277.18581) (xy 401.361103 -277.199502) (xy 401.312248 -277.205434) (xy 401.263073 -277.203453)
			(xy 401.214854 -277.193609) (xy 401.168838 -277.176157) (xy 401.126217 -277.15155) (xy 401.088096 -277.120425)
			(xy 401.055461 -277.083588) (xy 401.029158 -277.041992) (xy 401.009867 -276.996716) (xy 400.99809 -276.948932)
			(xy 400.99413 -276.899878) (xy 400.655282 -276.899878) (xy 400.654787 -276.924485) (xy 400.646892 -276.973062)
			(xy 400.631308 -277.019743) (xy 400.608437 -277.06332) (xy 400.578872 -277.102664) (xy 400.543379 -277.136756)
			(xy 400.502876 -277.164712) (xy 400.458414 -277.18581) (xy 400.411143 -277.199502) (xy 400.362288 -277.205434)
			(xy 400.313113 -277.203453) (xy 400.264894 -277.193609) (xy 400.218878 -277.176157) (xy 400.176257 -277.15155)
			(xy 400.138136 -277.120425) (xy 400.105501 -277.083588) (xy 400.079198 -277.041992) (xy 400.059907 -276.996716)
			(xy 400.04813 -276.948932) (xy 400.04417 -276.899878) (xy 399.705322 -276.899878) (xy 399.704827 -276.924485)
			(xy 399.696932 -276.973062) (xy 399.681348 -277.019743) (xy 399.658477 -277.06332) (xy 399.628912 -277.102664)
			(xy 399.593419 -277.136756) (xy 399.552916 -277.164712) (xy 399.508454 -277.18581) (xy 399.461183 -277.199502)
			(xy 399.412328 -277.205434) (xy 399.363153 -277.203453) (xy 399.314934 -277.193609) (xy 399.268918 -277.176157)
			(xy 399.226297 -277.15155) (xy 399.188176 -277.120425) (xy 399.155541 -277.083588) (xy 399.129238 -277.041992)
			(xy 399.109947 -276.996716) (xy 399.09817 -276.948932) (xy 399.09421 -276.899878) (xy 398.755108 -276.899878)
			(xy 398.754613 -276.924485) (xy 398.746718 -276.973062) (xy 398.731134 -277.019743) (xy 398.708263 -277.06332)
			(xy 398.678698 -277.102664) (xy 398.643205 -277.136756) (xy 398.602702 -277.164712) (xy 398.55824 -277.18581)
			(xy 398.510969 -277.199502) (xy 398.462114 -277.205434) (xy 398.412939 -277.203453) (xy 398.36472 -277.193609)
			(xy 398.318704 -277.176157) (xy 398.276083 -277.15155) (xy 398.237962 -277.120425) (xy 398.205327 -277.083588)
			(xy 398.179024 -277.041992) (xy 398.159733 -276.996716) (xy 398.147956 -276.948932) (xy 398.143996 -276.899878)
			(xy 397.805148 -276.899878) (xy 397.804653 -276.924485) (xy 397.796758 -276.973062) (xy 397.781174 -277.019743)
			(xy 397.758303 -277.06332) (xy 397.728738 -277.102664) (xy 397.693245 -277.136756) (xy 397.652742 -277.164712)
			(xy 397.60828 -277.18581) (xy 397.561009 -277.199502) (xy 397.512154 -277.205434) (xy 397.462979 -277.203453)
			(xy 397.41476 -277.193609) (xy 397.368744 -277.176157) (xy 397.326123 -277.15155) (xy 397.288002 -277.120425)
			(xy 397.255367 -277.083588) (xy 397.229064 -277.041992) (xy 397.209773 -276.996716) (xy 397.197996 -276.948932)
			(xy 397.194036 -276.899878) (xy 396.855188 -276.899878) (xy 396.854693 -276.924485) (xy 396.846798 -276.973062)
			(xy 396.831214 -277.019743) (xy 396.808343 -277.06332) (xy 396.778778 -277.102664) (xy 396.743285 -277.136756)
			(xy 396.702782 -277.164712) (xy 396.65832 -277.18581) (xy 396.611049 -277.199502) (xy 396.562194 -277.205434)
			(xy 396.513019 -277.203453) (xy 396.4648 -277.193609) (xy 396.418784 -277.176157) (xy 396.376163 -277.15155)
			(xy 396.338042 -277.120425) (xy 396.305407 -277.083588) (xy 396.279104 -277.041992) (xy 396.259813 -276.996716)
			(xy 396.248036 -276.948932) (xy 396.244076 -276.899878) (xy 395.905228 -276.899878) (xy 395.904733 -276.924485)
			(xy 395.896838 -276.973062) (xy 395.881254 -277.019743) (xy 395.858383 -277.06332) (xy 395.828818 -277.102664)
			(xy 395.793325 -277.136756) (xy 395.752822 -277.164712) (xy 395.70836 -277.18581) (xy 395.661089 -277.199502)
			(xy 395.612234 -277.205434) (xy 395.563059 -277.203453) (xy 395.51484 -277.193609) (xy 395.468824 -277.176157)
			(xy 395.426203 -277.15155) (xy 395.388082 -277.120425) (xy 395.355447 -277.083588) (xy 395.329144 -277.041992)
			(xy 395.309853 -276.996716) (xy 395.298076 -276.948932) (xy 395.294116 -276.899878) (xy 394.955268 -276.899878)
			(xy 394.954773 -276.924485) (xy 394.946878 -276.973062) (xy 394.931294 -277.019743) (xy 394.908423 -277.06332)
			(xy 394.878858 -277.102664) (xy 394.843365 -277.136756) (xy 394.802862 -277.164712) (xy 394.7584 -277.18581)
			(xy 394.711129 -277.199502) (xy 394.662274 -277.205434) (xy 394.613099 -277.203453) (xy 394.56488 -277.193609)
			(xy 394.518864 -277.176157) (xy 394.476243 -277.15155) (xy 394.438122 -277.120425) (xy 394.405487 -277.083588)
			(xy 394.379184 -277.041992) (xy 394.359893 -276.996716) (xy 394.348116 -276.948932) (xy 394.344156 -276.899878)
			(xy 394.005308 -276.899878) (xy 394.004813 -276.924485) (xy 393.996918 -276.973062) (xy 393.981334 -277.019743)
			(xy 393.958463 -277.06332) (xy 393.928898 -277.102664) (xy 393.893405 -277.136756) (xy 393.852902 -277.164712)
			(xy 393.80844 -277.18581) (xy 393.761169 -277.199502) (xy 393.712314 -277.205434) (xy 393.663139 -277.203453)
			(xy 393.61492 -277.193609) (xy 393.568904 -277.176157) (xy 393.526283 -277.15155) (xy 393.488162 -277.120425)
			(xy 393.455527 -277.083588) (xy 393.429224 -277.041992) (xy 393.409933 -276.996716) (xy 393.398156 -276.948932)
			(xy 393.394196 -276.899878) (xy 393.055094 -276.899878) (xy 393.054599 -276.924485) (xy 393.046704 -276.973062)
			(xy 393.03112 -277.019743) (xy 393.008249 -277.06332) (xy 392.978684 -277.102664) (xy 392.943191 -277.136756)
			(xy 392.902688 -277.164712) (xy 392.858226 -277.18581) (xy 392.810955 -277.199502) (xy 392.7621 -277.205434)
			(xy 392.712925 -277.203453) (xy 392.664706 -277.193609) (xy 392.61869 -277.176157) (xy 392.576069 -277.15155)
			(xy 392.537948 -277.120425) (xy 392.505313 -277.083588) (xy 392.47901 -277.041992) (xy 392.459719 -276.996716)
			(xy 392.447942 -276.948932) (xy 392.443982 -276.899878) (xy 371.709804 -276.899878) (xy 371.706919 -276.911394)
			(xy 371.658772 -277.070112) (xy 371.602895 -277.226277) (xy 371.54135 -277.374858) (xy 384.369068 -277.374858)
			(xy 384.373028 -277.325804) (xy 384.384805 -277.27802) (xy 384.404096 -277.232744) (xy 384.430399 -277.191148)
			(xy 384.463034 -277.154311) (xy 384.501155 -277.123186) (xy 384.543776 -277.098579) (xy 384.589792 -277.081127)
			(xy 384.638011 -277.071283) (xy 384.687186 -277.069302) (xy 384.736041 -277.075234) (xy 384.783312 -277.088926)
			(xy 384.827774 -277.110024) (xy 384.868277 -277.13798) (xy 384.90377 -277.172072) (xy 384.933335 -277.211416)
			(xy 384.956206 -277.254993) (xy 384.97179 -277.301674) (xy 384.979685 -277.350251) (xy 384.98018 -277.374858)
			(xy 385.319028 -277.374858) (xy 385.322988 -277.325804) (xy 385.334765 -277.27802) (xy 385.354056 -277.232744)
			(xy 385.380359 -277.191148) (xy 385.412994 -277.154311) (xy 385.451115 -277.123186) (xy 385.493736 -277.098579)
			(xy 385.539752 -277.081127) (xy 385.587971 -277.071283) (xy 385.637146 -277.069302) (xy 385.686001 -277.075234)
			(xy 385.733272 -277.088926) (xy 385.777734 -277.110024) (xy 385.818237 -277.13798) (xy 385.85373 -277.172072)
			(xy 385.883295 -277.211416) (xy 385.906166 -277.254993) (xy 385.92175 -277.301674) (xy 385.929645 -277.350251)
			(xy 385.93014 -277.374858) (xy 386.269242 -277.374858) (xy 386.273202 -277.325804) (xy 386.284979 -277.27802)
			(xy 386.30427 -277.232744) (xy 386.330573 -277.191148) (xy 386.363208 -277.154311) (xy 386.401329 -277.123186)
			(xy 386.44395 -277.098579) (xy 386.489966 -277.081127) (xy 386.538185 -277.071283) (xy 386.58736 -277.069302)
			(xy 386.636215 -277.075234) (xy 386.683486 -277.088926) (xy 386.727948 -277.110024) (xy 386.768451 -277.13798)
			(xy 386.803944 -277.172072) (xy 386.833509 -277.211416) (xy 386.85638 -277.254993) (xy 386.871964 -277.301674)
			(xy 386.879859 -277.350251) (xy 386.880354 -277.374858) (xy 387.219202 -277.374858) (xy 387.223162 -277.325804)
			(xy 387.234939 -277.27802) (xy 387.25423 -277.232744) (xy 387.280533 -277.191148) (xy 387.313168 -277.154311)
			(xy 387.351289 -277.123186) (xy 387.39391 -277.098579) (xy 387.439926 -277.081127) (xy 387.488145 -277.071283)
			(xy 387.53732 -277.069302) (xy 387.586175 -277.075234) (xy 387.633446 -277.088926) (xy 387.677908 -277.110024)
			(xy 387.718411 -277.13798) (xy 387.753904 -277.172072) (xy 387.783469 -277.211416) (xy 387.80634 -277.254993)
			(xy 387.821924 -277.301674) (xy 387.829819 -277.350251) (xy 387.830314 -277.374858) (xy 388.169162 -277.374858)
			(xy 388.173122 -277.325804) (xy 388.184899 -277.27802) (xy 388.20419 -277.232744) (xy 388.230493 -277.191148)
			(xy 388.263128 -277.154311) (xy 388.301249 -277.123186) (xy 388.34387 -277.098579) (xy 388.389886 -277.081127)
			(xy 388.438105 -277.071283) (xy 388.48728 -277.069302) (xy 388.536135 -277.075234) (xy 388.583406 -277.088926)
			(xy 388.627868 -277.110024) (xy 388.668371 -277.13798) (xy 388.703864 -277.172072) (xy 388.733429 -277.211416)
			(xy 388.7563 -277.254993) (xy 388.771884 -277.301674) (xy 388.779779 -277.350251) (xy 388.780274 -277.374858)
			(xy 389.119122 -277.374858) (xy 389.123082 -277.325804) (xy 389.134859 -277.27802) (xy 389.15415 -277.232744)
			(xy 389.180453 -277.191148) (xy 389.213088 -277.154311) (xy 389.251209 -277.123186) (xy 389.29383 -277.098579)
			(xy 389.339846 -277.081127) (xy 389.388065 -277.071283) (xy 389.43724 -277.069302) (xy 389.486095 -277.075234)
			(xy 389.533366 -277.088926) (xy 389.577828 -277.110024) (xy 389.618331 -277.13798) (xy 389.653824 -277.172072)
			(xy 389.683389 -277.211416) (xy 389.70626 -277.254993) (xy 389.721844 -277.301674) (xy 389.729739 -277.350251)
			(xy 389.730234 -277.374858) (xy 390.069082 -277.374858) (xy 390.073042 -277.325804) (xy 390.084819 -277.27802)
			(xy 390.10411 -277.232744) (xy 390.130413 -277.191148) (xy 390.163048 -277.154311) (xy 390.201169 -277.123186)
			(xy 390.24379 -277.098579) (xy 390.289806 -277.081127) (xy 390.338025 -277.071283) (xy 390.3872 -277.069302)
			(xy 390.436055 -277.075234) (xy 390.483326 -277.088926) (xy 390.527788 -277.110024) (xy 390.568291 -277.13798)
			(xy 390.603784 -277.172072) (xy 390.633349 -277.211416) (xy 390.65622 -277.254993) (xy 390.671804 -277.301674)
			(xy 390.679699 -277.350251) (xy 390.680194 -277.374858) (xy 391.019042 -277.374858) (xy 391.023002 -277.325804)
			(xy 391.034779 -277.27802) (xy 391.05407 -277.232744) (xy 391.080373 -277.191148) (xy 391.113008 -277.154311)
			(xy 391.151129 -277.123186) (xy 391.19375 -277.098579) (xy 391.239766 -277.081127) (xy 391.287985 -277.071283)
			(xy 391.33716 -277.069302) (xy 391.386015 -277.075234) (xy 391.433286 -277.088926) (xy 391.477748 -277.110024)
			(xy 391.518251 -277.13798) (xy 391.553744 -277.172072) (xy 391.583309 -277.211416) (xy 391.60618 -277.254993)
			(xy 391.621764 -277.301674) (xy 391.629659 -277.350251) (xy 391.630154 -277.374858) (xy 391.629659 -277.399465)
			(xy 391.621764 -277.448042) (xy 391.60618 -277.494723) (xy 391.583309 -277.5383) (xy 391.553744 -277.577644)
			(xy 391.518251 -277.611736) (xy 391.477748 -277.639692) (xy 391.433286 -277.66079) (xy 391.386015 -277.674482)
			(xy 391.33716 -277.680414) (xy 391.287985 -277.678433) (xy 391.239766 -277.668589) (xy 391.19375 -277.651137)
			(xy 391.151129 -277.62653) (xy 391.113008 -277.595405) (xy 391.080373 -277.558568) (xy 391.05407 -277.516972)
			(xy 391.034779 -277.471696) (xy 391.023002 -277.423912) (xy 391.019042 -277.374858) (xy 390.680194 -277.374858)
			(xy 390.679699 -277.399465) (xy 390.671804 -277.448042) (xy 390.65622 -277.494723) (xy 390.633349 -277.5383)
			(xy 390.603784 -277.577644) (xy 390.568291 -277.611736) (xy 390.527788 -277.639692) (xy 390.483326 -277.66079)
			(xy 390.436055 -277.674482) (xy 390.3872 -277.680414) (xy 390.338025 -277.678433) (xy 390.289806 -277.668589)
			(xy 390.24379 -277.651137) (xy 390.201169 -277.62653) (xy 390.163048 -277.595405) (xy 390.130413 -277.558568)
			(xy 390.10411 -277.516972) (xy 390.084819 -277.471696) (xy 390.073042 -277.423912) (xy 390.069082 -277.374858)
			(xy 389.730234 -277.374858) (xy 389.729739 -277.399465) (xy 389.721844 -277.448042) (xy 389.70626 -277.494723)
			(xy 389.683389 -277.5383) (xy 389.653824 -277.577644) (xy 389.618331 -277.611736) (xy 389.577828 -277.639692)
			(xy 389.533366 -277.66079) (xy 389.486095 -277.674482) (xy 389.43724 -277.680414) (xy 389.388065 -277.678433)
			(xy 389.339846 -277.668589) (xy 389.29383 -277.651137) (xy 389.251209 -277.62653) (xy 389.213088 -277.595405)
			(xy 389.180453 -277.558568) (xy 389.15415 -277.516972) (xy 389.134859 -277.471696) (xy 389.123082 -277.423912)
			(xy 389.119122 -277.374858) (xy 388.780274 -277.374858) (xy 388.779779 -277.399465) (xy 388.771884 -277.448042)
			(xy 388.7563 -277.494723) (xy 388.733429 -277.5383) (xy 388.703864 -277.577644) (xy 388.668371 -277.611736)
			(xy 388.627868 -277.639692) (xy 388.583406 -277.66079) (xy 388.536135 -277.674482) (xy 388.48728 -277.680414)
			(xy 388.438105 -277.678433) (xy 388.389886 -277.668589) (xy 388.34387 -277.651137) (xy 388.301249 -277.62653)
			(xy 388.263128 -277.595405) (xy 388.230493 -277.558568) (xy 388.20419 -277.516972) (xy 388.184899 -277.471696)
			(xy 388.173122 -277.423912) (xy 388.169162 -277.374858) (xy 387.830314 -277.374858) (xy 387.829819 -277.399465)
			(xy 387.821924 -277.448042) (xy 387.80634 -277.494723) (xy 387.783469 -277.5383) (xy 387.753904 -277.577644)
			(xy 387.718411 -277.611736) (xy 387.677908 -277.639692) (xy 387.633446 -277.66079) (xy 387.586175 -277.674482)
			(xy 387.53732 -277.680414) (xy 387.488145 -277.678433) (xy 387.439926 -277.668589) (xy 387.39391 -277.651137)
			(xy 387.351289 -277.62653) (xy 387.313168 -277.595405) (xy 387.280533 -277.558568) (xy 387.25423 -277.516972)
			(xy 387.234939 -277.471696) (xy 387.223162 -277.423912) (xy 387.219202 -277.374858) (xy 386.880354 -277.374858)
			(xy 386.879859 -277.399465) (xy 386.871964 -277.448042) (xy 386.85638 -277.494723) (xy 386.833509 -277.5383)
			(xy 386.803944 -277.577644) (xy 386.768451 -277.611736) (xy 386.727948 -277.639692) (xy 386.683486 -277.66079)
			(xy 386.636215 -277.674482) (xy 386.58736 -277.680414) (xy 386.538185 -277.678433) (xy 386.489966 -277.668589)
			(xy 386.44395 -277.651137) (xy 386.401329 -277.62653) (xy 386.363208 -277.595405) (xy 386.330573 -277.558568)
			(xy 386.30427 -277.516972) (xy 386.284979 -277.471696) (xy 386.273202 -277.423912) (xy 386.269242 -277.374858)
			(xy 385.93014 -277.374858) (xy 385.929645 -277.399465) (xy 385.92175 -277.448042) (xy 385.906166 -277.494723)
			(xy 385.883295 -277.5383) (xy 385.85373 -277.577644) (xy 385.818237 -277.611736) (xy 385.777734 -277.639692)
			(xy 385.733272 -277.66079) (xy 385.686001 -277.674482) (xy 385.637146 -277.680414) (xy 385.587971 -277.678433)
			(xy 385.539752 -277.668589) (xy 385.493736 -277.651137) (xy 385.451115 -277.62653) (xy 385.412994 -277.595405)
			(xy 385.380359 -277.558568) (xy 385.354056 -277.516972) (xy 385.334765 -277.471696) (xy 385.322988 -277.423912)
			(xy 385.319028 -277.374858) (xy 384.98018 -277.374858) (xy 384.979685 -277.399465) (xy 384.97179 -277.448042)
			(xy 384.956206 -277.494723) (xy 384.933335 -277.5383) (xy 384.90377 -277.577644) (xy 384.868277 -277.611736)
			(xy 384.827774 -277.639692) (xy 384.783312 -277.66079) (xy 384.736041 -277.674482) (xy 384.687186 -277.680414)
			(xy 384.638011 -277.678433) (xy 384.589792 -277.668589) (xy 384.543776 -277.651137) (xy 384.501155 -277.62653)
			(xy 384.463034 -277.595405) (xy 384.430399 -277.558568) (xy 384.404096 -277.516972) (xy 384.384805 -277.471696)
			(xy 384.373028 -277.423912) (xy 384.369068 -277.374858) (xy 371.54135 -277.374858) (xy 371.539423 -277.379511)
			(xy 371.468508 -277.529447) (xy 371.390322 -277.675722) (xy 371.305053 -277.817985) (xy 371.283769 -277.849838)
			(xy 392.443982 -277.849838) (xy 392.447942 -277.800784) (xy 392.459719 -277.753) (xy 392.47901 -277.707724)
			(xy 392.505313 -277.666128) (xy 392.537948 -277.629291) (xy 392.576069 -277.598166) (xy 392.61869 -277.573559)
			(xy 392.664706 -277.556107) (xy 392.712925 -277.546263) (xy 392.7621 -277.544282) (xy 392.810955 -277.550214)
			(xy 392.858226 -277.563906) (xy 392.902688 -277.585004) (xy 392.943191 -277.61296) (xy 392.978684 -277.647052)
			(xy 393.008249 -277.686396) (xy 393.03112 -277.729973) (xy 393.046704 -277.776654) (xy 393.054599 -277.825231)
			(xy 393.055094 -277.849838) (xy 393.394196 -277.849838) (xy 393.398156 -277.800784) (xy 393.409933 -277.753)
			(xy 393.429224 -277.707724) (xy 393.455527 -277.666128) (xy 393.488162 -277.629291) (xy 393.526283 -277.598166)
			(xy 393.568904 -277.573559) (xy 393.61492 -277.556107) (xy 393.663139 -277.546263) (xy 393.712314 -277.544282)
			(xy 393.761169 -277.550214) (xy 393.80844 -277.563906) (xy 393.852902 -277.585004) (xy 393.893405 -277.61296)
			(xy 393.928898 -277.647052) (xy 393.958463 -277.686396) (xy 393.981334 -277.729973) (xy 393.996918 -277.776654)
			(xy 394.004813 -277.825231) (xy 394.005308 -277.849838) (xy 394.344156 -277.849838) (xy 394.348116 -277.800784)
			(xy 394.359893 -277.753) (xy 394.379184 -277.707724) (xy 394.405487 -277.666128) (xy 394.438122 -277.629291)
			(xy 394.476243 -277.598166) (xy 394.518864 -277.573559) (xy 394.56488 -277.556107) (xy 394.613099 -277.546263)
			(xy 394.662274 -277.544282) (xy 394.711129 -277.550214) (xy 394.7584 -277.563906) (xy 394.802862 -277.585004)
			(xy 394.843365 -277.61296) (xy 394.878858 -277.647052) (xy 394.908423 -277.686396) (xy 394.931294 -277.729973)
			(xy 394.946878 -277.776654) (xy 394.954773 -277.825231) (xy 394.955268 -277.849838) (xy 395.294116 -277.849838)
			(xy 395.298076 -277.800784) (xy 395.309853 -277.753) (xy 395.329144 -277.707724) (xy 395.355447 -277.666128)
			(xy 395.388082 -277.629291) (xy 395.426203 -277.598166) (xy 395.468824 -277.573559) (xy 395.51484 -277.556107)
			(xy 395.563059 -277.546263) (xy 395.612234 -277.544282) (xy 395.661089 -277.550214) (xy 395.70836 -277.563906)
			(xy 395.752822 -277.585004) (xy 395.793325 -277.61296) (xy 395.828818 -277.647052) (xy 395.858383 -277.686396)
			(xy 395.881254 -277.729973) (xy 395.896838 -277.776654) (xy 395.904733 -277.825231) (xy 395.905228 -277.849838)
			(xy 396.244076 -277.849838) (xy 396.248036 -277.800784) (xy 396.259813 -277.753) (xy 396.279104 -277.707724)
			(xy 396.305407 -277.666128) (xy 396.338042 -277.629291) (xy 396.376163 -277.598166) (xy 396.418784 -277.573559)
			(xy 396.4648 -277.556107) (xy 396.513019 -277.546263) (xy 396.562194 -277.544282) (xy 396.611049 -277.550214)
			(xy 396.65832 -277.563906) (xy 396.702782 -277.585004) (xy 396.743285 -277.61296) (xy 396.778778 -277.647052)
			(xy 396.808343 -277.686396) (xy 396.831214 -277.729973) (xy 396.846798 -277.776654) (xy 396.854693 -277.825231)
			(xy 396.855188 -277.849838) (xy 397.194036 -277.849838) (xy 397.197996 -277.800784) (xy 397.209773 -277.753)
			(xy 397.229064 -277.707724) (xy 397.255367 -277.666128) (xy 397.288002 -277.629291) (xy 397.326123 -277.598166)
			(xy 397.368744 -277.573559) (xy 397.41476 -277.556107) (xy 397.462979 -277.546263) (xy 397.512154 -277.544282)
			(xy 397.561009 -277.550214) (xy 397.60828 -277.563906) (xy 397.652742 -277.585004) (xy 397.693245 -277.61296)
			(xy 397.728738 -277.647052) (xy 397.758303 -277.686396) (xy 397.781174 -277.729973) (xy 397.796758 -277.776654)
			(xy 397.804653 -277.825231) (xy 397.805148 -277.849838) (xy 398.143996 -277.849838) (xy 398.147956 -277.800784)
			(xy 398.159733 -277.753) (xy 398.179024 -277.707724) (xy 398.205327 -277.666128) (xy 398.237962 -277.629291)
			(xy 398.276083 -277.598166) (xy 398.318704 -277.573559) (xy 398.36472 -277.556107) (xy 398.412939 -277.546263)
			(xy 398.462114 -277.544282) (xy 398.510969 -277.550214) (xy 398.55824 -277.563906) (xy 398.602702 -277.585004)
			(xy 398.643205 -277.61296) (xy 398.678698 -277.647052) (xy 398.708263 -277.686396) (xy 398.731134 -277.729973)
			(xy 398.746718 -277.776654) (xy 398.754613 -277.825231) (xy 398.755108 -277.849838) (xy 399.09421 -277.849838)
			(xy 399.09817 -277.800784) (xy 399.109947 -277.753) (xy 399.129238 -277.707724) (xy 399.155541 -277.666128)
			(xy 399.188176 -277.629291) (xy 399.226297 -277.598166) (xy 399.268918 -277.573559) (xy 399.314934 -277.556107)
			(xy 399.363153 -277.546263) (xy 399.412328 -277.544282) (xy 399.461183 -277.550214) (xy 399.508454 -277.563906)
			(xy 399.552916 -277.585004) (xy 399.593419 -277.61296) (xy 399.628912 -277.647052) (xy 399.658477 -277.686396)
			(xy 399.681348 -277.729973) (xy 399.696932 -277.776654) (xy 399.704827 -277.825231) (xy 399.705322 -277.849838)
			(xy 400.04417 -277.849838) (xy 400.04813 -277.800784) (xy 400.059907 -277.753) (xy 400.079198 -277.707724)
			(xy 400.105501 -277.666128) (xy 400.138136 -277.629291) (xy 400.176257 -277.598166) (xy 400.218878 -277.573559)
			(xy 400.264894 -277.556107) (xy 400.313113 -277.546263) (xy 400.362288 -277.544282) (xy 400.411143 -277.550214)
			(xy 400.458414 -277.563906) (xy 400.502876 -277.585004) (xy 400.543379 -277.61296) (xy 400.578872 -277.647052)
			(xy 400.608437 -277.686396) (xy 400.631308 -277.729973) (xy 400.646892 -277.776654) (xy 400.654787 -277.825231)
			(xy 400.655282 -277.849838) (xy 400.99413 -277.849838) (xy 400.99809 -277.800784) (xy 401.009867 -277.753)
			(xy 401.029158 -277.707724) (xy 401.055461 -277.666128) (xy 401.088096 -277.629291) (xy 401.126217 -277.598166)
			(xy 401.168838 -277.573559) (xy 401.214854 -277.556107) (xy 401.263073 -277.546263) (xy 401.312248 -277.544282)
			(xy 401.361103 -277.550214) (xy 401.408374 -277.563906) (xy 401.452836 -277.585004) (xy 401.493339 -277.61296)
			(xy 401.528832 -277.647052) (xy 401.558397 -277.686396) (xy 401.581268 -277.729973) (xy 401.596852 -277.776654)
			(xy 401.604747 -277.825231) (xy 401.605242 -277.849838) (xy 401.94409 -277.849838) (xy 401.94805 -277.800784)
			(xy 401.959827 -277.753) (xy 401.979118 -277.707724) (xy 402.005421 -277.666128) (xy 402.038056 -277.629291)
			(xy 402.076177 -277.598166) (xy 402.118798 -277.573559) (xy 402.164814 -277.556107) (xy 402.213033 -277.546263)
			(xy 402.262208 -277.544282) (xy 402.311063 -277.550214) (xy 402.358334 -277.563906) (xy 402.402796 -277.585004)
			(xy 402.443299 -277.61296) (xy 402.478792 -277.647052) (xy 402.508357 -277.686396) (xy 402.531228 -277.729973)
			(xy 402.546812 -277.776654) (xy 402.554707 -277.825231) (xy 402.555202 -277.849838) (xy 402.89405 -277.849838)
			(xy 402.89801 -277.800784) (xy 402.909787 -277.753) (xy 402.929078 -277.707724) (xy 402.955381 -277.666128)
			(xy 402.988016 -277.629291) (xy 403.026137 -277.598166) (xy 403.068758 -277.573559) (xy 403.114774 -277.556107)
			(xy 403.162993 -277.546263) (xy 403.212168 -277.544282) (xy 403.261023 -277.550214) (xy 403.308294 -277.563906)
			(xy 403.352756 -277.585004) (xy 403.393259 -277.61296) (xy 403.428752 -277.647052) (xy 403.458317 -277.686396)
			(xy 403.481188 -277.729973) (xy 403.496772 -277.776654) (xy 403.504667 -277.825231) (xy 403.505162 -277.849838)
			(xy 403.84401 -277.849838) (xy 403.84797 -277.800784) (xy 403.859747 -277.753) (xy 403.879038 -277.707724)
			(xy 403.905341 -277.666128) (xy 403.937976 -277.629291) (xy 403.976097 -277.598166) (xy 404.018718 -277.573559)
			(xy 404.064734 -277.556107) (xy 404.112953 -277.546263) (xy 404.162128 -277.544282) (xy 404.210983 -277.550214)
			(xy 404.258254 -277.563906) (xy 404.302716 -277.585004) (xy 404.343219 -277.61296) (xy 404.378712 -277.647052)
			(xy 404.408277 -277.686396) (xy 404.431148 -277.729973) (xy 404.446732 -277.776654) (xy 404.454627 -277.825231)
			(xy 404.455122 -277.849838) (xy 404.794224 -277.849838) (xy 404.798184 -277.800784) (xy 404.809961 -277.753)
			(xy 404.829252 -277.707724) (xy 404.855555 -277.666128) (xy 404.88819 -277.629291) (xy 404.926311 -277.598166)
			(xy 404.968932 -277.573559) (xy 405.014948 -277.556107) (xy 405.063167 -277.546263) (xy 405.112342 -277.544282)
			(xy 405.161197 -277.550214) (xy 405.208468 -277.563906) (xy 405.25293 -277.585004) (xy 405.293433 -277.61296)
			(xy 405.328926 -277.647052) (xy 405.358491 -277.686396) (xy 405.381362 -277.729973) (xy 405.396946 -277.776654)
			(xy 405.404841 -277.825231) (xy 405.405336 -277.849838) (xy 405.744184 -277.849838) (xy 405.748144 -277.800784)
			(xy 405.759921 -277.753) (xy 405.779212 -277.707724) (xy 405.805515 -277.666128) (xy 405.83815 -277.629291)
			(xy 405.876271 -277.598166) (xy 405.918892 -277.573559) (xy 405.964908 -277.556107) (xy 406.013127 -277.546263)
			(xy 406.062302 -277.544282) (xy 406.111157 -277.550214) (xy 406.158428 -277.563906) (xy 406.20289 -277.585004)
			(xy 406.243393 -277.61296) (xy 406.278886 -277.647052) (xy 406.308451 -277.686396) (xy 406.331322 -277.729973)
			(xy 406.346906 -277.776654) (xy 406.354801 -277.825231) (xy 406.355296 -277.849838) (xy 406.694144 -277.849838)
			(xy 406.698104 -277.800784) (xy 406.709881 -277.753) (xy 406.729172 -277.707724) (xy 406.755475 -277.666128)
			(xy 406.78811 -277.629291) (xy 406.826231 -277.598166) (xy 406.868852 -277.573559) (xy 406.914868 -277.556107)
			(xy 406.963087 -277.546263) (xy 407.012262 -277.544282) (xy 407.061117 -277.550214) (xy 407.108388 -277.563906)
			(xy 407.15285 -277.585004) (xy 407.193353 -277.61296) (xy 407.228846 -277.647052) (xy 407.258411 -277.686396)
			(xy 407.281282 -277.729973) (xy 407.296866 -277.776654) (xy 407.304761 -277.825231) (xy 407.305256 -277.849838)
			(xy 407.304761 -277.874445) (xy 407.296866 -277.923022) (xy 407.281282 -277.969703) (xy 407.258411 -278.01328)
			(xy 407.228846 -278.052624) (xy 407.193353 -278.086716) (xy 407.15285 -278.114672) (xy 407.108388 -278.13577)
			(xy 407.061117 -278.149462) (xy 407.012262 -278.155394) (xy 406.963087 -278.153413) (xy 406.914868 -278.143569)
			(xy 406.868852 -278.126117) (xy 406.826231 -278.10151) (xy 406.78811 -278.070385) (xy 406.755475 -278.033548)
			(xy 406.729172 -277.991952) (xy 406.709881 -277.946676) (xy 406.698104 -277.898892) (xy 406.694144 -277.849838)
			(xy 406.355296 -277.849838) (xy 406.354801 -277.874445) (xy 406.346906 -277.923022) (xy 406.331322 -277.969703)
			(xy 406.308451 -278.01328) (xy 406.278886 -278.052624) (xy 406.243393 -278.086716) (xy 406.20289 -278.114672)
			(xy 406.158428 -278.13577) (xy 406.111157 -278.149462) (xy 406.062302 -278.155394) (xy 406.013127 -278.153413)
			(xy 405.964908 -278.143569) (xy 405.918892 -278.126117) (xy 405.876271 -278.10151) (xy 405.83815 -278.070385)
			(xy 405.805515 -278.033548) (xy 405.779212 -277.991952) (xy 405.759921 -277.946676) (xy 405.748144 -277.898892)
			(xy 405.744184 -277.849838) (xy 405.405336 -277.849838) (xy 405.404841 -277.874445) (xy 405.396946 -277.923022)
			(xy 405.381362 -277.969703) (xy 405.358491 -278.01328) (xy 405.328926 -278.052624) (xy 405.293433 -278.086716)
			(xy 405.25293 -278.114672) (xy 405.208468 -278.13577) (xy 405.161197 -278.149462) (xy 405.112342 -278.155394)
			(xy 405.063167 -278.153413) (xy 405.014948 -278.143569) (xy 404.968932 -278.126117) (xy 404.926311 -278.10151)
			(xy 404.88819 -278.070385) (xy 404.855555 -278.033548) (xy 404.829252 -277.991952) (xy 404.809961 -277.946676)
			(xy 404.798184 -277.898892) (xy 404.794224 -277.849838) (xy 404.455122 -277.849838) (xy 404.454627 -277.874445)
			(xy 404.446732 -277.923022) (xy 404.431148 -277.969703) (xy 404.408277 -278.01328) (xy 404.378712 -278.052624)
			(xy 404.343219 -278.086716) (xy 404.302716 -278.114672) (xy 404.258254 -278.13577) (xy 404.210983 -278.149462)
			(xy 404.162128 -278.155394) (xy 404.112953 -278.153413) (xy 404.064734 -278.143569) (xy 404.018718 -278.126117)
			(xy 403.976097 -278.10151) (xy 403.937976 -278.070385) (xy 403.905341 -278.033548) (xy 403.879038 -277.991952)
			(xy 403.859747 -277.946676) (xy 403.84797 -277.898892) (xy 403.84401 -277.849838) (xy 403.505162 -277.849838)
			(xy 403.504667 -277.874445) (xy 403.496772 -277.923022) (xy 403.481188 -277.969703) (xy 403.458317 -278.01328)
			(xy 403.428752 -278.052624) (xy 403.393259 -278.086716) (xy 403.352756 -278.114672) (xy 403.308294 -278.13577)
			(xy 403.261023 -278.149462) (xy 403.212168 -278.155394) (xy 403.162993 -278.153413) (xy 403.114774 -278.143569)
			(xy 403.068758 -278.126117) (xy 403.026137 -278.10151) (xy 402.988016 -278.070385) (xy 402.955381 -278.033548)
			(xy 402.929078 -277.991952) (xy 402.909787 -277.946676) (xy 402.89801 -277.898892) (xy 402.89405 -277.849838)
			(xy 402.555202 -277.849838) (xy 402.554707 -277.874445) (xy 402.546812 -277.923022) (xy 402.531228 -277.969703)
			(xy 402.508357 -278.01328) (xy 402.478792 -278.052624) (xy 402.443299 -278.086716) (xy 402.402796 -278.114672)
			(xy 402.358334 -278.13577) (xy 402.311063 -278.149462) (xy 402.262208 -278.155394) (xy 402.213033 -278.153413)
			(xy 402.164814 -278.143569) (xy 402.118798 -278.126117) (xy 402.076177 -278.10151) (xy 402.038056 -278.070385)
			(xy 402.005421 -278.033548) (xy 401.979118 -277.991952) (xy 401.959827 -277.946676) (xy 401.94805 -277.898892)
			(xy 401.94409 -277.849838) (xy 401.605242 -277.849838) (xy 401.604747 -277.874445) (xy 401.596852 -277.923022)
			(xy 401.581268 -277.969703) (xy 401.558397 -278.01328) (xy 401.528832 -278.052624) (xy 401.493339 -278.086716)
			(xy 401.452836 -278.114672) (xy 401.408374 -278.13577) (xy 401.361103 -278.149462) (xy 401.312248 -278.155394)
			(xy 401.263073 -278.153413) (xy 401.214854 -278.143569) (xy 401.168838 -278.126117) (xy 401.126217 -278.10151)
			(xy 401.088096 -278.070385) (xy 401.055461 -278.033548) (xy 401.029158 -277.991952) (xy 401.009867 -277.946676)
			(xy 400.99809 -277.898892) (xy 400.99413 -277.849838) (xy 400.655282 -277.849838) (xy 400.654787 -277.874445)
			(xy 400.646892 -277.923022) (xy 400.631308 -277.969703) (xy 400.608437 -278.01328) (xy 400.578872 -278.052624)
			(xy 400.543379 -278.086716) (xy 400.502876 -278.114672) (xy 400.458414 -278.13577) (xy 400.411143 -278.149462)
			(xy 400.362288 -278.155394) (xy 400.313113 -278.153413) (xy 400.264894 -278.143569) (xy 400.218878 -278.126117)
			(xy 400.176257 -278.10151) (xy 400.138136 -278.070385) (xy 400.105501 -278.033548) (xy 400.079198 -277.991952)
			(xy 400.059907 -277.946676) (xy 400.04813 -277.898892) (xy 400.04417 -277.849838) (xy 399.705322 -277.849838)
			(xy 399.704827 -277.874445) (xy 399.696932 -277.923022) (xy 399.681348 -277.969703) (xy 399.658477 -278.01328)
			(xy 399.628912 -278.052624) (xy 399.593419 -278.086716) (xy 399.552916 -278.114672) (xy 399.508454 -278.13577)
			(xy 399.461183 -278.149462) (xy 399.412328 -278.155394) (xy 399.363153 -278.153413) (xy 399.314934 -278.143569)
			(xy 399.268918 -278.126117) (xy 399.226297 -278.10151) (xy 399.188176 -278.070385) (xy 399.155541 -278.033548)
			(xy 399.129238 -277.991952) (xy 399.109947 -277.946676) (xy 399.09817 -277.898892) (xy 399.09421 -277.849838)
			(xy 398.755108 -277.849838) (xy 398.754613 -277.874445) (xy 398.746718 -277.923022) (xy 398.731134 -277.969703)
			(xy 398.708263 -278.01328) (xy 398.678698 -278.052624) (xy 398.643205 -278.086716) (xy 398.602702 -278.114672)
			(xy 398.55824 -278.13577) (xy 398.510969 -278.149462) (xy 398.462114 -278.155394) (xy 398.412939 -278.153413)
			(xy 398.36472 -278.143569) (xy 398.318704 -278.126117) (xy 398.276083 -278.10151) (xy 398.237962 -278.070385)
			(xy 398.205327 -278.033548) (xy 398.179024 -277.991952) (xy 398.159733 -277.946676) (xy 398.147956 -277.898892)
			(xy 398.143996 -277.849838) (xy 397.805148 -277.849838) (xy 397.804653 -277.874445) (xy 397.796758 -277.923022)
			(xy 397.781174 -277.969703) (xy 397.758303 -278.01328) (xy 397.728738 -278.052624) (xy 397.693245 -278.086716)
			(xy 397.652742 -278.114672) (xy 397.60828 -278.13577) (xy 397.561009 -278.149462) (xy 397.512154 -278.155394)
			(xy 397.462979 -278.153413) (xy 397.41476 -278.143569) (xy 397.368744 -278.126117) (xy 397.326123 -278.10151)
			(xy 397.288002 -278.070385) (xy 397.255367 -278.033548) (xy 397.229064 -277.991952) (xy 397.209773 -277.946676)
			(xy 397.197996 -277.898892) (xy 397.194036 -277.849838) (xy 396.855188 -277.849838) (xy 396.854693 -277.874445)
			(xy 396.846798 -277.923022) (xy 396.831214 -277.969703) (xy 396.808343 -278.01328) (xy 396.778778 -278.052624)
			(xy 396.743285 -278.086716) (xy 396.702782 -278.114672) (xy 396.65832 -278.13577) (xy 396.611049 -278.149462)
			(xy 396.562194 -278.155394) (xy 396.513019 -278.153413) (xy 396.4648 -278.143569) (xy 396.418784 -278.126117)
			(xy 396.376163 -278.10151) (xy 396.338042 -278.070385) (xy 396.305407 -278.033548) (xy 396.279104 -277.991952)
			(xy 396.259813 -277.946676) (xy 396.248036 -277.898892) (xy 396.244076 -277.849838) (xy 395.905228 -277.849838)
			(xy 395.904733 -277.874445) (xy 395.896838 -277.923022) (xy 395.881254 -277.969703) (xy 395.858383 -278.01328)
			(xy 395.828818 -278.052624) (xy 395.793325 -278.086716) (xy 395.752822 -278.114672) (xy 395.70836 -278.13577)
			(xy 395.661089 -278.149462) (xy 395.612234 -278.155394) (xy 395.563059 -278.153413) (xy 395.51484 -278.143569)
			(xy 395.468824 -278.126117) (xy 395.426203 -278.10151) (xy 395.388082 -278.070385) (xy 395.355447 -278.033548)
			(xy 395.329144 -277.991952) (xy 395.309853 -277.946676) (xy 395.298076 -277.898892) (xy 395.294116 -277.849838)
			(xy 394.955268 -277.849838) (xy 394.954773 -277.874445) (xy 394.946878 -277.923022) (xy 394.931294 -277.969703)
			(xy 394.908423 -278.01328) (xy 394.878858 -278.052624) (xy 394.843365 -278.086716) (xy 394.802862 -278.114672)
			(xy 394.7584 -278.13577) (xy 394.711129 -278.149462) (xy 394.662274 -278.155394) (xy 394.613099 -278.153413)
			(xy 394.56488 -278.143569) (xy 394.518864 -278.126117) (xy 394.476243 -278.10151) (xy 394.438122 -278.070385)
			(xy 394.405487 -278.033548) (xy 394.379184 -277.991952) (xy 394.359893 -277.946676) (xy 394.348116 -277.898892)
			(xy 394.344156 -277.849838) (xy 394.005308 -277.849838) (xy 394.004813 -277.874445) (xy 393.996918 -277.923022)
			(xy 393.981334 -277.969703) (xy 393.958463 -278.01328) (xy 393.928898 -278.052624) (xy 393.893405 -278.086716)
			(xy 393.852902 -278.114672) (xy 393.80844 -278.13577) (xy 393.761169 -278.149462) (xy 393.712314 -278.155394)
			(xy 393.663139 -278.153413) (xy 393.61492 -278.143569) (xy 393.568904 -278.126117) (xy 393.526283 -278.10151)
			(xy 393.488162 -278.070385) (xy 393.455527 -278.033548) (xy 393.429224 -277.991952) (xy 393.409933 -277.946676)
			(xy 393.398156 -277.898892) (xy 393.394196 -277.849838) (xy 393.055094 -277.849838) (xy 393.054599 -277.874445)
			(xy 393.046704 -277.923022) (xy 393.03112 -277.969703) (xy 393.008249 -278.01328) (xy 392.978684 -278.052624)
			(xy 392.943191 -278.086716) (xy 392.902688 -278.114672) (xy 392.858226 -278.13577) (xy 392.810955 -278.149462)
			(xy 392.7621 -278.155394) (xy 392.712925 -278.153413) (xy 392.664706 -278.143569) (xy 392.61869 -278.126117)
			(xy 392.576069 -278.10151) (xy 392.537948 -278.070385) (xy 392.505313 -278.033548) (xy 392.47901 -277.991952)
			(xy 392.459719 -277.946676) (xy 392.447942 -277.898892) (xy 392.443982 -277.849838) (xy 371.283769 -277.849838)
			(xy 371.212905 -277.955892) (xy 371.114103 -278.089112) (xy 371.008882 -278.217324) (xy 370.911455 -278.324818)
			(xy 384.369068 -278.324818) (xy 384.373028 -278.275764) (xy 384.384805 -278.22798) (xy 384.404096 -278.182704)
			(xy 384.430399 -278.141108) (xy 384.463034 -278.104271) (xy 384.501155 -278.073146) (xy 384.543776 -278.048539)
			(xy 384.589792 -278.031087) (xy 384.638011 -278.021243) (xy 384.687186 -278.019262) (xy 384.736041 -278.025194)
			(xy 384.783312 -278.038886) (xy 384.827774 -278.059984) (xy 384.868277 -278.08794) (xy 384.90377 -278.122032)
			(xy 384.933335 -278.161376) (xy 384.956206 -278.204953) (xy 384.97179 -278.251634) (xy 384.979685 -278.300211)
			(xy 384.98018 -278.324818) (xy 385.319028 -278.324818) (xy 385.322988 -278.275764) (xy 385.334765 -278.22798)
			(xy 385.354056 -278.182704) (xy 385.380359 -278.141108) (xy 385.412994 -278.104271) (xy 385.451115 -278.073146)
			(xy 385.493736 -278.048539) (xy 385.539752 -278.031087) (xy 385.587971 -278.021243) (xy 385.637146 -278.019262)
			(xy 385.686001 -278.025194) (xy 385.733272 -278.038886) (xy 385.777734 -278.059984) (xy 385.818237 -278.08794)
			(xy 385.85373 -278.122032) (xy 385.883295 -278.161376) (xy 385.906166 -278.204953) (xy 385.92175 -278.251634)
			(xy 385.929645 -278.300211) (xy 385.93014 -278.324818) (xy 386.269242 -278.324818) (xy 386.273202 -278.275764)
			(xy 386.284979 -278.22798) (xy 386.30427 -278.182704) (xy 386.330573 -278.141108) (xy 386.363208 -278.104271)
			(xy 386.401329 -278.073146) (xy 386.44395 -278.048539) (xy 386.489966 -278.031087) (xy 386.538185 -278.021243)
			(xy 386.58736 -278.019262) (xy 386.636215 -278.025194) (xy 386.683486 -278.038886) (xy 386.727948 -278.059984)
			(xy 386.768451 -278.08794) (xy 386.803944 -278.122032) (xy 386.833509 -278.161376) (xy 386.85638 -278.204953)
			(xy 386.871964 -278.251634) (xy 386.879859 -278.300211) (xy 386.880354 -278.324818) (xy 387.219202 -278.324818)
			(xy 387.223162 -278.275764) (xy 387.234939 -278.22798) (xy 387.25423 -278.182704) (xy 387.280533 -278.141108)
			(xy 387.313168 -278.104271) (xy 387.351289 -278.073146) (xy 387.39391 -278.048539) (xy 387.439926 -278.031087)
			(xy 387.488145 -278.021243) (xy 387.53732 -278.019262) (xy 387.586175 -278.025194) (xy 387.633446 -278.038886)
			(xy 387.677908 -278.059984) (xy 387.718411 -278.08794) (xy 387.753904 -278.122032) (xy 387.783469 -278.161376)
			(xy 387.80634 -278.204953) (xy 387.821924 -278.251634) (xy 387.829819 -278.300211) (xy 387.830314 -278.324818)
			(xy 388.169162 -278.324818) (xy 388.173122 -278.275764) (xy 388.184899 -278.22798) (xy 388.20419 -278.182704)
			(xy 388.230493 -278.141108) (xy 388.263128 -278.104271) (xy 388.301249 -278.073146) (xy 388.34387 -278.048539)
			(xy 388.389886 -278.031087) (xy 388.438105 -278.021243) (xy 388.48728 -278.019262) (xy 388.536135 -278.025194)
			(xy 388.583406 -278.038886) (xy 388.627868 -278.059984) (xy 388.668371 -278.08794) (xy 388.703864 -278.122032)
			(xy 388.733429 -278.161376) (xy 388.7563 -278.204953) (xy 388.771884 -278.251634) (xy 388.779779 -278.300211)
			(xy 388.780274 -278.324818) (xy 389.119122 -278.324818) (xy 389.123082 -278.275764) (xy 389.134859 -278.22798)
			(xy 389.15415 -278.182704) (xy 389.180453 -278.141108) (xy 389.213088 -278.104271) (xy 389.251209 -278.073146)
			(xy 389.29383 -278.048539) (xy 389.339846 -278.031087) (xy 389.388065 -278.021243) (xy 389.43724 -278.019262)
			(xy 389.486095 -278.025194) (xy 389.533366 -278.038886) (xy 389.577828 -278.059984) (xy 389.618331 -278.08794)
			(xy 389.653824 -278.122032) (xy 389.683389 -278.161376) (xy 389.70626 -278.204953) (xy 389.721844 -278.251634)
			(xy 389.729739 -278.300211) (xy 389.730234 -278.324818) (xy 390.069082 -278.324818) (xy 390.073042 -278.275764)
			(xy 390.084819 -278.22798) (xy 390.10411 -278.182704) (xy 390.130413 -278.141108) (xy 390.163048 -278.104271)
			(xy 390.201169 -278.073146) (xy 390.24379 -278.048539) (xy 390.289806 -278.031087) (xy 390.338025 -278.021243)
			(xy 390.3872 -278.019262) (xy 390.436055 -278.025194) (xy 390.483326 -278.038886) (xy 390.527788 -278.059984)
			(xy 390.568291 -278.08794) (xy 390.603784 -278.122032) (xy 390.633349 -278.161376) (xy 390.65622 -278.204953)
			(xy 390.671804 -278.251634) (xy 390.679699 -278.300211) (xy 390.680194 -278.324818) (xy 391.019042 -278.324818)
			(xy 391.023002 -278.275764) (xy 391.034779 -278.22798) (xy 391.05407 -278.182704) (xy 391.080373 -278.141108)
			(xy 391.113008 -278.104271) (xy 391.151129 -278.073146) (xy 391.19375 -278.048539) (xy 391.239766 -278.031087)
			(xy 391.287985 -278.021243) (xy 391.33716 -278.019262) (xy 391.386015 -278.025194) (xy 391.433286 -278.038886)
			(xy 391.477748 -278.059984) (xy 391.518251 -278.08794) (xy 391.553744 -278.122032) (xy 391.583309 -278.161376)
			(xy 391.60618 -278.204953) (xy 391.621764 -278.251634) (xy 391.629659 -278.300211) (xy 391.630154 -278.324818)
			(xy 391.629659 -278.349425) (xy 391.621764 -278.398002) (xy 391.60618 -278.444683) (xy 391.583309 -278.48826)
			(xy 391.553744 -278.527604) (xy 391.518251 -278.561696) (xy 391.477748 -278.589652) (xy 391.433286 -278.61075)
			(xy 391.386015 -278.624442) (xy 391.33716 -278.630374) (xy 391.287985 -278.628393) (xy 391.239766 -278.618549)
			(xy 391.19375 -278.601097) (xy 391.151129 -278.57649) (xy 391.113008 -278.545365) (xy 391.080373 -278.508528)
			(xy 391.05407 -278.466932) (xy 391.034779 -278.421656) (xy 391.023002 -278.373872) (xy 391.019042 -278.324818)
			(xy 390.680194 -278.324818) (xy 390.679699 -278.349425) (xy 390.671804 -278.398002) (xy 390.65622 -278.444683)
			(xy 390.633349 -278.48826) (xy 390.603784 -278.527604) (xy 390.568291 -278.561696) (xy 390.527788 -278.589652)
			(xy 390.483326 -278.61075) (xy 390.436055 -278.624442) (xy 390.3872 -278.630374) (xy 390.338025 -278.628393)
			(xy 390.289806 -278.618549) (xy 390.24379 -278.601097) (xy 390.201169 -278.57649) (xy 390.163048 -278.545365)
			(xy 390.130413 -278.508528) (xy 390.10411 -278.466932) (xy 390.084819 -278.421656) (xy 390.073042 -278.373872)
			(xy 390.069082 -278.324818) (xy 389.730234 -278.324818) (xy 389.729739 -278.349425) (xy 389.721844 -278.398002)
			(xy 389.70626 -278.444683) (xy 389.683389 -278.48826) (xy 389.653824 -278.527604) (xy 389.618331 -278.561696)
			(xy 389.577828 -278.589652) (xy 389.533366 -278.61075) (xy 389.486095 -278.624442) (xy 389.43724 -278.630374)
			(xy 389.388065 -278.628393) (xy 389.339846 -278.618549) (xy 389.29383 -278.601097) (xy 389.251209 -278.57649)
			(xy 389.213088 -278.545365) (xy 389.180453 -278.508528) (xy 389.15415 -278.466932) (xy 389.134859 -278.421656)
			(xy 389.123082 -278.373872) (xy 389.119122 -278.324818) (xy 388.780274 -278.324818) (xy 388.779779 -278.349425)
			(xy 388.771884 -278.398002) (xy 388.7563 -278.444683) (xy 388.733429 -278.48826) (xy 388.703864 -278.527604)
			(xy 388.668371 -278.561696) (xy 388.627868 -278.589652) (xy 388.583406 -278.61075) (xy 388.536135 -278.624442)
			(xy 388.48728 -278.630374) (xy 388.438105 -278.628393) (xy 388.389886 -278.618549) (xy 388.34387 -278.601097)
			(xy 388.301249 -278.57649) (xy 388.263128 -278.545365) (xy 388.230493 -278.508528) (xy 388.20419 -278.466932)
			(xy 388.184899 -278.421656) (xy 388.173122 -278.373872) (xy 388.169162 -278.324818) (xy 387.830314 -278.324818)
			(xy 387.829819 -278.349425) (xy 387.821924 -278.398002) (xy 387.80634 -278.444683) (xy 387.783469 -278.48826)
			(xy 387.753904 -278.527604) (xy 387.718411 -278.561696) (xy 387.677908 -278.589652) (xy 387.633446 -278.61075)
			(xy 387.586175 -278.624442) (xy 387.53732 -278.630374) (xy 387.488145 -278.628393) (xy 387.439926 -278.618549)
			(xy 387.39391 -278.601097) (xy 387.351289 -278.57649) (xy 387.313168 -278.545365) (xy 387.280533 -278.508528)
			(xy 387.25423 -278.466932) (xy 387.234939 -278.421656) (xy 387.223162 -278.373872) (xy 387.219202 -278.324818)
			(xy 386.880354 -278.324818) (xy 386.879859 -278.349425) (xy 386.871964 -278.398002) (xy 386.85638 -278.444683)
			(xy 386.833509 -278.48826) (xy 386.803944 -278.527604) (xy 386.768451 -278.561696) (xy 386.727948 -278.589652)
			(xy 386.683486 -278.61075) (xy 386.636215 -278.624442) (xy 386.58736 -278.630374) (xy 386.538185 -278.628393)
			(xy 386.489966 -278.618549) (xy 386.44395 -278.601097) (xy 386.401329 -278.57649) (xy 386.363208 -278.545365)
			(xy 386.330573 -278.508528) (xy 386.30427 -278.466932) (xy 386.284979 -278.421656) (xy 386.273202 -278.373872)
			(xy 386.269242 -278.324818) (xy 385.93014 -278.324818) (xy 385.929645 -278.349425) (xy 385.92175 -278.398002)
			(xy 385.906166 -278.444683) (xy 385.883295 -278.48826) (xy 385.85373 -278.527604) (xy 385.818237 -278.561696)
			(xy 385.777734 -278.589652) (xy 385.733272 -278.61075) (xy 385.686001 -278.624442) (xy 385.637146 -278.630374)
			(xy 385.587971 -278.628393) (xy 385.539752 -278.618549) (xy 385.493736 -278.601097) (xy 385.451115 -278.57649)
			(xy 385.412994 -278.545365) (xy 385.380359 -278.508528) (xy 385.354056 -278.466932) (xy 385.334765 -278.421656)
			(xy 385.322988 -278.373872) (xy 385.319028 -278.324818) (xy 384.98018 -278.324818) (xy 384.979685 -278.349425)
			(xy 384.97179 -278.398002) (xy 384.956206 -278.444683) (xy 384.933335 -278.48826) (xy 384.90377 -278.527604)
			(xy 384.868277 -278.561696) (xy 384.827774 -278.589652) (xy 384.783312 -278.61075) (xy 384.736041 -278.624442)
			(xy 384.687186 -278.630374) (xy 384.638011 -278.628393) (xy 384.589792 -278.618549) (xy 384.543776 -278.601097)
			(xy 384.501155 -278.57649) (xy 384.463034 -278.545365) (xy 384.430399 -278.508528) (xy 384.404096 -278.466932)
			(xy 384.384805 -278.421656) (xy 384.373028 -278.373872) (xy 384.369068 -278.324818) (xy 370.911455 -278.324818)
			(xy 370.897497 -278.340218) (xy 370.780216 -278.457499) (xy 370.657322 -278.568883) (xy 370.529111 -278.674104)
			(xy 370.395891 -278.772907) (xy 370.257983 -278.865054) (xy 370.11572 -278.950323) (xy 369.969445 -279.028509)
			(xy 369.81951 -279.099424) (xy 369.666275 -279.162896) (xy 369.510111 -279.218773) (xy 369.351393 -279.26692)
			(xy 369.320022 -279.274778) (xy 384.369068 -279.274778) (xy 384.373028 -279.225724) (xy 384.384805 -279.17794)
			(xy 384.404096 -279.132664) (xy 384.430399 -279.091068) (xy 384.463034 -279.054231) (xy 384.501155 -279.023106)
			(xy 384.543776 -278.998499) (xy 384.589792 -278.981047) (xy 384.638011 -278.971203) (xy 384.687186 -278.969222)
			(xy 384.736041 -278.975154) (xy 384.783312 -278.988846) (xy 384.827774 -279.009944) (xy 384.868277 -279.0379)
			(xy 384.90377 -279.071992) (xy 384.933335 -279.111336) (xy 384.956206 -279.154913) (xy 384.97179 -279.201594)
			(xy 384.979685 -279.250171) (xy 384.98018 -279.274778) (xy 385.319028 -279.274778) (xy 385.322988 -279.225724)
			(xy 385.334765 -279.17794) (xy 385.354056 -279.132664) (xy 385.380359 -279.091068) (xy 385.412994 -279.054231)
			(xy 385.451115 -279.023106) (xy 385.493736 -278.998499) (xy 385.539752 -278.981047) (xy 385.587971 -278.971203)
			(xy 385.637146 -278.969222) (xy 385.686001 -278.975154) (xy 385.733272 -278.988846) (xy 385.777734 -279.009944)
			(xy 385.818237 -279.0379) (xy 385.85373 -279.071992) (xy 385.883295 -279.111336) (xy 385.906166 -279.154913)
			(xy 385.92175 -279.201594) (xy 385.929645 -279.250171) (xy 385.93014 -279.274778) (xy 386.269242 -279.274778)
			(xy 386.273202 -279.225724) (xy 386.284979 -279.17794) (xy 386.30427 -279.132664) (xy 386.330573 -279.091068)
			(xy 386.363208 -279.054231) (xy 386.401329 -279.023106) (xy 386.44395 -278.998499) (xy 386.489966 -278.981047)
			(xy 386.538185 -278.971203) (xy 386.58736 -278.969222) (xy 386.636215 -278.975154) (xy 386.683486 -278.988846)
			(xy 386.727948 -279.009944) (xy 386.768451 -279.0379) (xy 386.803944 -279.071992) (xy 386.833509 -279.111336)
			(xy 386.85638 -279.154913) (xy 386.871964 -279.201594) (xy 386.879859 -279.250171) (xy 386.880354 -279.274778)
			(xy 387.219202 -279.274778) (xy 387.223162 -279.225724) (xy 387.234939 -279.17794) (xy 387.25423 -279.132664)
			(xy 387.280533 -279.091068) (xy 387.313168 -279.054231) (xy 387.351289 -279.023106) (xy 387.39391 -278.998499)
			(xy 387.439926 -278.981047) (xy 387.488145 -278.971203) (xy 387.53732 -278.969222) (xy 387.586175 -278.975154)
			(xy 387.633446 -278.988846) (xy 387.677908 -279.009944) (xy 387.718411 -279.0379) (xy 387.753904 -279.071992)
			(xy 387.783469 -279.111336) (xy 387.80634 -279.154913) (xy 387.821924 -279.201594) (xy 387.829819 -279.250171)
			(xy 387.830314 -279.274778) (xy 388.169162 -279.274778) (xy 388.173122 -279.225724) (xy 388.184899 -279.17794)
			(xy 388.20419 -279.132664) (xy 388.230493 -279.091068) (xy 388.263128 -279.054231) (xy 388.301249 -279.023106)
			(xy 388.34387 -278.998499) (xy 388.389886 -278.981047) (xy 388.438105 -278.971203) (xy 388.48728 -278.969222)
			(xy 388.536135 -278.975154) (xy 388.583406 -278.988846) (xy 388.627868 -279.009944) (xy 388.668371 -279.0379)
			(xy 388.703864 -279.071992) (xy 388.733429 -279.111336) (xy 388.7563 -279.154913) (xy 388.771884 -279.201594)
			(xy 388.779779 -279.250171) (xy 388.780274 -279.274778) (xy 389.119122 -279.274778) (xy 389.123082 -279.225724)
			(xy 389.134859 -279.17794) (xy 389.15415 -279.132664) (xy 389.180453 -279.091068) (xy 389.213088 -279.054231)
			(xy 389.251209 -279.023106) (xy 389.29383 -278.998499) (xy 389.339846 -278.981047) (xy 389.388065 -278.971203)
			(xy 389.43724 -278.969222) (xy 389.486095 -278.975154) (xy 389.533366 -278.988846) (xy 389.577828 -279.009944)
			(xy 389.618331 -279.0379) (xy 389.653824 -279.071992) (xy 389.683389 -279.111336) (xy 389.70626 -279.154913)
			(xy 389.721844 -279.201594) (xy 389.729739 -279.250171) (xy 389.730234 -279.274778) (xy 390.069082 -279.274778)
			(xy 390.073042 -279.225724) (xy 390.084819 -279.17794) (xy 390.10411 -279.132664) (xy 390.130413 -279.091068)
			(xy 390.163048 -279.054231) (xy 390.201169 -279.023106) (xy 390.24379 -278.998499) (xy 390.289806 -278.981047)
			(xy 390.338025 -278.971203) (xy 390.3872 -278.969222) (xy 390.436055 -278.975154) (xy 390.483326 -278.988846)
			(xy 390.527788 -279.009944) (xy 390.568291 -279.0379) (xy 390.603784 -279.071992) (xy 390.633349 -279.111336)
			(xy 390.65622 -279.154913) (xy 390.671804 -279.201594) (xy 390.679699 -279.250171) (xy 390.680194 -279.274778)
			(xy 391.019042 -279.274778) (xy 391.023002 -279.225724) (xy 391.034779 -279.17794) (xy 391.05407 -279.132664)
			(xy 391.080373 -279.091068) (xy 391.113008 -279.054231) (xy 391.151129 -279.023106) (xy 391.19375 -278.998499)
			(xy 391.239766 -278.981047) (xy 391.287985 -278.971203) (xy 391.33716 -278.969222) (xy 391.386015 -278.975154)
			(xy 391.433286 -278.988846) (xy 391.477748 -279.009944) (xy 391.518251 -279.0379) (xy 391.553744 -279.071992)
			(xy 391.583309 -279.111336) (xy 391.60618 -279.154913) (xy 391.621764 -279.201594) (xy 391.629659 -279.250171)
			(xy 391.630154 -279.274778) (xy 391.630154 -279.2748) (xy 391.968918 -279.2748) (xy 391.97309 -279.224453)
			(xy 391.985492 -279.175479) (xy 392.005786 -279.129215) (xy 392.033418 -279.086921) (xy 392.067634 -279.049753)
			(xy 392.107502 -279.018724) (xy 392.151933 -278.99468) (xy 392.199715 -278.978277) (xy 392.249546 -278.969962)
			(xy 392.274806 -278.96947) (xy 392.288989 -278.969646) (xy 392.317229 -278.972319) (xy 392.331194 -278.974804)
			(xy 392.34364 -278.97709) (xy 392.367262 -278.969724) (xy 392.444732 -278.892254) (xy 392.452098 -278.868632)
			(xy 392.449812 -278.856186) (xy 392.447338 -278.84222) (xy 392.444664 -278.81398) (xy 392.444478 -278.799798)
			(xy 392.44498 -278.774977) (xy 392.453012 -278.725989) (xy 392.468863 -278.678946) (xy 392.492116 -278.635087)
			(xy 392.522158 -278.595568) (xy 392.558198 -278.56143) (xy 392.599287 -278.533572) (xy 392.644341 -278.512729)
			(xy 392.692173 -278.499449) (xy 392.741524 -278.494083) (xy 392.791093 -278.496772) (xy 392.839574 -278.507444)
			(xy 392.88569 -278.525819) (xy 392.928225 -278.551414) (xy 392.966059 -278.583552) (xy 392.998196 -278.621388)
			(xy 393.023788 -278.663925) (xy 393.042161 -278.710041) (xy 393.052831 -278.758523) (xy 393.055068 -278.799798)
			(xy 393.394196 -278.799798) (xy 393.398156 -278.750744) (xy 393.409933 -278.70296) (xy 393.429224 -278.657684)
			(xy 393.455527 -278.616088) (xy 393.488162 -278.579251) (xy 393.526283 -278.548126) (xy 393.568904 -278.523519)
			(xy 393.61492 -278.506067) (xy 393.663139 -278.496223) (xy 393.712314 -278.494242) (xy 393.761169 -278.500174)
			(xy 393.80844 -278.513866) (xy 393.852902 -278.534964) (xy 393.893405 -278.56292) (xy 393.928898 -278.597012)
			(xy 393.958463 -278.636356) (xy 393.981334 -278.679933) (xy 393.996918 -278.726614) (xy 394.004813 -278.775191)
			(xy 394.005308 -278.799798) (xy 394.344156 -278.799798) (xy 394.348116 -278.750744) (xy 394.359893 -278.70296)
			(xy 394.379184 -278.657684) (xy 394.405487 -278.616088) (xy 394.438122 -278.579251) (xy 394.476243 -278.548126)
			(xy 394.518864 -278.523519) (xy 394.56488 -278.506067) (xy 394.613099 -278.496223) (xy 394.662274 -278.494242)
			(xy 394.711129 -278.500174) (xy 394.7584 -278.513866) (xy 394.802862 -278.534964) (xy 394.843365 -278.56292)
			(xy 394.878858 -278.597012) (xy 394.908423 -278.636356) (xy 394.931294 -278.679933) (xy 394.946878 -278.726614)
			(xy 394.954773 -278.775191) (xy 394.955268 -278.799798) (xy 395.294116 -278.799798) (xy 395.298076 -278.750744)
			(xy 395.309853 -278.70296) (xy 395.329144 -278.657684) (xy 395.355447 -278.616088) (xy 395.388082 -278.579251)
			(xy 395.426203 -278.548126) (xy 395.468824 -278.523519) (xy 395.51484 -278.506067) (xy 395.563059 -278.496223)
			(xy 395.612234 -278.494242) (xy 395.661089 -278.500174) (xy 395.70836 -278.513866) (xy 395.752822 -278.534964)
			(xy 395.793325 -278.56292) (xy 395.828818 -278.597012) (xy 395.858383 -278.636356) (xy 395.881254 -278.679933)
			(xy 395.896838 -278.726614) (xy 395.904733 -278.775191) (xy 395.905228 -278.799798) (xy 396.244076 -278.799798)
			(xy 396.248036 -278.750744) (xy 396.259813 -278.70296) (xy 396.279104 -278.657684) (xy 396.305407 -278.616088)
			(xy 396.338042 -278.579251) (xy 396.376163 -278.548126) (xy 396.418784 -278.523519) (xy 396.4648 -278.506067)
			(xy 396.513019 -278.496223) (xy 396.562194 -278.494242) (xy 396.611049 -278.500174) (xy 396.65832 -278.513866)
			(xy 396.702782 -278.534964) (xy 396.743285 -278.56292) (xy 396.778778 -278.597012) (xy 396.808343 -278.636356)
			(xy 396.831214 -278.679933) (xy 396.846798 -278.726614) (xy 396.854693 -278.775191) (xy 396.855188 -278.799798)
			(xy 397.194036 -278.799798) (xy 397.197996 -278.750744) (xy 397.209773 -278.70296) (xy 397.229064 -278.657684)
			(xy 397.255367 -278.616088) (xy 397.288002 -278.579251) (xy 397.326123 -278.548126) (xy 397.368744 -278.523519)
			(xy 397.41476 -278.506067) (xy 397.462979 -278.496223) (xy 397.512154 -278.494242) (xy 397.561009 -278.500174)
			(xy 397.60828 -278.513866) (xy 397.652742 -278.534964) (xy 397.693245 -278.56292) (xy 397.728738 -278.597012)
			(xy 397.758303 -278.636356) (xy 397.781174 -278.679933) (xy 397.796758 -278.726614) (xy 397.804653 -278.775191)
			(xy 397.805148 -278.799798) (xy 398.143996 -278.799798) (xy 398.147956 -278.750744) (xy 398.159733 -278.70296)
			(xy 398.179024 -278.657684) (xy 398.205327 -278.616088) (xy 398.237962 -278.579251) (xy 398.276083 -278.548126)
			(xy 398.318704 -278.523519) (xy 398.36472 -278.506067) (xy 398.412939 -278.496223) (xy 398.462114 -278.494242)
			(xy 398.510969 -278.500174) (xy 398.55824 -278.513866) (xy 398.602702 -278.534964) (xy 398.643205 -278.56292)
			(xy 398.678698 -278.597012) (xy 398.708263 -278.636356) (xy 398.731134 -278.679933) (xy 398.746718 -278.726614)
			(xy 398.754613 -278.775191) (xy 398.755108 -278.799798) (xy 399.09421 -278.799798) (xy 399.09817 -278.750744)
			(xy 399.109947 -278.70296) (xy 399.129238 -278.657684) (xy 399.155541 -278.616088) (xy 399.188176 -278.579251)
			(xy 399.226297 -278.548126) (xy 399.268918 -278.523519) (xy 399.314934 -278.506067) (xy 399.363153 -278.496223)
			(xy 399.412328 -278.494242) (xy 399.461183 -278.500174) (xy 399.508454 -278.513866) (xy 399.552916 -278.534964)
			(xy 399.593419 -278.56292) (xy 399.628912 -278.597012) (xy 399.658477 -278.636356) (xy 399.681348 -278.679933)
			(xy 399.696932 -278.726614) (xy 399.704827 -278.775191) (xy 399.705322 -278.799798) (xy 400.04417 -278.799798)
			(xy 400.04813 -278.750744) (xy 400.059907 -278.70296) (xy 400.079198 -278.657684) (xy 400.105501 -278.616088)
			(xy 400.138136 -278.579251) (xy 400.176257 -278.548126) (xy 400.218878 -278.523519) (xy 400.264894 -278.506067)
			(xy 400.313113 -278.496223) (xy 400.362288 -278.494242) (xy 400.411143 -278.500174) (xy 400.458414 -278.513866)
			(xy 400.502876 -278.534964) (xy 400.543379 -278.56292) (xy 400.578872 -278.597012) (xy 400.608437 -278.636356)
			(xy 400.631308 -278.679933) (xy 400.646892 -278.726614) (xy 400.654787 -278.775191) (xy 400.655282 -278.799798)
			(xy 400.99413 -278.799798) (xy 400.99809 -278.750744) (xy 401.009867 -278.70296) (xy 401.029158 -278.657684)
			(xy 401.055461 -278.616088) (xy 401.088096 -278.579251) (xy 401.126217 -278.548126) (xy 401.168838 -278.523519)
			(xy 401.214854 -278.506067) (xy 401.263073 -278.496223) (xy 401.312248 -278.494242) (xy 401.361103 -278.500174)
			(xy 401.408374 -278.513866) (xy 401.452836 -278.534964) (xy 401.493339 -278.56292) (xy 401.528832 -278.597012)
			(xy 401.558397 -278.636356) (xy 401.581268 -278.679933) (xy 401.596852 -278.726614) (xy 401.604747 -278.775191)
			(xy 401.605242 -278.799798) (xy 401.94409 -278.799798) (xy 401.94805 -278.750744) (xy 401.959827 -278.70296)
			(xy 401.979118 -278.657684) (xy 402.005421 -278.616088) (xy 402.038056 -278.579251) (xy 402.076177 -278.548126)
			(xy 402.118798 -278.523519) (xy 402.164814 -278.506067) (xy 402.213033 -278.496223) (xy 402.262208 -278.494242)
			(xy 402.311063 -278.500174) (xy 402.358334 -278.513866) (xy 402.402796 -278.534964) (xy 402.443299 -278.56292)
			(xy 402.478792 -278.597012) (xy 402.508357 -278.636356) (xy 402.531228 -278.679933) (xy 402.546812 -278.726614)
			(xy 402.554707 -278.775191) (xy 402.555202 -278.799798) (xy 402.89405 -278.799798) (xy 402.89801 -278.750744)
			(xy 402.909787 -278.70296) (xy 402.929078 -278.657684) (xy 402.955381 -278.616088) (xy 402.988016 -278.579251)
			(xy 403.026137 -278.548126) (xy 403.068758 -278.523519) (xy 403.114774 -278.506067) (xy 403.162993 -278.496223)
			(xy 403.212168 -278.494242) (xy 403.261023 -278.500174) (xy 403.308294 -278.513866) (xy 403.352756 -278.534964)
			(xy 403.393259 -278.56292) (xy 403.428752 -278.597012) (xy 403.458317 -278.636356) (xy 403.481188 -278.679933)
			(xy 403.496772 -278.726614) (xy 403.504667 -278.775191) (xy 403.505162 -278.799798) (xy 403.84401 -278.799798)
			(xy 403.84797 -278.750744) (xy 403.859747 -278.70296) (xy 403.879038 -278.657684) (xy 403.905341 -278.616088)
			(xy 403.937976 -278.579251) (xy 403.976097 -278.548126) (xy 404.018718 -278.523519) (xy 404.064734 -278.506067)
			(xy 404.112953 -278.496223) (xy 404.162128 -278.494242) (xy 404.210983 -278.500174) (xy 404.258254 -278.513866)
			(xy 404.302716 -278.534964) (xy 404.343219 -278.56292) (xy 404.378712 -278.597012) (xy 404.408277 -278.636356)
			(xy 404.431148 -278.679933) (xy 404.446732 -278.726614) (xy 404.454627 -278.775191) (xy 404.455122 -278.799798)
			(xy 404.794224 -278.799798) (xy 404.798184 -278.750744) (xy 404.809961 -278.70296) (xy 404.829252 -278.657684)
			(xy 404.855555 -278.616088) (xy 404.88819 -278.579251) (xy 404.926311 -278.548126) (xy 404.968932 -278.523519)
			(xy 405.014948 -278.506067) (xy 405.063167 -278.496223) (xy 405.112342 -278.494242) (xy 405.161197 -278.500174)
			(xy 405.208468 -278.513866) (xy 405.25293 -278.534964) (xy 405.293433 -278.56292) (xy 405.328926 -278.597012)
			(xy 405.358491 -278.636356) (xy 405.381362 -278.679933) (xy 405.396946 -278.726614) (xy 405.404841 -278.775191)
			(xy 405.405336 -278.799798) (xy 405.744184 -278.799798) (xy 405.748144 -278.750744) (xy 405.759921 -278.70296)
			(xy 405.779212 -278.657684) (xy 405.805515 -278.616088) (xy 405.83815 -278.579251) (xy 405.876271 -278.548126)
			(xy 405.918892 -278.523519) (xy 405.964908 -278.506067) (xy 406.013127 -278.496223) (xy 406.062302 -278.494242)
			(xy 406.111157 -278.500174) (xy 406.158428 -278.513866) (xy 406.20289 -278.534964) (xy 406.243393 -278.56292)
			(xy 406.278886 -278.597012) (xy 406.308451 -278.636356) (xy 406.331322 -278.679933) (xy 406.346906 -278.726614)
			(xy 406.354801 -278.775191) (xy 406.355296 -278.799798) (xy 406.694144 -278.799798) (xy 406.698104 -278.750744)
			(xy 406.709881 -278.70296) (xy 406.729172 -278.657684) (xy 406.755475 -278.616088) (xy 406.78811 -278.579251)
			(xy 406.826231 -278.548126) (xy 406.868852 -278.523519) (xy 406.914868 -278.506067) (xy 406.963087 -278.496223)
			(xy 407.012262 -278.494242) (xy 407.061117 -278.500174) (xy 407.108388 -278.513866) (xy 407.15285 -278.534964)
			(xy 407.193353 -278.56292) (xy 407.228846 -278.597012) (xy 407.258411 -278.636356) (xy 407.281282 -278.679933)
			(xy 407.296866 -278.726614) (xy 407.304761 -278.775191) (xy 407.305256 -278.799798) (xy 407.304761 -278.824405)
			(xy 407.296866 -278.872982) (xy 407.281282 -278.919663) (xy 407.258411 -278.96324) (xy 407.228846 -279.002584)
			(xy 407.193353 -279.036676) (xy 407.15285 -279.064632) (xy 407.108388 -279.08573) (xy 407.061117 -279.099422)
			(xy 407.012262 -279.105354) (xy 406.963087 -279.103373) (xy 406.914868 -279.093529) (xy 406.868852 -279.076077)
			(xy 406.826231 -279.05147) (xy 406.78811 -279.020345) (xy 406.755475 -278.983508) (xy 406.729172 -278.941912)
			(xy 406.709881 -278.896636) (xy 406.698104 -278.848852) (xy 406.694144 -278.799798) (xy 406.355296 -278.799798)
			(xy 406.354801 -278.824405) (xy 406.346906 -278.872982) (xy 406.331322 -278.919663) (xy 406.308451 -278.96324)
			(xy 406.278886 -279.002584) (xy 406.243393 -279.036676) (xy 406.20289 -279.064632) (xy 406.158428 -279.08573)
			(xy 406.111157 -279.099422) (xy 406.062302 -279.105354) (xy 406.013127 -279.103373) (xy 405.964908 -279.093529)
			(xy 405.918892 -279.076077) (xy 405.876271 -279.05147) (xy 405.83815 -279.020345) (xy 405.805515 -278.983508)
			(xy 405.779212 -278.941912) (xy 405.759921 -278.896636) (xy 405.748144 -278.848852) (xy 405.744184 -278.799798)
			(xy 405.405336 -278.799798) (xy 405.404841 -278.824405) (xy 405.396946 -278.872982) (xy 405.381362 -278.919663)
			(xy 405.358491 -278.96324) (xy 405.328926 -279.002584) (xy 405.293433 -279.036676) (xy 405.25293 -279.064632)
			(xy 405.208468 -279.08573) (xy 405.161197 -279.099422) (xy 405.112342 -279.105354) (xy 405.063167 -279.103373)
			(xy 405.014948 -279.093529) (xy 404.968932 -279.076077) (xy 404.926311 -279.05147) (xy 404.88819 -279.020345)
			(xy 404.855555 -278.983508) (xy 404.829252 -278.941912) (xy 404.809961 -278.896636) (xy 404.798184 -278.848852)
			(xy 404.794224 -278.799798) (xy 404.455122 -278.799798) (xy 404.454627 -278.824405) (xy 404.446732 -278.872982)
			(xy 404.431148 -278.919663) (xy 404.408277 -278.96324) (xy 404.378712 -279.002584) (xy 404.343219 -279.036676)
			(xy 404.302716 -279.064632) (xy 404.258254 -279.08573) (xy 404.210983 -279.099422) (xy 404.162128 -279.105354)
			(xy 404.112953 -279.103373) (xy 404.064734 -279.093529) (xy 404.018718 -279.076077) (xy 403.976097 -279.05147)
			(xy 403.937976 -279.020345) (xy 403.905341 -278.983508) (xy 403.879038 -278.941912) (xy 403.859747 -278.896636)
			(xy 403.84797 -278.848852) (xy 403.84401 -278.799798) (xy 403.505162 -278.799798) (xy 403.504667 -278.824405)
			(xy 403.496772 -278.872982) (xy 403.481188 -278.919663) (xy 403.458317 -278.96324) (xy 403.428752 -279.002584)
			(xy 403.393259 -279.036676) (xy 403.352756 -279.064632) (xy 403.308294 -279.08573) (xy 403.261023 -279.099422)
			(xy 403.212168 -279.105354) (xy 403.162993 -279.103373) (xy 403.114774 -279.093529) (xy 403.068758 -279.076077)
			(xy 403.026137 -279.05147) (xy 402.988016 -279.020345) (xy 402.955381 -278.983508) (xy 402.929078 -278.941912)
			(xy 402.909787 -278.896636) (xy 402.89801 -278.848852) (xy 402.89405 -278.799798) (xy 402.555202 -278.799798)
			(xy 402.554707 -278.824405) (xy 402.546812 -278.872982) (xy 402.531228 -278.919663) (xy 402.508357 -278.96324)
			(xy 402.478792 -279.002584) (xy 402.443299 -279.036676) (xy 402.402796 -279.064632) (xy 402.358334 -279.08573)
			(xy 402.311063 -279.099422) (xy 402.262208 -279.105354) (xy 402.213033 -279.103373) (xy 402.164814 -279.093529)
			(xy 402.118798 -279.076077) (xy 402.076177 -279.05147) (xy 402.038056 -279.020345) (xy 402.005421 -278.983508)
			(xy 401.979118 -278.941912) (xy 401.959827 -278.896636) (xy 401.94805 -278.848852) (xy 401.94409 -278.799798)
			(xy 401.605242 -278.799798) (xy 401.604747 -278.824405) (xy 401.596852 -278.872982) (xy 401.581268 -278.919663)
			(xy 401.558397 -278.96324) (xy 401.528832 -279.002584) (xy 401.493339 -279.036676) (xy 401.452836 -279.064632)
			(xy 401.408374 -279.08573) (xy 401.361103 -279.099422) (xy 401.312248 -279.105354) (xy 401.263073 -279.103373)
			(xy 401.214854 -279.093529) (xy 401.168838 -279.076077) (xy 401.126217 -279.05147) (xy 401.088096 -279.020345)
			(xy 401.055461 -278.983508) (xy 401.029158 -278.941912) (xy 401.009867 -278.896636) (xy 400.99809 -278.848852)
			(xy 400.99413 -278.799798) (xy 400.655282 -278.799798) (xy 400.654787 -278.824405) (xy 400.646892 -278.872982)
			(xy 400.631308 -278.919663) (xy 400.608437 -278.96324) (xy 400.578872 -279.002584) (xy 400.543379 -279.036676)
			(xy 400.502876 -279.064632) (xy 400.458414 -279.08573) (xy 400.411143 -279.099422) (xy 400.362288 -279.105354)
			(xy 400.313113 -279.103373) (xy 400.264894 -279.093529) (xy 400.218878 -279.076077) (xy 400.176257 -279.05147)
			(xy 400.138136 -279.020345) (xy 400.105501 -278.983508) (xy 400.079198 -278.941912) (xy 400.059907 -278.896636)
			(xy 400.04813 -278.848852) (xy 400.04417 -278.799798) (xy 399.705322 -278.799798) (xy 399.704827 -278.824405)
			(xy 399.696932 -278.872982) (xy 399.681348 -278.919663) (xy 399.658477 -278.96324) (xy 399.628912 -279.002584)
			(xy 399.593419 -279.036676) (xy 399.552916 -279.064632) (xy 399.508454 -279.08573) (xy 399.461183 -279.099422)
			(xy 399.412328 -279.105354) (xy 399.363153 -279.103373) (xy 399.314934 -279.093529) (xy 399.268918 -279.076077)
			(xy 399.226297 -279.05147) (xy 399.188176 -279.020345) (xy 399.155541 -278.983508) (xy 399.129238 -278.941912)
			(xy 399.109947 -278.896636) (xy 399.09817 -278.848852) (xy 399.09421 -278.799798) (xy 398.755108 -278.799798)
			(xy 398.754613 -278.824405) (xy 398.746718 -278.872982) (xy 398.731134 -278.919663) (xy 398.708263 -278.96324)
			(xy 398.678698 -279.002584) (xy 398.643205 -279.036676) (xy 398.602702 -279.064632) (xy 398.55824 -279.08573)
			(xy 398.510969 -279.099422) (xy 398.462114 -279.105354) (xy 398.412939 -279.103373) (xy 398.36472 -279.093529)
			(xy 398.318704 -279.076077) (xy 398.276083 -279.05147) (xy 398.237962 -279.020345) (xy 398.205327 -278.983508)
			(xy 398.179024 -278.941912) (xy 398.159733 -278.896636) (xy 398.147956 -278.848852) (xy 398.143996 -278.799798)
			(xy 397.805148 -278.799798) (xy 397.804653 -278.824405) (xy 397.796758 -278.872982) (xy 397.781174 -278.919663)
			(xy 397.758303 -278.96324) (xy 397.728738 -279.002584) (xy 397.693245 -279.036676) (xy 397.652742 -279.064632)
			(xy 397.60828 -279.08573) (xy 397.561009 -279.099422) (xy 397.512154 -279.105354) (xy 397.462979 -279.103373)
			(xy 397.41476 -279.093529) (xy 397.368744 -279.076077) (xy 397.326123 -279.05147) (xy 397.288002 -279.020345)
			(xy 397.255367 -278.983508) (xy 397.229064 -278.941912) (xy 397.209773 -278.896636) (xy 397.197996 -278.848852)
			(xy 397.194036 -278.799798) (xy 396.855188 -278.799798) (xy 396.854693 -278.824405) (xy 396.846798 -278.872982)
			(xy 396.831214 -278.919663) (xy 396.808343 -278.96324) (xy 396.778778 -279.002584) (xy 396.743285 -279.036676)
			(xy 396.702782 -279.064632) (xy 396.65832 -279.08573) (xy 396.611049 -279.099422) (xy 396.562194 -279.105354)
			(xy 396.513019 -279.103373) (xy 396.4648 -279.093529) (xy 396.418784 -279.076077) (xy 396.376163 -279.05147)
			(xy 396.338042 -279.020345) (xy 396.305407 -278.983508) (xy 396.279104 -278.941912) (xy 396.259813 -278.896636)
			(xy 396.248036 -278.848852) (xy 396.244076 -278.799798) (xy 395.905228 -278.799798) (xy 395.904733 -278.824405)
			(xy 395.896838 -278.872982) (xy 395.881254 -278.919663) (xy 395.858383 -278.96324) (xy 395.828818 -279.002584)
			(xy 395.793325 -279.036676) (xy 395.752822 -279.064632) (xy 395.70836 -279.08573) (xy 395.661089 -279.099422)
			(xy 395.612234 -279.105354) (xy 395.563059 -279.103373) (xy 395.51484 -279.093529) (xy 395.468824 -279.076077)
			(xy 395.426203 -279.05147) (xy 395.388082 -279.020345) (xy 395.355447 -278.983508) (xy 395.329144 -278.941912)
			(xy 395.309853 -278.896636) (xy 395.298076 -278.848852) (xy 395.294116 -278.799798) (xy 394.955268 -278.799798)
			(xy 394.954773 -278.824405) (xy 394.946878 -278.872982) (xy 394.931294 -278.919663) (xy 394.908423 -278.96324)
			(xy 394.878858 -279.002584) (xy 394.843365 -279.036676) (xy 394.802862 -279.064632) (xy 394.7584 -279.08573)
			(xy 394.711129 -279.099422) (xy 394.662274 -279.105354) (xy 394.613099 -279.103373) (xy 394.56488 -279.093529)
			(xy 394.518864 -279.076077) (xy 394.476243 -279.05147) (xy 394.438122 -279.020345) (xy 394.405487 -278.983508)
			(xy 394.379184 -278.941912) (xy 394.359893 -278.896636) (xy 394.348116 -278.848852) (xy 394.344156 -278.799798)
			(xy 394.005308 -278.799798) (xy 394.004813 -278.824405) (xy 393.996918 -278.872982) (xy 393.981334 -278.919663)
			(xy 393.958463 -278.96324) (xy 393.928898 -279.002584) (xy 393.893405 -279.036676) (xy 393.852902 -279.064632)
			(xy 393.80844 -279.08573) (xy 393.761169 -279.099422) (xy 393.712314 -279.105354) (xy 393.663139 -279.103373)
			(xy 393.61492 -279.093529) (xy 393.568904 -279.076077) (xy 393.526283 -279.05147) (xy 393.488162 -279.020345)
			(xy 393.455527 -278.983508) (xy 393.429224 -278.941912) (xy 393.409933 -278.896636) (xy 393.398156 -278.848852)
			(xy 393.394196 -278.799798) (xy 393.055068 -278.799798) (xy 393.055517 -278.808092) (xy 393.050148 -278.857442)
			(xy 393.036865 -278.905274) (xy 393.01602 -278.950327) (xy 392.98816 -278.991414) (xy 392.95402 -279.027452)
			(xy 392.914499 -279.057493) (xy 392.870639 -279.080744) (xy 392.823595 -279.096592) (xy 392.774607 -279.104621)
			(xy 392.749786 -279.105106) (xy 392.735603 -279.104931) (xy 392.707363 -279.102258) (xy 392.693398 -279.099772)
			(xy 392.680952 -279.097486) (xy 392.65733 -279.104852) (xy 392.57986 -279.182322) (xy 392.572494 -279.205944)
			(xy 392.57478 -279.21839) (xy 392.577251 -279.232357) (xy 392.579926 -279.260596) (xy 392.580114 -279.274778)
			(xy 392.579934 -279.288961) (xy 392.577264 -279.317201) (xy 392.57478 -279.331166) (xy 392.572494 -279.343612)
			(xy 392.57986 -279.367234) (xy 392.65733 -279.444704) (xy 392.680952 -279.45207) (xy 392.693398 -279.449784)
			(xy 392.707365 -279.447312) (xy 392.735604 -279.444637) (xy 392.749786 -279.44445) (xy 392.774609 -279.444963)
			(xy 392.823601 -279.452993) (xy 392.870649 -279.468843) (xy 392.914512 -279.492097) (xy 392.954036 -279.52214)
			(xy 392.988178 -279.558182) (xy 393.016039 -279.599274) (xy 393.036884 -279.644331) (xy 393.050166 -279.692167)
			(xy 393.055533 -279.741522) (xy 393.0551 -279.749504) (xy 393.394196 -279.749504) (xy 393.398156 -279.70045)
			(xy 393.409933 -279.652666) (xy 393.429224 -279.60739) (xy 393.455527 -279.565794) (xy 393.488162 -279.528957)
			(xy 393.526283 -279.497832) (xy 393.568904 -279.473225) (xy 393.61492 -279.455773) (xy 393.663139 -279.445929)
			(xy 393.712314 -279.443948) (xy 393.761169 -279.44988) (xy 393.80844 -279.463572) (xy 393.852902 -279.48467)
			(xy 393.893405 -279.512626) (xy 393.928898 -279.546718) (xy 393.958463 -279.586062) (xy 393.981334 -279.629639)
			(xy 393.996918 -279.67632) (xy 394.004813 -279.724897) (xy 394.005308 -279.749504) (xy 394.005303 -279.749758)
			(xy 394.344156 -279.749758) (xy 394.348116 -279.700704) (xy 394.359893 -279.65292) (xy 394.379184 -279.607644)
			(xy 394.405487 -279.566048) (xy 394.438122 -279.529211) (xy 394.476243 -279.498086) (xy 394.518864 -279.473479)
			(xy 394.56488 -279.456027) (xy 394.613099 -279.446183) (xy 394.662274 -279.444202) (xy 394.711129 -279.450134)
			(xy 394.7584 -279.463826) (xy 394.802862 -279.484924) (xy 394.843365 -279.51288) (xy 394.878858 -279.546972)
			(xy 394.908423 -279.586316) (xy 394.931294 -279.629893) (xy 394.946878 -279.676574) (xy 394.954773 -279.725151)
			(xy 394.955263 -279.749504) (xy 395.294116 -279.749504) (xy 395.298076 -279.70045) (xy 395.309853 -279.652666)
			(xy 395.329144 -279.60739) (xy 395.355447 -279.565794) (xy 395.388082 -279.528957) (xy 395.426203 -279.497832)
			(xy 395.468824 -279.473225) (xy 395.51484 -279.455773) (xy 395.563059 -279.445929) (xy 395.612234 -279.443948)
			(xy 395.661089 -279.44988) (xy 395.70836 -279.463572) (xy 395.752822 -279.48467) (xy 395.793325 -279.512626)
			(xy 395.828818 -279.546718) (xy 395.858383 -279.586062) (xy 395.881254 -279.629639) (xy 395.896838 -279.67632)
			(xy 395.904733 -279.724897) (xy 395.905228 -279.749504) (xy 395.905223 -279.749758) (xy 396.244076 -279.749758)
			(xy 396.248036 -279.700704) (xy 396.259813 -279.65292) (xy 396.279104 -279.607644) (xy 396.305407 -279.566048)
			(xy 396.338042 -279.529211) (xy 396.376163 -279.498086) (xy 396.418784 -279.473479) (xy 396.4648 -279.456027)
			(xy 396.513019 -279.446183) (xy 396.562194 -279.444202) (xy 396.611049 -279.450134) (xy 396.65832 -279.463826)
			(xy 396.702782 -279.484924) (xy 396.743285 -279.51288) (xy 396.778778 -279.546972) (xy 396.808343 -279.586316)
			(xy 396.831214 -279.629893) (xy 396.846798 -279.676574) (xy 396.854693 -279.725151) (xy 396.855183 -279.749504)
			(xy 397.194036 -279.749504) (xy 397.197996 -279.70045) (xy 397.209773 -279.652666) (xy 397.229064 -279.60739)
			(xy 397.255367 -279.565794) (xy 397.288002 -279.528957) (xy 397.326123 -279.497832) (xy 397.368744 -279.473225)
			(xy 397.41476 -279.455773) (xy 397.462979 -279.445929) (xy 397.512154 -279.443948) (xy 397.561009 -279.44988)
			(xy 397.60828 -279.463572) (xy 397.652742 -279.48467) (xy 397.693245 -279.512626) (xy 397.728738 -279.546718)
			(xy 397.758303 -279.586062) (xy 397.781174 -279.629639) (xy 397.796758 -279.67632) (xy 397.804653 -279.724897)
			(xy 397.805148 -279.749504) (xy 397.805143 -279.749758) (xy 398.143996 -279.749758) (xy 398.147956 -279.700704)
			(xy 398.159733 -279.65292) (xy 398.179024 -279.607644) (xy 398.205327 -279.566048) (xy 398.237962 -279.529211)
			(xy 398.276083 -279.498086) (xy 398.318704 -279.473479) (xy 398.36472 -279.456027) (xy 398.412939 -279.446183)
			(xy 398.462114 -279.444202) (xy 398.510969 -279.450134) (xy 398.55824 -279.463826) (xy 398.602702 -279.484924)
			(xy 398.643205 -279.51288) (xy 398.678698 -279.546972) (xy 398.708263 -279.586316) (xy 398.731134 -279.629893)
			(xy 398.746718 -279.676574) (xy 398.754613 -279.725151) (xy 398.755103 -279.749504) (xy 399.09421 -279.749504)
			(xy 399.09817 -279.70045) (xy 399.109947 -279.652666) (xy 399.129238 -279.60739) (xy 399.155541 -279.565794)
			(xy 399.188176 -279.528957) (xy 399.226297 -279.497832) (xy 399.268918 -279.473225) (xy 399.314934 -279.455773)
			(xy 399.363153 -279.445929) (xy 399.412328 -279.443948) (xy 399.461183 -279.44988) (xy 399.508454 -279.463572)
			(xy 399.552916 -279.48467) (xy 399.593419 -279.512626) (xy 399.628912 -279.546718) (xy 399.658477 -279.586062)
			(xy 399.681348 -279.629639) (xy 399.696932 -279.67632) (xy 399.704827 -279.724897) (xy 399.705322 -279.749504)
			(xy 399.705317 -279.749758) (xy 400.04417 -279.749758) (xy 400.04813 -279.700704) (xy 400.059907 -279.65292)
			(xy 400.079198 -279.607644) (xy 400.105501 -279.566048) (xy 400.138136 -279.529211) (xy 400.176257 -279.498086)
			(xy 400.218878 -279.473479) (xy 400.264894 -279.456027) (xy 400.313113 -279.446183) (xy 400.362288 -279.444202)
			(xy 400.411143 -279.450134) (xy 400.458414 -279.463826) (xy 400.502876 -279.484924) (xy 400.543379 -279.51288)
			(xy 400.578872 -279.546972) (xy 400.608437 -279.586316) (xy 400.631308 -279.629893) (xy 400.646892 -279.676574)
			(xy 400.654787 -279.725151) (xy 400.655277 -279.749504) (xy 400.99413 -279.749504) (xy 400.99809 -279.70045)
			(xy 401.009867 -279.652666) (xy 401.029158 -279.60739) (xy 401.055461 -279.565794) (xy 401.088096 -279.528957)
			(xy 401.126217 -279.497832) (xy 401.168838 -279.473225) (xy 401.214854 -279.455773) (xy 401.263073 -279.445929)
			(xy 401.312248 -279.443948) (xy 401.361103 -279.44988) (xy 401.408374 -279.463572) (xy 401.452836 -279.48467)
			(xy 401.493339 -279.512626) (xy 401.528832 -279.546718) (xy 401.558397 -279.586062) (xy 401.581268 -279.629639)
			(xy 401.596852 -279.67632) (xy 401.604747 -279.724897) (xy 401.605242 -279.749504) (xy 401.605237 -279.749758)
			(xy 401.94409 -279.749758) (xy 401.94805 -279.700704) (xy 401.959827 -279.65292) (xy 401.979118 -279.607644)
			(xy 402.005421 -279.566048) (xy 402.038056 -279.529211) (xy 402.076177 -279.498086) (xy 402.118798 -279.473479)
			(xy 402.164814 -279.456027) (xy 402.213033 -279.446183) (xy 402.262208 -279.444202) (xy 402.311063 -279.450134)
			(xy 402.358334 -279.463826) (xy 402.402796 -279.484924) (xy 402.443299 -279.51288) (xy 402.478792 -279.546972)
			(xy 402.508357 -279.586316) (xy 402.531228 -279.629893) (xy 402.546812 -279.676574) (xy 402.554707 -279.725151)
			(xy 402.555197 -279.749504) (xy 402.89405 -279.749504) (xy 402.89801 -279.70045) (xy 402.909787 -279.652666)
			(xy 402.929078 -279.60739) (xy 402.955381 -279.565794) (xy 402.988016 -279.528957) (xy 403.026137 -279.497832)
			(xy 403.068758 -279.473225) (xy 403.114774 -279.455773) (xy 403.162993 -279.445929) (xy 403.212168 -279.443948)
			(xy 403.261023 -279.44988) (xy 403.308294 -279.463572) (xy 403.352756 -279.48467) (xy 403.393259 -279.512626)
			(xy 403.428752 -279.546718) (xy 403.458317 -279.586062) (xy 403.481188 -279.629639) (xy 403.496772 -279.67632)
			(xy 403.504667 -279.724897) (xy 403.505162 -279.749504) (xy 403.505157 -279.749758) (xy 403.84401 -279.749758)
			(xy 403.84797 -279.700704) (xy 403.859747 -279.65292) (xy 403.879038 -279.607644) (xy 403.905341 -279.566048)
			(xy 403.937976 -279.529211) (xy 403.976097 -279.498086) (xy 404.018718 -279.473479) (xy 404.064734 -279.456027)
			(xy 404.112953 -279.446183) (xy 404.162128 -279.444202) (xy 404.210983 -279.450134) (xy 404.258254 -279.463826)
			(xy 404.302716 -279.484924) (xy 404.343219 -279.51288) (xy 404.378712 -279.546972) (xy 404.408277 -279.586316)
			(xy 404.431148 -279.629893) (xy 404.446732 -279.676574) (xy 404.454627 -279.725151) (xy 404.455117 -279.749504)
			(xy 404.79397 -279.749504) (xy 404.79793 -279.70045) (xy 404.809707 -279.652666) (xy 404.828998 -279.60739)
			(xy 404.855301 -279.565794) (xy 404.887936 -279.528957) (xy 404.926057 -279.497832) (xy 404.968678 -279.473225)
			(xy 405.014694 -279.455773) (xy 405.062913 -279.445929) (xy 405.112088 -279.443948) (xy 405.160943 -279.44988)
			(xy 405.208214 -279.463572) (xy 405.252676 -279.48467) (xy 405.293179 -279.512626) (xy 405.328672 -279.546718)
			(xy 405.358237 -279.586062) (xy 405.381108 -279.629639) (xy 405.396692 -279.67632) (xy 405.404587 -279.724897)
			(xy 405.405082 -279.749504) (xy 405.405077 -279.749758) (xy 405.744184 -279.749758) (xy 405.748144 -279.700704)
			(xy 405.759921 -279.65292) (xy 405.779212 -279.607644) (xy 405.805515 -279.566048) (xy 405.83815 -279.529211)
			(xy 405.876271 -279.498086) (xy 405.918892 -279.473479) (xy 405.964908 -279.456027) (xy 406.013127 -279.446183)
			(xy 406.062302 -279.444202) (xy 406.111157 -279.450134) (xy 406.158428 -279.463826) (xy 406.20289 -279.484924)
			(xy 406.243393 -279.51288) (xy 406.278886 -279.546972) (xy 406.308451 -279.586316) (xy 406.331322 -279.629893)
			(xy 406.346906 -279.676574) (xy 406.354801 -279.725151) (xy 406.355291 -279.749504) (xy 406.694144 -279.749504)
			(xy 406.698104 -279.70045) (xy 406.709881 -279.652666) (xy 406.729172 -279.60739) (xy 406.755475 -279.565794)
			(xy 406.78811 -279.528957) (xy 406.826231 -279.497832) (xy 406.868852 -279.473225) (xy 406.914868 -279.455773)
			(xy 406.963087 -279.445929) (xy 407.012262 -279.443948) (xy 407.061117 -279.44988) (xy 407.108388 -279.463572)
			(xy 407.15285 -279.48467) (xy 407.193353 -279.512626) (xy 407.228846 -279.546718) (xy 407.258411 -279.586062)
			(xy 407.281282 -279.629639) (xy 407.296866 -279.67632) (xy 407.304761 -279.724897) (xy 407.305256 -279.749504)
			(xy 407.305251 -279.749758) (xy 407.644104 -279.749758) (xy 407.648064 -279.700704) (xy 407.659841 -279.65292)
			(xy 407.679132 -279.607644) (xy 407.705435 -279.566048) (xy 407.73807 -279.529211) (xy 407.776191 -279.498086)
			(xy 407.818812 -279.473479) (xy 407.864828 -279.456027) (xy 407.913047 -279.446183) (xy 407.962222 -279.444202)
			(xy 408.011077 -279.450134) (xy 408.058348 -279.463826) (xy 408.10281 -279.484924) (xy 408.143313 -279.51288)
			(xy 408.178806 -279.546972) (xy 408.208371 -279.586316) (xy 408.231242 -279.629893) (xy 408.246826 -279.676574)
			(xy 408.254721 -279.725151) (xy 408.255211 -279.749504) (xy 408.594064 -279.749504) (xy 408.598024 -279.70045)
			(xy 408.609801 -279.652666) (xy 408.629092 -279.60739) (xy 408.655395 -279.565794) (xy 408.68803 -279.528957)
			(xy 408.726151 -279.497832) (xy 408.768772 -279.473225) (xy 408.814788 -279.455773) (xy 408.863007 -279.445929)
			(xy 408.912182 -279.443948) (xy 408.961037 -279.44988) (xy 409.008308 -279.463572) (xy 409.05277 -279.48467)
			(xy 409.093273 -279.512626) (xy 409.128766 -279.546718) (xy 409.158331 -279.586062) (xy 409.181202 -279.629639)
			(xy 409.196786 -279.67632) (xy 409.204681 -279.724897) (xy 409.205176 -279.749504) (xy 409.205171 -279.749758)
			(xy 409.544024 -279.749758) (xy 409.547984 -279.700704) (xy 409.559761 -279.65292) (xy 409.579052 -279.607644)
			(xy 409.605355 -279.566048) (xy 409.63799 -279.529211) (xy 409.676111 -279.498086) (xy 409.718732 -279.473479)
			(xy 409.764748 -279.456027) (xy 409.812967 -279.446183) (xy 409.862142 -279.444202) (xy 409.910997 -279.450134)
			(xy 409.958268 -279.463826) (xy 410.00273 -279.484924) (xy 410.043233 -279.51288) (xy 410.078726 -279.546972)
			(xy 410.108291 -279.586316) (xy 410.131162 -279.629893) (xy 410.146746 -279.676574) (xy 410.154641 -279.725151)
			(xy 410.155131 -279.749504) (xy 410.493984 -279.749504) (xy 410.497944 -279.70045) (xy 410.509721 -279.652666)
			(xy 410.529012 -279.60739) (xy 410.555315 -279.565794) (xy 410.58795 -279.528957) (xy 410.626071 -279.497832)
			(xy 410.668692 -279.473225) (xy 410.714708 -279.455773) (xy 410.762927 -279.445929) (xy 410.812102 -279.443948)
			(xy 410.860957 -279.44988) (xy 410.908228 -279.463572) (xy 410.95269 -279.48467) (xy 410.993193 -279.512626)
			(xy 411.028686 -279.546718) (xy 411.058251 -279.586062) (xy 411.081122 -279.629639) (xy 411.096706 -279.67632)
			(xy 411.104601 -279.724897) (xy 411.105096 -279.749504) (xy 411.105091 -279.749758) (xy 411.444198 -279.749758)
			(xy 411.448158 -279.700704) (xy 411.459935 -279.65292) (xy 411.479226 -279.607644) (xy 411.505529 -279.566048)
			(xy 411.538164 -279.529211) (xy 411.576285 -279.498086) (xy 411.618906 -279.473479) (xy 411.664922 -279.456027)
			(xy 411.713141 -279.446183) (xy 411.762316 -279.444202) (xy 411.811171 -279.450134) (xy 411.858442 -279.463826)
			(xy 411.902904 -279.484924) (xy 411.943407 -279.51288) (xy 411.9789 -279.546972) (xy 412.008465 -279.586316)
			(xy 412.031336 -279.629893) (xy 412.04692 -279.676574) (xy 412.054815 -279.725151) (xy 412.055305 -279.749504)
			(xy 412.394158 -279.749504) (xy 412.398118 -279.70045) (xy 412.409895 -279.652666) (xy 412.429186 -279.60739)
			(xy 412.455489 -279.565794) (xy 412.488124 -279.528957) (xy 412.526245 -279.497832) (xy 412.568866 -279.473225)
			(xy 412.614882 -279.455773) (xy 412.663101 -279.445929) (xy 412.712276 -279.443948) (xy 412.761131 -279.44988)
			(xy 412.808402 -279.463572) (xy 412.852864 -279.48467) (xy 412.893367 -279.512626) (xy 412.92886 -279.546718)
			(xy 412.958425 -279.586062) (xy 412.981296 -279.629639) (xy 412.99688 -279.67632) (xy 413.004775 -279.724897)
			(xy 413.00527 -279.749504) (xy 413.005265 -279.749758) (xy 413.344118 -279.749758) (xy 413.348078 -279.700704)
			(xy 413.359855 -279.65292) (xy 413.379146 -279.607644) (xy 413.405449 -279.566048) (xy 413.438084 -279.529211)
			(xy 413.476205 -279.498086) (xy 413.518826 -279.473479) (xy 413.564842 -279.456027) (xy 413.613061 -279.446183)
			(xy 413.662236 -279.444202) (xy 413.711091 -279.450134) (xy 413.758362 -279.463826) (xy 413.802824 -279.484924)
			(xy 413.843327 -279.51288) (xy 413.87882 -279.546972) (xy 413.908385 -279.586316) (xy 413.931256 -279.629893)
			(xy 413.94684 -279.676574) (xy 413.954735 -279.725151) (xy 413.955225 -279.749504) (xy 414.294078 -279.749504)
			(xy 414.298038 -279.70045) (xy 414.309815 -279.652666) (xy 414.329106 -279.60739) (xy 414.355409 -279.565794)
			(xy 414.388044 -279.528957) (xy 414.426165 -279.497832) (xy 414.468786 -279.473225) (xy 414.514802 -279.455773)
			(xy 414.563021 -279.445929) (xy 414.612196 -279.443948) (xy 414.661051 -279.44988) (xy 414.708322 -279.463572)
			(xy 414.752784 -279.48467) (xy 414.793287 -279.512626) (xy 414.82878 -279.546718) (xy 414.858345 -279.586062)
			(xy 414.881216 -279.629639) (xy 414.8968 -279.67632) (xy 414.904695 -279.724897) (xy 414.90519 -279.749504)
			(xy 414.905185 -279.749758) (xy 415.244038 -279.749758) (xy 415.247998 -279.700704) (xy 415.259775 -279.65292)
			(xy 415.279066 -279.607644) (xy 415.305369 -279.566048) (xy 415.338004 -279.529211) (xy 415.376125 -279.498086)
			(xy 415.418746 -279.473479) (xy 415.464762 -279.456027) (xy 415.512981 -279.446183) (xy 415.562156 -279.444202)
			(xy 415.611011 -279.450134) (xy 415.658282 -279.463826) (xy 415.702744 -279.484924) (xy 415.743247 -279.51288)
			(xy 415.77874 -279.546972) (xy 415.808305 -279.586316) (xy 415.831176 -279.629893) (xy 415.84676 -279.676574)
			(xy 415.854655 -279.725151) (xy 415.855145 -279.749504) (xy 416.193998 -279.749504) (xy 416.197958 -279.70045)
			(xy 416.209735 -279.652666) (xy 416.229026 -279.60739) (xy 416.255329 -279.565794) (xy 416.287964 -279.528957)
			(xy 416.326085 -279.497832) (xy 416.368706 -279.473225) (xy 416.414722 -279.455773) (xy 416.462941 -279.445929)
			(xy 416.512116 -279.443948) (xy 416.560971 -279.44988) (xy 416.608242 -279.463572) (xy 416.652704 -279.48467)
			(xy 416.693207 -279.512626) (xy 416.7287 -279.546718) (xy 416.758265 -279.586062) (xy 416.781136 -279.629639)
			(xy 416.79672 -279.67632) (xy 416.804615 -279.724897) (xy 416.80511 -279.749504) (xy 416.804615 -279.774111)
			(xy 416.79672 -279.822688) (xy 416.781136 -279.869369) (xy 416.758265 -279.912946) (xy 416.7287 -279.95229)
			(xy 416.693207 -279.986382) (xy 416.652704 -280.014338) (xy 416.608242 -280.035436) (xy 416.560971 -280.049128)
			(xy 416.512116 -280.05506) (xy 416.462941 -280.053079) (xy 416.414722 -280.043235) (xy 416.368706 -280.025783)
			(xy 416.326085 -280.001176) (xy 416.287964 -279.970051) (xy 416.255329 -279.933214) (xy 416.229026 -279.891618)
			(xy 416.209735 -279.846342) (xy 416.197958 -279.798558) (xy 416.193998 -279.749504) (xy 415.855145 -279.749504)
			(xy 415.85515 -279.749758) (xy 415.854655 -279.774365) (xy 415.84676 -279.822942) (xy 415.831176 -279.869623)
			(xy 415.808305 -279.9132) (xy 415.77874 -279.952544) (xy 415.743247 -279.986636) (xy 415.702744 -280.014592)
			(xy 415.658282 -280.03569) (xy 415.611011 -280.049382) (xy 415.562156 -280.055314) (xy 415.512981 -280.053333)
			(xy 415.464762 -280.043489) (xy 415.418746 -280.026037) (xy 415.376125 -280.00143) (xy 415.338004 -279.970305)
			(xy 415.305369 -279.933468) (xy 415.279066 -279.891872) (xy 415.259775 -279.846596) (xy 415.247998 -279.798812)
			(xy 415.244038 -279.749758) (xy 414.905185 -279.749758) (xy 414.904695 -279.774111) (xy 414.8968 -279.822688)
			(xy 414.881216 -279.869369) (xy 414.858345 -279.912946) (xy 414.82878 -279.95229) (xy 414.793287 -279.986382)
			(xy 414.752784 -280.014338) (xy 414.708322 -280.035436) (xy 414.661051 -280.049128) (xy 414.612196 -280.05506)
			(xy 414.563021 -280.053079) (xy 414.514802 -280.043235) (xy 414.468786 -280.025783) (xy 414.426165 -280.001176)
			(xy 414.388044 -279.970051) (xy 414.355409 -279.933214) (xy 414.329106 -279.891618) (xy 414.309815 -279.846342)
			(xy 414.298038 -279.798558) (xy 414.294078 -279.749504) (xy 413.955225 -279.749504) (xy 413.95523 -279.749758)
			(xy 413.954735 -279.774365) (xy 413.94684 -279.822942) (xy 413.931256 -279.869623) (xy 413.908385 -279.9132)
			(xy 413.87882 -279.952544) (xy 413.843327 -279.986636) (xy 413.802824 -280.014592) (xy 413.758362 -280.03569)
			(xy 413.711091 -280.049382) (xy 413.662236 -280.055314) (xy 413.613061 -280.053333) (xy 413.564842 -280.043489)
			(xy 413.518826 -280.026037) (xy 413.476205 -280.00143) (xy 413.438084 -279.970305) (xy 413.405449 -279.933468)
			(xy 413.379146 -279.891872) (xy 413.359855 -279.846596) (xy 413.348078 -279.798812) (xy 413.344118 -279.749758)
			(xy 413.005265 -279.749758) (xy 413.004775 -279.774111) (xy 412.99688 -279.822688) (xy 412.981296 -279.869369)
			(xy 412.958425 -279.912946) (xy 412.92886 -279.95229) (xy 412.893367 -279.986382) (xy 412.852864 -280.014338)
			(xy 412.808402 -280.035436) (xy 412.761131 -280.049128) (xy 412.712276 -280.05506) (xy 412.663101 -280.053079)
			(xy 412.614882 -280.043235) (xy 412.568866 -280.025783) (xy 412.526245 -280.001176) (xy 412.488124 -279.970051)
			(xy 412.455489 -279.933214) (xy 412.429186 -279.891618) (xy 412.409895 -279.846342) (xy 412.398118 -279.798558)
			(xy 412.394158 -279.749504) (xy 412.055305 -279.749504) (xy 412.05531 -279.749758) (xy 412.054815 -279.774365)
			(xy 412.04692 -279.822942) (xy 412.031336 -279.869623) (xy 412.008465 -279.9132) (xy 411.9789 -279.952544)
			(xy 411.943407 -279.986636) (xy 411.902904 -280.014592) (xy 411.858442 -280.03569) (xy 411.811171 -280.049382)
			(xy 411.762316 -280.055314) (xy 411.713141 -280.053333) (xy 411.664922 -280.043489) (xy 411.618906 -280.026037)
			(xy 411.576285 -280.00143) (xy 411.538164 -279.970305) (xy 411.505529 -279.933468) (xy 411.479226 -279.891872)
			(xy 411.459935 -279.846596) (xy 411.448158 -279.798812) (xy 411.444198 -279.749758) (xy 411.105091 -279.749758)
			(xy 411.104601 -279.774111) (xy 411.096706 -279.822688) (xy 411.081122 -279.869369) (xy 411.058251 -279.912946)
			(xy 411.028686 -279.95229) (xy 410.993193 -279.986382) (xy 410.95269 -280.014338) (xy 410.908228 -280.035436)
			(xy 410.860957 -280.049128) (xy 410.812102 -280.05506) (xy 410.762927 -280.053079) (xy 410.714708 -280.043235)
			(xy 410.668692 -280.025783) (xy 410.626071 -280.001176) (xy 410.58795 -279.970051) (xy 410.555315 -279.933214)
			(xy 410.529012 -279.891618) (xy 410.509721 -279.846342) (xy 410.497944 -279.798558) (xy 410.493984 -279.749504)
			(xy 410.155131 -279.749504) (xy 410.155136 -279.749758) (xy 410.154641 -279.774365) (xy 410.146746 -279.822942)
			(xy 410.131162 -279.869623) (xy 410.108291 -279.9132) (xy 410.078726 -279.952544) (xy 410.043233 -279.986636)
			(xy 410.00273 -280.014592) (xy 409.958268 -280.03569) (xy 409.910997 -280.049382) (xy 409.862142 -280.055314)
			(xy 409.812967 -280.053333) (xy 409.764748 -280.043489) (xy 409.718732 -280.026037) (xy 409.676111 -280.00143)
			(xy 409.63799 -279.970305) (xy 409.605355 -279.933468) (xy 409.579052 -279.891872) (xy 409.559761 -279.846596)
			(xy 409.547984 -279.798812) (xy 409.544024 -279.749758) (xy 409.205171 -279.749758) (xy 409.204681 -279.774111)
			(xy 409.196786 -279.822688) (xy 409.181202 -279.869369) (xy 409.158331 -279.912946) (xy 409.128766 -279.95229)
			(xy 409.093273 -279.986382) (xy 409.05277 -280.014338) (xy 409.008308 -280.035436) (xy 408.961037 -280.049128)
			(xy 408.912182 -280.05506) (xy 408.863007 -280.053079) (xy 408.814788 -280.043235) (xy 408.768772 -280.025783)
			(xy 408.726151 -280.001176) (xy 408.68803 -279.970051) (xy 408.655395 -279.933214) (xy 408.629092 -279.891618)
			(xy 408.609801 -279.846342) (xy 408.598024 -279.798558) (xy 408.594064 -279.749504) (xy 408.255211 -279.749504)
			(xy 408.255216 -279.749758) (xy 408.254721 -279.774365) (xy 408.246826 -279.822942) (xy 408.231242 -279.869623)
			(xy 408.208371 -279.9132) (xy 408.178806 -279.952544) (xy 408.143313 -279.986636) (xy 408.10281 -280.014592)
			(xy 408.058348 -280.03569) (xy 408.011077 -280.049382) (xy 407.962222 -280.055314) (xy 407.913047 -280.053333)
			(xy 407.864828 -280.043489) (xy 407.818812 -280.026037) (xy 407.776191 -280.00143) (xy 407.73807 -279.970305)
			(xy 407.705435 -279.933468) (xy 407.679132 -279.891872) (xy 407.659841 -279.846596) (xy 407.648064 -279.798812)
			(xy 407.644104 -279.749758) (xy 407.305251 -279.749758) (xy 407.304761 -279.774111) (xy 407.296866 -279.822688)
			(xy 407.281282 -279.869369) (xy 407.258411 -279.912946) (xy 407.228846 -279.95229) (xy 407.193353 -279.986382)
			(xy 407.15285 -280.014338) (xy 407.108388 -280.035436) (xy 407.061117 -280.049128) (xy 407.012262 -280.05506)
			(xy 406.963087 -280.053079) (xy 406.914868 -280.043235) (xy 406.868852 -280.025783) (xy 406.826231 -280.001176)
			(xy 406.78811 -279.970051) (xy 406.755475 -279.933214) (xy 406.729172 -279.891618) (xy 406.709881 -279.846342)
			(xy 406.698104 -279.798558) (xy 406.694144 -279.749504) (xy 406.355291 -279.749504) (xy 406.355296 -279.749758)
			(xy 406.354801 -279.774365) (xy 406.346906 -279.822942) (xy 406.331322 -279.869623) (xy 406.308451 -279.9132)
			(xy 406.278886 -279.952544) (xy 406.243393 -279.986636) (xy 406.20289 -280.014592) (xy 406.158428 -280.03569)
			(xy 406.111157 -280.049382) (xy 406.062302 -280.055314) (xy 406.013127 -280.053333) (xy 405.964908 -280.043489)
			(xy 405.918892 -280.026037) (xy 405.876271 -280.00143) (xy 405.83815 -279.970305) (xy 405.805515 -279.933468)
			(xy 405.779212 -279.891872) (xy 405.759921 -279.846596) (xy 405.748144 -279.798812) (xy 405.744184 -279.749758)
			(xy 405.405077 -279.749758) (xy 405.404587 -279.774111) (xy 405.396692 -279.822688) (xy 405.381108 -279.869369)
			(xy 405.358237 -279.912946) (xy 405.328672 -279.95229) (xy 405.293179 -279.986382) (xy 405.252676 -280.014338)
			(xy 405.208214 -280.035436) (xy 405.160943 -280.049128) (xy 405.112088 -280.05506) (xy 405.062913 -280.053079)
			(xy 405.014694 -280.043235) (xy 404.968678 -280.025783) (xy 404.926057 -280.001176) (xy 404.887936 -279.970051)
			(xy 404.855301 -279.933214) (xy 404.828998 -279.891618) (xy 404.809707 -279.846342) (xy 404.79793 -279.798558)
			(xy 404.79397 -279.749504) (xy 404.455117 -279.749504) (xy 404.455122 -279.749758) (xy 404.454627 -279.774365)
			(xy 404.446732 -279.822942) (xy 404.431148 -279.869623) (xy 404.408277 -279.9132) (xy 404.378712 -279.952544)
			(xy 404.343219 -279.986636) (xy 404.302716 -280.014592) (xy 404.258254 -280.03569) (xy 404.210983 -280.049382)
			(xy 404.162128 -280.055314) (xy 404.112953 -280.053333) (xy 404.064734 -280.043489) (xy 404.018718 -280.026037)
			(xy 403.976097 -280.00143) (xy 403.937976 -279.970305) (xy 403.905341 -279.933468) (xy 403.879038 -279.891872)
			(xy 403.859747 -279.846596) (xy 403.84797 -279.798812) (xy 403.84401 -279.749758) (xy 403.505157 -279.749758)
			(xy 403.504667 -279.774111) (xy 403.496772 -279.822688) (xy 403.481188 -279.869369) (xy 403.458317 -279.912946)
			(xy 403.428752 -279.95229) (xy 403.393259 -279.986382) (xy 403.352756 -280.014338) (xy 403.308294 -280.035436)
			(xy 403.261023 -280.049128) (xy 403.212168 -280.05506) (xy 403.162993 -280.053079) (xy 403.114774 -280.043235)
			(xy 403.068758 -280.025783) (xy 403.026137 -280.001176) (xy 402.988016 -279.970051) (xy 402.955381 -279.933214)
			(xy 402.929078 -279.891618) (xy 402.909787 -279.846342) (xy 402.89801 -279.798558) (xy 402.89405 -279.749504)
			(xy 402.555197 -279.749504) (xy 402.555202 -279.749758) (xy 402.554707 -279.774365) (xy 402.546812 -279.822942)
			(xy 402.531228 -279.869623) (xy 402.508357 -279.9132) (xy 402.478792 -279.952544) (xy 402.443299 -279.986636)
			(xy 402.402796 -280.014592) (xy 402.358334 -280.03569) (xy 402.311063 -280.049382) (xy 402.262208 -280.055314)
			(xy 402.213033 -280.053333) (xy 402.164814 -280.043489) (xy 402.118798 -280.026037) (xy 402.076177 -280.00143)
			(xy 402.038056 -279.970305) (xy 402.005421 -279.933468) (xy 401.979118 -279.891872) (xy 401.959827 -279.846596)
			(xy 401.94805 -279.798812) (xy 401.94409 -279.749758) (xy 401.605237 -279.749758) (xy 401.604747 -279.774111)
			(xy 401.596852 -279.822688) (xy 401.581268 -279.869369) (xy 401.558397 -279.912946) (xy 401.528832 -279.95229)
			(xy 401.493339 -279.986382) (xy 401.452836 -280.014338) (xy 401.408374 -280.035436) (xy 401.361103 -280.049128)
			(xy 401.312248 -280.05506) (xy 401.263073 -280.053079) (xy 401.214854 -280.043235) (xy 401.168838 -280.025783)
			(xy 401.126217 -280.001176) (xy 401.088096 -279.970051) (xy 401.055461 -279.933214) (xy 401.029158 -279.891618)
			(xy 401.009867 -279.846342) (xy 400.99809 -279.798558) (xy 400.99413 -279.749504) (xy 400.655277 -279.749504)
			(xy 400.655282 -279.749758) (xy 400.654787 -279.774365) (xy 400.646892 -279.822942) (xy 400.631308 -279.869623)
			(xy 400.608437 -279.9132) (xy 400.578872 -279.952544) (xy 400.543379 -279.986636) (xy 400.502876 -280.014592)
			(xy 400.458414 -280.03569) (xy 400.411143 -280.049382) (xy 400.362288 -280.055314) (xy 400.313113 -280.053333)
			(xy 400.264894 -280.043489) (xy 400.218878 -280.026037) (xy 400.176257 -280.00143) (xy 400.138136 -279.970305)
			(xy 400.105501 -279.933468) (xy 400.079198 -279.891872) (xy 400.059907 -279.846596) (xy 400.04813 -279.798812)
			(xy 400.04417 -279.749758) (xy 399.705317 -279.749758) (xy 399.704827 -279.774111) (xy 399.696932 -279.822688)
			(xy 399.681348 -279.869369) (xy 399.658477 -279.912946) (xy 399.628912 -279.95229) (xy 399.593419 -279.986382)
			(xy 399.552916 -280.014338) (xy 399.508454 -280.035436) (xy 399.461183 -280.049128) (xy 399.412328 -280.05506)
			(xy 399.363153 -280.053079) (xy 399.314934 -280.043235) (xy 399.268918 -280.025783) (xy 399.226297 -280.001176)
			(xy 399.188176 -279.970051) (xy 399.155541 -279.933214) (xy 399.129238 -279.891618) (xy 399.109947 -279.846342)
			(xy 399.09817 -279.798558) (xy 399.09421 -279.749504) (xy 398.755103 -279.749504) (xy 398.755108 -279.749758)
			(xy 398.754613 -279.774365) (xy 398.746718 -279.822942) (xy 398.731134 -279.869623) (xy 398.708263 -279.9132)
			(xy 398.678698 -279.952544) (xy 398.643205 -279.986636) (xy 398.602702 -280.014592) (xy 398.55824 -280.03569)
			(xy 398.510969 -280.049382) (xy 398.462114 -280.055314) (xy 398.412939 -280.053333) (xy 398.36472 -280.043489)
			(xy 398.318704 -280.026037) (xy 398.276083 -280.00143) (xy 398.237962 -279.970305) (xy 398.205327 -279.933468)
			(xy 398.179024 -279.891872) (xy 398.159733 -279.846596) (xy 398.147956 -279.798812) (xy 398.143996 -279.749758)
			(xy 397.805143 -279.749758) (xy 397.804653 -279.774111) (xy 397.796758 -279.822688) (xy 397.781174 -279.869369)
			(xy 397.758303 -279.912946) (xy 397.728738 -279.95229) (xy 397.693245 -279.986382) (xy 397.652742 -280.014338)
			(xy 397.60828 -280.035436) (xy 397.561009 -280.049128) (xy 397.512154 -280.05506) (xy 397.462979 -280.053079)
			(xy 397.41476 -280.043235) (xy 397.368744 -280.025783) (xy 397.326123 -280.001176) (xy 397.288002 -279.970051)
			(xy 397.255367 -279.933214) (xy 397.229064 -279.891618) (xy 397.209773 -279.846342) (xy 397.197996 -279.798558)
			(xy 397.194036 -279.749504) (xy 396.855183 -279.749504) (xy 396.855188 -279.749758) (xy 396.854693 -279.774365)
			(xy 396.846798 -279.822942) (xy 396.831214 -279.869623) (xy 396.808343 -279.9132) (xy 396.778778 -279.952544)
			(xy 396.743285 -279.986636) (xy 396.702782 -280.014592) (xy 396.65832 -280.03569) (xy 396.611049 -280.049382)
			(xy 396.562194 -280.055314) (xy 396.513019 -280.053333) (xy 396.4648 -280.043489) (xy 396.418784 -280.026037)
			(xy 396.376163 -280.00143) (xy 396.338042 -279.970305) (xy 396.305407 -279.933468) (xy 396.279104 -279.891872)
			(xy 396.259813 -279.846596) (xy 396.248036 -279.798812) (xy 396.244076 -279.749758) (xy 395.905223 -279.749758)
			(xy 395.904733 -279.774111) (xy 395.896838 -279.822688) (xy 395.881254 -279.869369) (xy 395.858383 -279.912946)
			(xy 395.828818 -279.95229) (xy 395.793325 -279.986382) (xy 395.752822 -280.014338) (xy 395.70836 -280.035436)
			(xy 395.661089 -280.049128) (xy 395.612234 -280.05506) (xy 395.563059 -280.053079) (xy 395.51484 -280.043235)
			(xy 395.468824 -280.025783) (xy 395.426203 -280.001176) (xy 395.388082 -279.970051) (xy 395.355447 -279.933214)
			(xy 395.329144 -279.891618) (xy 395.309853 -279.846342) (xy 395.298076 -279.798558) (xy 395.294116 -279.749504)
			(xy 394.955263 -279.749504) (xy 394.955268 -279.749758) (xy 394.954773 -279.774365) (xy 394.946878 -279.822942)
			(xy 394.931294 -279.869623) (xy 394.908423 -279.9132) (xy 394.878858 -279.952544) (xy 394.843365 -279.986636)
			(xy 394.802862 -280.014592) (xy 394.7584 -280.03569) (xy 394.711129 -280.049382) (xy 394.662274 -280.055314)
			(xy 394.613099 -280.053333) (xy 394.56488 -280.043489) (xy 394.518864 -280.026037) (xy 394.476243 -280.00143)
			(xy 394.438122 -279.970305) (xy 394.405487 -279.933468) (xy 394.379184 -279.891872) (xy 394.359893 -279.846596)
			(xy 394.348116 -279.798812) (xy 394.344156 -279.749758) (xy 394.005303 -279.749758) (xy 394.004813 -279.774111)
			(xy 393.996918 -279.822688) (xy 393.981334 -279.869369) (xy 393.958463 -279.912946) (xy 393.928898 -279.95229)
			(xy 393.893405 -279.986382) (xy 393.852902 -280.014338) (xy 393.80844 -280.035436) (xy 393.761169 -280.049128)
			(xy 393.712314 -280.05506) (xy 393.663139 -280.053079) (xy 393.61492 -280.043235) (xy 393.568904 -280.025783)
			(xy 393.526283 -280.001176) (xy 393.488162 -279.970051) (xy 393.455527 -279.933214) (xy 393.429224 -279.891618)
			(xy 393.409933 -279.846342) (xy 393.398156 -279.798558) (xy 393.394196 -279.749504) (xy 393.0551 -279.749504)
			(xy 393.052844 -279.791095) (xy 393.042171 -279.83958) (xy 393.023794 -279.8857) (xy 392.998197 -279.928238)
			(xy 392.966055 -279.966075) (xy 392.928215 -279.998213) (xy 392.885674 -280.023806) (xy 392.839553 -280.042179)
			(xy 392.791068 -280.052848) (xy 392.741494 -280.055532) (xy 392.69214 -280.050161) (xy 392.644305 -280.036875)
			(xy 392.599249 -280.016025) (xy 392.558161 -279.98816) (xy 392.522121 -279.954015) (xy 392.492081 -279.914489)
			(xy 392.468832 -279.870623) (xy 392.452986 -279.823574) (xy 392.444961 -279.774581) (xy 392.444478 -279.749758)
			(xy 392.444649 -279.735575) (xy 392.447325 -279.707335) (xy 392.449812 -279.69337) (xy 392.452098 -279.680924)
			(xy 392.444732 -279.657302) (xy 392.367262 -279.579832) (xy 392.34364 -279.572466) (xy 392.331194 -279.574752)
			(xy 392.317228 -279.577225) (xy 392.288988 -279.579899) (xy 392.274806 -279.580086) (xy 392.249546 -279.579638)
			(xy 392.199715 -279.571323) (xy 392.151933 -279.55492) (xy 392.107502 -279.530876) (xy 392.067634 -279.499847)
			(xy 392.033418 -279.462679) (xy 392.005786 -279.420385) (xy 391.985492 -279.374121) (xy 391.97309 -279.325147)
			(xy 391.968918 -279.2748) (xy 391.630154 -279.2748) (xy 391.629659 -279.299385) (xy 391.621764 -279.347962)
			(xy 391.60618 -279.394643) (xy 391.583309 -279.43822) (xy 391.553744 -279.477564) (xy 391.518251 -279.511656)
			(xy 391.477748 -279.539612) (xy 391.433286 -279.56071) (xy 391.386015 -279.574402) (xy 391.33716 -279.580334)
			(xy 391.287985 -279.578353) (xy 391.239766 -279.568509) (xy 391.19375 -279.551057) (xy 391.151129 -279.52645)
			(xy 391.113008 -279.495325) (xy 391.080373 -279.458488) (xy 391.05407 -279.416892) (xy 391.034779 -279.371616)
			(xy 391.023002 -279.323832) (xy 391.019042 -279.274778) (xy 390.680194 -279.274778) (xy 390.679699 -279.299385)
			(xy 390.671804 -279.347962) (xy 390.65622 -279.394643) (xy 390.633349 -279.43822) (xy 390.603784 -279.477564)
			(xy 390.568291 -279.511656) (xy 390.527788 -279.539612) (xy 390.483326 -279.56071) (xy 390.436055 -279.574402)
			(xy 390.3872 -279.580334) (xy 390.338025 -279.578353) (xy 390.289806 -279.568509) (xy 390.24379 -279.551057)
			(xy 390.201169 -279.52645) (xy 390.163048 -279.495325) (xy 390.130413 -279.458488) (xy 390.10411 -279.416892)
			(xy 390.084819 -279.371616) (xy 390.073042 -279.323832) (xy 390.069082 -279.274778) (xy 389.730234 -279.274778)
			(xy 389.729739 -279.299385) (xy 389.721844 -279.347962) (xy 389.70626 -279.394643) (xy 389.683389 -279.43822)
			(xy 389.653824 -279.477564) (xy 389.618331 -279.511656) (xy 389.577828 -279.539612) (xy 389.533366 -279.56071)
			(xy 389.486095 -279.574402) (xy 389.43724 -279.580334) (xy 389.388065 -279.578353) (xy 389.339846 -279.568509)
			(xy 389.29383 -279.551057) (xy 389.251209 -279.52645) (xy 389.213088 -279.495325) (xy 389.180453 -279.458488)
			(xy 389.15415 -279.416892) (xy 389.134859 -279.371616) (xy 389.123082 -279.323832) (xy 389.119122 -279.274778)
			(xy 388.780274 -279.274778) (xy 388.779779 -279.299385) (xy 388.771884 -279.347962) (xy 388.7563 -279.394643)
			(xy 388.733429 -279.43822) (xy 388.703864 -279.477564) (xy 388.668371 -279.511656) (xy 388.627868 -279.539612)
			(xy 388.583406 -279.56071) (xy 388.536135 -279.574402) (xy 388.48728 -279.580334) (xy 388.438105 -279.578353)
			(xy 388.389886 -279.568509) (xy 388.34387 -279.551057) (xy 388.301249 -279.52645) (xy 388.263128 -279.495325)
			(xy 388.230493 -279.458488) (xy 388.20419 -279.416892) (xy 388.184899 -279.371616) (xy 388.173122 -279.323832)
			(xy 388.169162 -279.274778) (xy 387.830314 -279.274778) (xy 387.829819 -279.299385) (xy 387.821924 -279.347962)
			(xy 387.80634 -279.394643) (xy 387.783469 -279.43822) (xy 387.753904 -279.477564) (xy 387.718411 -279.511656)
			(xy 387.677908 -279.539612) (xy 387.633446 -279.56071) (xy 387.586175 -279.574402) (xy 387.53732 -279.580334)
			(xy 387.488145 -279.578353) (xy 387.439926 -279.568509) (xy 387.39391 -279.551057) (xy 387.351289 -279.52645)
			(xy 387.313168 -279.495325) (xy 387.280533 -279.458488) (xy 387.25423 -279.416892) (xy 387.234939 -279.371616)
			(xy 387.223162 -279.323832) (xy 387.219202 -279.274778) (xy 386.880354 -279.274778) (xy 386.879859 -279.299385)
			(xy 386.871964 -279.347962) (xy 386.85638 -279.394643) (xy 386.833509 -279.43822) (xy 386.803944 -279.477564)
			(xy 386.768451 -279.511656) (xy 386.727948 -279.539612) (xy 386.683486 -279.56071) (xy 386.636215 -279.574402)
			(xy 386.58736 -279.580334) (xy 386.538185 -279.578353) (xy 386.489966 -279.568509) (xy 386.44395 -279.551057)
			(xy 386.401329 -279.52645) (xy 386.363208 -279.495325) (xy 386.330573 -279.458488) (xy 386.30427 -279.416892)
			(xy 386.284979 -279.371616) (xy 386.273202 -279.323832) (xy 386.269242 -279.274778) (xy 385.93014 -279.274778)
			(xy 385.929645 -279.299385) (xy 385.92175 -279.347962) (xy 385.906166 -279.394643) (xy 385.883295 -279.43822)
			(xy 385.85373 -279.477564) (xy 385.818237 -279.511656) (xy 385.777734 -279.539612) (xy 385.733272 -279.56071)
			(xy 385.686001 -279.574402) (xy 385.637146 -279.580334) (xy 385.587971 -279.578353) (xy 385.539752 -279.568509)
			(xy 385.493736 -279.551057) (xy 385.451115 -279.52645) (xy 385.412994 -279.495325) (xy 385.380359 -279.458488)
			(xy 385.354056 -279.416892) (xy 385.334765 -279.371616) (xy 385.322988 -279.323832) (xy 385.319028 -279.274778)
			(xy 384.98018 -279.274778) (xy 384.979685 -279.299385) (xy 384.97179 -279.347962) (xy 384.956206 -279.394643)
			(xy 384.933335 -279.43822) (xy 384.90377 -279.477564) (xy 384.868277 -279.511656) (xy 384.827774 -279.539612)
			(xy 384.783312 -279.56071) (xy 384.736041 -279.574402) (xy 384.687186 -279.580334) (xy 384.638011 -279.578353)
			(xy 384.589792 -279.568509) (xy 384.543776 -279.551057) (xy 384.501155 -279.52645) (xy 384.463034 -279.495325)
			(xy 384.430399 -279.458488) (xy 384.404096 -279.416892) (xy 384.384805 -279.371616) (xy 384.373028 -279.323832)
			(xy 384.369068 -279.274778) (xy 369.320022 -279.274778) (xy 369.190503 -279.307221) (xy 369.02783 -279.339579)
			(xy 368.863766 -279.363916) (xy 368.698704 -279.380174) (xy 368.533044 -279.388313) (xy 368.450114 -279.388824)
			(xy 368.449606 -279.388824) (xy 368.369576 -279.38835) (xy 368.209697 -279.38076) (xy 368.050356 -279.365607)
			(xy 367.891912 -279.342925) (xy 367.73472 -279.312765) (xy 367.579132 -279.275193) (xy 367.502186 -279.253188)
			(xy 367.49863 -279.252172) (xy 367.48466 -279.25014) (xy 367.476531 -279.250478) (xy 367.461117 -279.255659)
			(xy 367.454434 -279.2603) (xy 367.38941 -279.309068) (xy 367.380307 -279.316672) (xy 367.369718 -279.337863)
			(xy 367.36909 -279.349708) (xy 367.36909 -279.931114) (xy 374.111518 -279.931114) (xy 374.115589 -279.875492)
			(xy 374.127715 -279.821055) (xy 374.147638 -279.768964) (xy 374.174934 -279.720329) (xy 374.20902 -279.676186)
			(xy 374.249169 -279.637477) (xy 374.294527 -279.605026) (xy 374.344127 -279.579525) (xy 374.396911 -279.561518)
			(xy 374.451754 -279.551388) (xy 374.507488 -279.549351) (xy 374.562925 -279.555451) (xy 374.616882 -279.569557)
			(xy 374.668211 -279.591369) (xy 374.715817 -279.620423) (xy 374.758685 -279.656098) (xy 374.795902 -279.697635)
			(xy 374.826675 -279.744148) (xy 374.850347 -279.794645) (xy 374.866415 -279.848052) (xy 374.874535 -279.903228)
			(xy 374.875044 -279.931114) (xy 375.587004 -279.931114) (xy 375.591075 -279.875492) (xy 375.603201 -279.821055)
			(xy 375.623124 -279.768964) (xy 375.65042 -279.720329) (xy 375.684506 -279.676186) (xy 375.724655 -279.637477)
			(xy 375.770013 -279.605026) (xy 375.819613 -279.579525) (xy 375.872397 -279.561518) (xy 375.92724 -279.551388)
			(xy 375.982974 -279.549351) (xy 376.038411 -279.555451) (xy 376.092368 -279.569557) (xy 376.143697 -279.591369)
			(xy 376.191303 -279.620423) (xy 376.234171 -279.656098) (xy 376.271388 -279.697635) (xy 376.302161 -279.744148)
			(xy 376.325833 -279.794645) (xy 376.341901 -279.848052) (xy 376.350021 -279.903228) (xy 376.35053 -279.931114)
			(xy 376.476004 -279.931114) (xy 376.480075 -279.875492) (xy 376.492201 -279.821055) (xy 376.512124 -279.768964)
			(xy 376.53942 -279.720329) (xy 376.573506 -279.676186) (xy 376.613655 -279.637477) (xy 376.659013 -279.605026)
			(xy 376.708613 -279.579525) (xy 376.761397 -279.561518) (xy 376.81624 -279.551388) (xy 376.871974 -279.549351)
			(xy 376.927411 -279.555451) (xy 376.981368 -279.569557) (xy 377.032697 -279.591369) (xy 377.080303 -279.620423)
			(xy 377.123171 -279.656098) (xy 377.160388 -279.697635) (xy 377.191161 -279.744148) (xy 377.214833 -279.794645)
			(xy 377.230901 -279.848052) (xy 377.239021 -279.903228) (xy 377.23953 -279.931114) (xy 377.239021 -279.959)
			(xy 377.230901 -280.014176) (xy 377.214833 -280.067583) (xy 377.191161 -280.11808) (xy 377.160388 -280.164593)
			(xy 377.123171 -280.20613) (xy 377.080303 -280.241805) (xy 377.032697 -280.270859) (xy 376.981368 -280.292671)
			(xy 376.927411 -280.306777) (xy 376.871974 -280.312877) (xy 376.81624 -280.31084) (xy 376.761397 -280.30071)
			(xy 376.708613 -280.282703) (xy 376.659013 -280.257202) (xy 376.613655 -280.224751) (xy 376.573506 -280.186042)
			(xy 376.53942 -280.141899) (xy 376.512124 -280.093264) (xy 376.492201 -280.041173) (xy 376.480075 -279.986736)
			(xy 376.476004 -279.931114) (xy 376.35053 -279.931114) (xy 376.350021 -279.959) (xy 376.341901 -280.014176)
			(xy 376.325833 -280.067583) (xy 376.302161 -280.11808) (xy 376.271388 -280.164593) (xy 376.234171 -280.20613)
			(xy 376.191303 -280.241805) (xy 376.143697 -280.270859) (xy 376.092368 -280.292671) (xy 376.038411 -280.306777)
			(xy 375.982974 -280.312877) (xy 375.92724 -280.31084) (xy 375.872397 -280.30071) (xy 375.819613 -280.282703)
			(xy 375.770013 -280.257202) (xy 375.724655 -280.224751) (xy 375.684506 -280.186042) (xy 375.65042 -280.141899)
			(xy 375.623124 -280.093264) (xy 375.603201 -280.041173) (xy 375.591075 -279.986736) (xy 375.587004 -279.931114)
			(xy 374.875044 -279.931114) (xy 374.874535 -279.959) (xy 374.866415 -280.014176) (xy 374.850347 -280.067583)
			(xy 374.826675 -280.11808) (xy 374.795902 -280.164593) (xy 374.758685 -280.20613) (xy 374.715817 -280.241805)
			(xy 374.668211 -280.270859) (xy 374.616882 -280.292671) (xy 374.562925 -280.306777) (xy 374.507488 -280.312877)
			(xy 374.451754 -280.31084) (xy 374.396911 -280.30071) (xy 374.344127 -280.282703) (xy 374.294527 -280.257202)
			(xy 374.249169 -280.224751) (xy 374.20902 -280.186042) (xy 374.174934 -280.141899) (xy 374.147638 -280.093264)
			(xy 374.127715 -280.041173) (xy 374.115589 -279.986736) (xy 374.111518 -279.931114) (xy 367.36909 -279.931114)
			(xy 367.36909 -280.693114) (xy 379.638052 -280.693114) (xy 379.638619 -280.663733) (xy 379.647646 -280.605668)
			(xy 379.665474 -280.549675) (xy 379.691681 -280.49708) (xy 379.725646 -280.449128) (xy 379.766565 -280.406954)
			(xy 379.78969 -280.388822) (xy 379.798622 -280.38135) (xy 379.809075 -280.360569) (xy 379.809756 -280.348944)
			(xy 379.811026 -280.256996) (xy 379.80112 -280.235914) (xy 379.791976 -280.228548) (xy 379.770116 -280.210356)
			(xy 379.731578 -280.168534) (xy 379.699673 -280.121455) (xy 379.675108 -280.070163) (xy 379.658427 -280.015793)
			(xy 379.65 -279.95955) (xy 379.649482 -279.931114) (xy 379.649968 -279.903863) (xy 379.657724 -279.849915)
			(xy 379.673079 -279.79762) (xy 379.695721 -279.748043) (xy 379.725187 -279.702193) (xy 379.760878 -279.661002)
			(xy 379.802069 -279.625311) (xy 379.847919 -279.595845) (xy 379.897496 -279.573203) (xy 379.949791 -279.557848)
			(xy 380.003739 -279.550092) (xy 380.058241 -279.550092) (xy 380.112189 -279.557848) (xy 380.164484 -279.573203)
			(xy 380.214061 -279.595845) (xy 380.259911 -279.625311) (xy 380.301102 -279.661002) (xy 380.336793 -279.702193)
			(xy 380.366259 -279.748043) (xy 380.388901 -279.79762) (xy 380.404256 -279.849915) (xy 380.412012 -279.903863)
			(xy 380.412498 -279.931114) (xy 380.411971 -279.960497) (xy 380.402938 -280.018564) (xy 380.385103 -280.074559)
			(xy 380.358889 -280.127154) (xy 380.324916 -280.175105) (xy 380.283989 -280.217276) (xy 380.274469 -280.224738)
			(xy 384.369068 -280.224738) (xy 384.373028 -280.175684) (xy 384.384805 -280.1279) (xy 384.404096 -280.082624)
			(xy 384.430399 -280.041028) (xy 384.463034 -280.004191) (xy 384.501155 -279.973066) (xy 384.543776 -279.948459)
			(xy 384.589792 -279.931007) (xy 384.638011 -279.921163) (xy 384.687186 -279.919182) (xy 384.736041 -279.925114)
			(xy 384.783312 -279.938806) (xy 384.827774 -279.959904) (xy 384.868277 -279.98786) (xy 384.90377 -280.021952)
			(xy 384.933335 -280.061296) (xy 384.956206 -280.104873) (xy 384.97179 -280.151554) (xy 384.979685 -280.200131)
			(xy 384.98018 -280.224738) (xy 385.319028 -280.224738) (xy 385.322988 -280.175684) (xy 385.334765 -280.1279)
			(xy 385.354056 -280.082624) (xy 385.380359 -280.041028) (xy 385.412994 -280.004191) (xy 385.451115 -279.973066)
			(xy 385.493736 -279.948459) (xy 385.539752 -279.931007) (xy 385.587971 -279.921163) (xy 385.637146 -279.919182)
			(xy 385.686001 -279.925114) (xy 385.733272 -279.938806) (xy 385.777734 -279.959904) (xy 385.818237 -279.98786)
			(xy 385.85373 -280.021952) (xy 385.883295 -280.061296) (xy 385.906166 -280.104873) (xy 385.92175 -280.151554)
			(xy 385.929645 -280.200131) (xy 385.93014 -280.224738) (xy 386.269242 -280.224738) (xy 386.273202 -280.175684)
			(xy 386.284979 -280.1279) (xy 386.30427 -280.082624) (xy 386.330573 -280.041028) (xy 386.363208 -280.004191)
			(xy 386.401329 -279.973066) (xy 386.44395 -279.948459) (xy 386.489966 -279.931007) (xy 386.538185 -279.921163)
			(xy 386.58736 -279.919182) (xy 386.636215 -279.925114) (xy 386.683486 -279.938806) (xy 386.727948 -279.959904)
			(xy 386.768451 -279.98786) (xy 386.803944 -280.021952) (xy 386.833509 -280.061296) (xy 386.85638 -280.104873)
			(xy 386.871964 -280.151554) (xy 386.879859 -280.200131) (xy 386.880354 -280.224738) (xy 387.219202 -280.224738)
			(xy 387.223162 -280.175684) (xy 387.234939 -280.1279) (xy 387.25423 -280.082624) (xy 387.280533 -280.041028)
			(xy 387.313168 -280.004191) (xy 387.351289 -279.973066) (xy 387.39391 -279.948459) (xy 387.439926 -279.931007)
			(xy 387.488145 -279.921163) (xy 387.53732 -279.919182) (xy 387.586175 -279.925114) (xy 387.633446 -279.938806)
			(xy 387.677908 -279.959904) (xy 387.718411 -279.98786) (xy 387.753904 -280.021952) (xy 387.783469 -280.061296)
			(xy 387.80634 -280.104873) (xy 387.821924 -280.151554) (xy 387.829819 -280.200131) (xy 387.830314 -280.224738)
			(xy 388.169162 -280.224738) (xy 388.173122 -280.175684) (xy 388.184899 -280.1279) (xy 388.20419 -280.082624)
			(xy 388.230493 -280.041028) (xy 388.263128 -280.004191) (xy 388.301249 -279.973066) (xy 388.34387 -279.948459)
			(xy 388.389886 -279.931007) (xy 388.438105 -279.921163) (xy 388.48728 -279.919182) (xy 388.536135 -279.925114)
			(xy 388.583406 -279.938806) (xy 388.627868 -279.959904) (xy 388.668371 -279.98786) (xy 388.703864 -280.021952)
			(xy 388.733429 -280.061296) (xy 388.7563 -280.104873) (xy 388.771884 -280.151554) (xy 388.779779 -280.200131)
			(xy 388.780274 -280.224738) (xy 389.119122 -280.224738) (xy 389.123082 -280.175684) (xy 389.134859 -280.1279)
			(xy 389.15415 -280.082624) (xy 389.180453 -280.041028) (xy 389.213088 -280.004191) (xy 389.251209 -279.973066)
			(xy 389.29383 -279.948459) (xy 389.339846 -279.931007) (xy 389.388065 -279.921163) (xy 389.43724 -279.919182)
			(xy 389.486095 -279.925114) (xy 389.533366 -279.938806) (xy 389.577828 -279.959904) (xy 389.618331 -279.98786)
			(xy 389.653824 -280.021952) (xy 389.683389 -280.061296) (xy 389.70626 -280.104873) (xy 389.721844 -280.151554)
			(xy 389.729739 -280.200131) (xy 389.730234 -280.224738) (xy 390.069082 -280.224738) (xy 390.073042 -280.175684)
			(xy 390.084819 -280.1279) (xy 390.10411 -280.082624) (xy 390.130413 -280.041028) (xy 390.163048 -280.004191)
			(xy 390.201169 -279.973066) (xy 390.24379 -279.948459) (xy 390.289806 -279.931007) (xy 390.338025 -279.921163)
			(xy 390.3872 -279.919182) (xy 390.436055 -279.925114) (xy 390.483326 -279.938806) (xy 390.527788 -279.959904)
			(xy 390.568291 -279.98786) (xy 390.603784 -280.021952) (xy 390.633349 -280.061296) (xy 390.65622 -280.104873)
			(xy 390.671804 -280.151554) (xy 390.679699 -280.200131) (xy 390.680194 -280.224738) (xy 391.019042 -280.224738)
			(xy 391.023002 -280.175684) (xy 391.034779 -280.1279) (xy 391.05407 -280.082624) (xy 391.080373 -280.041028)
			(xy 391.113008 -280.004191) (xy 391.151129 -279.973066) (xy 391.19375 -279.948459) (xy 391.239766 -279.931007)
			(xy 391.287985 -279.921163) (xy 391.33716 -279.919182) (xy 391.386015 -279.925114) (xy 391.433286 -279.938806)
			(xy 391.477748 -279.959904) (xy 391.518251 -279.98786) (xy 391.553744 -280.021952) (xy 391.583309 -280.061296)
			(xy 391.60618 -280.104873) (xy 391.621764 -280.151554) (xy 391.629659 -280.200131) (xy 391.630154 -280.224738)
			(xy 391.629659 -280.249345) (xy 391.621764 -280.297922) (xy 391.60618 -280.344603) (xy 391.583309 -280.38818)
			(xy 391.553744 -280.427524) (xy 391.518251 -280.461616) (xy 391.477748 -280.489572) (xy 391.433286 -280.51067)
			(xy 391.386015 -280.524362) (xy 391.33716 -280.530294) (xy 391.287985 -280.528313) (xy 391.239766 -280.518469)
			(xy 391.19375 -280.501017) (xy 391.151129 -280.47641) (xy 391.113008 -280.445285) (xy 391.080373 -280.408448)
			(xy 391.05407 -280.366852) (xy 391.034779 -280.321576) (xy 391.023002 -280.273792) (xy 391.019042 -280.224738)
			(xy 390.680194 -280.224738) (xy 390.679699 -280.249345) (xy 390.671804 -280.297922) (xy 390.65622 -280.344603)
			(xy 390.633349 -280.38818) (xy 390.603784 -280.427524) (xy 390.568291 -280.461616) (xy 390.527788 -280.489572)
			(xy 390.483326 -280.51067) (xy 390.436055 -280.524362) (xy 390.3872 -280.530294) (xy 390.338025 -280.528313)
			(xy 390.289806 -280.518469) (xy 390.24379 -280.501017) (xy 390.201169 -280.47641) (xy 390.163048 -280.445285)
			(xy 390.130413 -280.408448) (xy 390.10411 -280.366852) (xy 390.084819 -280.321576) (xy 390.073042 -280.273792)
			(xy 390.069082 -280.224738) (xy 389.730234 -280.224738) (xy 389.729739 -280.249345) (xy 389.721844 -280.297922)
			(xy 389.70626 -280.344603) (xy 389.683389 -280.38818) (xy 389.653824 -280.427524) (xy 389.618331 -280.461616)
			(xy 389.577828 -280.489572) (xy 389.533366 -280.51067) (xy 389.486095 -280.524362) (xy 389.43724 -280.530294)
			(xy 389.388065 -280.528313) (xy 389.339846 -280.518469) (xy 389.29383 -280.501017) (xy 389.251209 -280.47641)
			(xy 389.213088 -280.445285) (xy 389.180453 -280.408448) (xy 389.15415 -280.366852) (xy 389.134859 -280.321576)
			(xy 389.123082 -280.273792) (xy 389.119122 -280.224738) (xy 388.780274 -280.224738) (xy 388.779779 -280.249345)
			(xy 388.771884 -280.297922) (xy 388.7563 -280.344603) (xy 388.733429 -280.38818) (xy 388.703864 -280.427524)
			(xy 388.668371 -280.461616) (xy 388.627868 -280.489572) (xy 388.583406 -280.51067) (xy 388.536135 -280.524362)
			(xy 388.48728 -280.530294) (xy 388.438105 -280.528313) (xy 388.389886 -280.518469) (xy 388.34387 -280.501017)
			(xy 388.301249 -280.47641) (xy 388.263128 -280.445285) (xy 388.230493 -280.408448) (xy 388.20419 -280.366852)
			(xy 388.184899 -280.321576) (xy 388.173122 -280.273792) (xy 388.169162 -280.224738) (xy 387.830314 -280.224738)
			(xy 387.829819 -280.249345) (xy 387.821924 -280.297922) (xy 387.80634 -280.344603) (xy 387.783469 -280.38818)
			(xy 387.753904 -280.427524) (xy 387.718411 -280.461616) (xy 387.677908 -280.489572) (xy 387.633446 -280.51067)
			(xy 387.586175 -280.524362) (xy 387.53732 -280.530294) (xy 387.488145 -280.528313) (xy 387.439926 -280.518469)
			(xy 387.39391 -280.501017) (xy 387.351289 -280.47641) (xy 387.313168 -280.445285) (xy 387.280533 -280.408448)
			(xy 387.25423 -280.366852) (xy 387.234939 -280.321576) (xy 387.223162 -280.273792) (xy 387.219202 -280.224738)
			(xy 386.880354 -280.224738) (xy 386.879859 -280.249345) (xy 386.871964 -280.297922) (xy 386.85638 -280.344603)
			(xy 386.833509 -280.38818) (xy 386.803944 -280.427524) (xy 386.768451 -280.461616) (xy 386.727948 -280.489572)
			(xy 386.683486 -280.51067) (xy 386.636215 -280.524362) (xy 386.58736 -280.530294) (xy 386.538185 -280.528313)
			(xy 386.489966 -280.518469) (xy 386.44395 -280.501017) (xy 386.401329 -280.47641) (xy 386.363208 -280.445285)
			(xy 386.330573 -280.408448) (xy 386.30427 -280.366852) (xy 386.284979 -280.321576) (xy 386.273202 -280.273792)
			(xy 386.269242 -280.224738) (xy 385.93014 -280.224738) (xy 385.929645 -280.249345) (xy 385.92175 -280.297922)
			(xy 385.906166 -280.344603) (xy 385.883295 -280.38818) (xy 385.85373 -280.427524) (xy 385.818237 -280.461616)
			(xy 385.777734 -280.489572) (xy 385.733272 -280.51067) (xy 385.686001 -280.524362) (xy 385.637146 -280.530294)
			(xy 385.587971 -280.528313) (xy 385.539752 -280.518469) (xy 385.493736 -280.501017) (xy 385.451115 -280.47641)
			(xy 385.412994 -280.445285) (xy 385.380359 -280.408448) (xy 385.354056 -280.366852) (xy 385.334765 -280.321576)
			(xy 385.322988 -280.273792) (xy 385.319028 -280.224738) (xy 384.98018 -280.224738) (xy 384.979685 -280.249345)
			(xy 384.97179 -280.297922) (xy 384.956206 -280.344603) (xy 384.933335 -280.38818) (xy 384.90377 -280.427524)
			(xy 384.868277 -280.461616) (xy 384.827774 -280.489572) (xy 384.783312 -280.51067) (xy 384.736041 -280.524362)
			(xy 384.687186 -280.530294) (xy 384.638011 -280.528313) (xy 384.589792 -280.518469) (xy 384.543776 -280.501017)
			(xy 384.501155 -280.47641) (xy 384.463034 -280.445285) (xy 384.430399 -280.408448) (xy 384.404096 -280.366852)
			(xy 384.384805 -280.321576) (xy 384.373028 -280.273792) (xy 384.369068 -280.224738) (xy 380.274469 -280.224738)
			(xy 380.26086 -280.235406) (xy 380.251924 -280.242875) (xy 380.241471 -280.263657) (xy 380.240794 -280.275284)
			(xy 380.239524 -280.367232) (xy 380.24943 -280.388314) (xy 380.258574 -280.39568) (xy 380.280389 -280.413924)
			(xy 380.318933 -280.455734) (xy 380.350844 -280.502801) (xy 380.375417 -280.554084) (xy 380.392107 -280.608445)
			(xy 380.400545 -280.664681) (xy 380.401068 -280.693114) (xy 381.034542 -280.693114) (xy 381.038613 -280.637492)
			(xy 381.050739 -280.583055) (xy 381.070662 -280.530964) (xy 381.097958 -280.482329) (xy 381.132044 -280.438186)
			(xy 381.172193 -280.399477) (xy 381.217551 -280.367026) (xy 381.267151 -280.341525) (xy 381.319935 -280.323518)
			(xy 381.374778 -280.313388) (xy 381.430512 -280.311351) (xy 381.485949 -280.317451) (xy 381.539906 -280.331557)
			(xy 381.591235 -280.353369) (xy 381.638841 -280.382423) (xy 381.681709 -280.418098) (xy 381.718926 -280.459635)
			(xy 381.749699 -280.506148) (xy 381.773371 -280.556645) (xy 381.789439 -280.610052) (xy 381.797559 -280.665228)
			(xy 381.798068 -280.693114) (xy 381.921002 -280.693114) (xy 381.925073 -280.637492) (xy 381.937199 -280.583055)
			(xy 381.957122 -280.530964) (xy 381.984418 -280.482329) (xy 382.018504 -280.438186) (xy 382.058653 -280.399477)
			(xy 382.104011 -280.367026) (xy 382.153611 -280.341525) (xy 382.206395 -280.323518) (xy 382.261238 -280.313388)
			(xy 382.316972 -280.311351) (xy 382.372409 -280.317451) (xy 382.426366 -280.331557) (xy 382.477695 -280.353369)
			(xy 382.525301 -280.382423) (xy 382.568169 -280.418098) (xy 382.605386 -280.459635) (xy 382.636159 -280.506148)
			(xy 382.659831 -280.556645) (xy 382.675899 -280.610052) (xy 382.684019 -280.665228) (xy 382.684528 -280.693114)
			(xy 382.684019 -280.721) (xy 382.675899 -280.776176) (xy 382.659831 -280.829583) (xy 382.636159 -280.88008)
			(xy 382.605386 -280.926593) (xy 382.568169 -280.96813) (xy 382.525301 -281.003805) (xy 382.477695 -281.032859)
			(xy 382.426366 -281.054671) (xy 382.372409 -281.068777) (xy 382.316972 -281.074877) (xy 382.261238 -281.07284)
			(xy 382.206395 -281.06271) (xy 382.153611 -281.044703) (xy 382.104011 -281.019202) (xy 382.058653 -280.986751)
			(xy 382.018504 -280.948042) (xy 381.984418 -280.903899) (xy 381.957122 -280.855264) (xy 381.937199 -280.803173)
			(xy 381.925073 -280.748736) (xy 381.921002 -280.693114) (xy 381.798068 -280.693114) (xy 381.797559 -280.721)
			(xy 381.789439 -280.776176) (xy 381.773371 -280.829583) (xy 381.749699 -280.88008) (xy 381.718926 -280.926593)
			(xy 381.681709 -280.96813) (xy 381.638841 -281.003805) (xy 381.591235 -281.032859) (xy 381.539906 -281.054671)
			(xy 381.485949 -281.068777) (xy 381.430512 -281.074877) (xy 381.374778 -281.07284) (xy 381.319935 -281.06271)
			(xy 381.267151 -281.044703) (xy 381.217551 -281.019202) (xy 381.172193 -280.986751) (xy 381.132044 -280.948042)
			(xy 381.097958 -280.903899) (xy 381.070662 -280.855264) (xy 381.050739 -280.803173) (xy 381.038613 -280.748736)
			(xy 381.034542 -280.693114) (xy 380.401068 -280.693114) (xy 380.400582 -280.720365) (xy 380.392826 -280.774313)
			(xy 380.377471 -280.826608) (xy 380.354829 -280.876185) (xy 380.325363 -280.922035) (xy 380.289672 -280.963226)
			(xy 380.248481 -280.998917) (xy 380.202631 -281.028383) (xy 380.153054 -281.051025) (xy 380.100759 -281.06638)
			(xy 380.046811 -281.074136) (xy 379.992309 -281.074136) (xy 379.938361 -281.06638) (xy 379.886066 -281.051025)
			(xy 379.836489 -281.028383) (xy 379.790639 -280.998917) (xy 379.749448 -280.963226) (xy 379.713757 -280.922035)
			(xy 379.684291 -280.876185) (xy 379.661649 -280.826608) (xy 379.646294 -280.774313) (xy 379.638538 -280.720365)
			(xy 379.638052 -280.693114) (xy 367.36909 -280.693114) (xy 367.36909 -281.174952) (xy 384.369068 -281.174952)
			(xy 384.373028 -281.125898) (xy 384.384805 -281.078114) (xy 384.404096 -281.032838) (xy 384.430399 -280.991242)
			(xy 384.463034 -280.954405) (xy 384.501155 -280.92328) (xy 384.543776 -280.898673) (xy 384.589792 -280.881221)
			(xy 384.638011 -280.871377) (xy 384.687186 -280.869396) (xy 384.736041 -280.875328) (xy 384.783312 -280.88902)
			(xy 384.827774 -280.910118) (xy 384.868277 -280.938074) (xy 384.90377 -280.972166) (xy 384.933335 -281.01151)
			(xy 384.956206 -281.055087) (xy 384.97179 -281.101768) (xy 384.979685 -281.150345) (xy 384.98018 -281.174952)
			(xy 385.319028 -281.174952) (xy 385.322988 -281.125898) (xy 385.334765 -281.078114) (xy 385.354056 -281.032838)
			(xy 385.380359 -280.991242) (xy 385.412994 -280.954405) (xy 385.451115 -280.92328) (xy 385.493736 -280.898673)
			(xy 385.539752 -280.881221) (xy 385.587971 -280.871377) (xy 385.637146 -280.869396) (xy 385.686001 -280.875328)
			(xy 385.733272 -280.88902) (xy 385.777734 -280.910118) (xy 385.818237 -280.938074) (xy 385.85373 -280.972166)
			(xy 385.883295 -281.01151) (xy 385.906166 -281.055087) (xy 385.92175 -281.101768) (xy 385.929645 -281.150345)
			(xy 385.93014 -281.174952) (xy 386.269242 -281.174952) (xy 386.273202 -281.125898) (xy 386.284979 -281.078114)
			(xy 386.30427 -281.032838) (xy 386.330573 -280.991242) (xy 386.363208 -280.954405) (xy 386.401329 -280.92328)
			(xy 386.44395 -280.898673) (xy 386.489966 -280.881221) (xy 386.538185 -280.871377) (xy 386.58736 -280.869396)
			(xy 386.636215 -280.875328) (xy 386.683486 -280.88902) (xy 386.727948 -280.910118) (xy 386.768451 -280.938074)
			(xy 386.803944 -280.972166) (xy 386.833509 -281.01151) (xy 386.85638 -281.055087) (xy 386.871964 -281.101768)
			(xy 386.879859 -281.150345) (xy 386.880354 -281.174952) (xy 387.219202 -281.174952) (xy 387.223162 -281.125898)
			(xy 387.234939 -281.078114) (xy 387.25423 -281.032838) (xy 387.280533 -280.991242) (xy 387.313168 -280.954405)
			(xy 387.351289 -280.92328) (xy 387.39391 -280.898673) (xy 387.439926 -280.881221) (xy 387.488145 -280.871377)
			(xy 387.53732 -280.869396) (xy 387.586175 -280.875328) (xy 387.633446 -280.88902) (xy 387.677908 -280.910118)
			(xy 387.718411 -280.938074) (xy 387.753904 -280.972166) (xy 387.783469 -281.01151) (xy 387.80634 -281.055087)
			(xy 387.821924 -281.101768) (xy 387.829819 -281.150345) (xy 387.830314 -281.174952) (xy 388.169162 -281.174952)
			(xy 388.173122 -281.125898) (xy 388.184899 -281.078114) (xy 388.20419 -281.032838) (xy 388.230493 -280.991242)
			(xy 388.263128 -280.954405) (xy 388.301249 -280.92328) (xy 388.34387 -280.898673) (xy 388.389886 -280.881221)
			(xy 388.438105 -280.871377) (xy 388.48728 -280.869396) (xy 388.536135 -280.875328) (xy 388.583406 -280.88902)
			(xy 388.627868 -280.910118) (xy 388.668371 -280.938074) (xy 388.703864 -280.972166) (xy 388.733429 -281.01151)
			(xy 388.7563 -281.055087) (xy 388.771884 -281.101768) (xy 388.779779 -281.150345) (xy 388.780274 -281.174952)
			(xy 389.119122 -281.174952) (xy 389.123082 -281.125898) (xy 389.134859 -281.078114) (xy 389.15415 -281.032838)
			(xy 389.180453 -280.991242) (xy 389.213088 -280.954405) (xy 389.251209 -280.92328) (xy 389.29383 -280.898673)
			(xy 389.339846 -280.881221) (xy 389.388065 -280.871377) (xy 389.43724 -280.869396) (xy 389.486095 -280.875328)
			(xy 389.533366 -280.88902) (xy 389.577828 -280.910118) (xy 389.618331 -280.938074) (xy 389.653824 -280.972166)
			(xy 389.683389 -281.01151) (xy 389.70626 -281.055087) (xy 389.721844 -281.101768) (xy 389.729739 -281.150345)
			(xy 389.730234 -281.174952) (xy 390.069082 -281.174952) (xy 390.073042 -281.125898) (xy 390.084819 -281.078114)
			(xy 390.10411 -281.032838) (xy 390.130413 -280.991242) (xy 390.163048 -280.954405) (xy 390.201169 -280.92328)
			(xy 390.24379 -280.898673) (xy 390.289806 -280.881221) (xy 390.338025 -280.871377) (xy 390.3872 -280.869396)
			(xy 390.436055 -280.875328) (xy 390.483326 -280.88902) (xy 390.527788 -280.910118) (xy 390.568291 -280.938074)
			(xy 390.603784 -280.972166) (xy 390.633349 -281.01151) (xy 390.65622 -281.055087) (xy 390.671804 -281.101768)
			(xy 390.679699 -281.150345) (xy 390.680194 -281.174952) (xy 391.019042 -281.174952) (xy 391.023002 -281.125898)
			(xy 391.034779 -281.078114) (xy 391.05407 -281.032838) (xy 391.080373 -280.991242) (xy 391.113008 -280.954405)
			(xy 391.151129 -280.92328) (xy 391.19375 -280.898673) (xy 391.239766 -280.881221) (xy 391.287985 -280.871377)
			(xy 391.33716 -280.869396) (xy 391.386015 -280.875328) (xy 391.433286 -280.88902) (xy 391.477748 -280.910118)
			(xy 391.518251 -280.938074) (xy 391.553744 -280.972166) (xy 391.583309 -281.01151) (xy 391.60618 -281.055087)
			(xy 391.621764 -281.101768) (xy 391.629659 -281.150345) (xy 391.629989 -281.166729) (xy 391.969032 -281.166729)
			(xy 391.974399 -281.117368) (xy 391.987681 -281.069526) (xy 392.008528 -281.024463) (xy 392.036391 -280.983367)
			(xy 392.070536 -280.94732) (xy 392.110063 -280.917272) (xy 392.15393 -280.894015) (xy 392.200983 -280.878161)
			(xy 392.24998 -280.870129) (xy 392.274806 -280.869644) (xy 392.288989 -280.869819) (xy 392.317229 -280.872492)
			(xy 392.331194 -280.874978) (xy 392.345156 -280.877182) (xy 392.373296 -280.874604) (xy 392.399651 -280.864411)
			(xy 392.422203 -280.847384) (xy 392.439224 -280.824827) (xy 392.44941 -280.798469) (xy 392.451981 -280.770329)
			(xy 392.449812 -280.75636) (xy 392.447324 -280.742332) (xy 392.444654 -280.713964) (xy 392.444478 -280.699718)
			(xy 392.444959 -280.674895) (xy 392.452988 -280.625903) (xy 392.468837 -280.578855) (xy 392.492089 -280.534991)
			(xy 392.522132 -280.495468) (xy 392.558173 -280.461325) (xy 392.599263 -280.433463) (xy 392.64432 -280.412615)
			(xy 392.692156 -280.399332) (xy 392.74151 -280.393963) (xy 392.791083 -280.39665) (xy 392.839569 -280.407321)
			(xy 392.885689 -280.425696) (xy 392.928228 -280.451291) (xy 392.966066 -280.483431) (xy 392.998207 -280.521269)
			(xy 393.023802 -280.563808) (xy 393.042177 -280.609928) (xy 393.052849 -280.658413) (xy 393.055089 -280.699718)
			(xy 393.394196 -280.699718) (xy 393.398156 -280.650664) (xy 393.409933 -280.60288) (xy 393.429224 -280.557604)
			(xy 393.455527 -280.516008) (xy 393.488162 -280.479171) (xy 393.526283 -280.448046) (xy 393.568904 -280.423439)
			(xy 393.61492 -280.405987) (xy 393.663139 -280.396143) (xy 393.712314 -280.394162) (xy 393.761169 -280.400094)
			(xy 393.80844 -280.413786) (xy 393.852902 -280.434884) (xy 393.893405 -280.46284) (xy 393.928898 -280.496932)
			(xy 393.958463 -280.536276) (xy 393.981334 -280.579853) (xy 393.996918 -280.626534) (xy 394.004813 -280.675111)
			(xy 394.005308 -280.699718) (xy 394.344156 -280.699718) (xy 394.348116 -280.650664) (xy 394.359893 -280.60288)
			(xy 394.379184 -280.557604) (xy 394.405487 -280.516008) (xy 394.438122 -280.479171) (xy 394.476243 -280.448046)
			(xy 394.518864 -280.423439) (xy 394.56488 -280.405987) (xy 394.613099 -280.396143) (xy 394.662274 -280.394162)
			(xy 394.711129 -280.400094) (xy 394.7584 -280.413786) (xy 394.802862 -280.434884) (xy 394.843365 -280.46284)
			(xy 394.878858 -280.496932) (xy 394.908423 -280.536276) (xy 394.931294 -280.579853) (xy 394.946878 -280.626534)
			(xy 394.954773 -280.675111) (xy 394.955268 -280.699718) (xy 395.294116 -280.699718) (xy 395.298076 -280.650664)
			(xy 395.309853 -280.60288) (xy 395.329144 -280.557604) (xy 395.355447 -280.516008) (xy 395.388082 -280.479171)
			(xy 395.426203 -280.448046) (xy 395.468824 -280.423439) (xy 395.51484 -280.405987) (xy 395.563059 -280.396143)
			(xy 395.612234 -280.394162) (xy 395.661089 -280.400094) (xy 395.70836 -280.413786) (xy 395.752822 -280.434884)
			(xy 395.793325 -280.46284) (xy 395.828818 -280.496932) (xy 395.858383 -280.536276) (xy 395.881254 -280.579853)
			(xy 395.896838 -280.626534) (xy 395.904733 -280.675111) (xy 395.905228 -280.699718) (xy 396.244076 -280.699718)
			(xy 396.248036 -280.650664) (xy 396.259813 -280.60288) (xy 396.279104 -280.557604) (xy 396.305407 -280.516008)
			(xy 396.338042 -280.479171) (xy 396.376163 -280.448046) (xy 396.418784 -280.423439) (xy 396.4648 -280.405987)
			(xy 396.513019 -280.396143) (xy 396.562194 -280.394162) (xy 396.611049 -280.400094) (xy 396.65832 -280.413786)
			(xy 396.702782 -280.434884) (xy 396.743285 -280.46284) (xy 396.778778 -280.496932) (xy 396.808343 -280.536276)
			(xy 396.831214 -280.579853) (xy 396.846798 -280.626534) (xy 396.854693 -280.675111) (xy 396.855188 -280.699718)
			(xy 397.194036 -280.699718) (xy 397.197996 -280.650664) (xy 397.209773 -280.60288) (xy 397.229064 -280.557604)
			(xy 397.255367 -280.516008) (xy 397.288002 -280.479171) (xy 397.326123 -280.448046) (xy 397.368744 -280.423439)
			(xy 397.41476 -280.405987) (xy 397.462979 -280.396143) (xy 397.512154 -280.394162) (xy 397.561009 -280.400094)
			(xy 397.60828 -280.413786) (xy 397.652742 -280.434884) (xy 397.693245 -280.46284) (xy 397.728738 -280.496932)
			(xy 397.758303 -280.536276) (xy 397.781174 -280.579853) (xy 397.796758 -280.626534) (xy 397.804653 -280.675111)
			(xy 397.805148 -280.699718) (xy 398.143996 -280.699718) (xy 398.147956 -280.650664) (xy 398.159733 -280.60288)
			(xy 398.179024 -280.557604) (xy 398.205327 -280.516008) (xy 398.237962 -280.479171) (xy 398.276083 -280.448046)
			(xy 398.318704 -280.423439) (xy 398.36472 -280.405987) (xy 398.412939 -280.396143) (xy 398.462114 -280.394162)
			(xy 398.510969 -280.400094) (xy 398.55824 -280.413786) (xy 398.602702 -280.434884) (xy 398.643205 -280.46284)
			(xy 398.678698 -280.496932) (xy 398.708263 -280.536276) (xy 398.731134 -280.579853) (xy 398.746718 -280.626534)
			(xy 398.754613 -280.675111) (xy 398.755108 -280.699718) (xy 399.09421 -280.699718) (xy 399.09817 -280.650664)
			(xy 399.109947 -280.60288) (xy 399.129238 -280.557604) (xy 399.155541 -280.516008) (xy 399.188176 -280.479171)
			(xy 399.226297 -280.448046) (xy 399.268918 -280.423439) (xy 399.314934 -280.405987) (xy 399.363153 -280.396143)
			(xy 399.412328 -280.394162) (xy 399.461183 -280.400094) (xy 399.508454 -280.413786) (xy 399.552916 -280.434884)
			(xy 399.593419 -280.46284) (xy 399.628912 -280.496932) (xy 399.658477 -280.536276) (xy 399.681348 -280.579853)
			(xy 399.696932 -280.626534) (xy 399.704827 -280.675111) (xy 399.705322 -280.699718) (xy 400.04417 -280.699718)
			(xy 400.04813 -280.650664) (xy 400.059907 -280.60288) (xy 400.079198 -280.557604) (xy 400.105501 -280.516008)
			(xy 400.138136 -280.479171) (xy 400.176257 -280.448046) (xy 400.218878 -280.423439) (xy 400.264894 -280.405987)
			(xy 400.313113 -280.396143) (xy 400.362288 -280.394162) (xy 400.411143 -280.400094) (xy 400.458414 -280.413786)
			(xy 400.502876 -280.434884) (xy 400.543379 -280.46284) (xy 400.578872 -280.496932) (xy 400.608437 -280.536276)
			(xy 400.631308 -280.579853) (xy 400.646892 -280.626534) (xy 400.654787 -280.675111) (xy 400.655282 -280.699718)
			(xy 400.99413 -280.699718) (xy 400.99809 -280.650664) (xy 401.009867 -280.60288) (xy 401.029158 -280.557604)
			(xy 401.055461 -280.516008) (xy 401.088096 -280.479171) (xy 401.126217 -280.448046) (xy 401.168838 -280.423439)
			(xy 401.214854 -280.405987) (xy 401.263073 -280.396143) (xy 401.312248 -280.394162) (xy 401.361103 -280.400094)
			(xy 401.408374 -280.413786) (xy 401.452836 -280.434884) (xy 401.493339 -280.46284) (xy 401.528832 -280.496932)
			(xy 401.558397 -280.536276) (xy 401.581268 -280.579853) (xy 401.596852 -280.626534) (xy 401.604747 -280.675111)
			(xy 401.605242 -280.699718) (xy 401.94409 -280.699718) (xy 401.94805 -280.650664) (xy 401.959827 -280.60288)
			(xy 401.979118 -280.557604) (xy 402.005421 -280.516008) (xy 402.038056 -280.479171) (xy 402.076177 -280.448046)
			(xy 402.118798 -280.423439) (xy 402.164814 -280.405987) (xy 402.213033 -280.396143) (xy 402.262208 -280.394162)
			(xy 402.311063 -280.400094) (xy 402.358334 -280.413786) (xy 402.402796 -280.434884) (xy 402.443299 -280.46284)
			(xy 402.478792 -280.496932) (xy 402.508357 -280.536276) (xy 402.531228 -280.579853) (xy 402.546812 -280.626534)
			(xy 402.554707 -280.675111) (xy 402.555202 -280.699718) (xy 402.89405 -280.699718) (xy 402.89801 -280.650664)
			(xy 402.909787 -280.60288) (xy 402.929078 -280.557604) (xy 402.955381 -280.516008) (xy 402.988016 -280.479171)
			(xy 403.026137 -280.448046) (xy 403.068758 -280.423439) (xy 403.114774 -280.405987) (xy 403.162993 -280.396143)
			(xy 403.212168 -280.394162) (xy 403.261023 -280.400094) (xy 403.308294 -280.413786) (xy 403.352756 -280.434884)
			(xy 403.393259 -280.46284) (xy 403.428752 -280.496932) (xy 403.458317 -280.536276) (xy 403.481188 -280.579853)
			(xy 403.496772 -280.626534) (xy 403.504667 -280.675111) (xy 403.505162 -280.699718) (xy 403.84401 -280.699718)
			(xy 403.84797 -280.650664) (xy 403.859747 -280.60288) (xy 403.879038 -280.557604) (xy 403.905341 -280.516008)
			(xy 403.937976 -280.479171) (xy 403.976097 -280.448046) (xy 404.018718 -280.423439) (xy 404.064734 -280.405987)
			(xy 404.112953 -280.396143) (xy 404.162128 -280.394162) (xy 404.210983 -280.400094) (xy 404.258254 -280.413786)
			(xy 404.302716 -280.434884) (xy 404.343219 -280.46284) (xy 404.378712 -280.496932) (xy 404.408277 -280.536276)
			(xy 404.431148 -280.579853) (xy 404.446732 -280.626534) (xy 404.454627 -280.675111) (xy 404.455122 -280.699718)
			(xy 404.79397 -280.699718) (xy 404.79793 -280.650664) (xy 404.809707 -280.60288) (xy 404.828998 -280.557604)
			(xy 404.855301 -280.516008) (xy 404.887936 -280.479171) (xy 404.926057 -280.448046) (xy 404.968678 -280.423439)
			(xy 405.014694 -280.405987) (xy 405.062913 -280.396143) (xy 405.112088 -280.394162) (xy 405.160943 -280.400094)
			(xy 405.208214 -280.413786) (xy 405.252676 -280.434884) (xy 405.293179 -280.46284) (xy 405.328672 -280.496932)
			(xy 405.358237 -280.536276) (xy 405.381108 -280.579853) (xy 405.396692 -280.626534) (xy 405.404587 -280.675111)
			(xy 405.405082 -280.699718) (xy 405.744184 -280.699718) (xy 405.748144 -280.650664) (xy 405.759921 -280.60288)
			(xy 405.779212 -280.557604) (xy 405.805515 -280.516008) (xy 405.83815 -280.479171) (xy 405.876271 -280.448046)
			(xy 405.918892 -280.423439) (xy 405.964908 -280.405987) (xy 406.013127 -280.396143) (xy 406.062302 -280.394162)
			(xy 406.111157 -280.400094) (xy 406.158428 -280.413786) (xy 406.20289 -280.434884) (xy 406.243393 -280.46284)
			(xy 406.278886 -280.496932) (xy 406.308451 -280.536276) (xy 406.331322 -280.579853) (xy 406.346906 -280.626534)
			(xy 406.354801 -280.675111) (xy 406.355296 -280.699718) (xy 406.694144 -280.699718) (xy 406.698104 -280.650664)
			(xy 406.709881 -280.60288) (xy 406.729172 -280.557604) (xy 406.755475 -280.516008) (xy 406.78811 -280.479171)
			(xy 406.826231 -280.448046) (xy 406.868852 -280.423439) (xy 406.914868 -280.405987) (xy 406.963087 -280.396143)
			(xy 407.012262 -280.394162) (xy 407.061117 -280.400094) (xy 407.108388 -280.413786) (xy 407.15285 -280.434884)
			(xy 407.193353 -280.46284) (xy 407.228846 -280.496932) (xy 407.258411 -280.536276) (xy 407.281282 -280.579853)
			(xy 407.296866 -280.626534) (xy 407.304761 -280.675111) (xy 407.305256 -280.699718) (xy 407.644104 -280.699718)
			(xy 407.648064 -280.650664) (xy 407.659841 -280.60288) (xy 407.679132 -280.557604) (xy 407.705435 -280.516008)
			(xy 407.73807 -280.479171) (xy 407.776191 -280.448046) (xy 407.818812 -280.423439) (xy 407.864828 -280.405987)
			(xy 407.913047 -280.396143) (xy 407.962222 -280.394162) (xy 408.011077 -280.400094) (xy 408.058348 -280.413786)
			(xy 408.10281 -280.434884) (xy 408.143313 -280.46284) (xy 408.178806 -280.496932) (xy 408.208371 -280.536276)
			(xy 408.231242 -280.579853) (xy 408.246826 -280.626534) (xy 408.254721 -280.675111) (xy 408.255216 -280.699718)
			(xy 408.594064 -280.699718) (xy 408.598024 -280.650664) (xy 408.609801 -280.60288) (xy 408.629092 -280.557604)
			(xy 408.655395 -280.516008) (xy 408.68803 -280.479171) (xy 408.726151 -280.448046) (xy 408.768772 -280.423439)
			(xy 408.814788 -280.405987) (xy 408.863007 -280.396143) (xy 408.912182 -280.394162) (xy 408.961037 -280.400094)
			(xy 409.008308 -280.413786) (xy 409.05277 -280.434884) (xy 409.093273 -280.46284) (xy 409.128766 -280.496932)
			(xy 409.158331 -280.536276) (xy 409.181202 -280.579853) (xy 409.196786 -280.626534) (xy 409.204681 -280.675111)
			(xy 409.205176 -280.699718) (xy 409.544024 -280.699718) (xy 409.547984 -280.650664) (xy 409.559761 -280.60288)
			(xy 409.579052 -280.557604) (xy 409.605355 -280.516008) (xy 409.63799 -280.479171) (xy 409.676111 -280.448046)
			(xy 409.718732 -280.423439) (xy 409.764748 -280.405987) (xy 409.812967 -280.396143) (xy 409.862142 -280.394162)
			(xy 409.910997 -280.400094) (xy 409.958268 -280.413786) (xy 410.00273 -280.434884) (xy 410.043233 -280.46284)
			(xy 410.078726 -280.496932) (xy 410.108291 -280.536276) (xy 410.131162 -280.579853) (xy 410.146746 -280.626534)
			(xy 410.154641 -280.675111) (xy 410.155136 -280.699718) (xy 410.493984 -280.699718) (xy 410.497944 -280.650664)
			(xy 410.509721 -280.60288) (xy 410.529012 -280.557604) (xy 410.555315 -280.516008) (xy 410.58795 -280.479171)
			(xy 410.626071 -280.448046) (xy 410.668692 -280.423439) (xy 410.714708 -280.405987) (xy 410.762927 -280.396143)
			(xy 410.812102 -280.394162) (xy 410.860957 -280.400094) (xy 410.908228 -280.413786) (xy 410.95269 -280.434884)
			(xy 410.993193 -280.46284) (xy 411.028686 -280.496932) (xy 411.058251 -280.536276) (xy 411.081122 -280.579853)
			(xy 411.096706 -280.626534) (xy 411.104601 -280.675111) (xy 411.105096 -280.699718) (xy 411.444198 -280.699718)
			(xy 411.448158 -280.650664) (xy 411.459935 -280.60288) (xy 411.479226 -280.557604) (xy 411.505529 -280.516008)
			(xy 411.538164 -280.479171) (xy 411.576285 -280.448046) (xy 411.618906 -280.423439) (xy 411.664922 -280.405987)
			(xy 411.713141 -280.396143) (xy 411.762316 -280.394162) (xy 411.811171 -280.400094) (xy 411.858442 -280.413786)
			(xy 411.902904 -280.434884) (xy 411.943407 -280.46284) (xy 411.9789 -280.496932) (xy 412.008465 -280.536276)
			(xy 412.031336 -280.579853) (xy 412.04692 -280.626534) (xy 412.054815 -280.675111) (xy 412.05531 -280.699718)
			(xy 412.394158 -280.699718) (xy 412.398118 -280.650664) (xy 412.409895 -280.60288) (xy 412.429186 -280.557604)
			(xy 412.455489 -280.516008) (xy 412.488124 -280.479171) (xy 412.526245 -280.448046) (xy 412.568866 -280.423439)
			(xy 412.614882 -280.405987) (xy 412.663101 -280.396143) (xy 412.712276 -280.394162) (xy 412.761131 -280.400094)
			(xy 412.808402 -280.413786) (xy 412.852864 -280.434884) (xy 412.893367 -280.46284) (xy 412.92886 -280.496932)
			(xy 412.958425 -280.536276) (xy 412.981296 -280.579853) (xy 412.99688 -280.626534) (xy 413.004775 -280.675111)
			(xy 413.00527 -280.699718) (xy 413.344118 -280.699718) (xy 413.348078 -280.650664) (xy 413.359855 -280.60288)
			(xy 413.379146 -280.557604) (xy 413.405449 -280.516008) (xy 413.438084 -280.479171) (xy 413.476205 -280.448046)
			(xy 413.518826 -280.423439) (xy 413.564842 -280.405987) (xy 413.613061 -280.396143) (xy 413.662236 -280.394162)
			(xy 413.711091 -280.400094) (xy 413.758362 -280.413786) (xy 413.802824 -280.434884) (xy 413.843327 -280.46284)
			(xy 413.87882 -280.496932) (xy 413.908385 -280.536276) (xy 413.931256 -280.579853) (xy 413.94684 -280.626534)
			(xy 413.954735 -280.675111) (xy 413.95523 -280.699718) (xy 414.294078 -280.699718) (xy 414.298038 -280.650664)
			(xy 414.309815 -280.60288) (xy 414.329106 -280.557604) (xy 414.355409 -280.516008) (xy 414.388044 -280.479171)
			(xy 414.426165 -280.448046) (xy 414.468786 -280.423439) (xy 414.514802 -280.405987) (xy 414.563021 -280.396143)
			(xy 414.612196 -280.394162) (xy 414.661051 -280.400094) (xy 414.708322 -280.413786) (xy 414.752784 -280.434884)
			(xy 414.793287 -280.46284) (xy 414.82878 -280.496932) (xy 414.858345 -280.536276) (xy 414.881216 -280.579853)
			(xy 414.8968 -280.626534) (xy 414.904695 -280.675111) (xy 414.90519 -280.699718) (xy 415.244038 -280.699718)
			(xy 415.247998 -280.650664) (xy 415.259775 -280.60288) (xy 415.279066 -280.557604) (xy 415.305369 -280.516008)
			(xy 415.338004 -280.479171) (xy 415.376125 -280.448046) (xy 415.418746 -280.423439) (xy 415.464762 -280.405987)
			(xy 415.512981 -280.396143) (xy 415.562156 -280.394162) (xy 415.611011 -280.400094) (xy 415.658282 -280.413786)
			(xy 415.702744 -280.434884) (xy 415.743247 -280.46284) (xy 415.77874 -280.496932) (xy 415.808305 -280.536276)
			(xy 415.831176 -280.579853) (xy 415.84676 -280.626534) (xy 415.854655 -280.675111) (xy 415.85515 -280.699718)
			(xy 416.193998 -280.699718) (xy 416.197958 -280.650664) (xy 416.209735 -280.60288) (xy 416.229026 -280.557604)
			(xy 416.255329 -280.516008) (xy 416.287964 -280.479171) (xy 416.326085 -280.448046) (xy 416.368706 -280.423439)
			(xy 416.414722 -280.405987) (xy 416.462941 -280.396143) (xy 416.512116 -280.394162) (xy 416.560971 -280.400094)
			(xy 416.608242 -280.413786) (xy 416.652704 -280.434884) (xy 416.693207 -280.46284) (xy 416.7287 -280.496932)
			(xy 416.758265 -280.536276) (xy 416.781136 -280.579853) (xy 416.79672 -280.626534) (xy 416.804615 -280.675111)
			(xy 416.80511 -280.699718) (xy 416.804615 -280.724325) (xy 416.79672 -280.772902) (xy 416.781136 -280.819583)
			(xy 416.758265 -280.86316) (xy 416.7287 -280.902504) (xy 416.693207 -280.936596) (xy 416.652704 -280.964552)
			(xy 416.608242 -280.98565) (xy 416.560971 -280.999342) (xy 416.512116 -281.005274) (xy 416.462941 -281.003293)
			(xy 416.414722 -280.993449) (xy 416.368706 -280.975997) (xy 416.326085 -280.95139) (xy 416.287964 -280.920265)
			(xy 416.255329 -280.883428) (xy 416.229026 -280.841832) (xy 416.209735 -280.796556) (xy 416.197958 -280.748772)
			(xy 416.193998 -280.699718) (xy 415.85515 -280.699718) (xy 415.854655 -280.724325) (xy 415.84676 -280.772902)
			(xy 415.831176 -280.819583) (xy 415.808305 -280.86316) (xy 415.77874 -280.902504) (xy 415.743247 -280.936596)
			(xy 415.702744 -280.964552) (xy 415.658282 -280.98565) (xy 415.611011 -280.999342) (xy 415.562156 -281.005274)
			(xy 415.512981 -281.003293) (xy 415.464762 -280.993449) (xy 415.418746 -280.975997) (xy 415.376125 -280.95139)
			(xy 415.338004 -280.920265) (xy 415.305369 -280.883428) (xy 415.279066 -280.841832) (xy 415.259775 -280.796556)
			(xy 415.247998 -280.748772) (xy 415.244038 -280.699718) (xy 414.90519 -280.699718) (xy 414.904695 -280.724325)
			(xy 414.8968 -280.772902) (xy 414.881216 -280.819583) (xy 414.858345 -280.86316) (xy 414.82878 -280.902504)
			(xy 414.793287 -280.936596) (xy 414.752784 -280.964552) (xy 414.708322 -280.98565) (xy 414.661051 -280.999342)
			(xy 414.612196 -281.005274) (xy 414.563021 -281.003293) (xy 414.514802 -280.993449) (xy 414.468786 -280.975997)
			(xy 414.426165 -280.95139) (xy 414.388044 -280.920265) (xy 414.355409 -280.883428) (xy 414.329106 -280.841832)
			(xy 414.309815 -280.796556) (xy 414.298038 -280.748772) (xy 414.294078 -280.699718) (xy 413.95523 -280.699718)
			(xy 413.954735 -280.724325) (xy 413.94684 -280.772902) (xy 413.931256 -280.819583) (xy 413.908385 -280.86316)
			(xy 413.87882 -280.902504) (xy 413.843327 -280.936596) (xy 413.802824 -280.964552) (xy 413.758362 -280.98565)
			(xy 413.711091 -280.999342) (xy 413.662236 -281.005274) (xy 413.613061 -281.003293) (xy 413.564842 -280.993449)
			(xy 413.518826 -280.975997) (xy 413.476205 -280.95139) (xy 413.438084 -280.920265) (xy 413.405449 -280.883428)
			(xy 413.379146 -280.841832) (xy 413.359855 -280.796556) (xy 413.348078 -280.748772) (xy 413.344118 -280.699718)
			(xy 413.00527 -280.699718) (xy 413.004775 -280.724325) (xy 412.99688 -280.772902) (xy 412.981296 -280.819583)
			(xy 412.958425 -280.86316) (xy 412.92886 -280.902504) (xy 412.893367 -280.936596) (xy 412.852864 -280.964552)
			(xy 412.808402 -280.98565) (xy 412.761131 -280.999342) (xy 412.712276 -281.005274) (xy 412.663101 -281.003293)
			(xy 412.614882 -280.993449) (xy 412.568866 -280.975997) (xy 412.526245 -280.95139) (xy 412.488124 -280.920265)
			(xy 412.455489 -280.883428) (xy 412.429186 -280.841832) (xy 412.409895 -280.796556) (xy 412.398118 -280.748772)
			(xy 412.394158 -280.699718) (xy 412.05531 -280.699718) (xy 412.054815 -280.724325) (xy 412.04692 -280.772902)
			(xy 412.031336 -280.819583) (xy 412.008465 -280.86316) (xy 411.9789 -280.902504) (xy 411.943407 -280.936596)
			(xy 411.902904 -280.964552) (xy 411.858442 -280.98565) (xy 411.811171 -280.999342) (xy 411.762316 -281.005274)
			(xy 411.713141 -281.003293) (xy 411.664922 -280.993449) (xy 411.618906 -280.975997) (xy 411.576285 -280.95139)
			(xy 411.538164 -280.920265) (xy 411.505529 -280.883428) (xy 411.479226 -280.841832) (xy 411.459935 -280.796556)
			(xy 411.448158 -280.748772) (xy 411.444198 -280.699718) (xy 411.105096 -280.699718) (xy 411.104601 -280.724325)
			(xy 411.096706 -280.772902) (xy 411.081122 -280.819583) (xy 411.058251 -280.86316) (xy 411.028686 -280.902504)
			(xy 410.993193 -280.936596) (xy 410.95269 -280.964552) (xy 410.908228 -280.98565) (xy 410.860957 -280.999342)
			(xy 410.812102 -281.005274) (xy 410.762927 -281.003293) (xy 410.714708 -280.993449) (xy 410.668692 -280.975997)
			(xy 410.626071 -280.95139) (xy 410.58795 -280.920265) (xy 410.555315 -280.883428) (xy 410.529012 -280.841832)
			(xy 410.509721 -280.796556) (xy 410.497944 -280.748772) (xy 410.493984 -280.699718) (xy 410.155136 -280.699718)
			(xy 410.154641 -280.724325) (xy 410.146746 -280.772902) (xy 410.131162 -280.819583) (xy 410.108291 -280.86316)
			(xy 410.078726 -280.902504) (xy 410.043233 -280.936596) (xy 410.00273 -280.964552) (xy 409.958268 -280.98565)
			(xy 409.910997 -280.999342) (xy 409.862142 -281.005274) (xy 409.812967 -281.003293) (xy 409.764748 -280.993449)
			(xy 409.718732 -280.975997) (xy 409.676111 -280.95139) (xy 409.63799 -280.920265) (xy 409.605355 -280.883428)
			(xy 409.579052 -280.841832) (xy 409.559761 -280.796556) (xy 409.547984 -280.748772) (xy 409.544024 -280.699718)
			(xy 409.205176 -280.699718) (xy 409.204681 -280.724325) (xy 409.196786 -280.772902) (xy 409.181202 -280.819583)
			(xy 409.158331 -280.86316) (xy 409.128766 -280.902504) (xy 409.093273 -280.936596) (xy 409.05277 -280.964552)
			(xy 409.008308 -280.98565) (xy 408.961037 -280.999342) (xy 408.912182 -281.005274) (xy 408.863007 -281.003293)
			(xy 408.814788 -280.993449) (xy 408.768772 -280.975997) (xy 408.726151 -280.95139) (xy 408.68803 -280.920265)
			(xy 408.655395 -280.883428) (xy 408.629092 -280.841832) (xy 408.609801 -280.796556) (xy 408.598024 -280.748772)
			(xy 408.594064 -280.699718) (xy 408.255216 -280.699718) (xy 408.254721 -280.724325) (xy 408.246826 -280.772902)
			(xy 408.231242 -280.819583) (xy 408.208371 -280.86316) (xy 408.178806 -280.902504) (xy 408.143313 -280.936596)
			(xy 408.10281 -280.964552) (xy 408.058348 -280.98565) (xy 408.011077 -280.999342) (xy 407.962222 -281.005274)
			(xy 407.913047 -281.003293) (xy 407.864828 -280.993449) (xy 407.818812 -280.975997) (xy 407.776191 -280.95139)
			(xy 407.73807 -280.920265) (xy 407.705435 -280.883428) (xy 407.679132 -280.841832) (xy 407.659841 -280.796556)
			(xy 407.648064 -280.748772) (xy 407.644104 -280.699718) (xy 407.305256 -280.699718) (xy 407.304761 -280.724325)
			(xy 407.296866 -280.772902) (xy 407.281282 -280.819583) (xy 407.258411 -280.86316) (xy 407.228846 -280.902504)
			(xy 407.193353 -280.936596) (xy 407.15285 -280.964552) (xy 407.108388 -280.98565) (xy 407.061117 -280.999342)
			(xy 407.012262 -281.005274) (xy 406.963087 -281.003293) (xy 406.914868 -280.993449) (xy 406.868852 -280.975997)
			(xy 406.826231 -280.95139) (xy 406.78811 -280.920265) (xy 406.755475 -280.883428) (xy 406.729172 -280.841832)
			(xy 406.709881 -280.796556) (xy 406.698104 -280.748772) (xy 406.694144 -280.699718) (xy 406.355296 -280.699718)
			(xy 406.354801 -280.724325) (xy 406.346906 -280.772902) (xy 406.331322 -280.819583) (xy 406.308451 -280.86316)
			(xy 406.278886 -280.902504) (xy 406.243393 -280.936596) (xy 406.20289 -280.964552) (xy 406.158428 -280.98565)
			(xy 406.111157 -280.999342) (xy 406.062302 -281.005274) (xy 406.013127 -281.003293) (xy 405.964908 -280.993449)
			(xy 405.918892 -280.975997) (xy 405.876271 -280.95139) (xy 405.83815 -280.920265) (xy 405.805515 -280.883428)
			(xy 405.779212 -280.841832) (xy 405.759921 -280.796556) (xy 405.748144 -280.748772) (xy 405.744184 -280.699718)
			(xy 405.405082 -280.699718) (xy 405.404587 -280.724325) (xy 405.396692 -280.772902) (xy 405.381108 -280.819583)
			(xy 405.358237 -280.86316) (xy 405.328672 -280.902504) (xy 405.293179 -280.936596) (xy 405.252676 -280.964552)
			(xy 405.208214 -280.98565) (xy 405.160943 -280.999342) (xy 405.112088 -281.005274) (xy 405.062913 -281.003293)
			(xy 405.014694 -280.993449) (xy 404.968678 -280.975997) (xy 404.926057 -280.95139) (xy 404.887936 -280.920265)
			(xy 404.855301 -280.883428) (xy 404.828998 -280.841832) (xy 404.809707 -280.796556) (xy 404.79793 -280.748772)
			(xy 404.79397 -280.699718) (xy 404.455122 -280.699718) (xy 404.454627 -280.724325) (xy 404.446732 -280.772902)
			(xy 404.431148 -280.819583) (xy 404.408277 -280.86316) (xy 404.378712 -280.902504) (xy 404.343219 -280.936596)
			(xy 404.302716 -280.964552) (xy 404.258254 -280.98565) (xy 404.210983 -280.999342) (xy 404.162128 -281.005274)
			(xy 404.112953 -281.003293) (xy 404.064734 -280.993449) (xy 404.018718 -280.975997) (xy 403.976097 -280.95139)
			(xy 403.937976 -280.920265) (xy 403.905341 -280.883428) (xy 403.879038 -280.841832) (xy 403.859747 -280.796556)
			(xy 403.84797 -280.748772) (xy 403.84401 -280.699718) (xy 403.505162 -280.699718) (xy 403.504667 -280.724325)
			(xy 403.496772 -280.772902) (xy 403.481188 -280.819583) (xy 403.458317 -280.86316) (xy 403.428752 -280.902504)
			(xy 403.393259 -280.936596) (xy 403.352756 -280.964552) (xy 403.308294 -280.98565) (xy 403.261023 -280.999342)
			(xy 403.212168 -281.005274) (xy 403.162993 -281.003293) (xy 403.114774 -280.993449) (xy 403.068758 -280.975997)
			(xy 403.026137 -280.95139) (xy 402.988016 -280.920265) (xy 402.955381 -280.883428) (xy 402.929078 -280.841832)
			(xy 402.909787 -280.796556) (xy 402.89801 -280.748772) (xy 402.89405 -280.699718) (xy 402.555202 -280.699718)
			(xy 402.554707 -280.724325) (xy 402.546812 -280.772902) (xy 402.531228 -280.819583) (xy 402.508357 -280.86316)
			(xy 402.478792 -280.902504) (xy 402.443299 -280.936596) (xy 402.402796 -280.964552) (xy 402.358334 -280.98565)
			(xy 402.311063 -280.999342) (xy 402.262208 -281.005274) (xy 402.213033 -281.003293) (xy 402.164814 -280.993449)
			(xy 402.118798 -280.975997) (xy 402.076177 -280.95139) (xy 402.038056 -280.920265) (xy 402.005421 -280.883428)
			(xy 401.979118 -280.841832) (xy 401.959827 -280.796556) (xy 401.94805 -280.748772) (xy 401.94409 -280.699718)
			(xy 401.605242 -280.699718) (xy 401.604747 -280.724325) (xy 401.596852 -280.772902) (xy 401.581268 -280.819583)
			(xy 401.558397 -280.86316) (xy 401.528832 -280.902504) (xy 401.493339 -280.936596) (xy 401.452836 -280.964552)
			(xy 401.408374 -280.98565) (xy 401.361103 -280.999342) (xy 401.312248 -281.005274) (xy 401.263073 -281.003293)
			(xy 401.214854 -280.993449) (xy 401.168838 -280.975997) (xy 401.126217 -280.95139) (xy 401.088096 -280.920265)
			(xy 401.055461 -280.883428) (xy 401.029158 -280.841832) (xy 401.009867 -280.796556) (xy 400.99809 -280.748772)
			(xy 400.99413 -280.699718) (xy 400.655282 -280.699718) (xy 400.654787 -280.724325) (xy 400.646892 -280.772902)
			(xy 400.631308 -280.819583) (xy 400.608437 -280.86316) (xy 400.578872 -280.902504) (xy 400.543379 -280.936596)
			(xy 400.502876 -280.964552) (xy 400.458414 -280.98565) (xy 400.411143 -280.999342) (xy 400.362288 -281.005274)
			(xy 400.313113 -281.003293) (xy 400.264894 -280.993449) (xy 400.218878 -280.975997) (xy 400.176257 -280.95139)
			(xy 400.138136 -280.920265) (xy 400.105501 -280.883428) (xy 400.079198 -280.841832) (xy 400.059907 -280.796556)
			(xy 400.04813 -280.748772) (xy 400.04417 -280.699718) (xy 399.705322 -280.699718) (xy 399.704827 -280.724325)
			(xy 399.696932 -280.772902) (xy 399.681348 -280.819583) (xy 399.658477 -280.86316) (xy 399.628912 -280.902504)
			(xy 399.593419 -280.936596) (xy 399.552916 -280.964552) (xy 399.508454 -280.98565) (xy 399.461183 -280.999342)
			(xy 399.412328 -281.005274) (xy 399.363153 -281.003293) (xy 399.314934 -280.993449) (xy 399.268918 -280.975997)
			(xy 399.226297 -280.95139) (xy 399.188176 -280.920265) (xy 399.155541 -280.883428) (xy 399.129238 -280.841832)
			(xy 399.109947 -280.796556) (xy 399.09817 -280.748772) (xy 399.09421 -280.699718) (xy 398.755108 -280.699718)
			(xy 398.754613 -280.724325) (xy 398.746718 -280.772902) (xy 398.731134 -280.819583) (xy 398.708263 -280.86316)
			(xy 398.678698 -280.902504) (xy 398.643205 -280.936596) (xy 398.602702 -280.964552) (xy 398.55824 -280.98565)
			(xy 398.510969 -280.999342) (xy 398.462114 -281.005274) (xy 398.412939 -281.003293) (xy 398.36472 -280.993449)
			(xy 398.318704 -280.975997) (xy 398.276083 -280.95139) (xy 398.237962 -280.920265) (xy 398.205327 -280.883428)
			(xy 398.179024 -280.841832) (xy 398.159733 -280.796556) (xy 398.147956 -280.748772) (xy 398.143996 -280.699718)
			(xy 397.805148 -280.699718) (xy 397.804653 -280.724325) (xy 397.796758 -280.772902) (xy 397.781174 -280.819583)
			(xy 397.758303 -280.86316) (xy 397.728738 -280.902504) (xy 397.693245 -280.936596) (xy 397.652742 -280.964552)
			(xy 397.60828 -280.98565) (xy 397.561009 -280.999342) (xy 397.512154 -281.005274) (xy 397.462979 -281.003293)
			(xy 397.41476 -280.993449) (xy 397.368744 -280.975997) (xy 397.326123 -280.95139) (xy 397.288002 -280.920265)
			(xy 397.255367 -280.883428) (xy 397.229064 -280.841832) (xy 397.209773 -280.796556) (xy 397.197996 -280.748772)
			(xy 397.194036 -280.699718) (xy 396.855188 -280.699718) (xy 396.854693 -280.724325) (xy 396.846798 -280.772902)
			(xy 396.831214 -280.819583) (xy 396.808343 -280.86316) (xy 396.778778 -280.902504) (xy 396.743285 -280.936596)
			(xy 396.702782 -280.964552) (xy 396.65832 -280.98565) (xy 396.611049 -280.999342) (xy 396.562194 -281.005274)
			(xy 396.513019 -281.003293) (xy 396.4648 -280.993449) (xy 396.418784 -280.975997) (xy 396.376163 -280.95139)
			(xy 396.338042 -280.920265) (xy 396.305407 -280.883428) (xy 396.279104 -280.841832) (xy 396.259813 -280.796556)
			(xy 396.248036 -280.748772) (xy 396.244076 -280.699718) (xy 395.905228 -280.699718) (xy 395.904733 -280.724325)
			(xy 395.896838 -280.772902) (xy 395.881254 -280.819583) (xy 395.858383 -280.86316) (xy 395.828818 -280.902504)
			(xy 395.793325 -280.936596) (xy 395.752822 -280.964552) (xy 395.70836 -280.98565) (xy 395.661089 -280.999342)
			(xy 395.612234 -281.005274) (xy 395.563059 -281.003293) (xy 395.51484 -280.993449) (xy 395.468824 -280.975997)
			(xy 395.426203 -280.95139) (xy 395.388082 -280.920265) (xy 395.355447 -280.883428) (xy 395.329144 -280.841832)
			(xy 395.309853 -280.796556) (xy 395.298076 -280.748772) (xy 395.294116 -280.699718) (xy 394.955268 -280.699718)
			(xy 394.954773 -280.724325) (xy 394.946878 -280.772902) (xy 394.931294 -280.819583) (xy 394.908423 -280.86316)
			(xy 394.878858 -280.902504) (xy 394.843365 -280.936596) (xy 394.802862 -280.964552) (xy 394.7584 -280.98565)
			(xy 394.711129 -280.999342) (xy 394.662274 -281.005274) (xy 394.613099 -281.003293) (xy 394.56488 -280.993449)
			(xy 394.518864 -280.975997) (xy 394.476243 -280.95139) (xy 394.438122 -280.920265) (xy 394.405487 -280.883428)
			(xy 394.379184 -280.841832) (xy 394.359893 -280.796556) (xy 394.348116 -280.748772) (xy 394.344156 -280.699718)
			(xy 394.005308 -280.699718) (xy 394.004813 -280.724325) (xy 393.996918 -280.772902) (xy 393.981334 -280.819583)
			(xy 393.958463 -280.86316) (xy 393.928898 -280.902504) (xy 393.893405 -280.936596) (xy 393.852902 -280.964552)
			(xy 393.80844 -280.98565) (xy 393.761169 -280.999342) (xy 393.712314 -281.005274) (xy 393.663139 -281.003293)
			(xy 393.61492 -280.993449) (xy 393.568904 -280.975997) (xy 393.526283 -280.95139) (xy 393.488162 -280.920265)
			(xy 393.455527 -280.883428) (xy 393.429224 -280.841832) (xy 393.409933 -280.796556) (xy 393.398156 -280.748772)
			(xy 393.394196 -280.699718) (xy 393.055089 -280.699718) (xy 393.055537 -280.707986) (xy 393.050168 -280.75734)
			(xy 393.036886 -280.805176) (xy 393.016039 -280.850233) (xy 392.988178 -280.891324) (xy 392.954035 -280.927365)
			(xy 392.914512 -280.957408) (xy 392.870648 -280.980661) (xy 392.823601 -280.996511) (xy 392.774609 -281.004541)
			(xy 392.749786 -281.005026) (xy 392.735603 -281.004851) (xy 392.707363 -281.002178) (xy 392.693398 -280.999692)
			(xy 392.679434 -280.997515) (xy 392.6513 -281.000095) (xy 392.62495 -281.010286) (xy 392.602401 -281.027308)
			(xy 392.585381 -281.049858) (xy 392.575193 -281.076209) (xy 392.572616 -281.104343) (xy 392.57478 -281.11831)
			(xy 392.577264 -281.132339) (xy 392.579936 -281.160706) (xy 392.580114 -281.174952) (xy 392.579674 -281.199778)
			(xy 392.571649 -281.248776) (xy 392.555802 -281.295831) (xy 392.532551 -281.339702) (xy 392.502508 -281.379233)
			(xy 392.466466 -281.413383) (xy 392.425373 -281.441252) (xy 392.380313 -281.462105) (xy 392.332473 -281.475393)
			(xy 392.283113 -281.480767) (xy 392.233535 -281.478083) (xy 392.185043 -281.467414) (xy 392.138916 -281.44904)
			(xy 392.09637 -281.423445) (xy 392.058525 -281.391304) (xy 392.026379 -281.353464) (xy 392.000779 -281.310921)
			(xy 391.982398 -281.264797) (xy 391.971722 -281.216307) (xy 391.969032 -281.166729) (xy 391.629989 -281.166729)
			(xy 391.630154 -281.174952) (xy 391.629659 -281.199559) (xy 391.621764 -281.248136) (xy 391.60618 -281.294817)
			(xy 391.583309 -281.338394) (xy 391.553744 -281.377738) (xy 391.518251 -281.41183) (xy 391.477748 -281.439786)
			(xy 391.433286 -281.460884) (xy 391.386015 -281.474576) (xy 391.33716 -281.480508) (xy 391.287985 -281.478527)
			(xy 391.239766 -281.468683) (xy 391.19375 -281.451231) (xy 391.151129 -281.426624) (xy 391.113008 -281.395499)
			(xy 391.080373 -281.358662) (xy 391.05407 -281.317066) (xy 391.034779 -281.27179) (xy 391.023002 -281.224006)
			(xy 391.019042 -281.174952) (xy 390.680194 -281.174952) (xy 390.679699 -281.199559) (xy 390.671804 -281.248136)
			(xy 390.65622 -281.294817) (xy 390.633349 -281.338394) (xy 390.603784 -281.377738) (xy 390.568291 -281.41183)
			(xy 390.527788 -281.439786) (xy 390.483326 -281.460884) (xy 390.436055 -281.474576) (xy 390.3872 -281.480508)
			(xy 390.338025 -281.478527) (xy 390.289806 -281.468683) (xy 390.24379 -281.451231) (xy 390.201169 -281.426624)
			(xy 390.163048 -281.395499) (xy 390.130413 -281.358662) (xy 390.10411 -281.317066) (xy 390.084819 -281.27179)
			(xy 390.073042 -281.224006) (xy 390.069082 -281.174952) (xy 389.730234 -281.174952) (xy 389.729739 -281.199559)
			(xy 389.721844 -281.248136) (xy 389.70626 -281.294817) (xy 389.683389 -281.338394) (xy 389.653824 -281.377738)
			(xy 389.618331 -281.41183) (xy 389.577828 -281.439786) (xy 389.533366 -281.460884) (xy 389.486095 -281.474576)
			(xy 389.43724 -281.480508) (xy 389.388065 -281.478527) (xy 389.339846 -281.468683) (xy 389.29383 -281.451231)
			(xy 389.251209 -281.426624) (xy 389.213088 -281.395499) (xy 389.180453 -281.358662) (xy 389.15415 -281.317066)
			(xy 389.134859 -281.27179) (xy 389.123082 -281.224006) (xy 389.119122 -281.174952) (xy 388.780274 -281.174952)
			(xy 388.779779 -281.199559) (xy 388.771884 -281.248136) (xy 388.7563 -281.294817) (xy 388.733429 -281.338394)
			(xy 388.703864 -281.377738) (xy 388.668371 -281.41183) (xy 388.627868 -281.439786) (xy 388.583406 -281.460884)
			(xy 388.536135 -281.474576) (xy 388.48728 -281.480508) (xy 388.438105 -281.478527) (xy 388.389886 -281.468683)
			(xy 388.34387 -281.451231) (xy 388.301249 -281.426624) (xy 388.263128 -281.395499) (xy 388.230493 -281.358662)
			(xy 388.20419 -281.317066) (xy 388.184899 -281.27179) (xy 388.173122 -281.224006) (xy 388.169162 -281.174952)
			(xy 387.830314 -281.174952) (xy 387.829819 -281.199559) (xy 387.821924 -281.248136) (xy 387.80634 -281.294817)
			(xy 387.783469 -281.338394) (xy 387.753904 -281.377738) (xy 387.718411 -281.41183) (xy 387.677908 -281.439786)
			(xy 387.633446 -281.460884) (xy 387.586175 -281.474576) (xy 387.53732 -281.480508) (xy 387.488145 -281.478527)
			(xy 387.439926 -281.468683) (xy 387.39391 -281.451231) (xy 387.351289 -281.426624) (xy 387.313168 -281.395499)
			(xy 387.280533 -281.358662) (xy 387.25423 -281.317066) (xy 387.234939 -281.27179) (xy 387.223162 -281.224006)
			(xy 387.219202 -281.174952) (xy 386.880354 -281.174952) (xy 386.879859 -281.199559) (xy 386.871964 -281.248136)
			(xy 386.85638 -281.294817) (xy 386.833509 -281.338394) (xy 386.803944 -281.377738) (xy 386.768451 -281.41183)
			(xy 386.727948 -281.439786) (xy 386.683486 -281.460884) (xy 386.636215 -281.474576) (xy 386.58736 -281.480508)
			(xy 386.538185 -281.478527) (xy 386.489966 -281.468683) (xy 386.44395 -281.451231) (xy 386.401329 -281.426624)
			(xy 386.363208 -281.395499) (xy 386.330573 -281.358662) (xy 386.30427 -281.317066) (xy 386.284979 -281.27179)
			(xy 386.273202 -281.224006) (xy 386.269242 -281.174952) (xy 385.93014 -281.174952) (xy 385.929645 -281.199559)
			(xy 385.92175 -281.248136) (xy 385.906166 -281.294817) (xy 385.883295 -281.338394) (xy 385.85373 -281.377738)
			(xy 385.818237 -281.41183) (xy 385.777734 -281.439786) (xy 385.733272 -281.460884) (xy 385.686001 -281.474576)
			(xy 385.637146 -281.480508) (xy 385.587971 -281.478527) (xy 385.539752 -281.468683) (xy 385.493736 -281.451231)
			(xy 385.451115 -281.426624) (xy 385.412994 -281.395499) (xy 385.380359 -281.358662) (xy 385.354056 -281.317066)
			(xy 385.334765 -281.27179) (xy 385.322988 -281.224006) (xy 385.319028 -281.174952) (xy 384.98018 -281.174952)
			(xy 384.979685 -281.199559) (xy 384.97179 -281.248136) (xy 384.956206 -281.294817) (xy 384.933335 -281.338394)
			(xy 384.90377 -281.377738) (xy 384.868277 -281.41183) (xy 384.827774 -281.439786) (xy 384.783312 -281.460884)
			(xy 384.736041 -281.474576) (xy 384.687186 -281.480508) (xy 384.638011 -281.478527) (xy 384.589792 -281.468683)
			(xy 384.543776 -281.451231) (xy 384.501155 -281.426624) (xy 384.463034 -281.395499) (xy 384.430399 -281.358662)
			(xy 384.404096 -281.317066) (xy 384.384805 -281.27179) (xy 384.373028 -281.224006) (xy 384.369068 -281.174952)
			(xy 367.36909 -281.174952) (xy 367.36909 -281.829256) (xy 374.111518 -281.829256) (xy 374.115589 -281.773634)
			(xy 374.127715 -281.719197) (xy 374.147638 -281.667106) (xy 374.174934 -281.618471) (xy 374.20902 -281.574328)
			(xy 374.249169 -281.535619) (xy 374.294527 -281.503168) (xy 374.344127 -281.477667) (xy 374.396911 -281.45966)
			(xy 374.451754 -281.44953) (xy 374.507488 -281.447493) (xy 374.562925 -281.453593) (xy 374.616882 -281.467699)
			(xy 374.668211 -281.489511) (xy 374.715817 -281.518565) (xy 374.758685 -281.55424) (xy 374.795902 -281.595777)
			(xy 374.826675 -281.64229) (xy 374.850347 -281.692787) (xy 374.866415 -281.746194) (xy 374.874535 -281.80137)
			(xy 374.875044 -281.829256) (xy 375.596656 -281.829256) (xy 375.600727 -281.773634) (xy 375.612853 -281.719197)
			(xy 375.632776 -281.667106) (xy 375.660072 -281.618471) (xy 375.694158 -281.574328) (xy 375.734307 -281.535619)
			(xy 375.779665 -281.503168) (xy 375.829265 -281.477667) (xy 375.882049 -281.45966) (xy 375.936892 -281.44953)
			(xy 375.992626 -281.447493) (xy 376.048063 -281.453593) (xy 376.10202 -281.467699) (xy 376.153349 -281.489511)
			(xy 376.200955 -281.518565) (xy 376.243823 -281.55424) (xy 376.28104 -281.595777) (xy 376.311813 -281.64229)
			(xy 376.335485 -281.692787) (xy 376.351553 -281.746194) (xy 376.359673 -281.80137) (xy 376.360182 -281.829256)
			(xy 376.359673 -281.857142) (xy 376.351553 -281.912318) (xy 376.335485 -281.965725) (xy 376.311813 -282.016222)
			(xy 376.28104 -282.062735) (xy 376.243823 -282.104272) (xy 376.219021 -282.124912) (xy 384.369068 -282.124912)
			(xy 384.373028 -282.075858) (xy 384.384805 -282.028074) (xy 384.404096 -281.982798) (xy 384.430399 -281.941202)
			(xy 384.463034 -281.904365) (xy 384.501155 -281.87324) (xy 384.543776 -281.848633) (xy 384.589792 -281.831181)
			(xy 384.638011 -281.821337) (xy 384.687186 -281.819356) (xy 384.736041 -281.825288) (xy 384.783312 -281.83898)
			(xy 384.827774 -281.860078) (xy 384.868277 -281.888034) (xy 384.90377 -281.922126) (xy 384.933335 -281.96147)
			(xy 384.956206 -282.005047) (xy 384.97179 -282.051728) (xy 384.979685 -282.100305) (xy 384.98018 -282.124912)
			(xy 385.319028 -282.124912) (xy 385.322988 -282.075858) (xy 385.334765 -282.028074) (xy 385.354056 -281.982798)
			(xy 385.380359 -281.941202) (xy 385.412994 -281.904365) (xy 385.451115 -281.87324) (xy 385.493736 -281.848633)
			(xy 385.539752 -281.831181) (xy 385.587971 -281.821337) (xy 385.637146 -281.819356) (xy 385.686001 -281.825288)
			(xy 385.733272 -281.83898) (xy 385.777734 -281.860078) (xy 385.818237 -281.888034) (xy 385.85373 -281.922126)
			(xy 385.883295 -281.96147) (xy 385.906166 -282.005047) (xy 385.92175 -282.051728) (xy 385.929645 -282.100305)
			(xy 385.93014 -282.124912) (xy 386.269242 -282.124912) (xy 386.273202 -282.075858) (xy 386.284979 -282.028074)
			(xy 386.30427 -281.982798) (xy 386.330573 -281.941202) (xy 386.363208 -281.904365) (xy 386.401329 -281.87324)
			(xy 386.44395 -281.848633) (xy 386.489966 -281.831181) (xy 386.538185 -281.821337) (xy 386.58736 -281.819356)
			(xy 386.636215 -281.825288) (xy 386.683486 -281.83898) (xy 386.727948 -281.860078) (xy 386.768451 -281.888034)
			(xy 386.803944 -281.922126) (xy 386.833509 -281.96147) (xy 386.85638 -282.005047) (xy 386.871964 -282.051728)
			(xy 386.879859 -282.100305) (xy 386.880354 -282.124912) (xy 387.219202 -282.124912) (xy 387.223162 -282.075858)
			(xy 387.234939 -282.028074) (xy 387.25423 -281.982798) (xy 387.280533 -281.941202) (xy 387.313168 -281.904365)
			(xy 387.351289 -281.87324) (xy 387.39391 -281.848633) (xy 387.439926 -281.831181) (xy 387.488145 -281.821337)
			(xy 387.53732 -281.819356) (xy 387.586175 -281.825288) (xy 387.633446 -281.83898) (xy 387.677908 -281.860078)
			(xy 387.718411 -281.888034) (xy 387.753904 -281.922126) (xy 387.783469 -281.96147) (xy 387.80634 -282.005047)
			(xy 387.821924 -282.051728) (xy 387.829819 -282.100305) (xy 387.830314 -282.124912) (xy 388.169162 -282.124912)
			(xy 388.173122 -282.075858) (xy 388.184899 -282.028074) (xy 388.20419 -281.982798) (xy 388.230493 -281.941202)
			(xy 388.263128 -281.904365) (xy 388.301249 -281.87324) (xy 388.34387 -281.848633) (xy 388.389886 -281.831181)
			(xy 388.438105 -281.821337) (xy 388.48728 -281.819356) (xy 388.536135 -281.825288) (xy 388.583406 -281.83898)
			(xy 388.627868 -281.860078) (xy 388.668371 -281.888034) (xy 388.703864 -281.922126) (xy 388.733429 -281.96147)
			(xy 388.7563 -282.005047) (xy 388.771884 -282.051728) (xy 388.779779 -282.100305) (xy 388.780274 -282.124912)
			(xy 389.119122 -282.124912) (xy 389.123082 -282.075858) (xy 389.134859 -282.028074) (xy 389.15415 -281.982798)
			(xy 389.180453 -281.941202) (xy 389.213088 -281.904365) (xy 389.251209 -281.87324) (xy 389.29383 -281.848633)
			(xy 389.339846 -281.831181) (xy 389.388065 -281.821337) (xy 389.43724 -281.819356) (xy 389.486095 -281.825288)
			(xy 389.533366 -281.83898) (xy 389.577828 -281.860078) (xy 389.618331 -281.888034) (xy 389.653824 -281.922126)
			(xy 389.683389 -281.96147) (xy 389.70626 -282.005047) (xy 389.721844 -282.051728) (xy 389.729739 -282.100305)
			(xy 389.730234 -282.124912) (xy 390.069082 -282.124912) (xy 390.073042 -282.075858) (xy 390.084819 -282.028074)
			(xy 390.10411 -281.982798) (xy 390.130413 -281.941202) (xy 390.163048 -281.904365) (xy 390.201169 -281.87324)
			(xy 390.24379 -281.848633) (xy 390.289806 -281.831181) (xy 390.338025 -281.821337) (xy 390.3872 -281.819356)
			(xy 390.436055 -281.825288) (xy 390.483326 -281.83898) (xy 390.527788 -281.860078) (xy 390.568291 -281.888034)
			(xy 390.603784 -281.922126) (xy 390.633349 -281.96147) (xy 390.65622 -282.005047) (xy 390.671804 -282.051728)
			(xy 390.679699 -282.100305) (xy 390.680194 -282.124912) (xy 391.019042 -282.124912) (xy 391.023002 -282.075858)
			(xy 391.034779 -282.028074) (xy 391.05407 -281.982798) (xy 391.080373 -281.941202) (xy 391.113008 -281.904365)
			(xy 391.151129 -281.87324) (xy 391.19375 -281.848633) (xy 391.239766 -281.831181) (xy 391.287985 -281.821337)
			(xy 391.33716 -281.819356) (xy 391.386015 -281.825288) (xy 391.433286 -281.83898) (xy 391.477748 -281.860078)
			(xy 391.518251 -281.888034) (xy 391.553744 -281.922126) (xy 391.583309 -281.96147) (xy 391.60618 -282.005047)
			(xy 391.621764 -282.051728) (xy 391.629659 -282.100305) (xy 391.630154 -282.124912) (xy 391.969002 -282.124912)
			(xy 391.972962 -282.075858) (xy 391.984739 -282.028074) (xy 392.00403 -281.982798) (xy 392.030333 -281.941202)
			(xy 392.062968 -281.904365) (xy 392.101089 -281.87324) (xy 392.14371 -281.848633) (xy 392.189726 -281.831181)
			(xy 392.237945 -281.821337) (xy 392.28712 -281.819356) (xy 392.335975 -281.825288) (xy 392.383246 -281.83898)
			(xy 392.427708 -281.860078) (xy 392.468211 -281.888034) (xy 392.503704 -281.922126) (xy 392.533269 -281.96147)
			(xy 392.55614 -282.005047) (xy 392.571724 -282.051728) (xy 392.579619 -282.100305) (xy 392.579947 -282.116601)
			(xy 392.919294 -282.116601) (xy 392.924663 -282.067252) (xy 392.937946 -282.019423) (xy 392.958792 -281.974372)
			(xy 392.986652 -281.933287) (xy 393.020792 -281.897251) (xy 393.060312 -281.867212) (xy 393.104171 -281.843963)
			(xy 393.151213 -281.828116) (xy 393.2002 -281.820088) (xy 393.22502 -281.819604) (xy 393.239203 -281.819778)
			(xy 393.267443 -281.822452) (xy 393.281408 -281.824938) (xy 393.293854 -281.827224) (xy 393.317476 -281.819858)
			(xy 393.394946 -281.742388) (xy 393.402312 -281.718766) (xy 393.400026 -281.70632) (xy 393.397543 -281.692355)
			(xy 393.394875 -281.664115) (xy 393.394692 -281.649932) (xy 393.395214 -281.624677) (xy 393.403527 -281.574855)
			(xy 393.419928 -281.527081) (xy 393.443969 -281.482658) (xy 393.474993 -281.442798) (xy 393.512155 -281.408588)
			(xy 393.554441 -281.380962) (xy 393.600697 -281.360672) (xy 393.649662 -281.348272) (xy 393.7 -281.344101)
			(xy 393.750338 -281.348272) (xy 393.799303 -281.360672) (xy 393.845559 -281.380962) (xy 393.887845 -281.408588)
			(xy 393.925007 -281.442798) (xy 393.956031 -281.482658) (xy 393.980072 -281.527081) (xy 393.996473 -281.574855)
			(xy 394.004786 -281.624677) (xy 394.005308 -281.649932) (xy 394.005136 -281.664115) (xy 394.002461 -281.692355)
			(xy 393.999974 -281.70632) (xy 393.997688 -281.718766) (xy 394.005054 -281.742388) (xy 394.082524 -281.819858)
			(xy 394.106146 -281.827224) (xy 394.118592 -281.824938) (xy 394.132559 -281.822467) (xy 394.160798 -281.819791)
			(xy 394.17498 -281.819604) (xy 394.189163 -281.819783) (xy 394.217403 -281.822454) (xy 394.231368 -281.824938)
			(xy 394.243814 -281.827224) (xy 394.267436 -281.819858) (xy 394.344906 -281.742388) (xy 394.352272 -281.718766)
			(xy 394.349986 -281.70632) (xy 394.347502 -281.692355) (xy 394.344835 -281.664115) (xy 394.344652 -281.649932)
			(xy 394.345143 -281.625107) (xy 394.353171 -281.576111) (xy 394.36902 -281.529059) (xy 394.392273 -281.485192)
			(xy 394.422316 -281.445664) (xy 394.458359 -281.411518) (xy 394.499452 -281.383653) (xy 394.544512 -281.362804)
			(xy 394.592351 -281.349519) (xy 394.641709 -281.344149) (xy 394.691286 -281.346836) (xy 394.739774 -281.357509)
			(xy 394.785898 -281.375885) (xy 394.82844 -281.401482) (xy 394.866281 -281.433625) (xy 394.898422 -281.471466)
			(xy 394.924018 -281.51401) (xy 394.942394 -281.560133) (xy 394.953065 -281.608622) (xy 394.955302 -281.649932)
			(xy 395.294116 -281.649932) (xy 395.298076 -281.600878) (xy 395.309853 -281.553094) (xy 395.329144 -281.507818)
			(xy 395.355447 -281.466222) (xy 395.388082 -281.429385) (xy 395.426203 -281.39826) (xy 395.468824 -281.373653)
			(xy 395.51484 -281.356201) (xy 395.563059 -281.346357) (xy 395.612234 -281.344376) (xy 395.661089 -281.350308)
			(xy 395.70836 -281.364) (xy 395.752822 -281.385098) (xy 395.793325 -281.413054) (xy 395.828818 -281.447146)
			(xy 395.858383 -281.48649) (xy 395.881254 -281.530067) (xy 395.896838 -281.576748) (xy 395.904733 -281.625325)
			(xy 395.905228 -281.649932) (xy 396.244076 -281.649932) (xy 396.248036 -281.600878) (xy 396.259813 -281.553094)
			(xy 396.279104 -281.507818) (xy 396.305407 -281.466222) (xy 396.338042 -281.429385) (xy 396.376163 -281.39826)
			(xy 396.418784 -281.373653) (xy 396.4648 -281.356201) (xy 396.513019 -281.346357) (xy 396.562194 -281.344376)
			(xy 396.611049 -281.350308) (xy 396.65832 -281.364) (xy 396.702782 -281.385098) (xy 396.743285 -281.413054)
			(xy 396.778778 -281.447146) (xy 396.808343 -281.48649) (xy 396.831214 -281.530067) (xy 396.846798 -281.576748)
			(xy 396.854693 -281.625325) (xy 396.855188 -281.649932) (xy 397.194036 -281.649932) (xy 397.197996 -281.600878)
			(xy 397.209773 -281.553094) (xy 397.229064 -281.507818) (xy 397.255367 -281.466222) (xy 397.288002 -281.429385)
			(xy 397.326123 -281.39826) (xy 397.368744 -281.373653) (xy 397.41476 -281.356201) (xy 397.462979 -281.346357)
			(xy 397.512154 -281.344376) (xy 397.561009 -281.350308) (xy 397.60828 -281.364) (xy 397.652742 -281.385098)
			(xy 397.693245 -281.413054) (xy 397.728738 -281.447146) (xy 397.758303 -281.48649) (xy 397.781174 -281.530067)
			(xy 397.796758 -281.576748) (xy 397.804653 -281.625325) (xy 397.805148 -281.649932) (xy 398.143996 -281.649932)
			(xy 398.147956 -281.600878) (xy 398.159733 -281.553094) (xy 398.179024 -281.507818) (xy 398.205327 -281.466222)
			(xy 398.237962 -281.429385) (xy 398.276083 -281.39826) (xy 398.318704 -281.373653) (xy 398.36472 -281.356201)
			(xy 398.412939 -281.346357) (xy 398.462114 -281.344376) (xy 398.510969 -281.350308) (xy 398.55824 -281.364)
			(xy 398.602702 -281.385098) (xy 398.643205 -281.413054) (xy 398.678698 -281.447146) (xy 398.708263 -281.48649)
			(xy 398.731134 -281.530067) (xy 398.746718 -281.576748) (xy 398.754613 -281.625325) (xy 398.755108 -281.649932)
			(xy 399.09421 -281.649932) (xy 399.09817 -281.600878) (xy 399.109947 -281.553094) (xy 399.129238 -281.507818)
			(xy 399.155541 -281.466222) (xy 399.188176 -281.429385) (xy 399.226297 -281.39826) (xy 399.268918 -281.373653)
			(xy 399.314934 -281.356201) (xy 399.363153 -281.346357) (xy 399.412328 -281.344376) (xy 399.461183 -281.350308)
			(xy 399.508454 -281.364) (xy 399.552916 -281.385098) (xy 399.593419 -281.413054) (xy 399.628912 -281.447146)
			(xy 399.658477 -281.48649) (xy 399.681348 -281.530067) (xy 399.696932 -281.576748) (xy 399.704827 -281.625325)
			(xy 399.705322 -281.649932) (xy 400.04417 -281.649932) (xy 400.04813 -281.600878) (xy 400.059907 -281.553094)
			(xy 400.079198 -281.507818) (xy 400.105501 -281.466222) (xy 400.138136 -281.429385) (xy 400.176257 -281.39826)
			(xy 400.218878 -281.373653) (xy 400.264894 -281.356201) (xy 400.313113 -281.346357) (xy 400.362288 -281.344376)
			(xy 400.411143 -281.350308) (xy 400.458414 -281.364) (xy 400.502876 -281.385098) (xy 400.543379 -281.413054)
			(xy 400.578872 -281.447146) (xy 400.608437 -281.48649) (xy 400.631308 -281.530067) (xy 400.646892 -281.576748)
			(xy 400.654787 -281.625325) (xy 400.655282 -281.649932) (xy 400.99413 -281.649932) (xy 400.99809 -281.600878)
			(xy 401.009867 -281.553094) (xy 401.029158 -281.507818) (xy 401.055461 -281.466222) (xy 401.088096 -281.429385)
			(xy 401.126217 -281.39826) (xy 401.168838 -281.373653) (xy 401.214854 -281.356201) (xy 401.263073 -281.346357)
			(xy 401.312248 -281.344376) (xy 401.361103 -281.350308) (xy 401.408374 -281.364) (xy 401.452836 -281.385098)
			(xy 401.493339 -281.413054) (xy 401.528832 -281.447146) (xy 401.558397 -281.48649) (xy 401.581268 -281.530067)
			(xy 401.596852 -281.576748) (xy 401.604747 -281.625325) (xy 401.605242 -281.649932) (xy 401.94409 -281.649932)
			(xy 401.94805 -281.600878) (xy 401.959827 -281.553094) (xy 401.979118 -281.507818) (xy 402.005421 -281.466222)
			(xy 402.038056 -281.429385) (xy 402.076177 -281.39826) (xy 402.118798 -281.373653) (xy 402.164814 -281.356201)
			(xy 402.213033 -281.346357) (xy 402.262208 -281.344376) (xy 402.311063 -281.350308) (xy 402.358334 -281.364)
			(xy 402.402796 -281.385098) (xy 402.443299 -281.413054) (xy 402.478792 -281.447146) (xy 402.508357 -281.48649)
			(xy 402.531228 -281.530067) (xy 402.546812 -281.576748) (xy 402.554707 -281.625325) (xy 402.555202 -281.649932)
			(xy 402.89405 -281.649932) (xy 402.89801 -281.600878) (xy 402.909787 -281.553094) (xy 402.929078 -281.507818)
			(xy 402.955381 -281.466222) (xy 402.988016 -281.429385) (xy 403.026137 -281.39826) (xy 403.068758 -281.373653)
			(xy 403.114774 -281.356201) (xy 403.162993 -281.346357) (xy 403.212168 -281.344376) (xy 403.261023 -281.350308)
			(xy 403.308294 -281.364) (xy 403.352756 -281.385098) (xy 403.393259 -281.413054) (xy 403.428752 -281.447146)
			(xy 403.458317 -281.48649) (xy 403.481188 -281.530067) (xy 403.496772 -281.576748) (xy 403.504667 -281.625325)
			(xy 403.505162 -281.649932) (xy 403.84401 -281.649932) (xy 403.84797 -281.600878) (xy 403.859747 -281.553094)
			(xy 403.879038 -281.507818) (xy 403.905341 -281.466222) (xy 403.937976 -281.429385) (xy 403.976097 -281.39826)
			(xy 404.018718 -281.373653) (xy 404.064734 -281.356201) (xy 404.112953 -281.346357) (xy 404.162128 -281.344376)
			(xy 404.210983 -281.350308) (xy 404.258254 -281.364) (xy 404.302716 -281.385098) (xy 404.343219 -281.413054)
			(xy 404.378712 -281.447146) (xy 404.408277 -281.48649) (xy 404.431148 -281.530067) (xy 404.446732 -281.576748)
			(xy 404.454627 -281.625325) (xy 404.455122 -281.649932) (xy 404.794224 -281.649932) (xy 404.798184 -281.600878)
			(xy 404.809961 -281.553094) (xy 404.829252 -281.507818) (xy 404.855555 -281.466222) (xy 404.88819 -281.429385)
			(xy 404.926311 -281.39826) (xy 404.968932 -281.373653) (xy 405.014948 -281.356201) (xy 405.063167 -281.346357)
			(xy 405.112342 -281.344376) (xy 405.161197 -281.350308) (xy 405.208468 -281.364) (xy 405.25293 -281.385098)
			(xy 405.293433 -281.413054) (xy 405.328926 -281.447146) (xy 405.358491 -281.48649) (xy 405.381362 -281.530067)
			(xy 405.396946 -281.576748) (xy 405.404841 -281.625325) (xy 405.405336 -281.649932) (xy 405.744184 -281.649932)
			(xy 405.748144 -281.600878) (xy 405.759921 -281.553094) (xy 405.779212 -281.507818) (xy 405.805515 -281.466222)
			(xy 405.83815 -281.429385) (xy 405.876271 -281.39826) (xy 405.918892 -281.373653) (xy 405.964908 -281.356201)
			(xy 406.013127 -281.346357) (xy 406.062302 -281.344376) (xy 406.111157 -281.350308) (xy 406.158428 -281.364)
			(xy 406.20289 -281.385098) (xy 406.243393 -281.413054) (xy 406.278886 -281.447146) (xy 406.308451 -281.48649)
			(xy 406.331322 -281.530067) (xy 406.346906 -281.576748) (xy 406.354801 -281.625325) (xy 406.355296 -281.649932)
			(xy 406.694144 -281.649932) (xy 406.698104 -281.600878) (xy 406.709881 -281.553094) (xy 406.729172 -281.507818)
			(xy 406.755475 -281.466222) (xy 406.78811 -281.429385) (xy 406.826231 -281.39826) (xy 406.868852 -281.373653)
			(xy 406.914868 -281.356201) (xy 406.963087 -281.346357) (xy 407.012262 -281.344376) (xy 407.061117 -281.350308)
			(xy 407.108388 -281.364) (xy 407.15285 -281.385098) (xy 407.193353 -281.413054) (xy 407.228846 -281.447146)
			(xy 407.258411 -281.48649) (xy 407.281282 -281.530067) (xy 407.296866 -281.576748) (xy 407.304761 -281.625325)
			(xy 407.305256 -281.649932) (xy 407.644104 -281.649932) (xy 407.648064 -281.600878) (xy 407.659841 -281.553094)
			(xy 407.679132 -281.507818) (xy 407.705435 -281.466222) (xy 407.73807 -281.429385) (xy 407.776191 -281.39826)
			(xy 407.818812 -281.373653) (xy 407.864828 -281.356201) (xy 407.913047 -281.346357) (xy 407.962222 -281.344376)
			(xy 408.011077 -281.350308) (xy 408.058348 -281.364) (xy 408.10281 -281.385098) (xy 408.143313 -281.413054)
			(xy 408.178806 -281.447146) (xy 408.208371 -281.48649) (xy 408.231242 -281.530067) (xy 408.246826 -281.576748)
			(xy 408.254721 -281.625325) (xy 408.255216 -281.649932) (xy 408.594064 -281.649932) (xy 408.598024 -281.600878)
			(xy 408.609801 -281.553094) (xy 408.629092 -281.507818) (xy 408.655395 -281.466222) (xy 408.68803 -281.429385)
			(xy 408.726151 -281.39826) (xy 408.768772 -281.373653) (xy 408.814788 -281.356201) (xy 408.863007 -281.346357)
			(xy 408.912182 -281.344376) (xy 408.961037 -281.350308) (xy 409.008308 -281.364) (xy 409.05277 -281.385098)
			(xy 409.093273 -281.413054) (xy 409.128766 -281.447146) (xy 409.158331 -281.48649) (xy 409.181202 -281.530067)
			(xy 409.196786 -281.576748) (xy 409.204681 -281.625325) (xy 409.205176 -281.649932) (xy 409.544024 -281.649932)
			(xy 409.547984 -281.600878) (xy 409.559761 -281.553094) (xy 409.579052 -281.507818) (xy 409.605355 -281.466222)
			(xy 409.63799 -281.429385) (xy 409.676111 -281.39826) (xy 409.718732 -281.373653) (xy 409.764748 -281.356201)
			(xy 409.812967 -281.346357) (xy 409.862142 -281.344376) (xy 409.910997 -281.350308) (xy 409.958268 -281.364)
			(xy 410.00273 -281.385098) (xy 410.043233 -281.413054) (xy 410.078726 -281.447146) (xy 410.108291 -281.48649)
			(xy 410.131162 -281.530067) (xy 410.146746 -281.576748) (xy 410.154641 -281.625325) (xy 410.155136 -281.649932)
			(xy 410.493984 -281.649932) (xy 410.497944 -281.600878) (xy 410.509721 -281.553094) (xy 410.529012 -281.507818)
			(xy 410.555315 -281.466222) (xy 410.58795 -281.429385) (xy 410.626071 -281.39826) (xy 410.668692 -281.373653)
			(xy 410.714708 -281.356201) (xy 410.762927 -281.346357) (xy 410.812102 -281.344376) (xy 410.860957 -281.350308)
			(xy 410.908228 -281.364) (xy 410.95269 -281.385098) (xy 410.993193 -281.413054) (xy 411.028686 -281.447146)
			(xy 411.058251 -281.48649) (xy 411.081122 -281.530067) (xy 411.096706 -281.576748) (xy 411.104601 -281.625325)
			(xy 411.105096 -281.649932) (xy 411.444198 -281.649932) (xy 411.448158 -281.600878) (xy 411.459935 -281.553094)
			(xy 411.479226 -281.507818) (xy 411.505529 -281.466222) (xy 411.538164 -281.429385) (xy 411.576285 -281.39826)
			(xy 411.618906 -281.373653) (xy 411.664922 -281.356201) (xy 411.713141 -281.346357) (xy 411.762316 -281.344376)
			(xy 411.811171 -281.350308) (xy 411.858442 -281.364) (xy 411.902904 -281.385098) (xy 411.943407 -281.413054)
			(xy 411.9789 -281.447146) (xy 412.008465 -281.48649) (xy 412.031336 -281.530067) (xy 412.04692 -281.576748)
			(xy 412.054815 -281.625325) (xy 412.05531 -281.649932) (xy 412.394158 -281.649932) (xy 412.398118 -281.600878)
			(xy 412.409895 -281.553094) (xy 412.429186 -281.507818) (xy 412.455489 -281.466222) (xy 412.488124 -281.429385)
			(xy 412.526245 -281.39826) (xy 412.568866 -281.373653) (xy 412.614882 -281.356201) (xy 412.663101 -281.346357)
			(xy 412.712276 -281.344376) (xy 412.761131 -281.350308) (xy 412.808402 -281.364) (xy 412.852864 -281.385098)
			(xy 412.893367 -281.413054) (xy 412.92886 -281.447146) (xy 412.958425 -281.48649) (xy 412.981296 -281.530067)
			(xy 412.99688 -281.576748) (xy 413.004775 -281.625325) (xy 413.00527 -281.649932) (xy 413.344118 -281.649932)
			(xy 413.348078 -281.600878) (xy 413.359855 -281.553094) (xy 413.379146 -281.507818) (xy 413.405449 -281.466222)
			(xy 413.438084 -281.429385) (xy 413.476205 -281.39826) (xy 413.518826 -281.373653) (xy 413.564842 -281.356201)
			(xy 413.613061 -281.346357) (xy 413.662236 -281.344376) (xy 413.711091 -281.350308) (xy 413.758362 -281.364)
			(xy 413.802824 -281.385098) (xy 413.843327 -281.413054) (xy 413.87882 -281.447146) (xy 413.908385 -281.48649)
			(xy 413.931256 -281.530067) (xy 413.94684 -281.576748) (xy 413.954735 -281.625325) (xy 413.95523 -281.649932)
			(xy 414.294078 -281.649932) (xy 414.298038 -281.600878) (xy 414.309815 -281.553094) (xy 414.329106 -281.507818)
			(xy 414.355409 -281.466222) (xy 414.388044 -281.429385) (xy 414.426165 -281.39826) (xy 414.468786 -281.373653)
			(xy 414.514802 -281.356201) (xy 414.563021 -281.346357) (xy 414.612196 -281.344376) (xy 414.661051 -281.350308)
			(xy 414.708322 -281.364) (xy 414.752784 -281.385098) (xy 414.793287 -281.413054) (xy 414.82878 -281.447146)
			(xy 414.858345 -281.48649) (xy 414.881216 -281.530067) (xy 414.8968 -281.576748) (xy 414.904695 -281.625325)
			(xy 414.90519 -281.649932) (xy 415.244038 -281.649932) (xy 415.247998 -281.600878) (xy 415.259775 -281.553094)
			(xy 415.279066 -281.507818) (xy 415.305369 -281.466222) (xy 415.338004 -281.429385) (xy 415.376125 -281.39826)
			(xy 415.418746 -281.373653) (xy 415.464762 -281.356201) (xy 415.512981 -281.346357) (xy 415.562156 -281.344376)
			(xy 415.611011 -281.350308) (xy 415.658282 -281.364) (xy 415.702744 -281.385098) (xy 415.743247 -281.413054)
			(xy 415.77874 -281.447146) (xy 415.808305 -281.48649) (xy 415.831176 -281.530067) (xy 415.84676 -281.576748)
			(xy 415.854655 -281.625325) (xy 415.85515 -281.649932) (xy 416.193998 -281.649932) (xy 416.197958 -281.600878)
			(xy 416.209735 -281.553094) (xy 416.229026 -281.507818) (xy 416.255329 -281.466222) (xy 416.287964 -281.429385)
			(xy 416.326085 -281.39826) (xy 416.368706 -281.373653) (xy 416.414722 -281.356201) (xy 416.462941 -281.346357)
			(xy 416.512116 -281.344376) (xy 416.560971 -281.350308) (xy 416.608242 -281.364) (xy 416.652704 -281.385098)
			(xy 416.693207 -281.413054) (xy 416.7287 -281.447146) (xy 416.758265 -281.48649) (xy 416.781136 -281.530067)
			(xy 416.79672 -281.576748) (xy 416.804615 -281.625325) (xy 416.80511 -281.649932) (xy 416.804615 -281.674539)
			(xy 416.79672 -281.723116) (xy 416.781136 -281.769797) (xy 416.758265 -281.813374) (xy 416.7287 -281.852718)
			(xy 416.693207 -281.88681) (xy 416.652704 -281.914766) (xy 416.608242 -281.935864) (xy 416.560971 -281.949556)
			(xy 416.512116 -281.955488) (xy 416.462941 -281.953507) (xy 416.414722 -281.943663) (xy 416.368706 -281.926211)
			(xy 416.326085 -281.901604) (xy 416.287964 -281.870479) (xy 416.255329 -281.833642) (xy 416.229026 -281.792046)
			(xy 416.209735 -281.74677) (xy 416.197958 -281.698986) (xy 416.193998 -281.649932) (xy 415.85515 -281.649932)
			(xy 415.854655 -281.674539) (xy 415.84676 -281.723116) (xy 415.831176 -281.769797) (xy 415.808305 -281.813374)
			(xy 415.77874 -281.852718) (xy 415.743247 -281.88681) (xy 415.702744 -281.914766) (xy 415.658282 -281.935864)
			(xy 415.611011 -281.949556) (xy 415.562156 -281.955488) (xy 415.512981 -281.953507) (xy 415.464762 -281.943663)
			(xy 415.418746 -281.926211) (xy 415.376125 -281.901604) (xy 415.338004 -281.870479) (xy 415.305369 -281.833642)
			(xy 415.279066 -281.792046) (xy 415.259775 -281.74677) (xy 415.247998 -281.698986) (xy 415.244038 -281.649932)
			(xy 414.90519 -281.649932) (xy 414.904695 -281.674539) (xy 414.8968 -281.723116) (xy 414.881216 -281.769797)
			(xy 414.858345 -281.813374) (xy 414.82878 -281.852718) (xy 414.793287 -281.88681) (xy 414.752784 -281.914766)
			(xy 414.708322 -281.935864) (xy 414.661051 -281.949556) (xy 414.612196 -281.955488) (xy 414.563021 -281.953507)
			(xy 414.514802 -281.943663) (xy 414.468786 -281.926211) (xy 414.426165 -281.901604) (xy 414.388044 -281.870479)
			(xy 414.355409 -281.833642) (xy 414.329106 -281.792046) (xy 414.309815 -281.74677) (xy 414.298038 -281.698986)
			(xy 414.294078 -281.649932) (xy 413.95523 -281.649932) (xy 413.954735 -281.674539) (xy 413.94684 -281.723116)
			(xy 413.931256 -281.769797) (xy 413.908385 -281.813374) (xy 413.87882 -281.852718) (xy 413.843327 -281.88681)
			(xy 413.802824 -281.914766) (xy 413.758362 -281.935864) (xy 413.711091 -281.949556) (xy 413.662236 -281.955488)
			(xy 413.613061 -281.953507) (xy 413.564842 -281.943663) (xy 413.518826 -281.926211) (xy 413.476205 -281.901604)
			(xy 413.438084 -281.870479) (xy 413.405449 -281.833642) (xy 413.379146 -281.792046) (xy 413.359855 -281.74677)
			(xy 413.348078 -281.698986) (xy 413.344118 -281.649932) (xy 413.00527 -281.649932) (xy 413.004775 -281.674539)
			(xy 412.99688 -281.723116) (xy 412.981296 -281.769797) (xy 412.958425 -281.813374) (xy 412.92886 -281.852718)
			(xy 412.893367 -281.88681) (xy 412.852864 -281.914766) (xy 412.808402 -281.935864) (xy 412.761131 -281.949556)
			(xy 412.712276 -281.955488) (xy 412.663101 -281.953507) (xy 412.614882 -281.943663) (xy 412.568866 -281.926211)
			(xy 412.526245 -281.901604) (xy 412.488124 -281.870479) (xy 412.455489 -281.833642) (xy 412.429186 -281.792046)
			(xy 412.409895 -281.74677) (xy 412.398118 -281.698986) (xy 412.394158 -281.649932) (xy 412.05531 -281.649932)
			(xy 412.054815 -281.674539) (xy 412.04692 -281.723116) (xy 412.031336 -281.769797) (xy 412.008465 -281.813374)
			(xy 411.9789 -281.852718) (xy 411.943407 -281.88681) (xy 411.902904 -281.914766) (xy 411.858442 -281.935864)
			(xy 411.811171 -281.949556) (xy 411.762316 -281.955488) (xy 411.713141 -281.953507) (xy 411.664922 -281.943663)
			(xy 411.618906 -281.926211) (xy 411.576285 -281.901604) (xy 411.538164 -281.870479) (xy 411.505529 -281.833642)
			(xy 411.479226 -281.792046) (xy 411.459935 -281.74677) (xy 411.448158 -281.698986) (xy 411.444198 -281.649932)
			(xy 411.105096 -281.649932) (xy 411.104601 -281.674539) (xy 411.096706 -281.723116) (xy 411.081122 -281.769797)
			(xy 411.058251 -281.813374) (xy 411.028686 -281.852718) (xy 410.993193 -281.88681) (xy 410.95269 -281.914766)
			(xy 410.908228 -281.935864) (xy 410.860957 -281.949556) (xy 410.812102 -281.955488) (xy 410.762927 -281.953507)
			(xy 410.714708 -281.943663) (xy 410.668692 -281.926211) (xy 410.626071 -281.901604) (xy 410.58795 -281.870479)
			(xy 410.555315 -281.833642) (xy 410.529012 -281.792046) (xy 410.509721 -281.74677) (xy 410.497944 -281.698986)
			(xy 410.493984 -281.649932) (xy 410.155136 -281.649932) (xy 410.154641 -281.674539) (xy 410.146746 -281.723116)
			(xy 410.131162 -281.769797) (xy 410.108291 -281.813374) (xy 410.078726 -281.852718) (xy 410.043233 -281.88681)
			(xy 410.00273 -281.914766) (xy 409.958268 -281.935864) (xy 409.910997 -281.949556) (xy 409.862142 -281.955488)
			(xy 409.812967 -281.953507) (xy 409.764748 -281.943663) (xy 409.718732 -281.926211) (xy 409.676111 -281.901604)
			(xy 409.63799 -281.870479) (xy 409.605355 -281.833642) (xy 409.579052 -281.792046) (xy 409.559761 -281.74677)
			(xy 409.547984 -281.698986) (xy 409.544024 -281.649932) (xy 409.205176 -281.649932) (xy 409.204681 -281.674539)
			(xy 409.196786 -281.723116) (xy 409.181202 -281.769797) (xy 409.158331 -281.813374) (xy 409.128766 -281.852718)
			(xy 409.093273 -281.88681) (xy 409.05277 -281.914766) (xy 409.008308 -281.935864) (xy 408.961037 -281.949556)
			(xy 408.912182 -281.955488) (xy 408.863007 -281.953507) (xy 408.814788 -281.943663) (xy 408.768772 -281.926211)
			(xy 408.726151 -281.901604) (xy 408.68803 -281.870479) (xy 408.655395 -281.833642) (xy 408.629092 -281.792046)
			(xy 408.609801 -281.74677) (xy 408.598024 -281.698986) (xy 408.594064 -281.649932) (xy 408.255216 -281.649932)
			(xy 408.254721 -281.674539) (xy 408.246826 -281.723116) (xy 408.231242 -281.769797) (xy 408.208371 -281.813374)
			(xy 408.178806 -281.852718) (xy 408.143313 -281.88681) (xy 408.10281 -281.914766) (xy 408.058348 -281.935864)
			(xy 408.011077 -281.949556) (xy 407.962222 -281.955488) (xy 407.913047 -281.953507) (xy 407.864828 -281.943663)
			(xy 407.818812 -281.926211) (xy 407.776191 -281.901604) (xy 407.73807 -281.870479) (xy 407.705435 -281.833642)
			(xy 407.679132 -281.792046) (xy 407.659841 -281.74677) (xy 407.648064 -281.698986) (xy 407.644104 -281.649932)
			(xy 407.305256 -281.649932) (xy 407.304761 -281.674539) (xy 407.296866 -281.723116) (xy 407.281282 -281.769797)
			(xy 407.258411 -281.813374) (xy 407.228846 -281.852718) (xy 407.193353 -281.88681) (xy 407.15285 -281.914766)
			(xy 407.108388 -281.935864) (xy 407.061117 -281.949556) (xy 407.012262 -281.955488) (xy 406.963087 -281.953507)
			(xy 406.914868 -281.943663) (xy 406.868852 -281.926211) (xy 406.826231 -281.901604) (xy 406.78811 -281.870479)
			(xy 406.755475 -281.833642) (xy 406.729172 -281.792046) (xy 406.709881 -281.74677) (xy 406.698104 -281.698986)
			(xy 406.694144 -281.649932) (xy 406.355296 -281.649932) (xy 406.354801 -281.674539) (xy 406.346906 -281.723116)
			(xy 406.331322 -281.769797) (xy 406.308451 -281.813374) (xy 406.278886 -281.852718) (xy 406.243393 -281.88681)
			(xy 406.20289 -281.914766) (xy 406.158428 -281.935864) (xy 406.111157 -281.949556) (xy 406.062302 -281.955488)
			(xy 406.013127 -281.953507) (xy 405.964908 -281.943663) (xy 405.918892 -281.926211) (xy 405.876271 -281.901604)
			(xy 405.83815 -281.870479) (xy 405.805515 -281.833642) (xy 405.779212 -281.792046) (xy 405.759921 -281.74677)
			(xy 405.748144 -281.698986) (xy 405.744184 -281.649932) (xy 405.405336 -281.649932) (xy 405.404841 -281.674539)
			(xy 405.396946 -281.723116) (xy 405.381362 -281.769797) (xy 405.358491 -281.813374) (xy 405.328926 -281.852718)
			(xy 405.293433 -281.88681) (xy 405.25293 -281.914766) (xy 405.208468 -281.935864) (xy 405.161197 -281.949556)
			(xy 405.112342 -281.955488) (xy 405.063167 -281.953507) (xy 405.014948 -281.943663) (xy 404.968932 -281.926211)
			(xy 404.926311 -281.901604) (xy 404.88819 -281.870479) (xy 404.855555 -281.833642) (xy 404.829252 -281.792046)
			(xy 404.809961 -281.74677) (xy 404.798184 -281.698986) (xy 404.794224 -281.649932) (xy 404.455122 -281.649932)
			(xy 404.454627 -281.674539) (xy 404.446732 -281.723116) (xy 404.431148 -281.769797) (xy 404.408277 -281.813374)
			(xy 404.378712 -281.852718) (xy 404.343219 -281.88681) (xy 404.302716 -281.914766) (xy 404.258254 -281.935864)
			(xy 404.210983 -281.949556) (xy 404.162128 -281.955488) (xy 404.112953 -281.953507) (xy 404.064734 -281.943663)
			(xy 404.018718 -281.926211) (xy 403.976097 -281.901604) (xy 403.937976 -281.870479) (xy 403.905341 -281.833642)
			(xy 403.879038 -281.792046) (xy 403.859747 -281.74677) (xy 403.84797 -281.698986) (xy 403.84401 -281.649932)
			(xy 403.505162 -281.649932) (xy 403.504667 -281.674539) (xy 403.496772 -281.723116) (xy 403.481188 -281.769797)
			(xy 403.458317 -281.813374) (xy 403.428752 -281.852718) (xy 403.393259 -281.88681) (xy 403.352756 -281.914766)
			(xy 403.308294 -281.935864) (xy 403.261023 -281.949556) (xy 403.212168 -281.955488) (xy 403.162993 -281.953507)
			(xy 403.114774 -281.943663) (xy 403.068758 -281.926211) (xy 403.026137 -281.901604) (xy 402.988016 -281.870479)
			(xy 402.955381 -281.833642) (xy 402.929078 -281.792046) (xy 402.909787 -281.74677) (xy 402.89801 -281.698986)
			(xy 402.89405 -281.649932) (xy 402.555202 -281.649932) (xy 402.554707 -281.674539) (xy 402.546812 -281.723116)
			(xy 402.531228 -281.769797) (xy 402.508357 -281.813374) (xy 402.478792 -281.852718) (xy 402.443299 -281.88681)
			(xy 402.402796 -281.914766) (xy 402.358334 -281.935864) (xy 402.311063 -281.949556) (xy 402.262208 -281.955488)
			(xy 402.213033 -281.953507) (xy 402.164814 -281.943663) (xy 402.118798 -281.926211) (xy 402.076177 -281.901604)
			(xy 402.038056 -281.870479) (xy 402.005421 -281.833642) (xy 401.979118 -281.792046) (xy 401.959827 -281.74677)
			(xy 401.94805 -281.698986) (xy 401.94409 -281.649932) (xy 401.605242 -281.649932) (xy 401.604747 -281.674539)
			(xy 401.596852 -281.723116) (xy 401.581268 -281.769797) (xy 401.558397 -281.813374) (xy 401.528832 -281.852718)
			(xy 401.493339 -281.88681) (xy 401.452836 -281.914766) (xy 401.408374 -281.935864) (xy 401.361103 -281.949556)
			(xy 401.312248 -281.955488) (xy 401.263073 -281.953507) (xy 401.214854 -281.943663) (xy 401.168838 -281.926211)
			(xy 401.126217 -281.901604) (xy 401.088096 -281.870479) (xy 401.055461 -281.833642) (xy 401.029158 -281.792046)
			(xy 401.009867 -281.74677) (xy 400.99809 -281.698986) (xy 400.99413 -281.649932) (xy 400.655282 -281.649932)
			(xy 400.654787 -281.674539) (xy 400.646892 -281.723116) (xy 400.631308 -281.769797) (xy 400.608437 -281.813374)
			(xy 400.578872 -281.852718) (xy 400.543379 -281.88681) (xy 400.502876 -281.914766) (xy 400.458414 -281.935864)
			(xy 400.411143 -281.949556) (xy 400.362288 -281.955488) (xy 400.313113 -281.953507) (xy 400.264894 -281.943663)
			(xy 400.218878 -281.926211) (xy 400.176257 -281.901604) (xy 400.138136 -281.870479) (xy 400.105501 -281.833642)
			(xy 400.079198 -281.792046) (xy 400.059907 -281.74677) (xy 400.04813 -281.698986) (xy 400.04417 -281.649932)
			(xy 399.705322 -281.649932) (xy 399.704827 -281.674539) (xy 399.696932 -281.723116) (xy 399.681348 -281.769797)
			(xy 399.658477 -281.813374) (xy 399.628912 -281.852718) (xy 399.593419 -281.88681) (xy 399.552916 -281.914766)
			(xy 399.508454 -281.935864) (xy 399.461183 -281.949556) (xy 399.412328 -281.955488) (xy 399.363153 -281.953507)
			(xy 399.314934 -281.943663) (xy 399.268918 -281.926211) (xy 399.226297 -281.901604) (xy 399.188176 -281.870479)
			(xy 399.155541 -281.833642) (xy 399.129238 -281.792046) (xy 399.109947 -281.74677) (xy 399.09817 -281.698986)
			(xy 399.09421 -281.649932) (xy 398.755108 -281.649932) (xy 398.754613 -281.674539) (xy 398.746718 -281.723116)
			(xy 398.731134 -281.769797) (xy 398.708263 -281.813374) (xy 398.678698 -281.852718) (xy 398.643205 -281.88681)
			(xy 398.602702 -281.914766) (xy 398.55824 -281.935864) (xy 398.510969 -281.949556) (xy 398.462114 -281.955488)
			(xy 398.412939 -281.953507) (xy 398.36472 -281.943663) (xy 398.318704 -281.926211) (xy 398.276083 -281.901604)
			(xy 398.237962 -281.870479) (xy 398.205327 -281.833642) (xy 398.179024 -281.792046) (xy 398.159733 -281.74677)
			(xy 398.147956 -281.698986) (xy 398.143996 -281.649932) (xy 397.805148 -281.649932) (xy 397.804653 -281.674539)
			(xy 397.796758 -281.723116) (xy 397.781174 -281.769797) (xy 397.758303 -281.813374) (xy 397.728738 -281.852718)
			(xy 397.693245 -281.88681) (xy 397.652742 -281.914766) (xy 397.60828 -281.935864) (xy 397.561009 -281.949556)
			(xy 397.512154 -281.955488) (xy 397.462979 -281.953507) (xy 397.41476 -281.943663) (xy 397.368744 -281.926211)
			(xy 397.326123 -281.901604) (xy 397.288002 -281.870479) (xy 397.255367 -281.833642) (xy 397.229064 -281.792046)
			(xy 397.209773 -281.74677) (xy 397.197996 -281.698986) (xy 397.194036 -281.649932) (xy 396.855188 -281.649932)
			(xy 396.854693 -281.674539) (xy 396.846798 -281.723116) (xy 396.831214 -281.769797) (xy 396.808343 -281.813374)
			(xy 396.778778 -281.852718) (xy 396.743285 -281.88681) (xy 396.702782 -281.914766) (xy 396.65832 -281.935864)
			(xy 396.611049 -281.949556) (xy 396.562194 -281.955488) (xy 396.513019 -281.953507) (xy 396.4648 -281.943663)
			(xy 396.418784 -281.926211) (xy 396.376163 -281.901604) (xy 396.338042 -281.870479) (xy 396.305407 -281.833642)
			(xy 396.279104 -281.792046) (xy 396.259813 -281.74677) (xy 396.248036 -281.698986) (xy 396.244076 -281.649932)
			(xy 395.905228 -281.649932) (xy 395.904733 -281.674539) (xy 395.896838 -281.723116) (xy 395.881254 -281.769797)
			(xy 395.858383 -281.813374) (xy 395.828818 -281.852718) (xy 395.793325 -281.88681) (xy 395.752822 -281.914766)
			(xy 395.70836 -281.935864) (xy 395.661089 -281.949556) (xy 395.612234 -281.955488) (xy 395.563059 -281.953507)
			(xy 395.51484 -281.943663) (xy 395.468824 -281.926211) (xy 395.426203 -281.901604) (xy 395.388082 -281.870479)
			(xy 395.355447 -281.833642) (xy 395.329144 -281.792046) (xy 395.309853 -281.74677) (xy 395.298076 -281.698986)
			(xy 395.294116 -281.649932) (xy 394.955302 -281.649932) (xy 394.95575 -281.658199) (xy 394.950379 -281.707557)
			(xy 394.937094 -281.755396) (xy 394.916243 -281.800455) (xy 394.888377 -281.841547) (xy 394.85423 -281.877589)
			(xy 394.814702 -281.907632) (xy 394.770833 -281.930883) (xy 394.723781 -281.946731) (xy 394.674785 -281.954757)
			(xy 394.64996 -281.95524) (xy 394.635777 -281.955068) (xy 394.607537 -281.952393) (xy 394.593572 -281.949906)
			(xy 394.581126 -281.94762) (xy 394.557504 -281.954986) (xy 394.480034 -282.032456) (xy 394.472668 -282.056078)
			(xy 394.474954 -282.068524) (xy 394.477429 -282.08249) (xy 394.480102 -282.11073) (xy 394.480288 -282.124912)
			(xy 394.479766 -282.150167) (xy 394.471453 -282.199989) (xy 394.455052 -282.247763) (xy 394.431011 -282.292186)
			(xy 394.399987 -282.332046) (xy 394.362825 -282.366256) (xy 394.320539 -282.393882) (xy 394.274283 -282.414172)
			(xy 394.225318 -282.426572) (xy 394.17498 -282.430743) (xy 394.124642 -282.426572) (xy 394.075677 -282.414172)
			(xy 394.029421 -282.393882) (xy 393.987135 -282.366256) (xy 393.949973 -282.332046) (xy 393.918949 -282.292186)
			(xy 393.894908 -282.247763) (xy 393.878507 -282.199989) (xy 393.870194 -282.150167) (xy 393.869672 -282.124912)
			(xy 393.869851 -282.110729) (xy 393.872521 -282.082489) (xy 393.875006 -282.068524) (xy 393.877292 -282.056078)
			(xy 393.869926 -282.032456) (xy 393.792456 -281.954986) (xy 393.768834 -281.94762) (xy 393.756388 -281.949906)
			(xy 393.742422 -281.95238) (xy 393.714182 -281.955053) (xy 393.7 -281.95524) (xy 393.685817 -281.955063)
			(xy 393.657577 -281.952391) (xy 393.643612 -281.949906) (xy 393.631166 -281.94762) (xy 393.607544 -281.954986)
			(xy 393.530074 -282.032456) (xy 393.522708 -282.056078) (xy 393.524994 -282.068524) (xy 393.52747 -282.08249)
			(xy 393.530142 -282.110729) (xy 393.530328 -282.124912) (xy 393.529809 -282.149732) (xy 393.521776 -282.198718)
			(xy 393.505924 -282.245759) (xy 393.482671 -282.289615) (xy 393.452628 -282.329132) (xy 393.416588 -282.363268)
			(xy 393.3755 -282.391123) (xy 393.330447 -282.411965) (xy 393.282616 -282.425243) (xy 393.233267 -282.430607)
			(xy 393.1837 -282.427917) (xy 393.135221 -282.417244) (xy 393.089107 -282.398868) (xy 393.046574 -282.373274)
			(xy 393.008742 -282.341135) (xy 392.976608 -282.3033) (xy 392.951018 -282.260764) (xy 392.932647 -282.214649)
			(xy 392.921978 -282.166169) (xy 392.919294 -282.116601) (xy 392.579947 -282.116601) (xy 392.580114 -282.124912)
			(xy 392.579619 -282.149519) (xy 392.571724 -282.198096) (xy 392.55614 -282.244777) (xy 392.533269 -282.288354)
			(xy 392.503704 -282.327698) (xy 392.468211 -282.36179) (xy 392.427708 -282.389746) (xy 392.383246 -282.410844)
			(xy 392.335975 -282.424536) (xy 392.28712 -282.430468) (xy 392.237945 -282.428487) (xy 392.189726 -282.418643)
			(xy 392.14371 -282.401191) (xy 392.101089 -282.376584) (xy 392.062968 -282.345459) (xy 392.030333 -282.308622)
			(xy 392.00403 -282.267026) (xy 391.984739 -282.22175) (xy 391.972962 -282.173966) (xy 391.969002 -282.124912)
			(xy 391.630154 -282.124912) (xy 391.629659 -282.149519) (xy 391.621764 -282.198096) (xy 391.60618 -282.244777)
			(xy 391.583309 -282.288354) (xy 391.553744 -282.327698) (xy 391.518251 -282.36179) (xy 391.477748 -282.389746)
			(xy 391.433286 -282.410844) (xy 391.386015 -282.424536) (xy 391.33716 -282.430468) (xy 391.287985 -282.428487)
			(xy 391.239766 -282.418643) (xy 391.19375 -282.401191) (xy 391.151129 -282.376584) (xy 391.113008 -282.345459)
			(xy 391.080373 -282.308622) (xy 391.05407 -282.267026) (xy 391.034779 -282.22175) (xy 391.023002 -282.173966)
			(xy 391.019042 -282.124912) (xy 390.680194 -282.124912) (xy 390.679699 -282.149519) (xy 390.671804 -282.198096)
			(xy 390.65622 -282.244777) (xy 390.633349 -282.288354) (xy 390.603784 -282.327698) (xy 390.568291 -282.36179)
			(xy 390.527788 -282.389746) (xy 390.483326 -282.410844) (xy 390.436055 -282.424536) (xy 390.3872 -282.430468)
			(xy 390.338025 -282.428487) (xy 390.289806 -282.418643) (xy 390.24379 -282.401191) (xy 390.201169 -282.376584)
			(xy 390.163048 -282.345459) (xy 390.130413 -282.308622) (xy 390.10411 -282.267026) (xy 390.084819 -282.22175)
			(xy 390.073042 -282.173966) (xy 390.069082 -282.124912) (xy 389.730234 -282.124912) (xy 389.729739 -282.149519)
			(xy 389.721844 -282.198096) (xy 389.70626 -282.244777) (xy 389.683389 -282.288354) (xy 389.653824 -282.327698)
			(xy 389.618331 -282.36179) (xy 389.577828 -282.389746) (xy 389.533366 -282.410844) (xy 389.486095 -282.424536)
			(xy 389.43724 -282.430468) (xy 389.388065 -282.428487) (xy 389.339846 -282.418643) (xy 389.29383 -282.401191)
			(xy 389.251209 -282.376584) (xy 389.213088 -282.345459) (xy 389.180453 -282.308622) (xy 389.15415 -282.267026)
			(xy 389.134859 -282.22175) (xy 389.123082 -282.173966) (xy 389.119122 -282.124912) (xy 388.780274 -282.124912)
			(xy 388.779779 -282.149519) (xy 388.771884 -282.198096) (xy 388.7563 -282.244777) (xy 388.733429 -282.288354)
			(xy 388.703864 -282.327698) (xy 388.668371 -282.36179) (xy 388.627868 -282.389746) (xy 388.583406 -282.410844)
			(xy 388.536135 -282.424536) (xy 388.48728 -282.430468) (xy 388.438105 -282.428487) (xy 388.389886 -282.418643)
			(xy 388.34387 -282.401191) (xy 388.301249 -282.376584) (xy 388.263128 -282.345459) (xy 388.230493 -282.308622)
			(xy 388.20419 -282.267026) (xy 388.184899 -282.22175) (xy 388.173122 -282.173966) (xy 388.169162 -282.124912)
			(xy 387.830314 -282.124912) (xy 387.829819 -282.149519) (xy 387.821924 -282.198096) (xy 387.80634 -282.244777)
			(xy 387.783469 -282.288354) (xy 387.753904 -282.327698) (xy 387.718411 -282.36179) (xy 387.677908 -282.389746)
			(xy 387.633446 -282.410844) (xy 387.586175 -282.424536) (xy 387.53732 -282.430468) (xy 387.488145 -282.428487)
			(xy 387.439926 -282.418643) (xy 387.39391 -282.401191) (xy 387.351289 -282.376584) (xy 387.313168 -282.345459)
			(xy 387.280533 -282.308622) (xy 387.25423 -282.267026) (xy 387.234939 -282.22175) (xy 387.223162 -282.173966)
			(xy 387.219202 -282.124912) (xy 386.880354 -282.124912) (xy 386.879859 -282.149519) (xy 386.871964 -282.198096)
			(xy 386.85638 -282.244777) (xy 386.833509 -282.288354) (xy 386.803944 -282.327698) (xy 386.768451 -282.36179)
			(xy 386.727948 -282.389746) (xy 386.683486 -282.410844) (xy 386.636215 -282.424536) (xy 386.58736 -282.430468)
			(xy 386.538185 -282.428487) (xy 386.489966 -282.418643) (xy 386.44395 -282.401191) (xy 386.401329 -282.376584)
			(xy 386.363208 -282.345459) (xy 386.330573 -282.308622) (xy 386.30427 -282.267026) (xy 386.284979 -282.22175)
			(xy 386.273202 -282.173966) (xy 386.269242 -282.124912) (xy 385.93014 -282.124912) (xy 385.929645 -282.149519)
			(xy 385.92175 -282.198096) (xy 385.906166 -282.244777) (xy 385.883295 -282.288354) (xy 385.85373 -282.327698)
			(xy 385.818237 -282.36179) (xy 385.777734 -282.389746) (xy 385.733272 -282.410844) (xy 385.686001 -282.424536)
			(xy 385.637146 -282.430468) (xy 385.587971 -282.428487) (xy 385.539752 -282.418643) (xy 385.493736 -282.401191)
			(xy 385.451115 -282.376584) (xy 385.412994 -282.345459) (xy 385.380359 -282.308622) (xy 385.354056 -282.267026)
			(xy 385.334765 -282.22175) (xy 385.322988 -282.173966) (xy 385.319028 -282.124912) (xy 384.98018 -282.124912)
			(xy 384.979685 -282.149519) (xy 384.97179 -282.198096) (xy 384.956206 -282.244777) (xy 384.933335 -282.288354)
			(xy 384.90377 -282.327698) (xy 384.868277 -282.36179) (xy 384.827774 -282.389746) (xy 384.783312 -282.410844)
			(xy 384.736041 -282.424536) (xy 384.687186 -282.430468) (xy 384.638011 -282.428487) (xy 384.589792 -282.418643)
			(xy 384.543776 -282.401191) (xy 384.501155 -282.376584) (xy 384.463034 -282.345459) (xy 384.430399 -282.308622)
			(xy 384.404096 -282.267026) (xy 384.384805 -282.22175) (xy 384.373028 -282.173966) (xy 384.369068 -282.124912)
			(xy 376.219021 -282.124912) (xy 376.200955 -282.139947) (xy 376.153349 -282.169001) (xy 376.10202 -282.190813)
			(xy 376.048063 -282.204919) (xy 375.992626 -282.211019) (xy 375.936892 -282.208982) (xy 375.882049 -282.198852)
			(xy 375.829265 -282.180845) (xy 375.779665 -282.155344) (xy 375.734307 -282.122893) (xy 375.694158 -282.084184)
			(xy 375.660072 -282.040041) (xy 375.632776 -281.991406) (xy 375.612853 -281.939315) (xy 375.600727 -281.884878)
			(xy 375.596656 -281.829256) (xy 374.875044 -281.829256) (xy 374.874535 -281.857142) (xy 374.866415 -281.912318)
			(xy 374.850347 -281.965725) (xy 374.826675 -282.016222) (xy 374.795902 -282.062735) (xy 374.758685 -282.104272)
			(xy 374.715817 -282.139947) (xy 374.668211 -282.169001) (xy 374.616882 -282.190813) (xy 374.562925 -282.204919)
			(xy 374.507488 -282.211019) (xy 374.451754 -282.208982) (xy 374.396911 -282.198852) (xy 374.344127 -282.180845)
			(xy 374.294527 -282.155344) (xy 374.249169 -282.122893) (xy 374.20902 -282.084184) (xy 374.174934 -282.040041)
			(xy 374.147638 -281.991406) (xy 374.127715 -281.939315) (xy 374.115589 -281.884878) (xy 374.111518 -281.829256)
			(xy 367.36909 -281.829256) (xy 367.36909 -282.135072) (xy 367.36885 -282.142023) (xy 367.365115 -282.155415)
			(xy 367.361724 -282.161488) (xy 367.357914 -282.167584) (xy 367.356136 -282.173934) (xy 367.354104 -282.187904)
			(xy 367.354104 -282.78582) (xy 367.354531 -282.795888) (xy 367.362251 -282.814487) (xy 367.36909 -282.821888)
			(xy 367.464848 -282.917392) (xy 367.485628 -282.939006) (xy 367.520867 -282.987511) (xy 367.548086 -283.04093)
			(xy 367.566617 -283.097948) (xy 367.571937 -283.131514) (xy 374.111518 -283.131514) (xy 374.115589 -283.075892)
			(xy 374.127715 -283.021455) (xy 374.147638 -282.969364) (xy 374.174934 -282.920729) (xy 374.20902 -282.876586)
			(xy 374.249169 -282.837877) (xy 374.294527 -282.805426) (xy 374.344127 -282.779925) (xy 374.396911 -282.761918)
			(xy 374.451754 -282.751788) (xy 374.507488 -282.749751) (xy 374.562925 -282.755851) (xy 374.616882 -282.769957)
			(xy 374.668211 -282.791769) (xy 374.715817 -282.820823) (xy 374.758685 -282.856498) (xy 374.795902 -282.898035)
			(xy 374.826675 -282.944548) (xy 374.850347 -282.995045) (xy 374.866415 -283.048452) (xy 374.874535 -283.103628)
			(xy 374.875044 -283.131514) (xy 375.587004 -283.131514) (xy 375.591075 -283.075892) (xy 375.603201 -283.021455)
			(xy 375.623124 -282.969364) (xy 375.65042 -282.920729) (xy 375.684506 -282.876586) (xy 375.724655 -282.837877)
			(xy 375.770013 -282.805426) (xy 375.819613 -282.779925) (xy 375.872397 -282.761918) (xy 375.92724 -282.751788)
			(xy 375.982974 -282.749751) (xy 376.038411 -282.755851) (xy 376.092368 -282.769957) (xy 376.143697 -282.791769)
			(xy 376.191303 -282.820823) (xy 376.234171 -282.856498) (xy 376.271388 -282.898035) (xy 376.302161 -282.944548)
			(xy 376.325833 -282.995045) (xy 376.341901 -283.048452) (xy 376.350021 -283.103628) (xy 376.35053 -283.131514)
			(xy 376.476004 -283.131514) (xy 376.480075 -283.075892) (xy 376.492201 -283.021455) (xy 376.512124 -282.969364)
			(xy 376.53942 -282.920729) (xy 376.573506 -282.876586) (xy 376.613655 -282.837877) (xy 376.659013 -282.805426)
			(xy 376.708613 -282.779925) (xy 376.761397 -282.761918) (xy 376.81624 -282.751788) (xy 376.871974 -282.749751)
			(xy 376.927411 -282.755851) (xy 376.981368 -282.769957) (xy 377.032697 -282.791769) (xy 377.080303 -282.820823)
			(xy 377.123171 -282.856498) (xy 377.160388 -282.898035) (xy 377.191161 -282.944548) (xy 377.214833 -282.995045)
			(xy 377.230901 -283.048452) (xy 377.239021 -283.103628) (xy 377.23953 -283.131514) (xy 377.239021 -283.1594)
			(xy 377.230901 -283.214576) (xy 377.214833 -283.267983) (xy 377.191161 -283.31848) (xy 377.160388 -283.364993)
			(xy 377.123171 -283.40653) (xy 377.080303 -283.442205) (xy 377.032697 -283.471259) (xy 376.981368 -283.493071)
			(xy 376.927411 -283.507177) (xy 376.871974 -283.513277) (xy 376.81624 -283.51124) (xy 376.761397 -283.50111)
			(xy 376.708613 -283.483103) (xy 376.659013 -283.457602) (xy 376.613655 -283.425151) (xy 376.573506 -283.386442)
			(xy 376.53942 -283.342299) (xy 376.512124 -283.293664) (xy 376.492201 -283.241573) (xy 376.480075 -283.187136)
			(xy 376.476004 -283.131514) (xy 376.35053 -283.131514) (xy 376.350021 -283.1594) (xy 376.341901 -283.214576)
			(xy 376.325833 -283.267983) (xy 376.302161 -283.31848) (xy 376.271388 -283.364993) (xy 376.234171 -283.40653)
			(xy 376.191303 -283.442205) (xy 376.143697 -283.471259) (xy 376.092368 -283.493071) (xy 376.038411 -283.507177)
			(xy 375.982974 -283.513277) (xy 375.92724 -283.51124) (xy 375.872397 -283.50111) (xy 375.819613 -283.483103)
			(xy 375.770013 -283.457602) (xy 375.724655 -283.425151) (xy 375.684506 -283.386442) (xy 375.65042 -283.342299)
			(xy 375.623124 -283.293664) (xy 375.603201 -283.241573) (xy 375.591075 -283.187136) (xy 375.587004 -283.131514)
			(xy 374.875044 -283.131514) (xy 374.874535 -283.1594) (xy 374.866415 -283.214576) (xy 374.850347 -283.267983)
			(xy 374.826675 -283.31848) (xy 374.795902 -283.364993) (xy 374.758685 -283.40653) (xy 374.715817 -283.442205)
			(xy 374.668211 -283.471259) (xy 374.616882 -283.493071) (xy 374.562925 -283.507177) (xy 374.507488 -283.513277)
			(xy 374.451754 -283.51124) (xy 374.396911 -283.50111) (xy 374.344127 -283.483103) (xy 374.294527 -283.457602)
			(xy 374.249169 -283.425151) (xy 374.20902 -283.386442) (xy 374.174934 -283.342299) (xy 374.147638 -283.293664)
			(xy 374.127715 -283.241573) (xy 374.115589 -283.187136) (xy 374.111518 -283.131514) (xy 367.571937 -283.131514)
			(xy 367.576002 -283.157163) (xy 367.576608 -283.18714) (xy 367.576608 -284.138116) (xy 373.346978 -284.138116)
			(xy 373.351049 -284.082494) (xy 373.363175 -284.028057) (xy 373.383098 -283.975966) (xy 373.410394 -283.927331)
			(xy 373.44448 -283.883188) (xy 373.484629 -283.844479) (xy 373.529987 -283.812028) (xy 373.579587 -283.786527)
			(xy 373.632371 -283.76852) (xy 373.687214 -283.75839) (xy 373.742948 -283.756353) (xy 373.798385 -283.762453)
			(xy 373.852342 -283.776559) (xy 373.903671 -283.798371) (xy 373.951277 -283.827425) (xy 373.994145 -283.8631)
			(xy 374.031362 -283.904637) (xy 374.062135 -283.95115) (xy 374.085807 -284.001647) (xy 374.101875 -284.055054)
			(xy 374.109995 -284.11023) (xy 374.110504 -284.138116) (xy 374.109995 -284.166002) (xy 374.101875 -284.221178)
			(xy 374.085807 -284.274585) (xy 374.062135 -284.325082) (xy 374.031362 -284.371595) (xy 373.994145 -284.413132)
			(xy 373.951277 -284.448807) (xy 373.903671 -284.477861) (xy 373.852342 -284.499673) (xy 373.798385 -284.513779)
			(xy 373.742948 -284.519879) (xy 373.687214 -284.517842) (xy 373.632371 -284.507712) (xy 373.579587 -284.489705)
			(xy 373.529987 -284.464204) (xy 373.484629 -284.431753) (xy 373.44448 -284.393044) (xy 373.410394 -284.348901)
			(xy 373.383098 -284.300266) (xy 373.363175 -284.248175) (xy 373.351049 -284.193738) (xy 373.346978 -284.138116)
			(xy 367.576608 -284.138116) (xy 367.576608 -284.828742) (xy 367.576054 -284.858724) (xy 367.566678 -284.917949)
			(xy 367.548147 -284.974977) (xy 367.520919 -285.028402) (xy 367.520008 -285.029656) (xy 374.111518 -285.029656)
			(xy 374.115589 -284.974034) (xy 374.127715 -284.919597) (xy 374.147638 -284.867506) (xy 374.174934 -284.818871)
			(xy 374.20902 -284.774728) (xy 374.249169 -284.736019) (xy 374.294527 -284.703568) (xy 374.344127 -284.678067)
			(xy 374.396911 -284.66006) (xy 374.451754 -284.64993) (xy 374.507488 -284.647893) (xy 374.562925 -284.653993)
			(xy 374.616882 -284.668099) (xy 374.668211 -284.689911) (xy 374.715817 -284.718965) (xy 374.758685 -284.75464)
			(xy 374.795902 -284.796177) (xy 374.826675 -284.84269) (xy 374.850347 -284.893187) (xy 374.866415 -284.946594)
			(xy 374.874535 -285.00177) (xy 374.875044 -285.029656) (xy 375.596656 -285.029656) (xy 375.600727 -284.974034)
			(xy 375.612853 -284.919597) (xy 375.632776 -284.867506) (xy 375.660072 -284.818871) (xy 375.694158 -284.774728)
			(xy 375.734307 -284.736019) (xy 375.779665 -284.703568) (xy 375.829265 -284.678067) (xy 375.882049 -284.66006)
			(xy 375.936892 -284.64993) (xy 375.992626 -284.647893) (xy 376.048063 -284.653993) (xy 376.10202 -284.668099)
			(xy 376.153349 -284.689911) (xy 376.200955 -284.718965) (xy 376.243823 -284.75464) (xy 376.28104 -284.796177)
			(xy 376.311813 -284.84269) (xy 376.335485 -284.893187) (xy 376.351553 -284.946594) (xy 376.359673 -285.00177)
			(xy 376.360182 -285.029656) (xy 376.359673 -285.057542) (xy 376.351553 -285.112718) (xy 376.335485 -285.166125)
			(xy 376.311813 -285.216622) (xy 376.28104 -285.263135) (xy 376.243823 -285.304672) (xy 376.200955 -285.340347)
			(xy 376.153349 -285.369401) (xy 376.10202 -285.391213) (xy 376.048063 -285.405319) (xy 375.992626 -285.411419)
			(xy 375.936892 -285.409382) (xy 375.882049 -285.399252) (xy 375.829265 -285.381245) (xy 375.779665 -285.355744)
			(xy 375.734307 -285.323293) (xy 375.694158 -285.284584) (xy 375.660072 -285.240441) (xy 375.632776 -285.191806)
			(xy 375.612853 -285.139715) (xy 375.600727 -285.085278) (xy 375.596656 -285.029656) (xy 374.875044 -285.029656)
			(xy 374.874535 -285.057542) (xy 374.866415 -285.112718) (xy 374.850347 -285.166125) (xy 374.826675 -285.216622)
			(xy 374.795902 -285.263135) (xy 374.758685 -285.304672) (xy 374.715817 -285.340347) (xy 374.668211 -285.369401)
			(xy 374.616882 -285.391213) (xy 374.562925 -285.405319) (xy 374.507488 -285.411419) (xy 374.451754 -285.409382)
			(xy 374.396911 -285.399252) (xy 374.344127 -285.381245) (xy 374.294527 -285.355744) (xy 374.249169 -285.323293)
			(xy 374.20902 -285.284584) (xy 374.174934 -285.240441) (xy 374.147638 -285.191806) (xy 374.127715 -285.139715)
			(xy 374.115589 -285.085278) (xy 374.111518 -285.029656) (xy 367.520008 -285.029656) (xy 367.485665 -285.076907)
			(xy 367.464848 -285.09849) (xy 367.36909 -285.193994) (xy 367.362233 -285.201388) (xy 367.354482 -285.219987)
			(xy 367.354104 -285.230062) (xy 367.354104 -286.331914) (xy 374.111518 -286.331914) (xy 374.115589 -286.276292)
			(xy 374.127715 -286.221855) (xy 374.147638 -286.169764) (xy 374.174934 -286.121129) (xy 374.20902 -286.076986)
			(xy 374.249169 -286.038277) (xy 374.294527 -286.005826) (xy 374.344127 -285.980325) (xy 374.396911 -285.962318)
			(xy 374.451754 -285.952188) (xy 374.507488 -285.950151) (xy 374.562925 -285.956251) (xy 374.616882 -285.970357)
			(xy 374.668211 -285.992169) (xy 374.715817 -286.021223) (xy 374.758685 -286.056898) (xy 374.795902 -286.098435)
			(xy 374.826675 -286.144948) (xy 374.850347 -286.195445) (xy 374.866415 -286.248852) (xy 374.874535 -286.304028)
			(xy 374.875044 -286.331914) (xy 375.587004 -286.331914) (xy 375.591075 -286.276292) (xy 375.603201 -286.221855)
			(xy 375.623124 -286.169764) (xy 375.65042 -286.121129) (xy 375.684506 -286.076986) (xy 375.724655 -286.038277)
			(xy 375.770013 -286.005826) (xy 375.819613 -285.980325) (xy 375.872397 -285.962318) (xy 375.92724 -285.952188)
			(xy 375.982974 -285.950151) (xy 376.038411 -285.956251) (xy 376.092368 -285.970357) (xy 376.143697 -285.992169)
			(xy 376.191303 -286.021223) (xy 376.234171 -286.056898) (xy 376.271388 -286.098435) (xy 376.302161 -286.144948)
			(xy 376.325833 -286.195445) (xy 376.341901 -286.248852) (xy 376.350021 -286.304028) (xy 376.35053 -286.331914)
			(xy 376.476004 -286.331914) (xy 376.480075 -286.276292) (xy 376.492201 -286.221855) (xy 376.512124 -286.169764)
			(xy 376.53942 -286.121129) (xy 376.573506 -286.076986) (xy 376.613655 -286.038277) (xy 376.659013 -286.005826)
			(xy 376.708613 -285.980325) (xy 376.761397 -285.962318) (xy 376.81624 -285.952188) (xy 376.871974 -285.950151)
			(xy 376.927411 -285.956251) (xy 376.981368 -285.970357) (xy 377.032697 -285.992169) (xy 377.080303 -286.021223)
			(xy 377.123171 -286.056898) (xy 377.160388 -286.098435) (xy 377.191161 -286.144948) (xy 377.214833 -286.195445)
			(xy 377.230901 -286.248852) (xy 377.239021 -286.304028) (xy 377.23953 -286.331914) (xy 377.239021 -286.3598)
			(xy 377.230901 -286.414976) (xy 377.214833 -286.468383) (xy 377.191161 -286.51888) (xy 377.160388 -286.565393)
			(xy 377.123171 -286.60693) (xy 377.080303 -286.642605) (xy 377.032697 -286.671659) (xy 376.981368 -286.693471)
			(xy 376.927411 -286.707577) (xy 376.871974 -286.713677) (xy 376.81624 -286.71164) (xy 376.761397 -286.70151)
			(xy 376.708613 -286.683503) (xy 376.659013 -286.658002) (xy 376.613655 -286.625551) (xy 376.573506 -286.586842)
			(xy 376.53942 -286.542699) (xy 376.512124 -286.494064) (xy 376.492201 -286.441973) (xy 376.480075 -286.387536)
			(xy 376.476004 -286.331914) (xy 376.35053 -286.331914) (xy 376.350021 -286.3598) (xy 376.341901 -286.414976)
			(xy 376.325833 -286.468383) (xy 376.302161 -286.51888) (xy 376.271388 -286.565393) (xy 376.234171 -286.60693)
			(xy 376.191303 -286.642605) (xy 376.143697 -286.671659) (xy 376.092368 -286.693471) (xy 376.038411 -286.707577)
			(xy 375.982974 -286.713677) (xy 375.92724 -286.71164) (xy 375.872397 -286.70151) (xy 375.819613 -286.683503)
			(xy 375.770013 -286.658002) (xy 375.724655 -286.625551) (xy 375.684506 -286.586842) (xy 375.65042 -286.542699)
			(xy 375.623124 -286.494064) (xy 375.603201 -286.441973) (xy 375.591075 -286.387536) (xy 375.587004 -286.331914)
			(xy 374.875044 -286.331914) (xy 374.874535 -286.3598) (xy 374.866415 -286.414976) (xy 374.850347 -286.468383)
			(xy 374.826675 -286.51888) (xy 374.795902 -286.565393) (xy 374.758685 -286.60693) (xy 374.715817 -286.642605)
			(xy 374.668211 -286.671659) (xy 374.616882 -286.693471) (xy 374.562925 -286.707577) (xy 374.507488 -286.713677)
			(xy 374.451754 -286.71164) (xy 374.396911 -286.70151) (xy 374.344127 -286.683503) (xy 374.294527 -286.658002)
			(xy 374.249169 -286.625551) (xy 374.20902 -286.586842) (xy 374.174934 -286.542699) (xy 374.147638 -286.494064)
			(xy 374.127715 -286.441973) (xy 374.115589 -286.387536) (xy 374.111518 -286.331914) (xy 367.354104 -286.331914)
			(xy 367.354104 -288.230056) (xy 374.111518 -288.230056) (xy 374.115589 -288.174434) (xy 374.127715 -288.119997)
			(xy 374.147638 -288.067906) (xy 374.174934 -288.019271) (xy 374.20902 -287.975128) (xy 374.249169 -287.936419)
			(xy 374.294527 -287.903968) (xy 374.344127 -287.878467) (xy 374.396911 -287.86046) (xy 374.451754 -287.85033)
			(xy 374.507488 -287.848293) (xy 374.562925 -287.854393) (xy 374.616882 -287.868499) (xy 374.668211 -287.890311)
			(xy 374.715817 -287.919365) (xy 374.758685 -287.95504) (xy 374.795902 -287.996577) (xy 374.826675 -288.04309)
			(xy 374.850347 -288.093587) (xy 374.866415 -288.146994) (xy 374.874535 -288.20217) (xy 374.875044 -288.230056)
			(xy 375.596656 -288.230056) (xy 375.600727 -288.174434) (xy 375.612853 -288.119997) (xy 375.632776 -288.067906)
			(xy 375.660072 -288.019271) (xy 375.694158 -287.975128) (xy 375.734307 -287.936419) (xy 375.779665 -287.903968)
			(xy 375.829265 -287.878467) (xy 375.882049 -287.86046) (xy 375.936892 -287.85033) (xy 375.992626 -287.848293)
			(xy 376.048063 -287.854393) (xy 376.10202 -287.868499) (xy 376.153349 -287.890311) (xy 376.200955 -287.919365)
			(xy 376.243823 -287.95504) (xy 376.28104 -287.996577) (xy 376.311813 -288.04309) (xy 376.335485 -288.093587)
			(xy 376.351553 -288.146994) (xy 376.359673 -288.20217) (xy 376.360182 -288.230056) (xy 376.359673 -288.257942)
			(xy 376.351553 -288.313118) (xy 376.335485 -288.366525) (xy 376.311813 -288.417022) (xy 376.28104 -288.463535)
			(xy 376.243823 -288.505072) (xy 376.200955 -288.540747) (xy 376.153349 -288.569801) (xy 376.10202 -288.591613)
			(xy 376.048063 -288.605719) (xy 375.992626 -288.611819) (xy 375.936892 -288.609782) (xy 375.882049 -288.599652)
			(xy 375.829265 -288.581645) (xy 375.779665 -288.556144) (xy 375.734307 -288.523693) (xy 375.694158 -288.484984)
			(xy 375.660072 -288.440841) (xy 375.632776 -288.392206) (xy 375.612853 -288.340115) (xy 375.600727 -288.285678)
			(xy 375.596656 -288.230056) (xy 374.875044 -288.230056) (xy 374.874535 -288.257942) (xy 374.866415 -288.313118)
			(xy 374.850347 -288.366525) (xy 374.826675 -288.417022) (xy 374.795902 -288.463535) (xy 374.758685 -288.505072)
			(xy 374.715817 -288.540747) (xy 374.668211 -288.569801) (xy 374.616882 -288.591613) (xy 374.562925 -288.605719)
			(xy 374.507488 -288.611819) (xy 374.451754 -288.609782) (xy 374.396911 -288.599652) (xy 374.344127 -288.581645)
			(xy 374.294527 -288.556144) (xy 374.249169 -288.523693) (xy 374.20902 -288.484984) (xy 374.174934 -288.440841)
			(xy 374.147638 -288.392206) (xy 374.127715 -288.340115) (xy 374.115589 -288.285678) (xy 374.111518 -288.230056)
			(xy 367.354104 -288.230056) (xy 367.354104 -289.532314) (xy 374.111518 -289.532314) (xy 374.115589 -289.476692)
			(xy 374.127715 -289.422255) (xy 374.147638 -289.370164) (xy 374.174934 -289.321529) (xy 374.20902 -289.277386)
			(xy 374.249169 -289.238677) (xy 374.294527 -289.206226) (xy 374.344127 -289.180725) (xy 374.396911 -289.162718)
			(xy 374.451754 -289.152588) (xy 374.507488 -289.150551) (xy 374.562925 -289.156651) (xy 374.616882 -289.170757)
			(xy 374.668211 -289.192569) (xy 374.715817 -289.221623) (xy 374.758685 -289.257298) (xy 374.795902 -289.298835)
			(xy 374.826675 -289.345348) (xy 374.850347 -289.395845) (xy 374.866415 -289.449252) (xy 374.874535 -289.504428)
			(xy 374.875044 -289.532314) (xy 375.587004 -289.532314) (xy 375.591075 -289.476692) (xy 375.603201 -289.422255)
			(xy 375.623124 -289.370164) (xy 375.65042 -289.321529) (xy 375.684506 -289.277386) (xy 375.724655 -289.238677)
			(xy 375.770013 -289.206226) (xy 375.819613 -289.180725) (xy 375.872397 -289.162718) (xy 375.92724 -289.152588)
			(xy 375.982974 -289.150551) (xy 376.038411 -289.156651) (xy 376.092368 -289.170757) (xy 376.143697 -289.192569)
			(xy 376.191303 -289.221623) (xy 376.234171 -289.257298) (xy 376.271388 -289.298835) (xy 376.302161 -289.345348)
			(xy 376.325833 -289.395845) (xy 376.341901 -289.449252) (xy 376.350021 -289.504428) (xy 376.35053 -289.532314)
			(xy 376.476004 -289.532314) (xy 376.480075 -289.476692) (xy 376.492201 -289.422255) (xy 376.512124 -289.370164)
			(xy 376.53942 -289.321529) (xy 376.573506 -289.277386) (xy 376.613655 -289.238677) (xy 376.659013 -289.206226)
			(xy 376.708613 -289.180725) (xy 376.761397 -289.162718) (xy 376.81624 -289.152588) (xy 376.871974 -289.150551)
			(xy 376.927411 -289.156651) (xy 376.981368 -289.170757) (xy 377.032697 -289.192569) (xy 377.080303 -289.221623)
			(xy 377.123171 -289.257298) (xy 377.160388 -289.298835) (xy 377.191161 -289.345348) (xy 377.214833 -289.395845)
			(xy 377.230901 -289.449252) (xy 377.239021 -289.504428) (xy 377.23953 -289.532314) (xy 377.239021 -289.5602)
			(xy 377.230901 -289.615376) (xy 377.214833 -289.668783) (xy 377.191161 -289.71928) (xy 377.160388 -289.765793)
			(xy 377.123171 -289.80733) (xy 377.080303 -289.843005) (xy 377.032697 -289.872059) (xy 376.981368 -289.893871)
			(xy 376.927411 -289.907977) (xy 376.871974 -289.914077) (xy 376.81624 -289.91204) (xy 376.761397 -289.90191)
			(xy 376.708613 -289.883903) (xy 376.659013 -289.858402) (xy 376.613655 -289.825951) (xy 376.573506 -289.787242)
			(xy 376.53942 -289.743099) (xy 376.512124 -289.694464) (xy 376.492201 -289.642373) (xy 376.480075 -289.587936)
			(xy 376.476004 -289.532314) (xy 376.35053 -289.532314) (xy 376.350021 -289.5602) (xy 376.341901 -289.615376)
			(xy 376.325833 -289.668783) (xy 376.302161 -289.71928) (xy 376.271388 -289.765793) (xy 376.234171 -289.80733)
			(xy 376.191303 -289.843005) (xy 376.143697 -289.872059) (xy 376.092368 -289.893871) (xy 376.038411 -289.907977)
			(xy 375.982974 -289.914077) (xy 375.92724 -289.91204) (xy 375.872397 -289.90191) (xy 375.819613 -289.883903)
			(xy 375.770013 -289.858402) (xy 375.724655 -289.825951) (xy 375.684506 -289.787242) (xy 375.65042 -289.743099)
			(xy 375.623124 -289.694464) (xy 375.603201 -289.642373) (xy 375.591075 -289.587936) (xy 375.587004 -289.532314)
			(xy 374.875044 -289.532314) (xy 374.874535 -289.5602) (xy 374.866415 -289.615376) (xy 374.850347 -289.668783)
			(xy 374.826675 -289.71928) (xy 374.795902 -289.765793) (xy 374.758685 -289.80733) (xy 374.715817 -289.843005)
			(xy 374.668211 -289.872059) (xy 374.616882 -289.893871) (xy 374.562925 -289.907977) (xy 374.507488 -289.914077)
			(xy 374.451754 -289.91204) (xy 374.396911 -289.90191) (xy 374.344127 -289.883903) (xy 374.294527 -289.858402)
			(xy 374.249169 -289.825951) (xy 374.20902 -289.787242) (xy 374.174934 -289.743099) (xy 374.147638 -289.694464)
			(xy 374.127715 -289.642373) (xy 374.115589 -289.587936) (xy 374.111518 -289.532314) (xy 367.354104 -289.532314)
			(xy 367.354104 -291.430456) (xy 374.111518 -291.430456) (xy 374.115589 -291.374834) (xy 374.127715 -291.320397)
			(xy 374.147638 -291.268306) (xy 374.174934 -291.219671) (xy 374.20902 -291.175528) (xy 374.249169 -291.136819)
			(xy 374.294527 -291.104368) (xy 374.344127 -291.078867) (xy 374.396911 -291.06086) (xy 374.451754 -291.05073)
			(xy 374.507488 -291.048693) (xy 374.562925 -291.054793) (xy 374.616882 -291.068899) (xy 374.668211 -291.090711)
			(xy 374.715817 -291.119765) (xy 374.758685 -291.15544) (xy 374.795902 -291.196977) (xy 374.826675 -291.24349)
			(xy 374.850347 -291.293987) (xy 374.866415 -291.347394) (xy 374.874535 -291.40257) (xy 374.875044 -291.430456)
			(xy 375.596656 -291.430456) (xy 375.600727 -291.374834) (xy 375.612853 -291.320397) (xy 375.632776 -291.268306)
			(xy 375.660072 -291.219671) (xy 375.694158 -291.175528) (xy 375.734307 -291.136819) (xy 375.779665 -291.104368)
			(xy 375.829265 -291.078867) (xy 375.882049 -291.06086) (xy 375.936892 -291.05073) (xy 375.992626 -291.048693)
			(xy 376.048063 -291.054793) (xy 376.10202 -291.068899) (xy 376.153349 -291.090711) (xy 376.200955 -291.119765)
			(xy 376.243823 -291.15544) (xy 376.28104 -291.196977) (xy 376.311813 -291.24349) (xy 376.335485 -291.293987)
			(xy 376.351553 -291.347394) (xy 376.359673 -291.40257) (xy 376.360182 -291.430456) (xy 376.359673 -291.458342)
			(xy 376.351553 -291.513518) (xy 376.335485 -291.566925) (xy 376.311813 -291.617422) (xy 376.28104 -291.663935)
			(xy 376.243823 -291.705472) (xy 376.200955 -291.741147) (xy 376.153349 -291.770201) (xy 376.10202 -291.792013)
			(xy 376.048063 -291.806119) (xy 375.992626 -291.812219) (xy 375.936892 -291.810182) (xy 375.882049 -291.800052)
			(xy 375.829265 -291.782045) (xy 375.779665 -291.756544) (xy 375.734307 -291.724093) (xy 375.694158 -291.685384)
			(xy 375.660072 -291.641241) (xy 375.632776 -291.592606) (xy 375.612853 -291.540515) (xy 375.600727 -291.486078)
			(xy 375.596656 -291.430456) (xy 374.875044 -291.430456) (xy 374.874535 -291.458342) (xy 374.866415 -291.513518)
			(xy 374.850347 -291.566925) (xy 374.826675 -291.617422) (xy 374.795902 -291.663935) (xy 374.758685 -291.705472)
			(xy 374.715817 -291.741147) (xy 374.668211 -291.770201) (xy 374.616882 -291.792013) (xy 374.562925 -291.806119)
			(xy 374.507488 -291.812219) (xy 374.451754 -291.810182) (xy 374.396911 -291.800052) (xy 374.344127 -291.782045)
			(xy 374.294527 -291.756544) (xy 374.249169 -291.724093) (xy 374.20902 -291.685384) (xy 374.174934 -291.641241)
			(xy 374.147638 -291.592606) (xy 374.127715 -291.540515) (xy 374.115589 -291.486078) (xy 374.111518 -291.430456)
			(xy 367.354104 -291.430456) (xy 367.354104 -292.732714) (xy 374.111518 -292.732714) (xy 374.115589 -292.677092)
			(xy 374.127715 -292.622655) (xy 374.147638 -292.570564) (xy 374.174934 -292.521929) (xy 374.20902 -292.477786)
			(xy 374.249169 -292.439077) (xy 374.294527 -292.406626) (xy 374.344127 -292.381125) (xy 374.396911 -292.363118)
			(xy 374.451754 -292.352988) (xy 374.507488 -292.350951) (xy 374.562925 -292.357051) (xy 374.616882 -292.371157)
			(xy 374.668211 -292.392969) (xy 374.715817 -292.422023) (xy 374.758685 -292.457698) (xy 374.795902 -292.499235)
			(xy 374.826675 -292.545748) (xy 374.850347 -292.596245) (xy 374.866415 -292.649652) (xy 374.874535 -292.704828)
			(xy 374.875044 -292.732714) (xy 375.587004 -292.732714) (xy 375.591075 -292.677092) (xy 375.603201 -292.622655)
			(xy 375.623124 -292.570564) (xy 375.65042 -292.521929) (xy 375.684506 -292.477786) (xy 375.724655 -292.439077)
			(xy 375.770013 -292.406626) (xy 375.819613 -292.381125) (xy 375.872397 -292.363118) (xy 375.92724 -292.352988)
			(xy 375.982974 -292.350951) (xy 376.038411 -292.357051) (xy 376.092368 -292.371157) (xy 376.143697 -292.392969)
			(xy 376.191303 -292.422023) (xy 376.234171 -292.457698) (xy 376.271388 -292.499235) (xy 376.302161 -292.545748)
			(xy 376.325833 -292.596245) (xy 376.341901 -292.649652) (xy 376.350021 -292.704828) (xy 376.35053 -292.732714)
			(xy 376.476004 -292.732714) (xy 376.480075 -292.677092) (xy 376.492201 -292.622655) (xy 376.512124 -292.570564)
			(xy 376.53942 -292.521929) (xy 376.573506 -292.477786) (xy 376.613655 -292.439077) (xy 376.659013 -292.406626)
			(xy 376.708613 -292.381125) (xy 376.761397 -292.363118) (xy 376.81624 -292.352988) (xy 376.871974 -292.350951)
			(xy 376.927411 -292.357051) (xy 376.981368 -292.371157) (xy 377.032697 -292.392969) (xy 377.080303 -292.422023)
			(xy 377.123171 -292.457698) (xy 377.160388 -292.499235) (xy 377.191161 -292.545748) (xy 377.214833 -292.596245)
			(xy 377.230901 -292.649652) (xy 377.239021 -292.704828) (xy 377.23953 -292.732714) (xy 377.239021 -292.7606)
			(xy 377.230901 -292.815776) (xy 377.214833 -292.869183) (xy 377.191161 -292.91968) (xy 377.160388 -292.966193)
			(xy 377.123171 -293.00773) (xy 377.080303 -293.043405) (xy 377.032697 -293.072459) (xy 376.981368 -293.094271)
			(xy 376.927411 -293.108377) (xy 376.871974 -293.114477) (xy 376.81624 -293.11244) (xy 376.761397 -293.10231)
			(xy 376.708613 -293.084303) (xy 376.659013 -293.058802) (xy 376.613655 -293.026351) (xy 376.573506 -292.987642)
			(xy 376.53942 -292.943499) (xy 376.512124 -292.894864) (xy 376.492201 -292.842773) (xy 376.480075 -292.788336)
			(xy 376.476004 -292.732714) (xy 376.35053 -292.732714) (xy 376.350021 -292.7606) (xy 376.341901 -292.815776)
			(xy 376.325833 -292.869183) (xy 376.302161 -292.91968) (xy 376.271388 -292.966193) (xy 376.234171 -293.00773)
			(xy 376.191303 -293.043405) (xy 376.143697 -293.072459) (xy 376.092368 -293.094271) (xy 376.038411 -293.108377)
			(xy 375.982974 -293.114477) (xy 375.92724 -293.11244) (xy 375.872397 -293.10231) (xy 375.819613 -293.084303)
			(xy 375.770013 -293.058802) (xy 375.724655 -293.026351) (xy 375.684506 -292.987642) (xy 375.65042 -292.943499)
			(xy 375.623124 -292.894864) (xy 375.603201 -292.842773) (xy 375.591075 -292.788336) (xy 375.587004 -292.732714)
			(xy 374.875044 -292.732714) (xy 374.874535 -292.7606) (xy 374.866415 -292.815776) (xy 374.850347 -292.869183)
			(xy 374.826675 -292.91968) (xy 374.795902 -292.966193) (xy 374.758685 -293.00773) (xy 374.715817 -293.043405)
			(xy 374.668211 -293.072459) (xy 374.616882 -293.094271) (xy 374.562925 -293.108377) (xy 374.507488 -293.114477)
			(xy 374.451754 -293.11244) (xy 374.396911 -293.10231) (xy 374.344127 -293.084303) (xy 374.294527 -293.058802)
			(xy 374.249169 -293.026351) (xy 374.20902 -292.987642) (xy 374.174934 -292.943499) (xy 374.147638 -292.894864)
			(xy 374.127715 -292.842773) (xy 374.115589 -292.788336) (xy 374.111518 -292.732714) (xy 367.354104 -292.732714)
			(xy 367.354104 -294.630856) (xy 374.111518 -294.630856) (xy 374.115589 -294.575234) (xy 374.127715 -294.520797)
			(xy 374.147638 -294.468706) (xy 374.174934 -294.420071) (xy 374.20902 -294.375928) (xy 374.249169 -294.337219)
			(xy 374.294527 -294.304768) (xy 374.344127 -294.279267) (xy 374.396911 -294.26126) (xy 374.451754 -294.25113)
			(xy 374.507488 -294.249093) (xy 374.562925 -294.255193) (xy 374.616882 -294.269299) (xy 374.668211 -294.291111)
			(xy 374.715817 -294.320165) (xy 374.758685 -294.35584) (xy 374.795902 -294.397377) (xy 374.826675 -294.44389)
			(xy 374.850347 -294.494387) (xy 374.866415 -294.547794) (xy 374.874535 -294.60297) (xy 374.875044 -294.630856)
			(xy 375.596656 -294.630856) (xy 375.600727 -294.575234) (xy 375.612853 -294.520797) (xy 375.632776 -294.468706)
			(xy 375.660072 -294.420071) (xy 375.694158 -294.375928) (xy 375.734307 -294.337219) (xy 375.779665 -294.304768)
			(xy 375.829265 -294.279267) (xy 375.882049 -294.26126) (xy 375.936892 -294.25113) (xy 375.992626 -294.249093)
			(xy 376.048063 -294.255193) (xy 376.10202 -294.269299) (xy 376.153349 -294.291111) (xy 376.200955 -294.320165)
			(xy 376.243823 -294.35584) (xy 376.28104 -294.397377) (xy 376.311813 -294.44389) (xy 376.335485 -294.494387)
			(xy 376.351553 -294.547794) (xy 376.359673 -294.60297) (xy 376.360182 -294.630856) (xy 376.359673 -294.658742)
			(xy 376.351553 -294.713918) (xy 376.335485 -294.767325) (xy 376.311813 -294.817822) (xy 376.28104 -294.864335)
			(xy 376.243823 -294.905872) (xy 376.200955 -294.941547) (xy 376.153349 -294.970601) (xy 376.10202 -294.992413)
			(xy 376.048063 -295.006519) (xy 375.992626 -295.012619) (xy 375.936892 -295.010582) (xy 375.882049 -295.000452)
			(xy 375.829265 -294.982445) (xy 375.779665 -294.956944) (xy 375.734307 -294.924493) (xy 375.694158 -294.885784)
			(xy 375.660072 -294.841641) (xy 375.632776 -294.793006) (xy 375.612853 -294.740915) (xy 375.600727 -294.686478)
			(xy 375.596656 -294.630856) (xy 374.875044 -294.630856) (xy 374.874535 -294.658742) (xy 374.866415 -294.713918)
			(xy 374.850347 -294.767325) (xy 374.826675 -294.817822) (xy 374.795902 -294.864335) (xy 374.758685 -294.905872)
			(xy 374.715817 -294.941547) (xy 374.668211 -294.970601) (xy 374.616882 -294.992413) (xy 374.562925 -295.006519)
			(xy 374.507488 -295.012619) (xy 374.451754 -295.010582) (xy 374.396911 -295.000452) (xy 374.344127 -294.982445)
			(xy 374.294527 -294.956944) (xy 374.249169 -294.924493) (xy 374.20902 -294.885784) (xy 374.174934 -294.841641)
			(xy 374.147638 -294.793006) (xy 374.127715 -294.740915) (xy 374.115589 -294.686478) (xy 374.111518 -294.630856)
			(xy 367.354104 -294.630856) (xy 367.354104 -295.933114) (xy 374.111518 -295.933114) (xy 374.115589 -295.877492)
			(xy 374.127715 -295.823055) (xy 374.147638 -295.770964) (xy 374.174934 -295.722329) (xy 374.20902 -295.678186)
			(xy 374.249169 -295.639477) (xy 374.294527 -295.607026) (xy 374.344127 -295.581525) (xy 374.396911 -295.563518)
			(xy 374.451754 -295.553388) (xy 374.507488 -295.551351) (xy 374.562925 -295.557451) (xy 374.616882 -295.571557)
			(xy 374.668211 -295.593369) (xy 374.715817 -295.622423) (xy 374.758685 -295.658098) (xy 374.795902 -295.699635)
			(xy 374.826675 -295.746148) (xy 374.850347 -295.796645) (xy 374.866415 -295.850052) (xy 374.874535 -295.905228)
			(xy 374.875044 -295.933114) (xy 375.587004 -295.933114) (xy 375.591075 -295.877492) (xy 375.603201 -295.823055)
			(xy 375.623124 -295.770964) (xy 375.65042 -295.722329) (xy 375.684506 -295.678186) (xy 375.724655 -295.639477)
			(xy 375.770013 -295.607026) (xy 375.819613 -295.581525) (xy 375.872397 -295.563518) (xy 375.92724 -295.553388)
			(xy 375.982974 -295.551351) (xy 376.038411 -295.557451) (xy 376.092368 -295.571557) (xy 376.143697 -295.593369)
			(xy 376.191303 -295.622423) (xy 376.234171 -295.658098) (xy 376.271388 -295.699635) (xy 376.302161 -295.746148)
			(xy 376.325833 -295.796645) (xy 376.341901 -295.850052) (xy 376.350021 -295.905228) (xy 376.35053 -295.933114)
			(xy 376.350021 -295.961) (xy 376.341901 -296.016176) (xy 376.325833 -296.069583) (xy 376.302161 -296.12008)
			(xy 376.271388 -296.166593) (xy 376.234171 -296.20813) (xy 376.191303 -296.243805) (xy 376.143697 -296.272859)
			(xy 376.092368 -296.294671) (xy 376.038411 -296.308777) (xy 375.982974 -296.314877) (xy 375.92724 -296.31284)
			(xy 375.872397 -296.30271) (xy 375.819613 -296.284703) (xy 375.770013 -296.259202) (xy 375.724655 -296.226751)
			(xy 375.684506 -296.188042) (xy 375.65042 -296.143899) (xy 375.623124 -296.095264) (xy 375.603201 -296.043173)
			(xy 375.591075 -295.988736) (xy 375.587004 -295.933114) (xy 374.875044 -295.933114) (xy 374.874535 -295.961)
			(xy 374.866415 -296.016176) (xy 374.850347 -296.069583) (xy 374.826675 -296.12008) (xy 374.795902 -296.166593)
			(xy 374.758685 -296.20813) (xy 374.715817 -296.243805) (xy 374.668211 -296.272859) (xy 374.616882 -296.294671)
			(xy 374.562925 -296.308777) (xy 374.507488 -296.314877) (xy 374.451754 -296.31284) (xy 374.396911 -296.30271)
			(xy 374.344127 -296.284703) (xy 374.294527 -296.259202) (xy 374.249169 -296.226751) (xy 374.20902 -296.188042)
			(xy 374.174934 -296.143899) (xy 374.147638 -296.095264) (xy 374.127715 -296.043173) (xy 374.115589 -295.988736)
			(xy 374.111518 -295.933114) (xy 367.354104 -295.933114) (xy 367.354104 -297.831256) (xy 374.111518 -297.831256)
			(xy 374.115589 -297.775634) (xy 374.127715 -297.721197) (xy 374.147638 -297.669106) (xy 374.174934 -297.620471)
			(xy 374.20902 -297.576328) (xy 374.249169 -297.537619) (xy 374.294527 -297.505168) (xy 374.344127 -297.479667)
			(xy 374.396911 -297.46166) (xy 374.451754 -297.45153) (xy 374.507488 -297.449493) (xy 374.562925 -297.455593)
			(xy 374.616882 -297.469699) (xy 374.668211 -297.491511) (xy 374.715817 -297.520565) (xy 374.758685 -297.55624)
			(xy 374.795902 -297.597777) (xy 374.826675 -297.64429) (xy 374.850347 -297.694787) (xy 374.866415 -297.748194)
			(xy 374.874535 -297.80337) (xy 374.875044 -297.831256) (xy 375.596656 -297.831256) (xy 375.600727 -297.775634)
			(xy 375.612853 -297.721197) (xy 375.632776 -297.669106) (xy 375.660072 -297.620471) (xy 375.694158 -297.576328)
			(xy 375.734307 -297.537619) (xy 375.779665 -297.505168) (xy 375.829265 -297.479667) (xy 375.882049 -297.46166)
			(xy 375.936892 -297.45153) (xy 375.992626 -297.449493) (xy 376.048063 -297.455593) (xy 376.10202 -297.469699)
			(xy 376.153349 -297.491511) (xy 376.200955 -297.520565) (xy 376.243823 -297.55624) (xy 376.28104 -297.597777)
			(xy 376.311813 -297.64429) (xy 376.335485 -297.694787) (xy 376.351553 -297.748194) (xy 376.359673 -297.80337)
			(xy 376.360182 -297.831256) (xy 376.359673 -297.859142) (xy 376.351553 -297.914318) (xy 376.335485 -297.967725)
			(xy 376.311813 -298.018222) (xy 376.28104 -298.064735) (xy 376.243823 -298.106272) (xy 376.200955 -298.141947)
			(xy 376.153349 -298.171001) (xy 376.10202 -298.192813) (xy 376.048063 -298.206919) (xy 375.992626 -298.213019)
			(xy 375.936892 -298.210982) (xy 375.882049 -298.200852) (xy 375.829265 -298.182845) (xy 375.779665 -298.157344)
			(xy 375.734307 -298.124893) (xy 375.694158 -298.086184) (xy 375.660072 -298.042041) (xy 375.632776 -297.993406)
			(xy 375.612853 -297.941315) (xy 375.600727 -297.886878) (xy 375.596656 -297.831256) (xy 374.875044 -297.831256)
			(xy 374.874535 -297.859142) (xy 374.866415 -297.914318) (xy 374.850347 -297.967725) (xy 374.826675 -298.018222)
			(xy 374.795902 -298.064735) (xy 374.758685 -298.106272) (xy 374.715817 -298.141947) (xy 374.668211 -298.171001)
			(xy 374.616882 -298.192813) (xy 374.562925 -298.206919) (xy 374.507488 -298.213019) (xy 374.451754 -298.210982)
			(xy 374.396911 -298.200852) (xy 374.344127 -298.182845) (xy 374.294527 -298.157344) (xy 374.249169 -298.124893)
			(xy 374.20902 -298.086184) (xy 374.174934 -298.042041) (xy 374.147638 -297.993406) (xy 374.127715 -297.941315)
			(xy 374.115589 -297.886878) (xy 374.111518 -297.831256) (xy 367.354104 -297.831256) (xy 367.354104 -299.133514)
			(xy 374.111518 -299.133514) (xy 374.115589 -299.077892) (xy 374.127715 -299.023455) (xy 374.147638 -298.971364)
			(xy 374.174934 -298.922729) (xy 374.20902 -298.878586) (xy 374.249169 -298.839877) (xy 374.294527 -298.807426)
			(xy 374.344127 -298.781925) (xy 374.396911 -298.763918) (xy 374.451754 -298.753788) (xy 374.507488 -298.751751)
			(xy 374.562925 -298.757851) (xy 374.616882 -298.771957) (xy 374.668211 -298.793769) (xy 374.715817 -298.822823)
			(xy 374.758685 -298.858498) (xy 374.795902 -298.900035) (xy 374.826675 -298.946548) (xy 374.850347 -298.997045)
			(xy 374.866415 -299.050452) (xy 374.874535 -299.105628) (xy 374.875044 -299.133514) (xy 375.587004 -299.133514)
			(xy 375.591075 -299.077892) (xy 375.603201 -299.023455) (xy 375.623124 -298.971364) (xy 375.65042 -298.922729)
			(xy 375.684506 -298.878586) (xy 375.724655 -298.839877) (xy 375.770013 -298.807426) (xy 375.819613 -298.781925)
			(xy 375.872397 -298.763918) (xy 375.92724 -298.753788) (xy 375.982974 -298.751751) (xy 376.038411 -298.757851)
			(xy 376.092368 -298.771957) (xy 376.143697 -298.793769) (xy 376.191303 -298.822823) (xy 376.234171 -298.858498)
			(xy 376.271388 -298.900035) (xy 376.302161 -298.946548) (xy 376.325833 -298.997045) (xy 376.341901 -299.050452)
			(xy 376.350021 -299.105628) (xy 376.35053 -299.133511) (xy 376.475889 -299.133511) (xy 376.480257 -299.075886)
			(xy 376.493266 -299.01958) (xy 376.514617 -298.965879) (xy 376.543822 -298.916012) (xy 376.561604 -298.89323)
			(xy 376.568228 -298.884218) (xy 376.573593 -298.862528) (xy 376.569267 -298.840606) (xy 376.563128 -298.831254)
			(xy 376.544332 -298.802044) (xy 376.532369 -298.780157) (xy 376.514965 -298.733417) (xy 376.505418 -298.684463)
			(xy 376.5042 -298.65955) (xy 376.5042 -296.55516) (xy 376.505405 -296.529145) (xy 376.51557 -296.478071)
			(xy 376.534251 -296.429462) (xy 376.547126 -296.406824) (xy 376.555564 -296.393126) (xy 376.574911 -296.367419)
			(xy 376.585734 -296.355516) (xy 376.616976 -296.32402) (xy 376.629676 -296.31132) (xy 376.636547 -296.303998)
			(xy 376.644285 -296.28548) (xy 376.644343 -296.26541) (xy 376.636711 -296.246847) (xy 376.62993 -296.239438)
			(xy 376.627644 -296.237152) (xy 376.62485 -296.23512) (xy 376.60218 -296.216943) (xy 376.562116 -296.174859)
			(xy 376.528894 -296.127189) (xy 376.503281 -296.075034) (xy 376.485868 -296.0196) (xy 376.477059 -295.962166)
			(xy 376.476514 -295.933114) (xy 376.476968 -295.90586) (xy 376.484724 -295.851908) (xy 376.500079 -295.799609)
			(xy 376.522722 -295.750027) (xy 376.55219 -295.704173) (xy 376.587885 -295.66298) (xy 376.629079 -295.627286)
			(xy 376.674934 -295.597818) (xy 376.724516 -295.575177) (xy 376.776816 -295.559822) (xy 376.830768 -295.552068)
			(xy 376.858022 -295.551606) (xy 376.885827 -295.552161) (xy 376.940847 -295.560251) (xy 376.994108 -295.576243)
			(xy 377.044485 -295.599798) (xy 377.090908 -295.630416) (xy 377.132394 -295.667449) (xy 377.168066 -295.710112)
			(xy 377.197165 -295.757501) (xy 377.219077 -295.808613) (xy 377.233338 -295.862365) (xy 377.23699 -295.889934)
			(xy 377.23699 -295.890188) (xy 377.23853 -295.899313) (xy 377.247153 -295.915671) (xy 377.261003 -295.927923)
			(xy 377.278291 -295.934484) (xy 377.287536 -295.934892) (xy 379.601476 -295.934892) (xy 379.610735 -295.934511)
			(xy 379.628063 -295.927993) (xy 379.641933 -295.915731) (xy 379.650525 -295.899332) (xy 379.652022 -295.890188)
			(xy 379.652022 -295.889934) (xy 379.655819 -295.86134) (xy 379.670884 -295.805661) (xy 379.694169 -295.75289)
			(xy 379.72514 -295.70423) (xy 379.743716 -295.682162) (xy 379.749609 -295.674789) (xy 379.756016 -295.657054)
			(xy 379.756162 -295.647618) (xy 379.755146 -295.596056) (xy 379.749812 -295.590976) (xy 379.582172 -295.423336)
			(xy 379.565579 -295.406038) (xy 379.537411 -295.36726) (xy 379.515641 -295.32456) (xy 379.500803 -295.278986)
			(xy 379.493262 -295.231654) (xy 379.492764 -295.20769) (xy 379.492764 -293.1795) (xy 379.493301 -293.153823)
			(xy 379.501923 -293.103196) (xy 379.518907 -293.054731) (xy 379.543771 -293.009796) (xy 379.575814 -292.969664)
			(xy 379.594618 -292.95217) (xy 379.663706 -292.890448) (xy 379.67158 -292.861492) (xy 379.667008 -292.847268)
			(xy 379.658807 -292.819343) (xy 379.650009 -292.761814) (xy 379.649482 -292.732714) (xy 379.649725 -292.712235)
			(xy 379.654047 -292.671506) (xy 379.658118 -292.651434) (xy 379.659807 -292.641911) (xy 379.656653 -292.622842)
			(xy 379.652022 -292.61435) (xy 379.611128 -292.546278) (xy 379.595634 -292.534594) (xy 379.58649 -292.532054)
			(xy 379.561497 -292.524493) (xy 379.514356 -292.502045) (xy 379.471714 -292.471915) (xy 379.452886 -292.453822)
			(xy 379.384306 -292.385242) (xy 379.367611 -292.367988) (xy 379.33936 -292.329169) (xy 379.31753 -292.286409)
			(xy 379.302657 -292.24076) (xy 379.295109 -292.193347) (xy 379.294644 -292.169342) (xy 379.294644 -289.830256)
			(xy 379.295106 -289.806605) (xy 379.302449 -289.759875) (xy 379.316905 -289.714834) (xy 379.338129 -289.67256)
			(xy 379.365615 -289.634061) (xy 379.398705 -289.600258) (xy 379.436609 -289.571958) (xy 379.478421 -289.549837)
			(xy 379.500638 -289.541712) (xy 379.635766 -289.49523) (xy 379.653546 -289.474656) (xy 379.656086 -289.461194)
			(xy 379.661008 -289.437395) (xy 379.676077 -289.391192) (xy 379.69688 -289.34727) (xy 379.723083 -289.30634)
			(xy 379.738382 -289.287458) (xy 379.743979 -289.280248) (xy 379.750085 -289.263056) (xy 379.75032 -289.25393)
			(xy 379.749558 -289.223704) (xy 379.748995 -289.21393) (xy 379.741408 -289.1959) (xy 379.734826 -289.188652)
			(xy 379.45187 -288.905696) (xy 379.445031 -288.898295) (xy 379.437312 -288.879696) (xy 379.436884 -288.869628)
			(xy 379.436884 -286.741362) (xy 379.437267 -286.731288) (xy 379.445015 -286.712689) (xy 379.45187 -286.705294)
			(xy 379.665738 -286.491172) (xy 379.672342 -286.463232) (xy 379.668024 -286.44977) (xy 379.659399 -286.421267)
			(xy 379.650092 -286.36245) (xy 379.649482 -286.332676) (xy 379.649482 -286.331914) (xy 379.649896 -286.306914)
			(xy 379.656435 -286.257343) (xy 379.669391 -286.20905) (xy 379.688542 -286.162862) (xy 379.713559 -286.11957)
			(xy 379.728476 -286.099504) (xy 379.72873 -286.09925) (xy 379.73395 -286.091701) (xy 379.73925 -286.074149)
			(xy 379.738011 -286.055857) (xy 379.730391 -286.039181) (xy 379.724158 -286.032448) (xy 379.660658 -285.968948)
			(xy 379.486922 -285.795466) (xy 379.480077 -285.788069) (xy 379.472359 -285.769468) (xy 379.471936 -285.759398)
			(xy 379.471936 -283.627068) (xy 379.472335 -283.616996) (xy 379.480073 -283.598398) (xy 379.486922 -283.591)
			(xy 379.705616 -283.372306) (xy 379.709934 -283.33827) (xy 379.701298 -283.323284) (xy 379.689007 -283.301362)
			(xy 379.669646 -283.254982) (xy 379.656535 -283.206463) (xy 379.649902 -283.156643) (xy 379.649482 -283.131514)
			(xy 379.649968 -283.104262) (xy 379.657723 -283.050312) (xy 379.673077 -282.998016) (xy 379.695717 -282.948436)
			(xy 379.725183 -282.902583) (xy 379.760874 -282.861391) (xy 379.802064 -282.825697) (xy 379.847915 -282.796229)
			(xy 379.897493 -282.773585) (xy 379.949789 -282.758228) (xy 380.003738 -282.75047) (xy 380.03099 -282.750006)
			(xy 380.057814 -282.750497) (xy 380.11093 -282.758032) (xy 380.162469 -282.772927) (xy 380.211416 -282.794889)
			(xy 380.256807 -282.823486) (xy 380.297748 -282.858154) (xy 380.333435 -282.898211) (xy 380.363164 -282.942869)
			(xy 380.386349 -282.991248) (xy 380.402536 -283.042396) (xy 380.407418 -283.068776) (xy 380.410466 -283.087318)
			(xy 380.43866 -283.111448) (xy 384.319018 -283.111448) (xy 384.328783 -283.111031) (xy 384.346905 -283.103756)
			(xy 384.360991 -283.090231) (xy 384.368996 -283.072419) (xy 384.369818 -283.06268) (xy 384.37127 -283.038105)
			(xy 384.381102 -282.989869) (xy 384.398546 -282.943836) (xy 384.42315 -282.901199) (xy 384.454277 -282.863061)
			(xy 384.491119 -282.830412) (xy 384.532722 -282.804096) (xy 384.578008 -282.784797) (xy 384.625804 -282.773013)
			(xy 384.674872 -282.769051) (xy 384.72394 -282.773013) (xy 384.771736 -282.784797) (xy 384.817022 -282.804096)
			(xy 384.858625 -282.830412) (xy 384.895467 -282.863061) (xy 384.926594 -282.901199) (xy 384.951198 -282.943836)
			(xy 384.968642 -282.989869) (xy 384.978474 -283.038105) (xy 384.979926 -283.06268) (xy 384.980829 -283.072402)
			(xy 384.988834 -283.090184) (xy 385.002892 -283.103699) (xy 385.020976 -283.110997) (xy 385.030726 -283.111448)
			(xy 385.268978 -283.111448) (xy 385.278747 -283.11108) (xy 385.296871 -283.103786) (xy 385.310955 -283.090246)
			(xy 385.318957 -283.072424) (xy 385.319778 -283.06268) (xy 385.32123 -283.038105) (xy 385.331062 -282.989869)
			(xy 385.348506 -282.943836) (xy 385.37311 -282.901199) (xy 385.404237 -282.863061) (xy 385.441079 -282.830412)
			(xy 385.482682 -282.804096) (xy 385.527968 -282.784797) (xy 385.575764 -282.773013) (xy 385.624832 -282.769051)
			(xy 385.6739 -282.773013) (xy 385.721696 -282.784797) (xy 385.766982 -282.804096) (xy 385.808585 -282.830412)
			(xy 385.845427 -282.863061) (xy 385.876554 -282.901199) (xy 385.901158 -282.943836) (xy 385.918602 -282.989869)
			(xy 385.928434 -283.038105) (xy 385.929886 -283.06268) (xy 385.930731 -283.072411) (xy 385.938748 -283.090204)
			(xy 385.952825 -283.10372) (xy 385.970928 -283.111008) (xy 385.980686 -283.111448) (xy 386.000244 -283.111448)
			(xy 386.018979 -283.111736) (xy 386.056169 -283.116316) (xy 386.074412 -283.120592) (xy 386.087903 -283.124102)
			(xy 386.114235 -283.133257) (xy 386.12699 -283.13888) (xy 386.13842 -283.144214) (xy 386.163058 -283.142944)
			(xy 386.245862 -283.093922) (xy 386.256085 -283.086932) (xy 386.268959 -283.065824) (xy 386.2705 -283.053536)
			(xy 386.27279 -283.02816) (xy 386.284728 -282.978631) (xy 386.304724 -282.931772) (xy 386.332222 -282.888883)
			(xy 386.366459 -282.851155) (xy 386.406486 -282.819635) (xy 386.45119 -282.795198) (xy 386.499331 -282.778522)
			(xy 386.549572 -282.770071) (xy 386.575046 -282.769564) (xy 386.600297 -282.770145) (xy 386.650108 -282.778464)
			(xy 386.697871 -282.794867) (xy 386.742283 -282.818908) (xy 386.782133 -282.84993) (xy 386.816333 -282.887087)
			(xy 386.843953 -282.929367) (xy 386.864237 -282.975615) (xy 386.876633 -283.024571) (xy 386.880801 -283.074872)
			(xy 387.219202 -283.074872) (xy 387.223162 -283.025818) (xy 387.234939 -282.978034) (xy 387.25423 -282.932758)
			(xy 387.280533 -282.891162) (xy 387.313168 -282.854325) (xy 387.351289 -282.8232) (xy 387.39391 -282.798593)
			(xy 387.439926 -282.781141) (xy 387.488145 -282.771297) (xy 387.53732 -282.769316) (xy 387.586175 -282.775248)
			(xy 387.633446 -282.78894) (xy 387.677908 -282.810038) (xy 387.718411 -282.837994) (xy 387.753904 -282.872086)
			(xy 387.783469 -282.91143) (xy 387.80634 -282.955007) (xy 387.821924 -283.001688) (xy 387.829819 -283.050265)
			(xy 387.830314 -283.074872) (xy 388.169162 -283.074872) (xy 388.173122 -283.025818) (xy 388.184899 -282.978034)
			(xy 388.20419 -282.932758) (xy 388.230493 -282.891162) (xy 388.263128 -282.854325) (xy 388.301249 -282.8232)
			(xy 388.34387 -282.798593) (xy 388.389886 -282.781141) (xy 388.438105 -282.771297) (xy 388.48728 -282.769316)
			(xy 388.536135 -282.775248) (xy 388.583406 -282.78894) (xy 388.627868 -282.810038) (xy 388.668371 -282.837994)
			(xy 388.703864 -282.872086) (xy 388.733429 -282.91143) (xy 388.7563 -282.955007) (xy 388.771884 -283.001688)
			(xy 388.779779 -283.050265) (xy 388.780274 -283.074872) (xy 389.119122 -283.074872) (xy 389.123082 -283.025818)
			(xy 389.134859 -282.978034) (xy 389.15415 -282.932758) (xy 389.180453 -282.891162) (xy 389.213088 -282.854325)
			(xy 389.251209 -282.8232) (xy 389.29383 -282.798593) (xy 389.339846 -282.781141) (xy 389.388065 -282.771297)
			(xy 389.43724 -282.769316) (xy 389.486095 -282.775248) (xy 389.533366 -282.78894) (xy 389.577828 -282.810038)
			(xy 389.618331 -282.837994) (xy 389.653824 -282.872086) (xy 389.683389 -282.91143) (xy 389.70626 -282.955007)
			(xy 389.721844 -283.001688) (xy 389.729739 -283.050265) (xy 389.730234 -283.074872) (xy 390.069082 -283.074872)
			(xy 390.073042 -283.025818) (xy 390.084819 -282.978034) (xy 390.10411 -282.932758) (xy 390.130413 -282.891162)
			(xy 390.163048 -282.854325) (xy 390.201169 -282.8232) (xy 390.24379 -282.798593) (xy 390.289806 -282.781141)
			(xy 390.338025 -282.771297) (xy 390.3872 -282.769316) (xy 390.436055 -282.775248) (xy 390.483326 -282.78894)
			(xy 390.527788 -282.810038) (xy 390.568291 -282.837994) (xy 390.603784 -282.872086) (xy 390.633349 -282.91143)
			(xy 390.65622 -282.955007) (xy 390.671804 -283.001688) (xy 390.679699 -283.050265) (xy 390.680194 -283.074872)
			(xy 391.019042 -283.074872) (xy 391.023002 -283.025818) (xy 391.034779 -282.978034) (xy 391.05407 -282.932758)
			(xy 391.080373 -282.891162) (xy 391.113008 -282.854325) (xy 391.151129 -282.8232) (xy 391.19375 -282.798593)
			(xy 391.239766 -282.781141) (xy 391.287985 -282.771297) (xy 391.33716 -282.769316) (xy 391.386015 -282.775248)
			(xy 391.433286 -282.78894) (xy 391.477748 -282.810038) (xy 391.518251 -282.837994) (xy 391.553744 -282.872086)
			(xy 391.583309 -282.91143) (xy 391.60618 -282.955007) (xy 391.621764 -283.001688) (xy 391.629659 -283.050265)
			(xy 391.630154 -283.074872) (xy 391.969002 -283.074872) (xy 391.972962 -283.025818) (xy 391.984739 -282.978034)
			(xy 392.00403 -282.932758) (xy 392.030333 -282.891162) (xy 392.062968 -282.854325) (xy 392.101089 -282.8232)
			(xy 392.14371 -282.798593) (xy 392.189726 -282.781141) (xy 392.237945 -282.771297) (xy 392.28712 -282.769316)
			(xy 392.335975 -282.775248) (xy 392.383246 -282.78894) (xy 392.427708 -282.810038) (xy 392.468211 -282.837994)
			(xy 392.503704 -282.872086) (xy 392.533269 -282.91143) (xy 392.55614 -282.955007) (xy 392.571724 -283.001688)
			(xy 392.579619 -283.050265) (xy 392.580114 -283.074872) (xy 392.919216 -283.074872) (xy 392.923176 -283.025818)
			(xy 392.934953 -282.978034) (xy 392.954244 -282.932758) (xy 392.980547 -282.891162) (xy 393.013182 -282.854325)
			(xy 393.051303 -282.8232) (xy 393.093924 -282.798593) (xy 393.13994 -282.781141) (xy 393.188159 -282.771297)
			(xy 393.237334 -282.769316) (xy 393.286189 -282.775248) (xy 393.33346 -282.78894) (xy 393.377922 -282.810038)
			(xy 393.418425 -282.837994) (xy 393.453918 -282.872086) (xy 393.483483 -282.91143) (xy 393.506354 -282.955007)
			(xy 393.521938 -283.001688) (xy 393.529833 -283.050265) (xy 393.530328 -283.074872) (xy 393.869176 -283.074872)
			(xy 393.873136 -283.025818) (xy 393.884913 -282.978034) (xy 393.904204 -282.932758) (xy 393.930507 -282.891162)
			(xy 393.963142 -282.854325) (xy 394.001263 -282.8232) (xy 394.043884 -282.798593) (xy 394.0899 -282.781141)
			(xy 394.138119 -282.771297) (xy 394.187294 -282.769316) (xy 394.236149 -282.775248) (xy 394.28342 -282.78894)
			(xy 394.327882 -282.810038) (xy 394.368385 -282.837994) (xy 394.403878 -282.872086) (xy 394.433443 -282.91143)
			(xy 394.456314 -282.955007) (xy 394.471898 -283.001688) (xy 394.479793 -283.050265) (xy 394.480288 -283.074872)
			(xy 394.819136 -283.074872) (xy 394.823096 -283.025818) (xy 394.834873 -282.978034) (xy 394.854164 -282.932758)
			(xy 394.880467 -282.891162) (xy 394.913102 -282.854325) (xy 394.951223 -282.8232) (xy 394.993844 -282.798593)
			(xy 395.03986 -282.781141) (xy 395.088079 -282.771297) (xy 395.137254 -282.769316) (xy 395.186109 -282.775248)
			(xy 395.23338 -282.78894) (xy 395.277842 -282.810038) (xy 395.318345 -282.837994) (xy 395.353838 -282.872086)
			(xy 395.383403 -282.91143) (xy 395.406274 -282.955007) (xy 395.421858 -283.001688) (xy 395.429753 -283.050265)
			(xy 395.430248 -283.074872) (xy 395.769096 -283.074872) (xy 395.773056 -283.025818) (xy 395.784833 -282.978034)
			(xy 395.804124 -282.932758) (xy 395.830427 -282.891162) (xy 395.863062 -282.854325) (xy 395.901183 -282.8232)
			(xy 395.943804 -282.798593) (xy 395.98982 -282.781141) (xy 396.038039 -282.771297) (xy 396.087214 -282.769316)
			(xy 396.136069 -282.775248) (xy 396.18334 -282.78894) (xy 396.227802 -282.810038) (xy 396.268305 -282.837994)
			(xy 396.303798 -282.872086) (xy 396.333363 -282.91143) (xy 396.356234 -282.955007) (xy 396.371818 -283.001688)
			(xy 396.379713 -283.050265) (xy 396.380208 -283.074872) (xy 396.719056 -283.074872) (xy 396.723016 -283.025818)
			(xy 396.734793 -282.978034) (xy 396.754084 -282.932758) (xy 396.780387 -282.891162) (xy 396.813022 -282.854325)
			(xy 396.851143 -282.8232) (xy 396.893764 -282.798593) (xy 396.93978 -282.781141) (xy 396.987999 -282.771297)
			(xy 397.037174 -282.769316) (xy 397.086029 -282.775248) (xy 397.1333 -282.78894) (xy 397.177762 -282.810038)
			(xy 397.218265 -282.837994) (xy 397.253758 -282.872086) (xy 397.283323 -282.91143) (xy 397.306194 -282.955007)
			(xy 397.321778 -283.001688) (xy 397.329673 -283.050265) (xy 397.330168 -283.074872) (xy 397.669016 -283.074872)
			(xy 397.672976 -283.025818) (xy 397.684753 -282.978034) (xy 397.704044 -282.932758) (xy 397.730347 -282.891162)
			(xy 397.762982 -282.854325) (xy 397.801103 -282.8232) (xy 397.843724 -282.798593) (xy 397.88974 -282.781141)
			(xy 397.937959 -282.771297) (xy 397.987134 -282.769316) (xy 398.035989 -282.775248) (xy 398.08326 -282.78894)
			(xy 398.127722 -282.810038) (xy 398.168225 -282.837994) (xy 398.203718 -282.872086) (xy 398.233283 -282.91143)
			(xy 398.256154 -282.955007) (xy 398.271738 -283.001688) (xy 398.279633 -283.050265) (xy 398.280128 -283.074872)
			(xy 398.61923 -283.074872) (xy 398.62319 -283.025818) (xy 398.634967 -282.978034) (xy 398.654258 -282.932758)
			(xy 398.680561 -282.891162) (xy 398.713196 -282.854325) (xy 398.751317 -282.8232) (xy 398.793938 -282.798593)
			(xy 398.839954 -282.781141) (xy 398.888173 -282.771297) (xy 398.937348 -282.769316) (xy 398.986203 -282.775248)
			(xy 399.033474 -282.78894) (xy 399.077936 -282.810038) (xy 399.118439 -282.837994) (xy 399.153932 -282.872086)
			(xy 399.183497 -282.91143) (xy 399.206368 -282.955007) (xy 399.221952 -283.001688) (xy 399.229847 -283.050265)
			(xy 399.230342 -283.074872) (xy 399.56919 -283.074872) (xy 399.57315 -283.025818) (xy 399.584927 -282.978034)
			(xy 399.604218 -282.932758) (xy 399.630521 -282.891162) (xy 399.663156 -282.854325) (xy 399.701277 -282.8232)
			(xy 399.743898 -282.798593) (xy 399.789914 -282.781141) (xy 399.838133 -282.771297) (xy 399.887308 -282.769316)
			(xy 399.936163 -282.775248) (xy 399.983434 -282.78894) (xy 400.027896 -282.810038) (xy 400.068399 -282.837994)
			(xy 400.103892 -282.872086) (xy 400.133457 -282.91143) (xy 400.156328 -282.955007) (xy 400.171912 -283.001688)
			(xy 400.179807 -283.050265) (xy 400.180302 -283.074872) (xy 400.51915 -283.074872) (xy 400.52311 -283.025818)
			(xy 400.534887 -282.978034) (xy 400.554178 -282.932758) (xy 400.580481 -282.891162) (xy 400.613116 -282.854325)
			(xy 400.651237 -282.8232) (xy 400.693858 -282.798593) (xy 400.739874 -282.781141) (xy 400.788093 -282.771297)
			(xy 400.837268 -282.769316) (xy 400.886123 -282.775248) (xy 400.933394 -282.78894) (xy 400.977856 -282.810038)
			(xy 401.018359 -282.837994) (xy 401.053852 -282.872086) (xy 401.083417 -282.91143) (xy 401.106288 -282.955007)
			(xy 401.121872 -283.001688) (xy 401.129767 -283.050265) (xy 401.130262 -283.074872) (xy 401.46911 -283.074872)
			(xy 401.47307 -283.025818) (xy 401.484847 -282.978034) (xy 401.504138 -282.932758) (xy 401.530441 -282.891162)
			(xy 401.563076 -282.854325) (xy 401.601197 -282.8232) (xy 401.643818 -282.798593) (xy 401.689834 -282.781141)
			(xy 401.738053 -282.771297) (xy 401.787228 -282.769316) (xy 401.836083 -282.775248) (xy 401.883354 -282.78894)
			(xy 401.927816 -282.810038) (xy 401.968319 -282.837994) (xy 402.003812 -282.872086) (xy 402.033377 -282.91143)
			(xy 402.056248 -282.955007) (xy 402.071832 -283.001688) (xy 402.079727 -283.050265) (xy 402.080056 -283.066644)
			(xy 402.419152 -283.066644) (xy 402.424516 -283.017288) (xy 402.437793 -282.969451) (xy 402.458636 -282.924391)
			(xy 402.486493 -282.883297) (xy 402.520631 -282.847251) (xy 402.560152 -282.817203) (xy 402.604013 -282.793944)
			(xy 402.651059 -282.778088) (xy 402.700051 -282.770052) (xy 402.724874 -282.769564) (xy 402.739057 -282.769745)
			(xy 402.767297 -282.772414) (xy 402.781262 -282.774898) (xy 402.793708 -282.777184) (xy 402.81733 -282.769818)
			(xy 402.8948 -282.692348) (xy 402.902166 -282.668726) (xy 402.89988 -282.65628) (xy 402.897404 -282.642314)
			(xy 402.894732 -282.614074) (xy 402.894546 -282.599892) (xy 402.895068 -282.574637) (xy 402.903381 -282.524815)
			(xy 402.919782 -282.477041) (xy 402.943823 -282.432618) (xy 402.974847 -282.392758) (xy 403.012009 -282.358548)
			(xy 403.054295 -282.330922) (xy 403.100551 -282.310632) (xy 403.149516 -282.298232) (xy 403.199854 -282.294061)
			(xy 403.250192 -282.298232) (xy 403.299157 -282.310632) (xy 403.345413 -282.330922) (xy 403.387699 -282.358548)
			(xy 403.424861 -282.392758) (xy 403.455885 -282.432618) (xy 403.479926 -282.477041) (xy 403.496327 -282.524815)
			(xy 403.50464 -282.574637) (xy 403.505162 -282.599892) (xy 403.504985 -282.614075) (xy 403.502313 -282.642315)
			(xy 403.499828 -282.65628) (xy 403.497542 -282.668726) (xy 403.504908 -282.692348) (xy 403.582378 -282.769818)
			(xy 403.606 -282.777184) (xy 403.618446 -282.774898) (xy 403.632411 -282.772419) (xy 403.660651 -282.769749)
			(xy 403.674834 -282.769564) (xy 403.699652 -282.770115) (xy 403.748633 -282.77815) (xy 403.795669 -282.794004)
			(xy 403.839521 -282.817259) (xy 403.879032 -282.847302) (xy 403.913163 -282.883341) (xy 403.941014 -282.924427)
			(xy 403.96185 -282.969478) (xy 403.975124 -283.017306) (xy 403.980486 -283.066651) (xy 403.980039 -283.074872)
			(xy 404.319244 -283.074872) (xy 404.323204 -283.025818) (xy 404.334981 -282.978034) (xy 404.354272 -282.932758)
			(xy 404.380575 -282.891162) (xy 404.41321 -282.854325) (xy 404.451331 -282.8232) (xy 404.493952 -282.798593)
			(xy 404.539968 -282.781141) (xy 404.588187 -282.771297) (xy 404.637362 -282.769316) (xy 404.686217 -282.775248)
			(xy 404.733488 -282.78894) (xy 404.77795 -282.810038) (xy 404.818453 -282.837994) (xy 404.853946 -282.872086)
			(xy 404.883511 -282.91143) (xy 404.906382 -282.955007) (xy 404.921966 -283.001688) (xy 404.929861 -283.050265)
			(xy 404.930356 -283.074872) (xy 405.269204 -283.074872) (xy 405.273164 -283.025818) (xy 405.284941 -282.978034)
			(xy 405.304232 -282.932758) (xy 405.330535 -282.891162) (xy 405.36317 -282.854325) (xy 405.401291 -282.8232)
			(xy 405.443912 -282.798593) (xy 405.489928 -282.781141) (xy 405.538147 -282.771297) (xy 405.587322 -282.769316)
			(xy 405.636177 -282.775248) (xy 405.683448 -282.78894) (xy 405.72791 -282.810038) (xy 405.768413 -282.837994)
			(xy 405.803906 -282.872086) (xy 405.833471 -282.91143) (xy 405.856342 -282.955007) (xy 405.871926 -283.001688)
			(xy 405.879821 -283.050265) (xy 405.880316 -283.074872) (xy 406.219164 -283.074872) (xy 406.223124 -283.025818)
			(xy 406.234901 -282.978034) (xy 406.254192 -282.932758) (xy 406.280495 -282.891162) (xy 406.31313 -282.854325)
			(xy 406.351251 -282.8232) (xy 406.393872 -282.798593) (xy 406.439888 -282.781141) (xy 406.488107 -282.771297)
			(xy 406.537282 -282.769316) (xy 406.586137 -282.775248) (xy 406.633408 -282.78894) (xy 406.67787 -282.810038)
			(xy 406.718373 -282.837994) (xy 406.753866 -282.872086) (xy 406.783431 -282.91143) (xy 406.806302 -282.955007)
			(xy 406.821886 -283.001688) (xy 406.829781 -283.050265) (xy 406.830276 -283.074872) (xy 408.119084 -283.074872)
			(xy 408.123044 -283.025818) (xy 408.134821 -282.978034) (xy 408.154112 -282.932758) (xy 408.180415 -282.891162)
			(xy 408.21305 -282.854325) (xy 408.251171 -282.8232) (xy 408.293792 -282.798593) (xy 408.339808 -282.781141)
			(xy 408.388027 -282.771297) (xy 408.437202 -282.769316) (xy 408.486057 -282.775248) (xy 408.533328 -282.78894)
			(xy 408.57779 -282.810038) (xy 408.618293 -282.837994) (xy 408.653786 -282.872086) (xy 408.683351 -282.91143)
			(xy 408.706222 -282.955007) (xy 408.721806 -283.001688) (xy 408.729701 -283.050265) (xy 408.730196 -283.074872)
			(xy 409.069044 -283.074872) (xy 409.073004 -283.025818) (xy 409.084781 -282.978034) (xy 409.104072 -282.932758)
			(xy 409.130375 -282.891162) (xy 409.16301 -282.854325) (xy 409.201131 -282.8232) (xy 409.243752 -282.798593)
			(xy 409.289768 -282.781141) (xy 409.337987 -282.771297) (xy 409.387162 -282.769316) (xy 409.436017 -282.775248)
			(xy 409.483288 -282.78894) (xy 409.52775 -282.810038) (xy 409.568253 -282.837994) (xy 409.603746 -282.872086)
			(xy 409.633311 -282.91143) (xy 409.656182 -282.955007) (xy 409.671766 -283.001688) (xy 409.679661 -283.050265)
			(xy 409.680156 -283.074872) (xy 410.019004 -283.074872) (xy 410.022964 -283.025818) (xy 410.034741 -282.978034)
			(xy 410.054032 -282.932758) (xy 410.080335 -282.891162) (xy 410.11297 -282.854325) (xy 410.151091 -282.8232)
			(xy 410.193712 -282.798593) (xy 410.239728 -282.781141) (xy 410.287947 -282.771297) (xy 410.337122 -282.769316)
			(xy 410.385977 -282.775248) (xy 410.433248 -282.78894) (xy 410.47771 -282.810038) (xy 410.518213 -282.837994)
			(xy 410.553706 -282.872086) (xy 410.583271 -282.91143) (xy 410.606142 -282.955007) (xy 410.621726 -283.001688)
			(xy 410.629621 -283.050265) (xy 410.630116 -283.074872) (xy 410.969218 -283.074872) (xy 410.973178 -283.025818)
			(xy 410.984955 -282.978034) (xy 411.004246 -282.932758) (xy 411.030549 -282.891162) (xy 411.063184 -282.854325)
			(xy 411.101305 -282.8232) (xy 411.143926 -282.798593) (xy 411.189942 -282.781141) (xy 411.238161 -282.771297)
			(xy 411.287336 -282.769316) (xy 411.336191 -282.775248) (xy 411.383462 -282.78894) (xy 411.427924 -282.810038)
			(xy 411.468427 -282.837994) (xy 411.50392 -282.872086) (xy 411.533485 -282.91143) (xy 411.556356 -282.955007)
			(xy 411.57194 -283.001688) (xy 411.579835 -283.050265) (xy 411.58033 -283.074872) (xy 411.919178 -283.074872)
			(xy 411.923138 -283.025818) (xy 411.934915 -282.978034) (xy 411.954206 -282.932758) (xy 411.980509 -282.891162)
			(xy 412.013144 -282.854325) (xy 412.051265 -282.8232) (xy 412.093886 -282.798593) (xy 412.139902 -282.781141)
			(xy 412.188121 -282.771297) (xy 412.237296 -282.769316) (xy 412.286151 -282.775248) (xy 412.333422 -282.78894)
			(xy 412.377884 -282.810038) (xy 412.418387 -282.837994) (xy 412.45388 -282.872086) (xy 412.483445 -282.91143)
			(xy 412.506316 -282.955007) (xy 412.5219 -283.001688) (xy 412.529795 -283.050265) (xy 412.53029 -283.074872)
			(xy 412.869138 -283.074872) (xy 412.873098 -283.025818) (xy 412.884875 -282.978034) (xy 412.904166 -282.932758)
			(xy 412.930469 -282.891162) (xy 412.963104 -282.854325) (xy 413.001225 -282.8232) (xy 413.043846 -282.798593)
			(xy 413.089862 -282.781141) (xy 413.138081 -282.771297) (xy 413.187256 -282.769316) (xy 413.236111 -282.775248)
			(xy 413.283382 -282.78894) (xy 413.327844 -282.810038) (xy 413.368347 -282.837994) (xy 413.40384 -282.872086)
			(xy 413.433405 -282.91143) (xy 413.456276 -282.955007) (xy 413.47186 -283.001688) (xy 413.479755 -283.050265)
			(xy 413.48025 -283.074872) (xy 413.819098 -283.074872) (xy 413.823058 -283.025818) (xy 413.834835 -282.978034)
			(xy 413.854126 -282.932758) (xy 413.880429 -282.891162) (xy 413.913064 -282.854325) (xy 413.951185 -282.8232)
			(xy 413.993806 -282.798593) (xy 414.039822 -282.781141) (xy 414.088041 -282.771297) (xy 414.137216 -282.769316)
			(xy 414.186071 -282.775248) (xy 414.233342 -282.78894) (xy 414.277804 -282.810038) (xy 414.318307 -282.837994)
			(xy 414.3538 -282.872086) (xy 414.383365 -282.91143) (xy 414.406236 -282.955007) (xy 414.42182 -283.001688)
			(xy 414.429715 -283.050265) (xy 414.43021 -283.074872) (xy 414.769058 -283.074872) (xy 414.773018 -283.025818)
			(xy 414.784795 -282.978034) (xy 414.804086 -282.932758) (xy 414.830389 -282.891162) (xy 414.863024 -282.854325)
			(xy 414.901145 -282.8232) (xy 414.943766 -282.798593) (xy 414.989782 -282.781141) (xy 415.038001 -282.771297)
			(xy 415.087176 -282.769316) (xy 415.136031 -282.775248) (xy 415.183302 -282.78894) (xy 415.227764 -282.810038)
			(xy 415.268267 -282.837994) (xy 415.30376 -282.872086) (xy 415.333325 -282.91143) (xy 415.356196 -282.955007)
			(xy 415.37178 -283.001688) (xy 415.379675 -283.050265) (xy 415.38017 -283.074872) (xy 415.719018 -283.074872)
			(xy 415.722978 -283.025818) (xy 415.734755 -282.978034) (xy 415.754046 -282.932758) (xy 415.780349 -282.891162)
			(xy 415.812984 -282.854325) (xy 415.851105 -282.8232) (xy 415.893726 -282.798593) (xy 415.939742 -282.781141)
			(xy 415.987961 -282.771297) (xy 416.037136 -282.769316) (xy 416.085991 -282.775248) (xy 416.133262 -282.78894)
			(xy 416.177724 -282.810038) (xy 416.218227 -282.837994) (xy 416.25372 -282.872086) (xy 416.283285 -282.91143)
			(xy 416.306156 -282.955007) (xy 416.32174 -283.001688) (xy 416.329635 -283.050265) (xy 416.33013 -283.074872)
			(xy 416.668978 -283.074872) (xy 416.672938 -283.025818) (xy 416.684715 -282.978034) (xy 416.704006 -282.932758)
			(xy 416.730309 -282.891162) (xy 416.762944 -282.854325) (xy 416.801065 -282.8232) (xy 416.843686 -282.798593)
			(xy 416.889702 -282.781141) (xy 416.937921 -282.771297) (xy 416.987096 -282.769316) (xy 417.035951 -282.775248)
			(xy 417.083222 -282.78894) (xy 417.127684 -282.810038) (xy 417.168187 -282.837994) (xy 417.20368 -282.872086)
			(xy 417.233245 -282.91143) (xy 417.256116 -282.955007) (xy 417.2717 -283.001688) (xy 417.279595 -283.050265)
			(xy 417.28009 -283.074872) (xy 417.279595 -283.099479) (xy 417.2717 -283.148056) (xy 417.256116 -283.194737)
			(xy 417.233245 -283.238314) (xy 417.20368 -283.277658) (xy 417.168187 -283.31175) (xy 417.127684 -283.339706)
			(xy 417.083222 -283.360804) (xy 417.035951 -283.374496) (xy 416.987096 -283.380428) (xy 416.937921 -283.378447)
			(xy 416.889702 -283.368603) (xy 416.843686 -283.351151) (xy 416.801065 -283.326544) (xy 416.762944 -283.295419)
			(xy 416.730309 -283.258582) (xy 416.704006 -283.216986) (xy 416.684715 -283.17171) (xy 416.672938 -283.123926)
			(xy 416.668978 -283.074872) (xy 416.33013 -283.074872) (xy 416.329635 -283.099479) (xy 416.32174 -283.148056)
			(xy 416.306156 -283.194737) (xy 416.283285 -283.238314) (xy 416.25372 -283.277658) (xy 416.218227 -283.31175)
			(xy 416.177724 -283.339706) (xy 416.133262 -283.360804) (xy 416.085991 -283.374496) (xy 416.037136 -283.380428)
			(xy 415.987961 -283.378447) (xy 415.939742 -283.368603) (xy 415.893726 -283.351151) (xy 415.851105 -283.326544)
			(xy 415.812984 -283.295419) (xy 415.780349 -283.258582) (xy 415.754046 -283.216986) (xy 415.734755 -283.17171)
			(xy 415.722978 -283.123926) (xy 415.719018 -283.074872) (xy 415.38017 -283.074872) (xy 415.379675 -283.099479)
			(xy 415.37178 -283.148056) (xy 415.356196 -283.194737) (xy 415.333325 -283.238314) (xy 415.30376 -283.277658)
			(xy 415.268267 -283.31175) (xy 415.227764 -283.339706) (xy 415.183302 -283.360804) (xy 415.136031 -283.374496)
			(xy 415.087176 -283.380428) (xy 415.038001 -283.378447) (xy 414.989782 -283.368603) (xy 414.943766 -283.351151)
			(xy 414.901145 -283.326544) (xy 414.863024 -283.295419) (xy 414.830389 -283.258582) (xy 414.804086 -283.216986)
			(xy 414.784795 -283.17171) (xy 414.773018 -283.123926) (xy 414.769058 -283.074872) (xy 414.43021 -283.074872)
			(xy 414.429715 -283.099479) (xy 414.42182 -283.148056) (xy 414.406236 -283.194737) (xy 414.383365 -283.238314)
			(xy 414.3538 -283.277658) (xy 414.318307 -283.31175) (xy 414.277804 -283.339706) (xy 414.233342 -283.360804)
			(xy 414.186071 -283.374496) (xy 414.137216 -283.380428) (xy 414.088041 -283.378447) (xy 414.039822 -283.368603)
			(xy 413.993806 -283.351151) (xy 413.951185 -283.326544) (xy 413.913064 -283.295419) (xy 413.880429 -283.258582)
			(xy 413.854126 -283.216986) (xy 413.834835 -283.17171) (xy 413.823058 -283.123926) (xy 413.819098 -283.074872)
			(xy 413.48025 -283.074872) (xy 413.479755 -283.099479) (xy 413.47186 -283.148056) (xy 413.456276 -283.194737)
			(xy 413.433405 -283.238314) (xy 413.40384 -283.277658) (xy 413.368347 -283.31175) (xy 413.327844 -283.339706)
			(xy 413.283382 -283.360804) (xy 413.236111 -283.374496) (xy 413.187256 -283.380428) (xy 413.138081 -283.378447)
			(xy 413.089862 -283.368603) (xy 413.043846 -283.351151) (xy 413.001225 -283.326544) (xy 412.963104 -283.295419)
			(xy 412.930469 -283.258582) (xy 412.904166 -283.216986) (xy 412.884875 -283.17171) (xy 412.873098 -283.123926)
			(xy 412.869138 -283.074872) (xy 412.53029 -283.074872) (xy 412.529795 -283.099479) (xy 412.5219 -283.148056)
			(xy 412.506316 -283.194737) (xy 412.483445 -283.238314) (xy 412.45388 -283.277658) (xy 412.418387 -283.31175)
			(xy 412.377884 -283.339706) (xy 412.333422 -283.360804) (xy 412.286151 -283.374496) (xy 412.237296 -283.380428)
			(xy 412.188121 -283.378447) (xy 412.139902 -283.368603) (xy 412.093886 -283.351151) (xy 412.051265 -283.326544)
			(xy 412.013144 -283.295419) (xy 411.980509 -283.258582) (xy 411.954206 -283.216986) (xy 411.934915 -283.17171)
			(xy 411.923138 -283.123926) (xy 411.919178 -283.074872) (xy 411.58033 -283.074872) (xy 411.579835 -283.099479)
			(xy 411.57194 -283.148056) (xy 411.556356 -283.194737) (xy 411.533485 -283.238314) (xy 411.50392 -283.277658)
			(xy 411.468427 -283.31175) (xy 411.427924 -283.339706) (xy 411.383462 -283.360804) (xy 411.336191 -283.374496)
			(xy 411.287336 -283.380428) (xy 411.238161 -283.378447) (xy 411.189942 -283.368603) (xy 411.143926 -283.351151)
			(xy 411.101305 -283.326544) (xy 411.063184 -283.295419) (xy 411.030549 -283.258582) (xy 411.004246 -283.216986)
			(xy 410.984955 -283.17171) (xy 410.973178 -283.123926) (xy 410.969218 -283.074872) (xy 410.630116 -283.074872)
			(xy 410.629621 -283.099479) (xy 410.621726 -283.148056) (xy 410.606142 -283.194737) (xy 410.583271 -283.238314)
			(xy 410.553706 -283.277658) (xy 410.518213 -283.31175) (xy 410.47771 -283.339706) (xy 410.433248 -283.360804)
			(xy 410.385977 -283.374496) (xy 410.337122 -283.380428) (xy 410.287947 -283.378447) (xy 410.239728 -283.368603)
			(xy 410.193712 -283.351151) (xy 410.151091 -283.326544) (xy 410.11297 -283.295419) (xy 410.080335 -283.258582)
			(xy 410.054032 -283.216986) (xy 410.034741 -283.17171) (xy 410.022964 -283.123926) (xy 410.019004 -283.074872)
			(xy 409.680156 -283.074872) (xy 409.679661 -283.099479) (xy 409.671766 -283.148056) (xy 409.656182 -283.194737)
			(xy 409.633311 -283.238314) (xy 409.603746 -283.277658) (xy 409.568253 -283.31175) (xy 409.52775 -283.339706)
			(xy 409.483288 -283.360804) (xy 409.436017 -283.374496) (xy 409.387162 -283.380428) (xy 409.337987 -283.378447)
			(xy 409.289768 -283.368603) (xy 409.243752 -283.351151) (xy 409.201131 -283.326544) (xy 409.16301 -283.295419)
			(xy 409.130375 -283.258582) (xy 409.104072 -283.216986) (xy 409.084781 -283.17171) (xy 409.073004 -283.123926)
			(xy 409.069044 -283.074872) (xy 408.730196 -283.074872) (xy 408.729701 -283.099479) (xy 408.721806 -283.148056)
			(xy 408.706222 -283.194737) (xy 408.683351 -283.238314) (xy 408.653786 -283.277658) (xy 408.618293 -283.31175)
			(xy 408.57779 -283.339706) (xy 408.533328 -283.360804) (xy 408.486057 -283.374496) (xy 408.437202 -283.380428)
			(xy 408.388027 -283.378447) (xy 408.339808 -283.368603) (xy 408.293792 -283.351151) (xy 408.251171 -283.326544)
			(xy 408.21305 -283.295419) (xy 408.180415 -283.258582) (xy 408.154112 -283.216986) (xy 408.134821 -283.17171)
			(xy 408.123044 -283.123926) (xy 408.119084 -283.074872) (xy 406.830276 -283.074872) (xy 406.829781 -283.099479)
			(xy 406.821886 -283.148056) (xy 406.806302 -283.194737) (xy 406.783431 -283.238314) (xy 406.753866 -283.277658)
			(xy 406.718373 -283.31175) (xy 406.67787 -283.339706) (xy 406.633408 -283.360804) (xy 406.586137 -283.374496)
			(xy 406.537282 -283.380428) (xy 406.488107 -283.378447) (xy 406.439888 -283.368603) (xy 406.393872 -283.351151)
			(xy 406.351251 -283.326544) (xy 406.31313 -283.295419) (xy 406.280495 -283.258582) (xy 406.254192 -283.216986)
			(xy 406.234901 -283.17171) (xy 406.223124 -283.123926) (xy 406.219164 -283.074872) (xy 405.880316 -283.074872)
			(xy 405.879821 -283.099479) (xy 405.871926 -283.148056) (xy 405.856342 -283.194737) (xy 405.833471 -283.238314)
			(xy 405.803906 -283.277658) (xy 405.768413 -283.31175) (xy 405.72791 -283.339706) (xy 405.683448 -283.360804)
			(xy 405.636177 -283.374496) (xy 405.587322 -283.380428) (xy 405.538147 -283.378447) (xy 405.489928 -283.368603)
			(xy 405.443912 -283.351151) (xy 405.401291 -283.326544) (xy 405.36317 -283.295419) (xy 405.330535 -283.258582)
			(xy 405.304232 -283.216986) (xy 405.284941 -283.17171) (xy 405.273164 -283.123926) (xy 405.269204 -283.074872)
			(xy 404.930356 -283.074872) (xy 404.929861 -283.099479) (xy 404.921966 -283.148056) (xy 404.906382 -283.194737)
			(xy 404.883511 -283.238314) (xy 404.853946 -283.277658) (xy 404.818453 -283.31175) (xy 404.77795 -283.339706)
			(xy 404.733488 -283.360804) (xy 404.686217 -283.374496) (xy 404.637362 -283.380428) (xy 404.588187 -283.378447)
			(xy 404.539968 -283.368603) (xy 404.493952 -283.351151) (xy 404.451331 -283.326544) (xy 404.41321 -283.295419)
			(xy 404.380575 -283.258582) (xy 404.354272 -283.216986) (xy 404.334981 -283.17171) (xy 404.323204 -283.123926)
			(xy 404.319244 -283.074872) (xy 403.980039 -283.074872) (xy 403.977793 -283.116214) (xy 403.967118 -283.164689)
			(xy 403.948741 -283.210797) (xy 403.923147 -283.253326) (xy 403.891009 -283.291153) (xy 403.853175 -283.323283)
			(xy 403.810642 -283.348869) (xy 403.764529 -283.367236) (xy 403.716053 -283.377902) (xy 403.666489 -283.380584)
			(xy 403.617145 -283.375213) (xy 403.569319 -283.361929) (xy 403.524273 -283.341083) (xy 403.483192 -283.313224)
			(xy 403.44716 -283.279086) (xy 403.417125 -283.239568) (xy 403.39388 -283.195712) (xy 403.378035 -283.148673)
			(xy 403.370009 -283.09969) (xy 403.369526 -283.074872) (xy 403.369698 -283.060689) (xy 403.372373 -283.032449)
			(xy 403.37486 -283.018484) (xy 403.377146 -283.006038) (xy 403.36978 -282.982416) (xy 403.29231 -282.904946)
			(xy 403.268688 -282.89758) (xy 403.256242 -282.899866) (xy 403.242277 -282.902346) (xy 403.214037 -282.905016)
			(xy 403.199854 -282.9052) (xy 403.185671 -282.905016) (xy 403.157431 -282.902349) (xy 403.143466 -282.899866)
			(xy 403.13102 -282.89758) (xy 403.107398 -282.904946) (xy 403.029928 -282.982416) (xy 403.022562 -283.006038)
			(xy 403.024848 -283.018484) (xy 403.027332 -283.032449) (xy 403.029999 -283.060689) (xy 403.030182 -283.074872)
			(xy 403.029752 -283.099695) (xy 403.021725 -283.148688) (xy 403.005877 -283.195737) (xy 402.982626 -283.239602)
			(xy 402.952585 -283.279128) (xy 402.916545 -283.313273) (xy 402.875456 -283.341138) (xy 402.8304 -283.361988)
			(xy 402.782565 -283.375274) (xy 402.73321 -283.380646) (xy 402.683636 -283.377963) (xy 402.63515 -283.367295)
			(xy 402.589028 -283.348923) (xy 402.546486 -283.323331) (xy 402.508644 -283.291194) (xy 402.4765 -283.253358)
			(xy 402.450901 -283.210821) (xy 402.432521 -283.164702) (xy 402.421845 -283.116217) (xy 402.419152 -283.066644)
			(xy 402.080056 -283.066644) (xy 402.080222 -283.074872) (xy 402.079727 -283.099479) (xy 402.071832 -283.148056)
			(xy 402.056248 -283.194737) (xy 402.033377 -283.238314) (xy 402.003812 -283.277658) (xy 401.968319 -283.31175)
			(xy 401.927816 -283.339706) (xy 401.883354 -283.360804) (xy 401.836083 -283.374496) (xy 401.787228 -283.380428)
			(xy 401.738053 -283.378447) (xy 401.689834 -283.368603) (xy 401.643818 -283.351151) (xy 401.601197 -283.326544)
			(xy 401.563076 -283.295419) (xy 401.530441 -283.258582) (xy 401.504138 -283.216986) (xy 401.484847 -283.17171)
			(xy 401.47307 -283.123926) (xy 401.46911 -283.074872) (xy 401.130262 -283.074872) (xy 401.129767 -283.099479)
			(xy 401.121872 -283.148056) (xy 401.106288 -283.194737) (xy 401.083417 -283.238314) (xy 401.053852 -283.277658)
			(xy 401.018359 -283.31175) (xy 400.977856 -283.339706) (xy 400.933394 -283.360804) (xy 400.886123 -283.374496)
			(xy 400.837268 -283.380428) (xy 400.788093 -283.378447) (xy 400.739874 -283.368603) (xy 400.693858 -283.351151)
			(xy 400.651237 -283.326544) (xy 400.613116 -283.295419) (xy 400.580481 -283.258582) (xy 400.554178 -283.216986)
			(xy 400.534887 -283.17171) (xy 400.52311 -283.123926) (xy 400.51915 -283.074872) (xy 400.180302 -283.074872)
			(xy 400.179807 -283.099479) (xy 400.171912 -283.148056) (xy 400.156328 -283.194737) (xy 400.133457 -283.238314)
			(xy 400.103892 -283.277658) (xy 400.068399 -283.31175) (xy 400.027896 -283.339706) (xy 399.983434 -283.360804)
			(xy 399.936163 -283.374496) (xy 399.887308 -283.380428) (xy 399.838133 -283.378447) (xy 399.789914 -283.368603)
			(xy 399.743898 -283.351151) (xy 399.701277 -283.326544) (xy 399.663156 -283.295419) (xy 399.630521 -283.258582)
			(xy 399.604218 -283.216986) (xy 399.584927 -283.17171) (xy 399.57315 -283.123926) (xy 399.56919 -283.074872)
			(xy 399.230342 -283.074872) (xy 399.229847 -283.099479) (xy 399.221952 -283.148056) (xy 399.206368 -283.194737)
			(xy 399.183497 -283.238314) (xy 399.153932 -283.277658) (xy 399.118439 -283.31175) (xy 399.077936 -283.339706)
			(xy 399.033474 -283.360804) (xy 398.986203 -283.374496) (xy 398.937348 -283.380428) (xy 398.888173 -283.378447)
			(xy 398.839954 -283.368603) (xy 398.793938 -283.351151) (xy 398.751317 -283.326544) (xy 398.713196 -283.295419)
			(xy 398.680561 -283.258582) (xy 398.654258 -283.216986) (xy 398.634967 -283.17171) (xy 398.62319 -283.123926)
			(xy 398.61923 -283.074872) (xy 398.280128 -283.074872) (xy 398.279633 -283.099479) (xy 398.271738 -283.148056)
			(xy 398.256154 -283.194737) (xy 398.233283 -283.238314) (xy 398.203718 -283.277658) (xy 398.168225 -283.31175)
			(xy 398.127722 -283.339706) (xy 398.08326 -283.360804) (xy 398.035989 -283.374496) (xy 397.987134 -283.380428)
			(xy 397.937959 -283.378447) (xy 397.88974 -283.368603) (xy 397.843724 -283.351151) (xy 397.801103 -283.326544)
			(xy 397.762982 -283.295419) (xy 397.730347 -283.258582) (xy 397.704044 -283.216986) (xy 397.684753 -283.17171)
			(xy 397.672976 -283.123926) (xy 397.669016 -283.074872) (xy 397.330168 -283.074872) (xy 397.329673 -283.099479)
			(xy 397.321778 -283.148056) (xy 397.306194 -283.194737) (xy 397.283323 -283.238314) (xy 397.253758 -283.277658)
			(xy 397.218265 -283.31175) (xy 397.177762 -283.339706) (xy 397.1333 -283.360804) (xy 397.086029 -283.374496)
			(xy 397.037174 -283.380428) (xy 396.987999 -283.378447) (xy 396.93978 -283.368603) (xy 396.893764 -283.351151)
			(xy 396.851143 -283.326544) (xy 396.813022 -283.295419) (xy 396.780387 -283.258582) (xy 396.754084 -283.216986)
			(xy 396.734793 -283.17171) (xy 396.723016 -283.123926) (xy 396.719056 -283.074872) (xy 396.380208 -283.074872)
			(xy 396.379713 -283.099479) (xy 396.371818 -283.148056) (xy 396.356234 -283.194737) (xy 396.333363 -283.238314)
			(xy 396.303798 -283.277658) (xy 396.268305 -283.31175) (xy 396.227802 -283.339706) (xy 396.18334 -283.360804)
			(xy 396.136069 -283.374496) (xy 396.087214 -283.380428) (xy 396.038039 -283.378447) (xy 395.98982 -283.368603)
			(xy 395.943804 -283.351151) (xy 395.901183 -283.326544) (xy 395.863062 -283.295419) (xy 395.830427 -283.258582)
			(xy 395.804124 -283.216986) (xy 395.784833 -283.17171) (xy 395.773056 -283.123926) (xy 395.769096 -283.074872)
			(xy 395.430248 -283.074872) (xy 395.429753 -283.099479) (xy 395.421858 -283.148056) (xy 395.406274 -283.194737)
			(xy 395.383403 -283.238314) (xy 395.353838 -283.277658) (xy 395.318345 -283.31175) (xy 395.277842 -283.339706)
			(xy 395.23338 -283.360804) (xy 395.186109 -283.374496) (xy 395.137254 -283.380428) (xy 395.088079 -283.378447)
			(xy 395.03986 -283.368603) (xy 394.993844 -283.351151) (xy 394.951223 -283.326544) (xy 394.913102 -283.295419)
			(xy 394.880467 -283.258582) (xy 394.854164 -283.216986) (xy 394.834873 -283.17171) (xy 394.823096 -283.123926)
			(xy 394.819136 -283.074872) (xy 394.480288 -283.074872) (xy 394.479793 -283.099479) (xy 394.471898 -283.148056)
			(xy 394.456314 -283.194737) (xy 394.433443 -283.238314) (xy 394.403878 -283.277658) (xy 394.368385 -283.31175)
			(xy 394.327882 -283.339706) (xy 394.28342 -283.360804) (xy 394.236149 -283.374496) (xy 394.187294 -283.380428)
			(xy 394.138119 -283.378447) (xy 394.0899 -283.368603) (xy 394.043884 -283.351151) (xy 394.001263 -283.326544)
			(xy 393.963142 -283.295419) (xy 393.930507 -283.258582) (xy 393.904204 -283.216986) (xy 393.884913 -283.17171)
			(xy 393.873136 -283.123926) (xy 393.869176 -283.074872) (xy 393.530328 -283.074872) (xy 393.529833 -283.099479)
			(xy 393.521938 -283.148056) (xy 393.506354 -283.194737) (xy 393.483483 -283.238314) (xy 393.453918 -283.277658)
			(xy 393.418425 -283.31175) (xy 393.377922 -283.339706) (xy 393.33346 -283.360804) (xy 393.286189 -283.374496)
			(xy 393.237334 -283.380428) (xy 393.188159 -283.378447) (xy 393.13994 -283.368603) (xy 393.093924 -283.351151)
			(xy 393.051303 -283.326544) (xy 393.013182 -283.295419) (xy 392.980547 -283.258582) (xy 392.954244 -283.216986)
			(xy 392.934953 -283.17171) (xy 392.923176 -283.123926) (xy 392.919216 -283.074872) (xy 392.580114 -283.074872)
			(xy 392.579619 -283.099479) (xy 392.571724 -283.148056) (xy 392.55614 -283.194737) (xy 392.533269 -283.238314)
			(xy 392.503704 -283.277658) (xy 392.468211 -283.31175) (xy 392.427708 -283.339706) (xy 392.383246 -283.360804)
			(xy 392.335975 -283.374496) (xy 392.28712 -283.380428) (xy 392.237945 -283.378447) (xy 392.189726 -283.368603)
			(xy 392.14371 -283.351151) (xy 392.101089 -283.326544) (xy 392.062968 -283.295419) (xy 392.030333 -283.258582)
			(xy 392.00403 -283.216986) (xy 391.984739 -283.17171) (xy 391.972962 -283.123926) (xy 391.969002 -283.074872)
			(xy 391.630154 -283.074872) (xy 391.629659 -283.099479) (xy 391.621764 -283.148056) (xy 391.60618 -283.194737)
			(xy 391.583309 -283.238314) (xy 391.553744 -283.277658) (xy 391.518251 -283.31175) (xy 391.477748 -283.339706)
			(xy 391.433286 -283.360804) (xy 391.386015 -283.374496) (xy 391.33716 -283.380428) (xy 391.287985 -283.378447)
			(xy 391.239766 -283.368603) (xy 391.19375 -283.351151) (xy 391.151129 -283.326544) (xy 391.113008 -283.295419)
			(xy 391.080373 -283.258582) (xy 391.05407 -283.216986) (xy 391.034779 -283.17171) (xy 391.023002 -283.123926)
			(xy 391.019042 -283.074872) (xy 390.680194 -283.074872) (xy 390.679699 -283.099479) (xy 390.671804 -283.148056)
			(xy 390.65622 -283.194737) (xy 390.633349 -283.238314) (xy 390.603784 -283.277658) (xy 390.568291 -283.31175)
			(xy 390.527788 -283.339706) (xy 390.483326 -283.360804) (xy 390.436055 -283.374496) (xy 390.3872 -283.380428)
			(xy 390.338025 -283.378447) (xy 390.289806 -283.368603) (xy 390.24379 -283.351151) (xy 390.201169 -283.326544)
			(xy 390.163048 -283.295419) (xy 390.130413 -283.258582) (xy 390.10411 -283.216986) (xy 390.084819 -283.17171)
			(xy 390.073042 -283.123926) (xy 390.069082 -283.074872) (xy 389.730234 -283.074872) (xy 389.729739 -283.099479)
			(xy 389.721844 -283.148056) (xy 389.70626 -283.194737) (xy 389.683389 -283.238314) (xy 389.653824 -283.277658)
			(xy 389.618331 -283.31175) (xy 389.577828 -283.339706) (xy 389.533366 -283.360804) (xy 389.486095 -283.374496)
			(xy 389.43724 -283.380428) (xy 389.388065 -283.378447) (xy 389.339846 -283.368603) (xy 389.29383 -283.351151)
			(xy 389.251209 -283.326544) (xy 389.213088 -283.295419) (xy 389.180453 -283.258582) (xy 389.15415 -283.216986)
			(xy 389.134859 -283.17171) (xy 389.123082 -283.123926) (xy 389.119122 -283.074872) (xy 388.780274 -283.074872)
			(xy 388.779779 -283.099479) (xy 388.771884 -283.148056) (xy 388.7563 -283.194737) (xy 388.733429 -283.238314)
			(xy 388.703864 -283.277658) (xy 388.668371 -283.31175) (xy 388.627868 -283.339706) (xy 388.583406 -283.360804)
			(xy 388.536135 -283.374496) (xy 388.48728 -283.380428) (xy 388.438105 -283.378447) (xy 388.389886 -283.368603)
			(xy 388.34387 -283.351151) (xy 388.301249 -283.326544) (xy 388.263128 -283.295419) (xy 388.230493 -283.258582)
			(xy 388.20419 -283.216986) (xy 388.184899 -283.17171) (xy 388.173122 -283.123926) (xy 388.169162 -283.074872)
			(xy 387.830314 -283.074872) (xy 387.829819 -283.099479) (xy 387.821924 -283.148056) (xy 387.80634 -283.194737)
			(xy 387.783469 -283.238314) (xy 387.753904 -283.277658) (xy 387.718411 -283.31175) (xy 387.677908 -283.339706)
			(xy 387.633446 -283.360804) (xy 387.586175 -283.374496) (xy 387.53732 -283.380428) (xy 387.488145 -283.378447)
			(xy 387.439926 -283.368603) (xy 387.39391 -283.351151) (xy 387.351289 -283.326544) (xy 387.313168 -283.295419)
			(xy 387.280533 -283.258582) (xy 387.25423 -283.216986) (xy 387.234939 -283.17171) (xy 387.223162 -283.123926)
			(xy 387.219202 -283.074872) (xy 386.880801 -283.074872) (xy 386.880803 -283.0749) (xy 386.876633 -283.125229)
			(xy 386.864237 -283.174185) (xy 386.843953 -283.220433) (xy 386.816333 -283.262713) (xy 386.782133 -283.29987)
			(xy 386.742283 -283.330892) (xy 386.697871 -283.354933) (xy 386.650108 -283.371336) (xy 386.600297 -283.379655)
			(xy 386.575046 -283.38018) (xy 386.56151 -283.380025) (xy 386.534546 -283.377609) (xy 386.521198 -283.375354)
			(xy 386.509006 -283.373322) (xy 386.485384 -283.380688) (xy 386.461254 -283.404564) (xy 386.461254 -283.44622)
			(xy 386.502656 -283.487368) (xy 386.519111 -283.50447) (xy 386.547019 -283.542855) (xy 386.568654 -283.585094)
			(xy 386.583494 -283.630172) (xy 386.591184 -283.677003) (xy 386.59181 -283.700728) (xy 386.59181 -283.701744)
			(xy 386.592318 -283.720032) (xy 386.616995 -283.721841) (xy 386.665295 -283.732576) (xy 386.711232 -283.750959)
			(xy 386.753604 -283.776509) (xy 386.791302 -283.808556) (xy 386.823339 -283.846263) (xy 386.848877 -283.888642)
			(xy 386.867248 -283.934584) (xy 386.877971 -283.982887) (xy 386.879846 -284.00756) (xy 386.89915 -284.008068)
			(xy 386.899912 -284.008068) (xy 386.923559 -284.008743) (xy 386.970224 -284.016502) (xy 387.015134 -284.031367)
			(xy 387.057213 -284.052982) (xy 387.095453 -284.08083) (xy 387.11251 -284.097222) (xy 387.138672 -284.123638)
			(xy 387.146083 -284.130464) (xy 387.164674 -284.138191) (xy 387.17474 -284.138624) (xy 387.195314 -284.138624)
			(xy 387.21919 -284.114494) (xy 387.226556 -284.090872) (xy 387.224524 -284.07868) (xy 387.222282 -284.06533)
			(xy 387.219862 -284.038367) (xy 387.219698 -284.024832) (xy 387.220143 -284.000008) (xy 387.228171 -283.951013)
			(xy 387.244019 -283.903963) (xy 387.26727 -283.860096) (xy 387.297312 -283.820569) (xy 387.333353 -283.786423)
			(xy 387.374443 -283.758558) (xy 387.419501 -283.737708) (xy 387.467338 -283.724422) (xy 387.516694 -283.71905)
			(xy 387.566269 -283.721734) (xy 387.614757 -283.732403) (xy 387.66088 -283.750777) (xy 387.703423 -283.77637)
			(xy 387.741264 -283.808509) (xy 387.773408 -283.846346) (xy 387.799007 -283.888886) (xy 387.817386 -283.935007)
			(xy 387.828061 -283.983493) (xy 387.830304 -284.024832) (xy 388.169162 -284.024832) (xy 388.173122 -283.975778)
			(xy 388.184899 -283.927994) (xy 388.20419 -283.882718) (xy 388.230493 -283.841122) (xy 388.263128 -283.804285)
			(xy 388.301249 -283.77316) (xy 388.34387 -283.748553) (xy 388.389886 -283.731101) (xy 388.438105 -283.721257)
			(xy 388.48728 -283.719276) (xy 388.536135 -283.725208) (xy 388.583406 -283.7389) (xy 388.627868 -283.759998)
			(xy 388.668371 -283.787954) (xy 388.703864 -283.822046) (xy 388.733429 -283.86139) (xy 388.7563 -283.904967)
			(xy 388.771884 -283.951648) (xy 388.779779 -284.000225) (xy 388.780274 -284.024832) (xy 389.119122 -284.024832)
			(xy 389.123082 -283.975778) (xy 389.134859 -283.927994) (xy 389.15415 -283.882718) (xy 389.180453 -283.841122)
			(xy 389.213088 -283.804285) (xy 389.251209 -283.77316) (xy 389.29383 -283.748553) (xy 389.339846 -283.731101)
			(xy 389.388065 -283.721257) (xy 389.43724 -283.719276) (xy 389.486095 -283.725208) (xy 389.533366 -283.7389)
			(xy 389.577828 -283.759998) (xy 389.618331 -283.787954) (xy 389.653824 -283.822046) (xy 389.683389 -283.86139)
			(xy 389.70626 -283.904967) (xy 389.721844 -283.951648) (xy 389.729739 -284.000225) (xy 389.730234 -284.024832)
			(xy 390.069082 -284.024832) (xy 390.073042 -283.975778) (xy 390.084819 -283.927994) (xy 390.10411 -283.882718)
			(xy 390.130413 -283.841122) (xy 390.163048 -283.804285) (xy 390.201169 -283.77316) (xy 390.24379 -283.748553)
			(xy 390.289806 -283.731101) (xy 390.338025 -283.721257) (xy 390.3872 -283.719276) (xy 390.436055 -283.725208)
			(xy 390.483326 -283.7389) (xy 390.527788 -283.759998) (xy 390.568291 -283.787954) (xy 390.603784 -283.822046)
			(xy 390.633349 -283.86139) (xy 390.65622 -283.904967) (xy 390.671804 -283.951648) (xy 390.679699 -284.000225)
			(xy 390.680194 -284.024832) (xy 391.019042 -284.024832) (xy 391.023002 -283.975778) (xy 391.034779 -283.927994)
			(xy 391.05407 -283.882718) (xy 391.080373 -283.841122) (xy 391.113008 -283.804285) (xy 391.151129 -283.77316)
			(xy 391.19375 -283.748553) (xy 391.239766 -283.731101) (xy 391.287985 -283.721257) (xy 391.33716 -283.719276)
			(xy 391.386015 -283.725208) (xy 391.433286 -283.7389) (xy 391.477748 -283.759998) (xy 391.518251 -283.787954)
			(xy 391.553744 -283.822046) (xy 391.583309 -283.86139) (xy 391.60618 -283.904967) (xy 391.621764 -283.951648)
			(xy 391.629659 -284.000225) (xy 391.630154 -284.024832) (xy 391.969002 -284.024832) (xy 391.972962 -283.975778)
			(xy 391.984739 -283.927994) (xy 392.00403 -283.882718) (xy 392.030333 -283.841122) (xy 392.062968 -283.804285)
			(xy 392.101089 -283.77316) (xy 392.14371 -283.748553) (xy 392.189726 -283.731101) (xy 392.237945 -283.721257)
			(xy 392.28712 -283.719276) (xy 392.335975 -283.725208) (xy 392.383246 -283.7389) (xy 392.427708 -283.759998)
			(xy 392.468211 -283.787954) (xy 392.503704 -283.822046) (xy 392.533269 -283.86139) (xy 392.55614 -283.904967)
			(xy 392.571724 -283.951648) (xy 392.579619 -284.000225) (xy 392.580114 -284.024832) (xy 392.919216 -284.024832)
			(xy 392.923176 -283.975778) (xy 392.934953 -283.927994) (xy 392.954244 -283.882718) (xy 392.980547 -283.841122)
			(xy 393.013182 -283.804285) (xy 393.051303 -283.77316) (xy 393.093924 -283.748553) (xy 393.13994 -283.731101)
			(xy 393.188159 -283.721257) (xy 393.237334 -283.719276) (xy 393.286189 -283.725208) (xy 393.33346 -283.7389)
			(xy 393.377922 -283.759998) (xy 393.418425 -283.787954) (xy 393.453918 -283.822046) (xy 393.483483 -283.86139)
			(xy 393.506354 -283.904967) (xy 393.521938 -283.951648) (xy 393.529833 -284.000225) (xy 393.530328 -284.024832)
			(xy 393.869176 -284.024832) (xy 393.873136 -283.975778) (xy 393.884913 -283.927994) (xy 393.904204 -283.882718)
			(xy 393.930507 -283.841122) (xy 393.963142 -283.804285) (xy 394.001263 -283.77316) (xy 394.043884 -283.748553)
			(xy 394.0899 -283.731101) (xy 394.138119 -283.721257) (xy 394.187294 -283.719276) (xy 394.236149 -283.725208)
			(xy 394.28342 -283.7389) (xy 394.327882 -283.759998) (xy 394.368385 -283.787954) (xy 394.403878 -283.822046)
			(xy 394.433443 -283.86139) (xy 394.456314 -283.904967) (xy 394.471898 -283.951648) (xy 394.479793 -284.000225)
			(xy 394.480288 -284.024832) (xy 394.819136 -284.024832) (xy 394.823096 -283.975778) (xy 394.834873 -283.927994)
			(xy 394.854164 -283.882718) (xy 394.880467 -283.841122) (xy 394.913102 -283.804285) (xy 394.951223 -283.77316)
			(xy 394.993844 -283.748553) (xy 395.03986 -283.731101) (xy 395.088079 -283.721257) (xy 395.137254 -283.719276)
			(xy 395.186109 -283.725208) (xy 395.23338 -283.7389) (xy 395.277842 -283.759998) (xy 395.318345 -283.787954)
			(xy 395.353838 -283.822046) (xy 395.383403 -283.86139) (xy 395.406274 -283.904967) (xy 395.421858 -283.951648)
			(xy 395.429753 -284.000225) (xy 395.430248 -284.024832) (xy 395.769096 -284.024832) (xy 395.773056 -283.975778)
			(xy 395.784833 -283.927994) (xy 395.804124 -283.882718) (xy 395.830427 -283.841122) (xy 395.863062 -283.804285)
			(xy 395.901183 -283.77316) (xy 395.943804 -283.748553) (xy 395.98982 -283.731101) (xy 396.038039 -283.721257)
			(xy 396.087214 -283.719276) (xy 396.136069 -283.725208) (xy 396.18334 -283.7389) (xy 396.227802 -283.759998)
			(xy 396.268305 -283.787954) (xy 396.303798 -283.822046) (xy 396.333363 -283.86139) (xy 396.356234 -283.904967)
			(xy 396.371818 -283.951648) (xy 396.379713 -284.000225) (xy 396.380208 -284.024832) (xy 396.719056 -284.024832)
			(xy 396.723016 -283.975778) (xy 396.734793 -283.927994) (xy 396.754084 -283.882718) (xy 396.780387 -283.841122)
			(xy 396.813022 -283.804285) (xy 396.851143 -283.77316) (xy 396.893764 -283.748553) (xy 396.93978 -283.731101)
			(xy 396.987999 -283.721257) (xy 397.037174 -283.719276) (xy 397.086029 -283.725208) (xy 397.1333 -283.7389)
			(xy 397.177762 -283.759998) (xy 397.218265 -283.787954) (xy 397.253758 -283.822046) (xy 397.283323 -283.86139)
			(xy 397.306194 -283.904967) (xy 397.321778 -283.951648) (xy 397.329673 -284.000225) (xy 397.330168 -284.024832)
			(xy 397.669016 -284.024832) (xy 397.672976 -283.975778) (xy 397.684753 -283.927994) (xy 397.704044 -283.882718)
			(xy 397.730347 -283.841122) (xy 397.762982 -283.804285) (xy 397.801103 -283.77316) (xy 397.843724 -283.748553)
			(xy 397.88974 -283.731101) (xy 397.937959 -283.721257) (xy 397.987134 -283.719276) (xy 398.035989 -283.725208)
			(xy 398.08326 -283.7389) (xy 398.127722 -283.759998) (xy 398.168225 -283.787954) (xy 398.203718 -283.822046)
			(xy 398.233283 -283.86139) (xy 398.256154 -283.904967) (xy 398.271738 -283.951648) (xy 398.279633 -284.000225)
			(xy 398.280128 -284.024832) (xy 398.61923 -284.024832) (xy 398.62319 -283.975778) (xy 398.634967 -283.927994)
			(xy 398.654258 -283.882718) (xy 398.680561 -283.841122) (xy 398.713196 -283.804285) (xy 398.751317 -283.77316)
			(xy 398.793938 -283.748553) (xy 398.839954 -283.731101) (xy 398.888173 -283.721257) (xy 398.937348 -283.719276)
			(xy 398.986203 -283.725208) (xy 399.033474 -283.7389) (xy 399.077936 -283.759998) (xy 399.118439 -283.787954)
			(xy 399.153932 -283.822046) (xy 399.183497 -283.86139) (xy 399.206368 -283.904967) (xy 399.221952 -283.951648)
			(xy 399.229847 -284.000225) (xy 399.230342 -284.024832) (xy 399.56919 -284.024832) (xy 399.57315 -283.975778)
			(xy 399.584927 -283.927994) (xy 399.604218 -283.882718) (xy 399.630521 -283.841122) (xy 399.663156 -283.804285)
			(xy 399.701277 -283.77316) (xy 399.743898 -283.748553) (xy 399.789914 -283.731101) (xy 399.838133 -283.721257)
			(xy 399.887308 -283.719276) (xy 399.936163 -283.725208) (xy 399.983434 -283.7389) (xy 400.027896 -283.759998)
			(xy 400.068399 -283.787954) (xy 400.103892 -283.822046) (xy 400.133457 -283.86139) (xy 400.156328 -283.904967)
			(xy 400.171912 -283.951648) (xy 400.179807 -284.000225) (xy 400.180302 -284.024832) (xy 400.51915 -284.024832)
			(xy 400.52311 -283.975778) (xy 400.534887 -283.927994) (xy 400.554178 -283.882718) (xy 400.580481 -283.841122)
			(xy 400.613116 -283.804285) (xy 400.651237 -283.77316) (xy 400.693858 -283.748553) (xy 400.739874 -283.731101)
			(xy 400.788093 -283.721257) (xy 400.837268 -283.719276) (xy 400.886123 -283.725208) (xy 400.933394 -283.7389)
			(xy 400.977856 -283.759998) (xy 401.018359 -283.787954) (xy 401.053852 -283.822046) (xy 401.083417 -283.86139)
			(xy 401.106288 -283.904967) (xy 401.121872 -283.951648) (xy 401.129767 -284.000225) (xy 401.130262 -284.024832)
			(xy 401.46911 -284.024832) (xy 401.47307 -283.975778) (xy 401.484847 -283.927994) (xy 401.504138 -283.882718)
			(xy 401.530441 -283.841122) (xy 401.563076 -283.804285) (xy 401.601197 -283.77316) (xy 401.643818 -283.748553)
			(xy 401.689834 -283.731101) (xy 401.738053 -283.721257) (xy 401.787228 -283.719276) (xy 401.836083 -283.725208)
			(xy 401.883354 -283.7389) (xy 401.927816 -283.759998) (xy 401.968319 -283.787954) (xy 402.003812 -283.822046)
			(xy 402.033377 -283.86139) (xy 402.056248 -283.904967) (xy 402.071832 -283.951648) (xy 402.079727 -284.000225)
			(xy 402.080222 -284.024832) (xy 402.41907 -284.024832) (xy 402.42303 -283.975778) (xy 402.434807 -283.927994)
			(xy 402.454098 -283.882718) (xy 402.480401 -283.841122) (xy 402.513036 -283.804285) (xy 402.551157 -283.77316)
			(xy 402.593778 -283.748553) (xy 402.639794 -283.731101) (xy 402.688013 -283.721257) (xy 402.737188 -283.719276)
			(xy 402.786043 -283.725208) (xy 402.833314 -283.7389) (xy 402.877776 -283.759998) (xy 402.918279 -283.787954)
			(xy 402.953772 -283.822046) (xy 402.983337 -283.86139) (xy 403.006208 -283.904967) (xy 403.021792 -283.951648)
			(xy 403.029687 -284.000225) (xy 403.030182 -284.024832) (xy 403.36903 -284.024832) (xy 403.37299 -283.975778)
			(xy 403.384767 -283.927994) (xy 403.404058 -283.882718) (xy 403.430361 -283.841122) (xy 403.462996 -283.804285)
			(xy 403.501117 -283.77316) (xy 403.543738 -283.748553) (xy 403.589754 -283.731101) (xy 403.637973 -283.721257)
			(xy 403.687148 -283.719276) (xy 403.736003 -283.725208) (xy 403.783274 -283.7389) (xy 403.827736 -283.759998)
			(xy 403.868239 -283.787954) (xy 403.903732 -283.822046) (xy 403.933297 -283.86139) (xy 403.956168 -283.904967)
			(xy 403.971752 -283.951648) (xy 403.979647 -284.000225) (xy 403.980142 -284.024832) (xy 404.31899 -284.024832)
			(xy 404.32295 -283.975778) (xy 404.334727 -283.927994) (xy 404.354018 -283.882718) (xy 404.380321 -283.841122)
			(xy 404.412956 -283.804285) (xy 404.451077 -283.77316) (xy 404.493698 -283.748553) (xy 404.539714 -283.731101)
			(xy 404.587933 -283.721257) (xy 404.637108 -283.719276) (xy 404.685963 -283.725208) (xy 404.733234 -283.7389)
			(xy 404.777696 -283.759998) (xy 404.818199 -283.787954) (xy 404.853692 -283.822046) (xy 404.883257 -283.86139)
			(xy 404.906128 -283.904967) (xy 404.921712 -283.951648) (xy 404.929607 -284.000225) (xy 404.930102 -284.024832)
			(xy 405.269204 -284.024832) (xy 405.273164 -283.975778) (xy 405.284941 -283.927994) (xy 405.304232 -283.882718)
			(xy 405.330535 -283.841122) (xy 405.36317 -283.804285) (xy 405.401291 -283.77316) (xy 405.443912 -283.748553)
			(xy 405.489928 -283.731101) (xy 405.538147 -283.721257) (xy 405.587322 -283.719276) (xy 405.636177 -283.725208)
			(xy 405.683448 -283.7389) (xy 405.72791 -283.759998) (xy 405.768413 -283.787954) (xy 405.803906 -283.822046)
			(xy 405.833471 -283.86139) (xy 405.856342 -283.904967) (xy 405.871926 -283.951648) (xy 405.879821 -284.000225)
			(xy 405.880316 -284.024832) (xy 406.219164 -284.024832) (xy 406.223124 -283.975778) (xy 406.234901 -283.927994)
			(xy 406.254192 -283.882718) (xy 406.280495 -283.841122) (xy 406.31313 -283.804285) (xy 406.351251 -283.77316)
			(xy 406.393872 -283.748553) (xy 406.439888 -283.731101) (xy 406.488107 -283.721257) (xy 406.537282 -283.719276)
			(xy 406.586137 -283.725208) (xy 406.633408 -283.7389) (xy 406.67787 -283.759998) (xy 406.718373 -283.787954)
			(xy 406.753866 -283.822046) (xy 406.783431 -283.86139) (xy 406.806302 -283.904967) (xy 406.821886 -283.951648)
			(xy 406.829781 -284.000225) (xy 406.830276 -284.024832) (xy 408.119084 -284.024832) (xy 408.123044 -283.975778)
			(xy 408.134821 -283.927994) (xy 408.154112 -283.882718) (xy 408.180415 -283.841122) (xy 408.21305 -283.804285)
			(xy 408.251171 -283.77316) (xy 408.293792 -283.748553) (xy 408.339808 -283.731101) (xy 408.388027 -283.721257)
			(xy 408.437202 -283.719276) (xy 408.486057 -283.725208) (xy 408.533328 -283.7389) (xy 408.57779 -283.759998)
			(xy 408.618293 -283.787954) (xy 408.653786 -283.822046) (xy 408.683351 -283.86139) (xy 408.706222 -283.904967)
			(xy 408.721806 -283.951648) (xy 408.729701 -284.000225) (xy 408.730196 -284.024832) (xy 409.069044 -284.024832)
			(xy 409.073004 -283.975778) (xy 409.084781 -283.927994) (xy 409.104072 -283.882718) (xy 409.130375 -283.841122)
			(xy 409.16301 -283.804285) (xy 409.201131 -283.77316) (xy 409.243752 -283.748553) (xy 409.289768 -283.731101)
			(xy 409.337987 -283.721257) (xy 409.387162 -283.719276) (xy 409.436017 -283.725208) (xy 409.483288 -283.7389)
			(xy 409.52775 -283.759998) (xy 409.568253 -283.787954) (xy 409.603746 -283.822046) (xy 409.633311 -283.86139)
			(xy 409.656182 -283.904967) (xy 409.671766 -283.951648) (xy 409.679661 -284.000225) (xy 409.680156 -284.024832)
			(xy 410.019004 -284.024832) (xy 410.022964 -283.975778) (xy 410.034741 -283.927994) (xy 410.054032 -283.882718)
			(xy 410.080335 -283.841122) (xy 410.11297 -283.804285) (xy 410.151091 -283.77316) (xy 410.193712 -283.748553)
			(xy 410.239728 -283.731101) (xy 410.287947 -283.721257) (xy 410.337122 -283.719276) (xy 410.385977 -283.725208)
			(xy 410.433248 -283.7389) (xy 410.47771 -283.759998) (xy 410.518213 -283.787954) (xy 410.553706 -283.822046)
			(xy 410.583271 -283.86139) (xy 410.606142 -283.904967) (xy 410.621726 -283.951648) (xy 410.629621 -284.000225)
			(xy 410.630116 -284.024832) (xy 410.969218 -284.024832) (xy 410.973178 -283.975778) (xy 410.984955 -283.927994)
			(xy 411.004246 -283.882718) (xy 411.030549 -283.841122) (xy 411.063184 -283.804285) (xy 411.101305 -283.77316)
			(xy 411.143926 -283.748553) (xy 411.189942 -283.731101) (xy 411.238161 -283.721257) (xy 411.287336 -283.719276)
			(xy 411.336191 -283.725208) (xy 411.383462 -283.7389) (xy 411.427924 -283.759998) (xy 411.468427 -283.787954)
			(xy 411.50392 -283.822046) (xy 411.533485 -283.86139) (xy 411.556356 -283.904967) (xy 411.57194 -283.951648)
			(xy 411.579835 -284.000225) (xy 411.58033 -284.024832) (xy 411.919178 -284.024832) (xy 411.923138 -283.975778)
			(xy 411.934915 -283.927994) (xy 411.954206 -283.882718) (xy 411.980509 -283.841122) (xy 412.013144 -283.804285)
			(xy 412.051265 -283.77316) (xy 412.093886 -283.748553) (xy 412.139902 -283.731101) (xy 412.188121 -283.721257)
			(xy 412.237296 -283.719276) (xy 412.286151 -283.725208) (xy 412.333422 -283.7389) (xy 412.377884 -283.759998)
			(xy 412.418387 -283.787954) (xy 412.45388 -283.822046) (xy 412.483445 -283.86139) (xy 412.506316 -283.904967)
			(xy 412.5219 -283.951648) (xy 412.529795 -284.000225) (xy 412.53029 -284.024832) (xy 412.869138 -284.024832)
			(xy 412.873098 -283.975778) (xy 412.884875 -283.927994) (xy 412.904166 -283.882718) (xy 412.930469 -283.841122)
			(xy 412.963104 -283.804285) (xy 413.001225 -283.77316) (xy 413.043846 -283.748553) (xy 413.089862 -283.731101)
			(xy 413.138081 -283.721257) (xy 413.187256 -283.719276) (xy 413.236111 -283.725208) (xy 413.283382 -283.7389)
			(xy 413.327844 -283.759998) (xy 413.368347 -283.787954) (xy 413.40384 -283.822046) (xy 413.433405 -283.86139)
			(xy 413.456276 -283.904967) (xy 413.47186 -283.951648) (xy 413.479755 -284.000225) (xy 413.48025 -284.024832)
			(xy 413.819098 -284.024832) (xy 413.823058 -283.975778) (xy 413.834835 -283.927994) (xy 413.854126 -283.882718)
			(xy 413.880429 -283.841122) (xy 413.913064 -283.804285) (xy 413.951185 -283.77316) (xy 413.993806 -283.748553)
			(xy 414.039822 -283.731101) (xy 414.088041 -283.721257) (xy 414.137216 -283.719276) (xy 414.186071 -283.725208)
			(xy 414.233342 -283.7389) (xy 414.277804 -283.759998) (xy 414.318307 -283.787954) (xy 414.3538 -283.822046)
			(xy 414.383365 -283.86139) (xy 414.406236 -283.904967) (xy 414.42182 -283.951648) (xy 414.429715 -284.000225)
			(xy 414.43021 -284.024832) (xy 414.769058 -284.024832) (xy 414.773018 -283.975778) (xy 414.784795 -283.927994)
			(xy 414.804086 -283.882718) (xy 414.830389 -283.841122) (xy 414.863024 -283.804285) (xy 414.901145 -283.77316)
			(xy 414.943766 -283.748553) (xy 414.989782 -283.731101) (xy 415.038001 -283.721257) (xy 415.087176 -283.719276)
			(xy 415.136031 -283.725208) (xy 415.183302 -283.7389) (xy 415.227764 -283.759998) (xy 415.268267 -283.787954)
			(xy 415.30376 -283.822046) (xy 415.333325 -283.86139) (xy 415.356196 -283.904967) (xy 415.37178 -283.951648)
			(xy 415.379675 -284.000225) (xy 415.38017 -284.024832) (xy 415.719018 -284.024832) (xy 415.722978 -283.975778)
			(xy 415.734755 -283.927994) (xy 415.754046 -283.882718) (xy 415.780349 -283.841122) (xy 415.812984 -283.804285)
			(xy 415.851105 -283.77316) (xy 415.893726 -283.748553) (xy 415.939742 -283.731101) (xy 415.987961 -283.721257)
			(xy 416.037136 -283.719276) (xy 416.085991 -283.725208) (xy 416.133262 -283.7389) (xy 416.177724 -283.759998)
			(xy 416.218227 -283.787954) (xy 416.25372 -283.822046) (xy 416.283285 -283.86139) (xy 416.306156 -283.904967)
			(xy 416.32174 -283.951648) (xy 416.329635 -284.000225) (xy 416.33013 -284.024832) (xy 416.668978 -284.024832)
			(xy 416.672938 -283.975778) (xy 416.684715 -283.927994) (xy 416.704006 -283.882718) (xy 416.730309 -283.841122)
			(xy 416.762944 -283.804285) (xy 416.801065 -283.77316) (xy 416.843686 -283.748553) (xy 416.889702 -283.731101)
			(xy 416.937921 -283.721257) (xy 416.987096 -283.719276) (xy 417.035951 -283.725208) (xy 417.083222 -283.7389)
			(xy 417.127684 -283.759998) (xy 417.168187 -283.787954) (xy 417.20368 -283.822046) (xy 417.233245 -283.86139)
			(xy 417.256116 -283.904967) (xy 417.2717 -283.951648) (xy 417.279595 -284.000225) (xy 417.28009 -284.024832)
			(xy 417.279595 -284.049439) (xy 417.2717 -284.098016) (xy 417.256116 -284.144697) (xy 417.233245 -284.188274)
			(xy 417.20368 -284.227618) (xy 417.168187 -284.26171) (xy 417.127684 -284.289666) (xy 417.083222 -284.310764)
			(xy 417.035951 -284.324456) (xy 416.987096 -284.330388) (xy 416.937921 -284.328407) (xy 416.889702 -284.318563)
			(xy 416.843686 -284.301111) (xy 416.801065 -284.276504) (xy 416.762944 -284.245379) (xy 416.730309 -284.208542)
			(xy 416.704006 -284.166946) (xy 416.684715 -284.12167) (xy 416.672938 -284.073886) (xy 416.668978 -284.024832)
			(xy 416.33013 -284.024832) (xy 416.329635 -284.049439) (xy 416.32174 -284.098016) (xy 416.306156 -284.144697)
			(xy 416.283285 -284.188274) (xy 416.25372 -284.227618) (xy 416.218227 -284.26171) (xy 416.177724 -284.289666)
			(xy 416.133262 -284.310764) (xy 416.085991 -284.324456) (xy 416.037136 -284.330388) (xy 415.987961 -284.328407)
			(xy 415.939742 -284.318563) (xy 415.893726 -284.301111) (xy 415.851105 -284.276504) (xy 415.812984 -284.245379)
			(xy 415.780349 -284.208542) (xy 415.754046 -284.166946) (xy 415.734755 -284.12167) (xy 415.722978 -284.073886)
			(xy 415.719018 -284.024832) (xy 415.38017 -284.024832) (xy 415.379675 -284.049439) (xy 415.37178 -284.098016)
			(xy 415.356196 -284.144697) (xy 415.333325 -284.188274) (xy 415.30376 -284.227618) (xy 415.268267 -284.26171)
			(xy 415.227764 -284.289666) (xy 415.183302 -284.310764) (xy 415.136031 -284.324456) (xy 415.087176 -284.330388)
			(xy 415.038001 -284.328407) (xy 414.989782 -284.318563) (xy 414.943766 -284.301111) (xy 414.901145 -284.276504)
			(xy 414.863024 -284.245379) (xy 414.830389 -284.208542) (xy 414.804086 -284.166946) (xy 414.784795 -284.12167)
			(xy 414.773018 -284.073886) (xy 414.769058 -284.024832) (xy 414.43021 -284.024832) (xy 414.429715 -284.049439)
			(xy 414.42182 -284.098016) (xy 414.406236 -284.144697) (xy 414.383365 -284.188274) (xy 414.3538 -284.227618)
			(xy 414.318307 -284.26171) (xy 414.277804 -284.289666) (xy 414.233342 -284.310764) (xy 414.186071 -284.324456)
			(xy 414.137216 -284.330388) (xy 414.088041 -284.328407) (xy 414.039822 -284.318563) (xy 413.993806 -284.301111)
			(xy 413.951185 -284.276504) (xy 413.913064 -284.245379) (xy 413.880429 -284.208542) (xy 413.854126 -284.166946)
			(xy 413.834835 -284.12167) (xy 413.823058 -284.073886) (xy 413.819098 -284.024832) (xy 413.48025 -284.024832)
			(xy 413.479755 -284.049439) (xy 413.47186 -284.098016) (xy 413.456276 -284.144697) (xy 413.433405 -284.188274)
			(xy 413.40384 -284.227618) (xy 413.368347 -284.26171) (xy 413.327844 -284.289666) (xy 413.283382 -284.310764)
			(xy 413.236111 -284.324456) (xy 413.187256 -284.330388) (xy 413.138081 -284.328407) (xy 413.089862 -284.318563)
			(xy 413.043846 -284.301111) (xy 413.001225 -284.276504) (xy 412.963104 -284.245379) (xy 412.930469 -284.208542)
			(xy 412.904166 -284.166946) (xy 412.884875 -284.12167) (xy 412.873098 -284.073886) (xy 412.869138 -284.024832)
			(xy 412.53029 -284.024832) (xy 412.529795 -284.049439) (xy 412.5219 -284.098016) (xy 412.506316 -284.144697)
			(xy 412.483445 -284.188274) (xy 412.45388 -284.227618) (xy 412.418387 -284.26171) (xy 412.377884 -284.289666)
			(xy 412.333422 -284.310764) (xy 412.286151 -284.324456) (xy 412.237296 -284.330388) (xy 412.188121 -284.328407)
			(xy 412.139902 -284.318563) (xy 412.093886 -284.301111) (xy 412.051265 -284.276504) (xy 412.013144 -284.245379)
			(xy 411.980509 -284.208542) (xy 411.954206 -284.166946) (xy 411.934915 -284.12167) (xy 411.923138 -284.073886)
			(xy 411.919178 -284.024832) (xy 411.58033 -284.024832) (xy 411.579835 -284.049439) (xy 411.57194 -284.098016)
			(xy 411.556356 -284.144697) (xy 411.533485 -284.188274) (xy 411.50392 -284.227618) (xy 411.468427 -284.26171)
			(xy 411.427924 -284.289666) (xy 411.383462 -284.310764) (xy 411.336191 -284.324456) (xy 411.287336 -284.330388)
			(xy 411.238161 -284.328407) (xy 411.189942 -284.318563) (xy 411.143926 -284.301111) (xy 411.101305 -284.276504)
			(xy 411.063184 -284.245379) (xy 411.030549 -284.208542) (xy 411.004246 -284.166946) (xy 410.984955 -284.12167)
			(xy 410.973178 -284.073886) (xy 410.969218 -284.024832) (xy 410.630116 -284.024832) (xy 410.629621 -284.049439)
			(xy 410.621726 -284.098016) (xy 410.606142 -284.144697) (xy 410.583271 -284.188274) (xy 410.553706 -284.227618)
			(xy 410.518213 -284.26171) (xy 410.47771 -284.289666) (xy 410.433248 -284.310764) (xy 410.385977 -284.324456)
			(xy 410.337122 -284.330388) (xy 410.287947 -284.328407) (xy 410.239728 -284.318563) (xy 410.193712 -284.301111)
			(xy 410.151091 -284.276504) (xy 410.11297 -284.245379) (xy 410.080335 -284.208542) (xy 410.054032 -284.166946)
			(xy 410.034741 -284.12167) (xy 410.022964 -284.073886) (xy 410.019004 -284.024832) (xy 409.680156 -284.024832)
			(xy 409.679661 -284.049439) (xy 409.671766 -284.098016) (xy 409.656182 -284.144697) (xy 409.633311 -284.188274)
			(xy 409.603746 -284.227618) (xy 409.568253 -284.26171) (xy 409.52775 -284.289666) (xy 409.483288 -284.310764)
			(xy 409.436017 -284.324456) (xy 409.387162 -284.330388) (xy 409.337987 -284.328407) (xy 409.289768 -284.318563)
			(xy 409.243752 -284.301111) (xy 409.201131 -284.276504) (xy 409.16301 -284.245379) (xy 409.130375 -284.208542)
			(xy 409.104072 -284.166946) (xy 409.084781 -284.12167) (xy 409.073004 -284.073886) (xy 409.069044 -284.024832)
			(xy 408.730196 -284.024832) (xy 408.729701 -284.049439) (xy 408.721806 -284.098016) (xy 408.706222 -284.144697)
			(xy 408.683351 -284.188274) (xy 408.653786 -284.227618) (xy 408.618293 -284.26171) (xy 408.57779 -284.289666)
			(xy 408.533328 -284.310764) (xy 408.486057 -284.324456) (xy 408.437202 -284.330388) (xy 408.388027 -284.328407)
			(xy 408.339808 -284.318563) (xy 408.293792 -284.301111) (xy 408.251171 -284.276504) (xy 408.21305 -284.245379)
			(xy 408.180415 -284.208542) (xy 408.154112 -284.166946) (xy 408.134821 -284.12167) (xy 408.123044 -284.073886)
			(xy 408.119084 -284.024832) (xy 406.830276 -284.024832) (xy 406.829781 -284.049439) (xy 406.821886 -284.098016)
			(xy 406.806302 -284.144697) (xy 406.783431 -284.188274) (xy 406.753866 -284.227618) (xy 406.718373 -284.26171)
			(xy 406.67787 -284.289666) (xy 406.633408 -284.310764) (xy 406.586137 -284.324456) (xy 406.537282 -284.330388)
			(xy 406.488107 -284.328407) (xy 406.439888 -284.318563) (xy 406.393872 -284.301111) (xy 406.351251 -284.276504)
			(xy 406.31313 -284.245379) (xy 406.280495 -284.208542) (xy 406.254192 -284.166946) (xy 406.234901 -284.12167)
			(xy 406.223124 -284.073886) (xy 406.219164 -284.024832) (xy 405.880316 -284.024832) (xy 405.879821 -284.049439)
			(xy 405.871926 -284.098016) (xy 405.856342 -284.144697) (xy 405.833471 -284.188274) (xy 405.803906 -284.227618)
			(xy 405.768413 -284.26171) (xy 405.72791 -284.289666) (xy 405.683448 -284.310764) (xy 405.636177 -284.324456)
			(xy 405.587322 -284.330388) (xy 405.538147 -284.328407) (xy 405.489928 -284.318563) (xy 405.443912 -284.301111)
			(xy 405.401291 -284.276504) (xy 405.36317 -284.245379) (xy 405.330535 -284.208542) (xy 405.304232 -284.166946)
			(xy 405.284941 -284.12167) (xy 405.273164 -284.073886) (xy 405.269204 -284.024832) (xy 404.930102 -284.024832)
			(xy 404.929607 -284.049439) (xy 404.921712 -284.098016) (xy 404.906128 -284.144697) (xy 404.883257 -284.188274)
			(xy 404.853692 -284.227618) (xy 404.818199 -284.26171) (xy 404.777696 -284.289666) (xy 404.733234 -284.310764)
			(xy 404.685963 -284.324456) (xy 404.637108 -284.330388) (xy 404.587933 -284.328407) (xy 404.539714 -284.318563)
			(xy 404.493698 -284.301111) (xy 404.451077 -284.276504) (xy 404.412956 -284.245379) (xy 404.380321 -284.208542)
			(xy 404.354018 -284.166946) (xy 404.334727 -284.12167) (xy 404.32295 -284.073886) (xy 404.31899 -284.024832)
			(xy 403.980142 -284.024832) (xy 403.979647 -284.049439) (xy 403.971752 -284.098016) (xy 403.956168 -284.144697)
			(xy 403.933297 -284.188274) (xy 403.903732 -284.227618) (xy 403.868239 -284.26171) (xy 403.827736 -284.289666)
			(xy 403.783274 -284.310764) (xy 403.736003 -284.324456) (xy 403.687148 -284.330388) (xy 403.637973 -284.328407)
			(xy 403.589754 -284.318563) (xy 403.543738 -284.301111) (xy 403.501117 -284.276504) (xy 403.462996 -284.245379)
			(xy 403.430361 -284.208542) (xy 403.404058 -284.166946) (xy 403.384767 -284.12167) (xy 403.37299 -284.073886)
			(xy 403.36903 -284.024832) (xy 403.030182 -284.024832) (xy 403.029687 -284.049439) (xy 403.021792 -284.098016)
			(xy 403.006208 -284.144697) (xy 402.983337 -284.188274) (xy 402.953772 -284.227618) (xy 402.918279 -284.26171)
			(xy 402.877776 -284.289666) (xy 402.833314 -284.310764) (xy 402.786043 -284.324456) (xy 402.737188 -284.330388)
			(xy 402.688013 -284.328407) (xy 402.639794 -284.318563) (xy 402.593778 -284.301111) (xy 402.551157 -284.276504)
			(xy 402.513036 -284.245379) (xy 402.480401 -284.208542) (xy 402.454098 -284.166946) (xy 402.434807 -284.12167)
			(xy 402.42303 -284.073886) (xy 402.41907 -284.024832) (xy 402.080222 -284.024832) (xy 402.079727 -284.049439)
			(xy 402.071832 -284.098016) (xy 402.056248 -284.144697) (xy 402.033377 -284.188274) (xy 402.003812 -284.227618)
			(xy 401.968319 -284.26171) (xy 401.927816 -284.289666) (xy 401.883354 -284.310764) (xy 401.836083 -284.324456)
			(xy 401.787228 -284.330388) (xy 401.738053 -284.328407) (xy 401.689834 -284.318563) (xy 401.643818 -284.301111)
			(xy 401.601197 -284.276504) (xy 401.563076 -284.245379) (xy 401.530441 -284.208542) (xy 401.504138 -284.166946)
			(xy 401.484847 -284.12167) (xy 401.47307 -284.073886) (xy 401.46911 -284.024832) (xy 401.130262 -284.024832)
			(xy 401.129767 -284.049439) (xy 401.121872 -284.098016) (xy 401.106288 -284.144697) (xy 401.083417 -284.188274)
			(xy 401.053852 -284.227618) (xy 401.018359 -284.26171) (xy 400.977856 -284.289666) (xy 400.933394 -284.310764)
			(xy 400.886123 -284.324456) (xy 400.837268 -284.330388) (xy 400.788093 -284.328407) (xy 400.739874 -284.318563)
			(xy 400.693858 -284.301111) (xy 400.651237 -284.276504) (xy 400.613116 -284.245379) (xy 400.580481 -284.208542)
			(xy 400.554178 -284.166946) (xy 400.534887 -284.12167) (xy 400.52311 -284.073886) (xy 400.51915 -284.024832)
			(xy 400.180302 -284.024832) (xy 400.179807 -284.049439) (xy 400.171912 -284.098016) (xy 400.156328 -284.144697)
			(xy 400.133457 -284.188274) (xy 400.103892 -284.227618) (xy 400.068399 -284.26171) (xy 400.027896 -284.289666)
			(xy 399.983434 -284.310764) (xy 399.936163 -284.324456) (xy 399.887308 -284.330388) (xy 399.838133 -284.328407)
			(xy 399.789914 -284.318563) (xy 399.743898 -284.301111) (xy 399.701277 -284.276504) (xy 399.663156 -284.245379)
			(xy 399.630521 -284.208542) (xy 399.604218 -284.166946) (xy 399.584927 -284.12167) (xy 399.57315 -284.073886)
			(xy 399.56919 -284.024832) (xy 399.230342 -284.024832) (xy 399.229847 -284.049439) (xy 399.221952 -284.098016)
			(xy 399.206368 -284.144697) (xy 399.183497 -284.188274) (xy 399.153932 -284.227618) (xy 399.118439 -284.26171)
			(xy 399.077936 -284.289666) (xy 399.033474 -284.310764) (xy 398.986203 -284.324456) (xy 398.937348 -284.330388)
			(xy 398.888173 -284.328407) (xy 398.839954 -284.318563) (xy 398.793938 -284.301111) (xy 398.751317 -284.276504)
			(xy 398.713196 -284.245379) (xy 398.680561 -284.208542) (xy 398.654258 -284.166946) (xy 398.634967 -284.12167)
			(xy 398.62319 -284.073886) (xy 398.61923 -284.024832) (xy 398.280128 -284.024832) (xy 398.279633 -284.049439)
			(xy 398.271738 -284.098016) (xy 398.256154 -284.144697) (xy 398.233283 -284.188274) (xy 398.203718 -284.227618)
			(xy 398.168225 -284.26171) (xy 398.127722 -284.289666) (xy 398.08326 -284.310764) (xy 398.035989 -284.324456)
			(xy 397.987134 -284.330388) (xy 397.937959 -284.328407) (xy 397.88974 -284.318563) (xy 397.843724 -284.301111)
			(xy 397.801103 -284.276504) (xy 397.762982 -284.245379) (xy 397.730347 -284.208542) (xy 397.704044 -284.166946)
			(xy 397.684753 -284.12167) (xy 397.672976 -284.073886) (xy 397.669016 -284.024832) (xy 397.330168 -284.024832)
			(xy 397.329673 -284.049439) (xy 397.321778 -284.098016) (xy 397.306194 -284.144697) (xy 397.283323 -284.188274)
			(xy 397.253758 -284.227618) (xy 397.218265 -284.26171) (xy 397.177762 -284.289666) (xy 397.1333 -284.310764)
			(xy 397.086029 -284.324456) (xy 397.037174 -284.330388) (xy 396.987999 -284.328407) (xy 396.93978 -284.318563)
			(xy 396.893764 -284.301111) (xy 396.851143 -284.276504) (xy 396.813022 -284.245379) (xy 396.780387 -284.208542)
			(xy 396.754084 -284.166946) (xy 396.734793 -284.12167) (xy 396.723016 -284.073886) (xy 396.719056 -284.024832)
			(xy 396.380208 -284.024832) (xy 396.379713 -284.049439) (xy 396.371818 -284.098016) (xy 396.356234 -284.144697)
			(xy 396.333363 -284.188274) (xy 396.303798 -284.227618) (xy 396.268305 -284.26171) (xy 396.227802 -284.289666)
			(xy 396.18334 -284.310764) (xy 396.136069 -284.324456) (xy 396.087214 -284.330388) (xy 396.038039 -284.328407)
			(xy 395.98982 -284.318563) (xy 395.943804 -284.301111) (xy 395.901183 -284.276504) (xy 395.863062 -284.245379)
			(xy 395.830427 -284.208542) (xy 395.804124 -284.166946) (xy 395.784833 -284.12167) (xy 395.773056 -284.073886)
			(xy 395.769096 -284.024832) (xy 395.430248 -284.024832) (xy 395.429753 -284.049439) (xy 395.421858 -284.098016)
			(xy 395.406274 -284.144697) (xy 395.383403 -284.188274) (xy 395.353838 -284.227618) (xy 395.318345 -284.26171)
			(xy 395.277842 -284.289666) (xy 395.23338 -284.310764) (xy 395.186109 -284.324456) (xy 395.137254 -284.330388)
			(xy 395.088079 -284.328407) (xy 395.03986 -284.318563) (xy 394.993844 -284.301111) (xy 394.951223 -284.276504)
			(xy 394.913102 -284.245379) (xy 394.880467 -284.208542) (xy 394.854164 -284.166946) (xy 394.834873 -284.12167)
			(xy 394.823096 -284.073886) (xy 394.819136 -284.024832) (xy 394.480288 -284.024832) (xy 394.479793 -284.049439)
			(xy 394.471898 -284.098016) (xy 394.456314 -284.144697) (xy 394.433443 -284.188274) (xy 394.403878 -284.227618)
			(xy 394.368385 -284.26171) (xy 394.327882 -284.289666) (xy 394.28342 -284.310764) (xy 394.236149 -284.324456)
			(xy 394.187294 -284.330388) (xy 394.138119 -284.328407) (xy 394.0899 -284.318563) (xy 394.043884 -284.301111)
			(xy 394.001263 -284.276504) (xy 393.963142 -284.245379) (xy 393.930507 -284.208542) (xy 393.904204 -284.166946)
			(xy 393.884913 -284.12167) (xy 393.873136 -284.073886) (xy 393.869176 -284.024832) (xy 393.530328 -284.024832)
			(xy 393.529833 -284.049439) (xy 393.521938 -284.098016) (xy 393.506354 -284.144697) (xy 393.483483 -284.188274)
			(xy 393.453918 -284.227618) (xy 393.418425 -284.26171) (xy 393.377922 -284.289666) (xy 393.33346 -284.310764)
			(xy 393.286189 -284.324456) (xy 393.237334 -284.330388) (xy 393.188159 -284.328407) (xy 393.13994 -284.318563)
			(xy 393.093924 -284.301111) (xy 393.051303 -284.276504) (xy 393.013182 -284.245379) (xy 392.980547 -284.208542)
			(xy 392.954244 -284.166946) (xy 392.934953 -284.12167) (xy 392.923176 -284.073886) (xy 392.919216 -284.024832)
			(xy 392.580114 -284.024832) (xy 392.579619 -284.049439) (xy 392.571724 -284.098016) (xy 392.55614 -284.144697)
			(xy 392.533269 -284.188274) (xy 392.503704 -284.227618) (xy 392.468211 -284.26171) (xy 392.427708 -284.289666)
			(xy 392.383246 -284.310764) (xy 392.335975 -284.324456) (xy 392.28712 -284.330388) (xy 392.237945 -284.328407)
			(xy 392.189726 -284.318563) (xy 392.14371 -284.301111) (xy 392.101089 -284.276504) (xy 392.062968 -284.245379)
			(xy 392.030333 -284.208542) (xy 392.00403 -284.166946) (xy 391.984739 -284.12167) (xy 391.972962 -284.073886)
			(xy 391.969002 -284.024832) (xy 391.630154 -284.024832) (xy 391.629659 -284.049439) (xy 391.621764 -284.098016)
			(xy 391.60618 -284.144697) (xy 391.583309 -284.188274) (xy 391.553744 -284.227618) (xy 391.518251 -284.26171)
			(xy 391.477748 -284.289666) (xy 391.433286 -284.310764) (xy 391.386015 -284.324456) (xy 391.33716 -284.330388)
			(xy 391.287985 -284.328407) (xy 391.239766 -284.318563) (xy 391.19375 -284.301111) (xy 391.151129 -284.276504)
			(xy 391.113008 -284.245379) (xy 391.080373 -284.208542) (xy 391.05407 -284.166946) (xy 391.034779 -284.12167)
			(xy 391.023002 -284.073886) (xy 391.019042 -284.024832) (xy 390.680194 -284.024832) (xy 390.679699 -284.049439)
			(xy 390.671804 -284.098016) (xy 390.65622 -284.144697) (xy 390.633349 -284.188274) (xy 390.603784 -284.227618)
			(xy 390.568291 -284.26171) (xy 390.527788 -284.289666) (xy 390.483326 -284.310764) (xy 390.436055 -284.324456)
			(xy 390.3872 -284.330388) (xy 390.338025 -284.328407) (xy 390.289806 -284.318563) (xy 390.24379 -284.301111)
			(xy 390.201169 -284.276504) (xy 390.163048 -284.245379) (xy 390.130413 -284.208542) (xy 390.10411 -284.166946)
			(xy 390.084819 -284.12167) (xy 390.073042 -284.073886) (xy 390.069082 -284.024832) (xy 389.730234 -284.024832)
			(xy 389.729739 -284.049439) (xy 389.721844 -284.098016) (xy 389.70626 -284.144697) (xy 389.683389 -284.188274)
			(xy 389.653824 -284.227618) (xy 389.618331 -284.26171) (xy 389.577828 -284.289666) (xy 389.533366 -284.310764)
			(xy 389.486095 -284.324456) (xy 389.43724 -284.330388) (xy 389.388065 -284.328407) (xy 389.339846 -284.318563)
			(xy 389.29383 -284.301111) (xy 389.251209 -284.276504) (xy 389.213088 -284.245379) (xy 389.180453 -284.208542)
			(xy 389.15415 -284.166946) (xy 389.134859 -284.12167) (xy 389.123082 -284.073886) (xy 389.119122 -284.024832)
			(xy 388.780274 -284.024832) (xy 388.779779 -284.049439) (xy 388.771884 -284.098016) (xy 388.7563 -284.144697)
			(xy 388.733429 -284.188274) (xy 388.703864 -284.227618) (xy 388.668371 -284.26171) (xy 388.627868 -284.289666)
			(xy 388.583406 -284.310764) (xy 388.536135 -284.324456) (xy 388.48728 -284.330388) (xy 388.438105 -284.328407)
			(xy 388.389886 -284.318563) (xy 388.34387 -284.301111) (xy 388.301249 -284.276504) (xy 388.263128 -284.245379)
			(xy 388.230493 -284.208542) (xy 388.20419 -284.166946) (xy 388.184899 -284.12167) (xy 388.173122 -284.073886)
			(xy 388.169162 -284.024832) (xy 387.830304 -284.024832) (xy 387.830751 -284.033068) (xy 387.825386 -284.082425)
			(xy 387.812106 -284.130264) (xy 387.791261 -284.175324) (xy 387.763401 -284.216418) (xy 387.729259 -284.252463)
			(xy 387.689736 -284.28251) (xy 387.645872 -284.305766) (xy 387.598823 -284.32162) (xy 387.54983 -284.329653)
			(xy 387.525006 -284.33014) (xy 387.51147 -284.32999) (xy 387.484506 -284.32757) (xy 387.471158 -284.325314)
			(xy 387.458966 -284.323282) (xy 387.435344 -284.330648) (xy 387.411214 -284.354524) (xy 387.411214 -284.39618)
			(xy 387.452616 -284.437328) (xy 387.469046 -284.454453) (xy 387.496958 -284.492831) (xy 387.518598 -284.535065)
			(xy 387.533445 -284.580138) (xy 387.541141 -284.626965) (xy 387.54177 -284.650688) (xy 387.54177 -284.651704)
			(xy 387.542278 -284.669992) (xy 387.566948 -284.671872) (xy 387.615243 -284.6826) (xy 387.661178 -284.700974)
			(xy 387.703548 -284.726515) (xy 387.741246 -284.758553) (xy 387.773284 -284.79625) (xy 387.798825 -284.838621)
			(xy 387.8172 -284.884555) (xy 387.827928 -284.93285) (xy 387.829806 -284.95752) (xy 387.84911 -284.958028)
			(xy 387.849872 -284.958028) (xy 387.87352 -284.958677) (xy 387.920186 -284.966444) (xy 387.965095 -284.981316)
			(xy 388.007173 -285.002936) (xy 388.045413 -285.030788) (xy 388.06247 -285.047182) (xy 388.088632 -285.073598)
			(xy 388.096027 -285.080444) (xy 388.11463 -285.08816) (xy 388.1247 -285.088584) (xy 388.145274 -285.088584)
			(xy 388.16915 -285.064454) (xy 388.176516 -285.040832) (xy 388.174484 -285.02864) (xy 388.172236 -285.015291)
			(xy 388.16982 -284.988328) (xy 388.169658 -284.974792) (xy 388.170187 -284.949971) (xy 388.178219 -284.900984)
			(xy 388.194071 -284.853942) (xy 388.217325 -284.810084) (xy 388.247368 -284.770566) (xy 388.283409 -284.736429)
			(xy 388.324498 -284.708573) (xy 388.369552 -284.687731) (xy 388.417384 -284.674453) (xy 388.466735 -284.669089)
			(xy 388.516303 -284.671779) (xy 388.564783 -284.682453) (xy 388.610898 -284.70083) (xy 388.653432 -284.726426)
			(xy 388.691264 -284.758565) (xy 388.723399 -284.796402) (xy 388.748988 -284.83894) (xy 388.767359 -284.885057)
			(xy 388.778027 -284.933538) (xy 388.78026 -284.974792) (xy 389.119122 -284.974792) (xy 389.123082 -284.925738)
			(xy 389.134859 -284.877954) (xy 389.15415 -284.832678) (xy 389.180453 -284.791082) (xy 389.213088 -284.754245)
			(xy 389.251209 -284.72312) (xy 389.29383 -284.698513) (xy 389.339846 -284.681061) (xy 389.388065 -284.671217)
			(xy 389.43724 -284.669236) (xy 389.486095 -284.675168) (xy 389.533366 -284.68886) (xy 389.577828 -284.709958)
			(xy 389.618331 -284.737914) (xy 389.653824 -284.772006) (xy 389.683389 -284.81135) (xy 389.70626 -284.854927)
			(xy 389.721844 -284.901608) (xy 389.729739 -284.950185) (xy 389.730234 -284.974792) (xy 391.019042 -284.974792)
			(xy 391.023002 -284.925738) (xy 391.034779 -284.877954) (xy 391.05407 -284.832678) (xy 391.080373 -284.791082)
			(xy 391.113008 -284.754245) (xy 391.151129 -284.72312) (xy 391.19375 -284.698513) (xy 391.239766 -284.681061)
			(xy 391.287985 -284.671217) (xy 391.33716 -284.669236) (xy 391.386015 -284.675168) (xy 391.433286 -284.68886)
			(xy 391.477748 -284.709958) (xy 391.518251 -284.737914) (xy 391.553744 -284.772006) (xy 391.583309 -284.81135)
			(xy 391.60618 -284.854927) (xy 391.621764 -284.901608) (xy 391.629659 -284.950185) (xy 391.630154 -284.974792)
			(xy 392.919216 -284.974792) (xy 392.923176 -284.925738) (xy 392.934953 -284.877954) (xy 392.954244 -284.832678)
			(xy 392.980547 -284.791082) (xy 393.013182 -284.754245) (xy 393.051303 -284.72312) (xy 393.093924 -284.698513)
			(xy 393.13994 -284.681061) (xy 393.188159 -284.671217) (xy 393.237334 -284.669236) (xy 393.286189 -284.675168)
			(xy 393.33346 -284.68886) (xy 393.377922 -284.709958) (xy 393.418425 -284.737914) (xy 393.453918 -284.772006)
			(xy 393.483483 -284.81135) (xy 393.506354 -284.854927) (xy 393.521938 -284.901608) (xy 393.529833 -284.950185)
			(xy 393.530328 -284.974792) (xy 393.869176 -284.974792) (xy 393.873136 -284.925738) (xy 393.884913 -284.877954)
			(xy 393.904204 -284.832678) (xy 393.930507 -284.791082) (xy 393.963142 -284.754245) (xy 394.001263 -284.72312)
			(xy 394.043884 -284.698513) (xy 394.0899 -284.681061) (xy 394.138119 -284.671217) (xy 394.187294 -284.669236)
			(xy 394.236149 -284.675168) (xy 394.28342 -284.68886) (xy 394.327882 -284.709958) (xy 394.368385 -284.737914)
			(xy 394.403878 -284.772006) (xy 394.433443 -284.81135) (xy 394.456314 -284.854927) (xy 394.471898 -284.901608)
			(xy 394.479793 -284.950185) (xy 394.480288 -284.974792) (xy 394.819136 -284.974792) (xy 394.823096 -284.925738)
			(xy 394.834873 -284.877954) (xy 394.854164 -284.832678) (xy 394.880467 -284.791082) (xy 394.913102 -284.754245)
			(xy 394.951223 -284.72312) (xy 394.993844 -284.698513) (xy 395.03986 -284.681061) (xy 395.088079 -284.671217)
			(xy 395.137254 -284.669236) (xy 395.186109 -284.675168) (xy 395.23338 -284.68886) (xy 395.277842 -284.709958)
			(xy 395.318345 -284.737914) (xy 395.353838 -284.772006) (xy 395.383403 -284.81135) (xy 395.406274 -284.854927)
			(xy 395.421858 -284.901608) (xy 395.429753 -284.950185) (xy 395.430248 -284.974792) (xy 395.769096 -284.974792)
			(xy 395.773056 -284.925738) (xy 395.784833 -284.877954) (xy 395.804124 -284.832678) (xy 395.830427 -284.791082)
			(xy 395.863062 -284.754245) (xy 395.901183 -284.72312) (xy 395.943804 -284.698513) (xy 395.98982 -284.681061)
			(xy 396.038039 -284.671217) (xy 396.087214 -284.669236) (xy 396.136069 -284.675168) (xy 396.18334 -284.68886)
			(xy 396.227802 -284.709958) (xy 396.268305 -284.737914) (xy 396.303798 -284.772006) (xy 396.333363 -284.81135)
			(xy 396.356234 -284.854927) (xy 396.371818 -284.901608) (xy 396.379713 -284.950185) (xy 396.380208 -284.974792)
			(xy 396.719056 -284.974792) (xy 396.723016 -284.925738) (xy 396.734793 -284.877954) (xy 396.754084 -284.832678)
			(xy 396.780387 -284.791082) (xy 396.813022 -284.754245) (xy 396.851143 -284.72312) (xy 396.893764 -284.698513)
			(xy 396.93978 -284.681061) (xy 396.987999 -284.671217) (xy 397.037174 -284.669236) (xy 397.086029 -284.675168)
			(xy 397.1333 -284.68886) (xy 397.177762 -284.709958) (xy 397.218265 -284.737914) (xy 397.253758 -284.772006)
			(xy 397.283323 -284.81135) (xy 397.306194 -284.854927) (xy 397.321778 -284.901608) (xy 397.329673 -284.950185)
			(xy 397.330168 -284.974792) (xy 397.669016 -284.974792) (xy 397.672976 -284.925738) (xy 397.684753 -284.877954)
			(xy 397.704044 -284.832678) (xy 397.730347 -284.791082) (xy 397.762982 -284.754245) (xy 397.801103 -284.72312)
			(xy 397.843724 -284.698513) (xy 397.88974 -284.681061) (xy 397.937959 -284.671217) (xy 397.987134 -284.669236)
			(xy 398.035989 -284.675168) (xy 398.08326 -284.68886) (xy 398.127722 -284.709958) (xy 398.168225 -284.737914)
			(xy 398.203718 -284.772006) (xy 398.233283 -284.81135) (xy 398.256154 -284.854927) (xy 398.271738 -284.901608)
			(xy 398.279633 -284.950185) (xy 398.280128 -284.974792) (xy 398.61923 -284.974792) (xy 398.62319 -284.925738)
			(xy 398.634967 -284.877954) (xy 398.654258 -284.832678) (xy 398.680561 -284.791082) (xy 398.713196 -284.754245)
			(xy 398.751317 -284.72312) (xy 398.793938 -284.698513) (xy 398.839954 -284.681061) (xy 398.888173 -284.671217)
			(xy 398.937348 -284.669236) (xy 398.986203 -284.675168) (xy 399.033474 -284.68886) (xy 399.077936 -284.709958)
			(xy 399.118439 -284.737914) (xy 399.153932 -284.772006) (xy 399.183497 -284.81135) (xy 399.206368 -284.854927)
			(xy 399.221952 -284.901608) (xy 399.229847 -284.950185) (xy 399.230342 -284.974792) (xy 399.56919 -284.974792)
			(xy 399.57315 -284.925738) (xy 399.584927 -284.877954) (xy 399.604218 -284.832678) (xy 399.630521 -284.791082)
			(xy 399.663156 -284.754245) (xy 399.701277 -284.72312) (xy 399.743898 -284.698513) (xy 399.789914 -284.681061)
			(xy 399.838133 -284.671217) (xy 399.887308 -284.669236) (xy 399.936163 -284.675168) (xy 399.983434 -284.68886)
			(xy 400.027896 -284.709958) (xy 400.068399 -284.737914) (xy 400.103892 -284.772006) (xy 400.133457 -284.81135)
			(xy 400.156328 -284.854927) (xy 400.171912 -284.901608) (xy 400.179807 -284.950185) (xy 400.180302 -284.974792)
			(xy 400.51915 -284.974792) (xy 400.52311 -284.925738) (xy 400.534887 -284.877954) (xy 400.554178 -284.832678)
			(xy 400.580481 -284.791082) (xy 400.613116 -284.754245) (xy 400.651237 -284.72312) (xy 400.693858 -284.698513)
			(xy 400.739874 -284.681061) (xy 400.788093 -284.671217) (xy 400.837268 -284.669236) (xy 400.886123 -284.675168)
			(xy 400.933394 -284.68886) (xy 400.977856 -284.709958) (xy 401.018359 -284.737914) (xy 401.053852 -284.772006)
			(xy 401.083417 -284.81135) (xy 401.106288 -284.854927) (xy 401.121872 -284.901608) (xy 401.129767 -284.950185)
			(xy 401.130262 -284.974792) (xy 401.46911 -284.974792) (xy 401.47307 -284.925738) (xy 401.484847 -284.877954)
			(xy 401.504138 -284.832678) (xy 401.530441 -284.791082) (xy 401.563076 -284.754245) (xy 401.601197 -284.72312)
			(xy 401.643818 -284.698513) (xy 401.689834 -284.681061) (xy 401.738053 -284.671217) (xy 401.787228 -284.669236)
			(xy 401.836083 -284.675168) (xy 401.883354 -284.68886) (xy 401.927816 -284.709958) (xy 401.968319 -284.737914)
			(xy 402.003812 -284.772006) (xy 402.033377 -284.81135) (xy 402.056248 -284.854927) (xy 402.071832 -284.901608)
			(xy 402.079727 -284.950185) (xy 402.080222 -284.974792) (xy 402.41907 -284.974792) (xy 402.42303 -284.925738)
			(xy 402.434807 -284.877954) (xy 402.454098 -284.832678) (xy 402.480401 -284.791082) (xy 402.513036 -284.754245)
			(xy 402.551157 -284.72312) (xy 402.593778 -284.698513) (xy 402.639794 -284.681061) (xy 402.688013 -284.671217)
			(xy 402.737188 -284.669236) (xy 402.786043 -284.675168) (xy 402.833314 -284.68886) (xy 402.877776 -284.709958)
			(xy 402.918279 -284.737914) (xy 402.953772 -284.772006) (xy 402.983337 -284.81135) (xy 403.006208 -284.854927)
			(xy 403.021792 -284.901608) (xy 403.029687 -284.950185) (xy 403.030182 -284.974792) (xy 403.36903 -284.974792)
			(xy 403.37299 -284.925738) (xy 403.384767 -284.877954) (xy 403.404058 -284.832678) (xy 403.430361 -284.791082)
			(xy 403.462996 -284.754245) (xy 403.501117 -284.72312) (xy 403.543738 -284.698513) (xy 403.589754 -284.681061)
			(xy 403.637973 -284.671217) (xy 403.687148 -284.669236) (xy 403.736003 -284.675168) (xy 403.783274 -284.68886)
			(xy 403.827736 -284.709958) (xy 403.868239 -284.737914) (xy 403.903732 -284.772006) (xy 403.933297 -284.81135)
			(xy 403.956168 -284.854927) (xy 403.971752 -284.901608) (xy 403.979647 -284.950185) (xy 403.980142 -284.974792)
			(xy 404.31899 -284.974792) (xy 404.32295 -284.925738) (xy 404.334727 -284.877954) (xy 404.354018 -284.832678)
			(xy 404.380321 -284.791082) (xy 404.412956 -284.754245) (xy 404.451077 -284.72312) (xy 404.493698 -284.698513)
			(xy 404.539714 -284.681061) (xy 404.587933 -284.671217) (xy 404.637108 -284.669236) (xy 404.685963 -284.675168)
			(xy 404.733234 -284.68886) (xy 404.777696 -284.709958) (xy 404.818199 -284.737914) (xy 404.853692 -284.772006)
			(xy 404.883257 -284.81135) (xy 404.906128 -284.854927) (xy 404.921712 -284.901608) (xy 404.929607 -284.950185)
			(xy 404.930102 -284.974792) (xy 405.269204 -284.974792) (xy 405.273164 -284.925738) (xy 405.284941 -284.877954)
			(xy 405.304232 -284.832678) (xy 405.330535 -284.791082) (xy 405.36317 -284.754245) (xy 405.401291 -284.72312)
			(xy 405.443912 -284.698513) (xy 405.489928 -284.681061) (xy 405.538147 -284.671217) (xy 405.587322 -284.669236)
			(xy 405.636177 -284.675168) (xy 405.683448 -284.68886) (xy 405.72791 -284.709958) (xy 405.768413 -284.737914)
			(xy 405.803906 -284.772006) (xy 405.833471 -284.81135) (xy 405.856342 -284.854927) (xy 405.871926 -284.901608)
			(xy 405.879821 -284.950185) (xy 405.880316 -284.974792) (xy 406.219164 -284.974792) (xy 406.223124 -284.925738)
			(xy 406.234901 -284.877954) (xy 406.254192 -284.832678) (xy 406.280495 -284.791082) (xy 406.31313 -284.754245)
			(xy 406.351251 -284.72312) (xy 406.393872 -284.698513) (xy 406.439888 -284.681061) (xy 406.488107 -284.671217)
			(xy 406.537282 -284.669236) (xy 406.586137 -284.675168) (xy 406.633408 -284.68886) (xy 406.67787 -284.709958)
			(xy 406.718373 -284.737914) (xy 406.753866 -284.772006) (xy 406.783431 -284.81135) (xy 406.806302 -284.854927)
			(xy 406.821886 -284.901608) (xy 406.829781 -284.950185) (xy 406.830276 -284.974792) (xy 408.119084 -284.974792)
			(xy 408.123044 -284.925738) (xy 408.134821 -284.877954) (xy 408.154112 -284.832678) (xy 408.180415 -284.791082)
			(xy 408.21305 -284.754245) (xy 408.251171 -284.72312) (xy 408.293792 -284.698513) (xy 408.339808 -284.681061)
			(xy 408.388027 -284.671217) (xy 408.437202 -284.669236) (xy 408.486057 -284.675168) (xy 408.533328 -284.68886)
			(xy 408.57779 -284.709958) (xy 408.618293 -284.737914) (xy 408.653786 -284.772006) (xy 408.683351 -284.81135)
			(xy 408.706222 -284.854927) (xy 408.721806 -284.901608) (xy 408.729701 -284.950185) (xy 408.730196 -284.974792)
			(xy 409.069044 -284.974792) (xy 409.073004 -284.925738) (xy 409.084781 -284.877954) (xy 409.104072 -284.832678)
			(xy 409.130375 -284.791082) (xy 409.16301 -284.754245) (xy 409.201131 -284.72312) (xy 409.243752 -284.698513)
			(xy 409.289768 -284.681061) (xy 409.337987 -284.671217) (xy 409.387162 -284.669236) (xy 409.436017 -284.675168)
			(xy 409.483288 -284.68886) (xy 409.52775 -284.709958) (xy 409.568253 -284.737914) (xy 409.603746 -284.772006)
			(xy 409.633311 -284.81135) (xy 409.656182 -284.854927) (xy 409.671766 -284.901608) (xy 409.679661 -284.950185)
			(xy 409.680156 -284.974792) (xy 410.019004 -284.974792) (xy 410.022964 -284.925738) (xy 410.034741 -284.877954)
			(xy 410.054032 -284.832678) (xy 410.080335 -284.791082) (xy 410.11297 -284.754245) (xy 410.151091 -284.72312)
			(xy 410.193712 -284.698513) (xy 410.239728 -284.681061) (xy 410.287947 -284.671217) (xy 410.337122 -284.669236)
			(xy 410.385977 -284.675168) (xy 410.433248 -284.68886) (xy 410.47771 -284.709958) (xy 410.518213 -284.737914)
			(xy 410.553706 -284.772006) (xy 410.583271 -284.81135) (xy 410.606142 -284.854927) (xy 410.621726 -284.901608)
			(xy 410.629621 -284.950185) (xy 410.630116 -284.974792) (xy 410.969218 -284.974792) (xy 410.973178 -284.925738)
			(xy 410.984955 -284.877954) (xy 411.004246 -284.832678) (xy 411.030549 -284.791082) (xy 411.063184 -284.754245)
			(xy 411.101305 -284.72312) (xy 411.143926 -284.698513) (xy 411.189942 -284.681061) (xy 411.238161 -284.671217)
			(xy 411.287336 -284.669236) (xy 411.336191 -284.675168) (xy 411.383462 -284.68886) (xy 411.427924 -284.709958)
			(xy 411.468427 -284.737914) (xy 411.50392 -284.772006) (xy 411.533485 -284.81135) (xy 411.556356 -284.854927)
			(xy 411.57194 -284.901608) (xy 411.579835 -284.950185) (xy 411.58033 -284.974792) (xy 411.919178 -284.974792)
			(xy 411.923138 -284.925738) (xy 411.934915 -284.877954) (xy 411.954206 -284.832678) (xy 411.980509 -284.791082)
			(xy 412.013144 -284.754245) (xy 412.051265 -284.72312) (xy 412.093886 -284.698513) (xy 412.139902 -284.681061)
			(xy 412.188121 -284.671217) (xy 412.237296 -284.669236) (xy 412.286151 -284.675168) (xy 412.333422 -284.68886)
			(xy 412.377884 -284.709958) (xy 412.418387 -284.737914) (xy 412.45388 -284.772006) (xy 412.483445 -284.81135)
			(xy 412.506316 -284.854927) (xy 412.5219 -284.901608) (xy 412.529795 -284.950185) (xy 412.53029 -284.974792)
			(xy 412.869138 -284.974792) (xy 412.873098 -284.925738) (xy 412.884875 -284.877954) (xy 412.904166 -284.832678)
			(xy 412.930469 -284.791082) (xy 412.963104 -284.754245) (xy 413.001225 -284.72312) (xy 413.043846 -284.698513)
			(xy 413.089862 -284.681061) (xy 413.138081 -284.671217) (xy 413.187256 -284.669236) (xy 413.236111 -284.675168)
			(xy 413.283382 -284.68886) (xy 413.327844 -284.709958) (xy 413.368347 -284.737914) (xy 413.40384 -284.772006)
			(xy 413.433405 -284.81135) (xy 413.456276 -284.854927) (xy 413.47186 -284.901608) (xy 413.479755 -284.950185)
			(xy 413.48025 -284.974792) (xy 413.819098 -284.974792) (xy 413.823058 -284.925738) (xy 413.834835 -284.877954)
			(xy 413.854126 -284.832678) (xy 413.880429 -284.791082) (xy 413.913064 -284.754245) (xy 413.951185 -284.72312)
			(xy 413.993806 -284.698513) (xy 414.039822 -284.681061) (xy 414.088041 -284.671217) (xy 414.137216 -284.669236)
			(xy 414.186071 -284.675168) (xy 414.233342 -284.68886) (xy 414.277804 -284.709958) (xy 414.318307 -284.737914)
			(xy 414.3538 -284.772006) (xy 414.383365 -284.81135) (xy 414.406236 -284.854927) (xy 414.42182 -284.901608)
			(xy 414.429715 -284.950185) (xy 414.43021 -284.974792) (xy 414.769058 -284.974792) (xy 414.773018 -284.925738)
			(xy 414.784795 -284.877954) (xy 414.804086 -284.832678) (xy 414.830389 -284.791082) (xy 414.863024 -284.754245)
			(xy 414.901145 -284.72312) (xy 414.943766 -284.698513) (xy 414.989782 -284.681061) (xy 415.038001 -284.671217)
			(xy 415.087176 -284.669236) (xy 415.136031 -284.675168) (xy 415.183302 -284.68886) (xy 415.227764 -284.709958)
			(xy 415.268267 -284.737914) (xy 415.30376 -284.772006) (xy 415.333325 -284.81135) (xy 415.356196 -284.854927)
			(xy 415.37178 -284.901608) (xy 415.379675 -284.950185) (xy 415.38017 -284.974792) (xy 415.719018 -284.974792)
			(xy 415.722978 -284.925738) (xy 415.734755 -284.877954) (xy 415.754046 -284.832678) (xy 415.780349 -284.791082)
			(xy 415.812984 -284.754245) (xy 415.851105 -284.72312) (xy 415.893726 -284.698513) (xy 415.939742 -284.681061)
			(xy 415.987961 -284.671217) (xy 416.037136 -284.669236) (xy 416.085991 -284.675168) (xy 416.133262 -284.68886)
			(xy 416.177724 -284.709958) (xy 416.218227 -284.737914) (xy 416.25372 -284.772006) (xy 416.283285 -284.81135)
			(xy 416.306156 -284.854927) (xy 416.32174 -284.901608) (xy 416.329635 -284.950185) (xy 416.33013 -284.974792)
			(xy 416.668978 -284.974792) (xy 416.672938 -284.925738) (xy 416.684715 -284.877954) (xy 416.704006 -284.832678)
			(xy 416.730309 -284.791082) (xy 416.762944 -284.754245) (xy 416.801065 -284.72312) (xy 416.843686 -284.698513)
			(xy 416.889702 -284.681061) (xy 416.937921 -284.671217) (xy 416.987096 -284.669236) (xy 417.035951 -284.675168)
			(xy 417.083222 -284.68886) (xy 417.127684 -284.709958) (xy 417.168187 -284.737914) (xy 417.20368 -284.772006)
			(xy 417.233245 -284.81135) (xy 417.256116 -284.854927) (xy 417.2717 -284.901608) (xy 417.279595 -284.950185)
			(xy 417.28009 -284.974792) (xy 417.279595 -284.999399) (xy 417.2717 -285.047976) (xy 417.256116 -285.094657)
			(xy 417.233245 -285.138234) (xy 417.20368 -285.177578) (xy 417.168187 -285.21167) (xy 417.127684 -285.239626)
			(xy 417.083222 -285.260724) (xy 417.035951 -285.274416) (xy 416.987096 -285.280348) (xy 416.937921 -285.278367)
			(xy 416.889702 -285.268523) (xy 416.843686 -285.251071) (xy 416.801065 -285.226464) (xy 416.762944 -285.195339)
			(xy 416.730309 -285.158502) (xy 416.704006 -285.116906) (xy 416.684715 -285.07163) (xy 416.672938 -285.023846)
			(xy 416.668978 -284.974792) (xy 416.33013 -284.974792) (xy 416.329635 -284.999399) (xy 416.32174 -285.047976)
			(xy 416.306156 -285.094657) (xy 416.283285 -285.138234) (xy 416.25372 -285.177578) (xy 416.218227 -285.21167)
			(xy 416.177724 -285.239626) (xy 416.133262 -285.260724) (xy 416.085991 -285.274416) (xy 416.037136 -285.280348)
			(xy 415.987961 -285.278367) (xy 415.939742 -285.268523) (xy 415.893726 -285.251071) (xy 415.851105 -285.226464)
			(xy 415.812984 -285.195339) (xy 415.780349 -285.158502) (xy 415.754046 -285.116906) (xy 415.734755 -285.07163)
			(xy 415.722978 -285.023846) (xy 415.719018 -284.974792) (xy 415.38017 -284.974792) (xy 415.379675 -284.999399)
			(xy 415.37178 -285.047976) (xy 415.356196 -285.094657) (xy 415.333325 -285.138234) (xy 415.30376 -285.177578)
			(xy 415.268267 -285.21167) (xy 415.227764 -285.239626) (xy 415.183302 -285.260724) (xy 415.136031 -285.274416)
			(xy 415.087176 -285.280348) (xy 415.038001 -285.278367) (xy 414.989782 -285.268523) (xy 414.943766 -285.251071)
			(xy 414.901145 -285.226464) (xy 414.863024 -285.195339) (xy 414.830389 -285.158502) (xy 414.804086 -285.116906)
			(xy 414.784795 -285.07163) (xy 414.773018 -285.023846) (xy 414.769058 -284.974792) (xy 414.43021 -284.974792)
			(xy 414.429715 -284.999399) (xy 414.42182 -285.047976) (xy 414.406236 -285.094657) (xy 414.383365 -285.138234)
			(xy 414.3538 -285.177578) (xy 414.318307 -285.21167) (xy 414.277804 -285.239626) (xy 414.233342 -285.260724)
			(xy 414.186071 -285.274416) (xy 414.137216 -285.280348) (xy 414.088041 -285.278367) (xy 414.039822 -285.268523)
			(xy 413.993806 -285.251071) (xy 413.951185 -285.226464) (xy 413.913064 -285.195339) (xy 413.880429 -285.158502)
			(xy 413.854126 -285.116906) (xy 413.834835 -285.07163) (xy 413.823058 -285.023846) (xy 413.819098 -284.974792)
			(xy 413.48025 -284.974792) (xy 413.479755 -284.999399) (xy 413.47186 -285.047976) (xy 413.456276 -285.094657)
			(xy 413.433405 -285.138234) (xy 413.40384 -285.177578) (xy 413.368347 -285.21167) (xy 413.327844 -285.239626)
			(xy 413.283382 -285.260724) (xy 413.236111 -285.274416) (xy 413.187256 -285.280348) (xy 413.138081 -285.278367)
			(xy 413.089862 -285.268523) (xy 413.043846 -285.251071) (xy 413.001225 -285.226464) (xy 412.963104 -285.195339)
			(xy 412.930469 -285.158502) (xy 412.904166 -285.116906) (xy 412.884875 -285.07163) (xy 412.873098 -285.023846)
			(xy 412.869138 -284.974792) (xy 412.53029 -284.974792) (xy 412.529795 -284.999399) (xy 412.5219 -285.047976)
			(xy 412.506316 -285.094657) (xy 412.483445 -285.138234) (xy 412.45388 -285.177578) (xy 412.418387 -285.21167)
			(xy 412.377884 -285.239626) (xy 412.333422 -285.260724) (xy 412.286151 -285.274416) (xy 412.237296 -285.280348)
			(xy 412.188121 -285.278367) (xy 412.139902 -285.268523) (xy 412.093886 -285.251071) (xy 412.051265 -285.226464)
			(xy 412.013144 -285.195339) (xy 411.980509 -285.158502) (xy 411.954206 -285.116906) (xy 411.934915 -285.07163)
			(xy 411.923138 -285.023846) (xy 411.919178 -284.974792) (xy 411.58033 -284.974792) (xy 411.579835 -284.999399)
			(xy 411.57194 -285.047976) (xy 411.556356 -285.094657) (xy 411.533485 -285.138234) (xy 411.50392 -285.177578)
			(xy 411.468427 -285.21167) (xy 411.427924 -285.239626) (xy 411.383462 -285.260724) (xy 411.336191 -285.274416)
			(xy 411.287336 -285.280348) (xy 411.238161 -285.278367) (xy 411.189942 -285.268523) (xy 411.143926 -285.251071)
			(xy 411.101305 -285.226464) (xy 411.063184 -285.195339) (xy 411.030549 -285.158502) (xy 411.004246 -285.116906)
			(xy 410.984955 -285.07163) (xy 410.973178 -285.023846) (xy 410.969218 -284.974792) (xy 410.630116 -284.974792)
			(xy 410.629621 -284.999399) (xy 410.621726 -285.047976) (xy 410.606142 -285.094657) (xy 410.583271 -285.138234)
			(xy 410.553706 -285.177578) (xy 410.518213 -285.21167) (xy 410.47771 -285.239626) (xy 410.433248 -285.260724)
			(xy 410.385977 -285.274416) (xy 410.337122 -285.280348) (xy 410.287947 -285.278367) (xy 410.239728 -285.268523)
			(xy 410.193712 -285.251071) (xy 410.151091 -285.226464) (xy 410.11297 -285.195339) (xy 410.080335 -285.158502)
			(xy 410.054032 -285.116906) (xy 410.034741 -285.07163) (xy 410.022964 -285.023846) (xy 410.019004 -284.974792)
			(xy 409.680156 -284.974792) (xy 409.679661 -284.999399) (xy 409.671766 -285.047976) (xy 409.656182 -285.094657)
			(xy 409.633311 -285.138234) (xy 409.603746 -285.177578) (xy 409.568253 -285.21167) (xy 409.52775 -285.239626)
			(xy 409.483288 -285.260724) (xy 409.436017 -285.274416) (xy 409.387162 -285.280348) (xy 409.337987 -285.278367)
			(xy 409.289768 -285.268523) (xy 409.243752 -285.251071) (xy 409.201131 -285.226464) (xy 409.16301 -285.195339)
			(xy 409.130375 -285.158502) (xy 409.104072 -285.116906) (xy 409.084781 -285.07163) (xy 409.073004 -285.023846)
			(xy 409.069044 -284.974792) (xy 408.730196 -284.974792) (xy 408.729701 -284.999399) (xy 408.721806 -285.047976)
			(xy 408.706222 -285.094657) (xy 408.683351 -285.138234) (xy 408.653786 -285.177578) (xy 408.618293 -285.21167)
			(xy 408.57779 -285.239626) (xy 408.533328 -285.260724) (xy 408.486057 -285.274416) (xy 408.437202 -285.280348)
			(xy 408.388027 -285.278367) (xy 408.339808 -285.268523) (xy 408.293792 -285.251071) (xy 408.251171 -285.226464)
			(xy 408.21305 -285.195339) (xy 408.180415 -285.158502) (xy 408.154112 -285.116906) (xy 408.134821 -285.07163)
			(xy 408.123044 -285.023846) (xy 408.119084 -284.974792) (xy 406.830276 -284.974792) (xy 406.829781 -284.999399)
			(xy 406.821886 -285.047976) (xy 406.806302 -285.094657) (xy 406.783431 -285.138234) (xy 406.753866 -285.177578)
			(xy 406.718373 -285.21167) (xy 406.67787 -285.239626) (xy 406.633408 -285.260724) (xy 406.586137 -285.274416)
			(xy 406.537282 -285.280348) (xy 406.488107 -285.278367) (xy 406.439888 -285.268523) (xy 406.393872 -285.251071)
			(xy 406.351251 -285.226464) (xy 406.31313 -285.195339) (xy 406.280495 -285.158502) (xy 406.254192 -285.116906)
			(xy 406.234901 -285.07163) (xy 406.223124 -285.023846) (xy 406.219164 -284.974792) (xy 405.880316 -284.974792)
			(xy 405.879821 -284.999399) (xy 405.871926 -285.047976) (xy 405.856342 -285.094657) (xy 405.833471 -285.138234)
			(xy 405.803906 -285.177578) (xy 405.768413 -285.21167) (xy 405.72791 -285.239626) (xy 405.683448 -285.260724)
			(xy 405.636177 -285.274416) (xy 405.587322 -285.280348) (xy 405.538147 -285.278367) (xy 405.489928 -285.268523)
			(xy 405.443912 -285.251071) (xy 405.401291 -285.226464) (xy 405.36317 -285.195339) (xy 405.330535 -285.158502)
			(xy 405.304232 -285.116906) (xy 405.284941 -285.07163) (xy 405.273164 -285.023846) (xy 405.269204 -284.974792)
			(xy 404.930102 -284.974792) (xy 404.929607 -284.999399) (xy 404.921712 -285.047976) (xy 404.906128 -285.094657)
			(xy 404.883257 -285.138234) (xy 404.853692 -285.177578) (xy 404.818199 -285.21167) (xy 404.777696 -285.239626)
			(xy 404.733234 -285.260724) (xy 404.685963 -285.274416) (xy 404.637108 -285.280348) (xy 404.587933 -285.278367)
			(xy 404.539714 -285.268523) (xy 404.493698 -285.251071) (xy 404.451077 -285.226464) (xy 404.412956 -285.195339)
			(xy 404.380321 -285.158502) (xy 404.354018 -285.116906) (xy 404.334727 -285.07163) (xy 404.32295 -285.023846)
			(xy 404.31899 -284.974792) (xy 403.980142 -284.974792) (xy 403.979647 -284.999399) (xy 403.971752 -285.047976)
			(xy 403.956168 -285.094657) (xy 403.933297 -285.138234) (xy 403.903732 -285.177578) (xy 403.868239 -285.21167)
			(xy 403.827736 -285.239626) (xy 403.783274 -285.260724) (xy 403.736003 -285.274416) (xy 403.687148 -285.280348)
			(xy 403.637973 -285.278367) (xy 403.589754 -285.268523) (xy 403.543738 -285.251071) (xy 403.501117 -285.226464)
			(xy 403.462996 -285.195339) (xy 403.430361 -285.158502) (xy 403.404058 -285.116906) (xy 403.384767 -285.07163)
			(xy 403.37299 -285.023846) (xy 403.36903 -284.974792) (xy 403.030182 -284.974792) (xy 403.029687 -284.999399)
			(xy 403.021792 -285.047976) (xy 403.006208 -285.094657) (xy 402.983337 -285.138234) (xy 402.953772 -285.177578)
			(xy 402.918279 -285.21167) (xy 402.877776 -285.239626) (xy 402.833314 -285.260724) (xy 402.786043 -285.274416)
			(xy 402.737188 -285.280348) (xy 402.688013 -285.278367) (xy 402.639794 -285.268523) (xy 402.593778 -285.251071)
			(xy 402.551157 -285.226464) (xy 402.513036 -285.195339) (xy 402.480401 -285.158502) (xy 402.454098 -285.116906)
			(xy 402.434807 -285.07163) (xy 402.42303 -285.023846) (xy 402.41907 -284.974792) (xy 402.080222 -284.974792)
			(xy 402.079727 -284.999399) (xy 402.071832 -285.047976) (xy 402.056248 -285.094657) (xy 402.033377 -285.138234)
			(xy 402.003812 -285.177578) (xy 401.968319 -285.21167) (xy 401.927816 -285.239626) (xy 401.883354 -285.260724)
			(xy 401.836083 -285.274416) (xy 401.787228 -285.280348) (xy 401.738053 -285.278367) (xy 401.689834 -285.268523)
			(xy 401.643818 -285.251071) (xy 401.601197 -285.226464) (xy 401.563076 -285.195339) (xy 401.530441 -285.158502)
			(xy 401.504138 -285.116906) (xy 401.484847 -285.07163) (xy 401.47307 -285.023846) (xy 401.46911 -284.974792)
			(xy 401.130262 -284.974792) (xy 401.129767 -284.999399) (xy 401.121872 -285.047976) (xy 401.106288 -285.094657)
			(xy 401.083417 -285.138234) (xy 401.053852 -285.177578) (xy 401.018359 -285.21167) (xy 400.977856 -285.239626)
			(xy 400.933394 -285.260724) (xy 400.886123 -285.274416) (xy 400.837268 -285.280348) (xy 400.788093 -285.278367)
			(xy 400.739874 -285.268523) (xy 400.693858 -285.251071) (xy 400.651237 -285.226464) (xy 400.613116 -285.195339)
			(xy 400.580481 -285.158502) (xy 400.554178 -285.116906) (xy 400.534887 -285.07163) (xy 400.52311 -285.023846)
			(xy 400.51915 -284.974792) (xy 400.180302 -284.974792) (xy 400.179807 -284.999399) (xy 400.171912 -285.047976)
			(xy 400.156328 -285.094657) (xy 400.133457 -285.138234) (xy 400.103892 -285.177578) (xy 400.068399 -285.21167)
			(xy 400.027896 -285.239626) (xy 399.983434 -285.260724) (xy 399.936163 -285.274416) (xy 399.887308 -285.280348)
			(xy 399.838133 -285.278367) (xy 399.789914 -285.268523) (xy 399.743898 -285.251071) (xy 399.701277 -285.226464)
			(xy 399.663156 -285.195339) (xy 399.630521 -285.158502) (xy 399.604218 -285.116906) (xy 399.584927 -285.07163)
			(xy 399.57315 -285.023846) (xy 399.56919 -284.974792) (xy 399.230342 -284.974792) (xy 399.229847 -284.999399)
			(xy 399.221952 -285.047976) (xy 399.206368 -285.094657) (xy 399.183497 -285.138234) (xy 399.153932 -285.177578)
			(xy 399.118439 -285.21167) (xy 399.077936 -285.239626) (xy 399.033474 -285.260724) (xy 398.986203 -285.274416)
			(xy 398.937348 -285.280348) (xy 398.888173 -285.278367) (xy 398.839954 -285.268523) (xy 398.793938 -285.251071)
			(xy 398.751317 -285.226464) (xy 398.713196 -285.195339) (xy 398.680561 -285.158502) (xy 398.654258 -285.116906)
			(xy 398.634967 -285.07163) (xy 398.62319 -285.023846) (xy 398.61923 -284.974792) (xy 398.280128 -284.974792)
			(xy 398.279633 -284.999399) (xy 398.271738 -285.047976) (xy 398.256154 -285.094657) (xy 398.233283 -285.138234)
			(xy 398.203718 -285.177578) (xy 398.168225 -285.21167) (xy 398.127722 -285.239626) (xy 398.08326 -285.260724)
			(xy 398.035989 -285.274416) (xy 397.987134 -285.280348) (xy 397.937959 -285.278367) (xy 397.88974 -285.268523)
			(xy 397.843724 -285.251071) (xy 397.801103 -285.226464) (xy 397.762982 -285.195339) (xy 397.730347 -285.158502)
			(xy 397.704044 -285.116906) (xy 397.684753 -285.07163) (xy 397.672976 -285.023846) (xy 397.669016 -284.974792)
			(xy 397.330168 -284.974792) (xy 397.329673 -284.999399) (xy 397.321778 -285.047976) (xy 397.306194 -285.094657)
			(xy 397.283323 -285.138234) (xy 397.253758 -285.177578) (xy 397.218265 -285.21167) (xy 397.177762 -285.239626)
			(xy 397.1333 -285.260724) (xy 397.086029 -285.274416) (xy 397.037174 -285.280348) (xy 396.987999 -285.278367)
			(xy 396.93978 -285.268523) (xy 396.893764 -285.251071) (xy 396.851143 -285.226464) (xy 396.813022 -285.195339)
			(xy 396.780387 -285.158502) (xy 396.754084 -285.116906) (xy 396.734793 -285.07163) (xy 396.723016 -285.023846)
			(xy 396.719056 -284.974792) (xy 396.380208 -284.974792) (xy 396.379713 -284.999399) (xy 396.371818 -285.047976)
			(xy 396.356234 -285.094657) (xy 396.333363 -285.138234) (xy 396.303798 -285.177578) (xy 396.268305 -285.21167)
			(xy 396.227802 -285.239626) (xy 396.18334 -285.260724) (xy 396.136069 -285.274416) (xy 396.087214 -285.280348)
			(xy 396.038039 -285.278367) (xy 395.98982 -285.268523) (xy 395.943804 -285.251071) (xy 395.901183 -285.226464)
			(xy 395.863062 -285.195339) (xy 395.830427 -285.158502) (xy 395.804124 -285.116906) (xy 395.784833 -285.07163)
			(xy 395.773056 -285.023846) (xy 395.769096 -284.974792) (xy 395.430248 -284.974792) (xy 395.429753 -284.999399)
			(xy 395.421858 -285.047976) (xy 395.406274 -285.094657) (xy 395.383403 -285.138234) (xy 395.353838 -285.177578)
			(xy 395.318345 -285.21167) (xy 395.277842 -285.239626) (xy 395.23338 -285.260724) (xy 395.186109 -285.274416)
			(xy 395.137254 -285.280348) (xy 395.088079 -285.278367) (xy 395.03986 -285.268523) (xy 394.993844 -285.251071)
			(xy 394.951223 -285.226464) (xy 394.913102 -285.195339) (xy 394.880467 -285.158502) (xy 394.854164 -285.116906)
			(xy 394.834873 -285.07163) (xy 394.823096 -285.023846) (xy 394.819136 -284.974792) (xy 394.480288 -284.974792)
			(xy 394.479793 -284.999399) (xy 394.471898 -285.047976) (xy 394.456314 -285.094657) (xy 394.433443 -285.138234)
			(xy 394.403878 -285.177578) (xy 394.368385 -285.21167) (xy 394.327882 -285.239626) (xy 394.28342 -285.260724)
			(xy 394.236149 -285.274416) (xy 394.187294 -285.280348) (xy 394.138119 -285.278367) (xy 394.0899 -285.268523)
			(xy 394.043884 -285.251071) (xy 394.001263 -285.226464) (xy 393.963142 -285.195339) (xy 393.930507 -285.158502)
			(xy 393.904204 -285.116906) (xy 393.884913 -285.07163) (xy 393.873136 -285.023846) (xy 393.869176 -284.974792)
			(xy 393.530328 -284.974792) (xy 393.529833 -284.999399) (xy 393.521938 -285.047976) (xy 393.506354 -285.094657)
			(xy 393.483483 -285.138234) (xy 393.453918 -285.177578) (xy 393.418425 -285.21167) (xy 393.377922 -285.239626)
			(xy 393.33346 -285.260724) (xy 393.286189 -285.274416) (xy 393.237334 -285.280348) (xy 393.188159 -285.278367)
			(xy 393.13994 -285.268523) (xy 393.093924 -285.251071) (xy 393.051303 -285.226464) (xy 393.013182 -285.195339)
			(xy 392.980547 -285.158502) (xy 392.954244 -285.116906) (xy 392.934953 -285.07163) (xy 392.923176 -285.023846)
			(xy 392.919216 -284.974792) (xy 391.630154 -284.974792) (xy 391.629659 -284.999399) (xy 391.621764 -285.047976)
			(xy 391.60618 -285.094657) (xy 391.583309 -285.138234) (xy 391.553744 -285.177578) (xy 391.518251 -285.21167)
			(xy 391.477748 -285.239626) (xy 391.433286 -285.260724) (xy 391.386015 -285.274416) (xy 391.33716 -285.280348)
			(xy 391.287985 -285.278367) (xy 391.239766 -285.268523) (xy 391.19375 -285.251071) (xy 391.151129 -285.226464)
			(xy 391.113008 -285.195339) (xy 391.080373 -285.158502) (xy 391.05407 -285.116906) (xy 391.034779 -285.07163)
			(xy 391.023002 -285.023846) (xy 391.019042 -284.974792) (xy 389.730234 -284.974792) (xy 389.729739 -284.999399)
			(xy 389.721844 -285.047976) (xy 389.70626 -285.094657) (xy 389.683389 -285.138234) (xy 389.653824 -285.177578)
			(xy 389.618331 -285.21167) (xy 389.577828 -285.239626) (xy 389.533366 -285.260724) (xy 389.486095 -285.274416)
			(xy 389.43724 -285.280348) (xy 389.388065 -285.278367) (xy 389.339846 -285.268523) (xy 389.29383 -285.251071)
			(xy 389.251209 -285.226464) (xy 389.213088 -285.195339) (xy 389.180453 -285.158502) (xy 389.15415 -285.116906)
			(xy 389.134859 -285.07163) (xy 389.123082 -285.023846) (xy 389.119122 -284.974792) (xy 388.78026 -284.974792)
			(xy 388.78071 -284.983107) (xy 388.775339 -285.032457) (xy 388.762054 -285.080288) (xy 388.741206 -285.125339)
			(xy 388.713344 -285.166424) (xy 388.679203 -285.20246) (xy 388.63968 -285.232498) (xy 388.595819 -285.255746)
			(xy 388.548775 -285.271591) (xy 388.499787 -285.279617) (xy 388.474966 -285.2801) (xy 388.46143 -285.279942)
			(xy 388.434466 -285.277528) (xy 388.421118 -285.275274) (xy 388.408926 -285.273242) (xy 388.385304 -285.280608)
			(xy 388.361174 -285.304484) (xy 388.361174 -285.34614) (xy 388.402576 -285.387288) (xy 388.419044 -285.404378)
			(xy 388.44695 -285.442766) (xy 388.468581 -285.485009) (xy 388.483419 -285.530089) (xy 388.491105 -285.576922)
			(xy 388.49173 -285.600648) (xy 388.49173 -285.601664) (xy 388.492238 -285.619952) (xy 388.516901 -285.621904)
			(xy 388.565192 -285.632623) (xy 388.611123 -285.650989) (xy 388.653492 -285.676521) (xy 388.691189 -285.70855)
			(xy 388.723229 -285.746238) (xy 388.748772 -285.7886) (xy 388.767151 -285.834525) (xy 388.777884 -285.882814)
			(xy 388.779766 -285.90748) (xy 388.79907 -285.907988) (xy 388.799832 -285.907988) (xy 388.823479 -285.908674)
			(xy 388.870142 -285.916433) (xy 388.915051 -285.931297) (xy 388.957129 -285.952909) (xy 388.995371 -285.980752)
			(xy 389.01243 -285.997142) (xy 389.038592 -286.023558) (xy 389.046006 -286.030381) (xy 389.064594 -286.038112)
			(xy 389.07466 -286.038544) (xy 389.095234 -286.038544) (xy 389.11911 -286.014414) (xy 389.126476 -285.990792)
			(xy 389.124444 -285.9786) (xy 389.122191 -285.965252) (xy 389.119778 -285.938288) (xy 389.119618 -285.924752)
			(xy 389.12013 -285.899936) (xy 389.128166 -285.85096) (xy 389.14402 -285.803929) (xy 389.167274 -285.760082)
			(xy 389.197314 -285.720575) (xy 389.23335 -285.686447) (xy 389.274433 -285.658599) (xy 389.319479 -285.637764)
			(xy 389.367303 -285.624491) (xy 389.416643 -285.619128) (xy 389.466202 -285.621819) (xy 389.514672 -285.632492)
			(xy 389.560777 -285.650865) (xy 389.603303 -285.676454) (xy 389.641129 -285.708587) (xy 389.673258 -285.746415)
			(xy 389.698845 -285.788942) (xy 389.717215 -285.835049) (xy 389.727884 -285.88352) (xy 389.73012 -285.924752)
			(xy 392.919216 -285.924752) (xy 392.923176 -285.875698) (xy 392.934953 -285.827914) (xy 392.954244 -285.782638)
			(xy 392.980547 -285.741042) (xy 393.013182 -285.704205) (xy 393.051303 -285.67308) (xy 393.093924 -285.648473)
			(xy 393.13994 -285.631021) (xy 393.188159 -285.621177) (xy 393.237334 -285.619196) (xy 393.286189 -285.625128)
			(xy 393.33346 -285.63882) (xy 393.377922 -285.659918) (xy 393.418425 -285.687874) (xy 393.453918 -285.721966)
			(xy 393.483483 -285.76131) (xy 393.506354 -285.804887) (xy 393.521938 -285.851568) (xy 393.529833 -285.900145)
			(xy 393.530328 -285.924752) (xy 393.869176 -285.924752) (xy 393.873136 -285.875698) (xy 393.884913 -285.827914)
			(xy 393.904204 -285.782638) (xy 393.930507 -285.741042) (xy 393.963142 -285.704205) (xy 394.001263 -285.67308)
			(xy 394.043884 -285.648473) (xy 394.0899 -285.631021) (xy 394.138119 -285.621177) (xy 394.187294 -285.619196)
			(xy 394.236149 -285.625128) (xy 394.28342 -285.63882) (xy 394.327882 -285.659918) (xy 394.368385 -285.687874)
			(xy 394.403878 -285.721966) (xy 394.433443 -285.76131) (xy 394.456314 -285.804887) (xy 394.471898 -285.851568)
			(xy 394.479793 -285.900145) (xy 394.480288 -285.924752) (xy 394.819136 -285.924752) (xy 394.823096 -285.875698)
			(xy 394.834873 -285.827914) (xy 394.854164 -285.782638) (xy 394.880467 -285.741042) (xy 394.913102 -285.704205)
			(xy 394.951223 -285.67308) (xy 394.993844 -285.648473) (xy 395.03986 -285.631021) (xy 395.088079 -285.621177)
			(xy 395.137254 -285.619196) (xy 395.186109 -285.625128) (xy 395.23338 -285.63882) (xy 395.277842 -285.659918)
			(xy 395.318345 -285.687874) (xy 395.353838 -285.721966) (xy 395.383403 -285.76131) (xy 395.406274 -285.804887)
			(xy 395.421858 -285.851568) (xy 395.429753 -285.900145) (xy 395.430248 -285.924752) (xy 395.769096 -285.924752)
			(xy 395.773056 -285.875698) (xy 395.784833 -285.827914) (xy 395.804124 -285.782638) (xy 395.830427 -285.741042)
			(xy 395.863062 -285.704205) (xy 395.901183 -285.67308) (xy 395.943804 -285.648473) (xy 395.98982 -285.631021)
			(xy 396.038039 -285.621177) (xy 396.087214 -285.619196) (xy 396.136069 -285.625128) (xy 396.18334 -285.63882)
			(xy 396.227802 -285.659918) (xy 396.268305 -285.687874) (xy 396.303798 -285.721966) (xy 396.333363 -285.76131)
			(xy 396.356234 -285.804887) (xy 396.371818 -285.851568) (xy 396.379713 -285.900145) (xy 396.380208 -285.924752)
			(xy 396.719056 -285.924752) (xy 396.723016 -285.875698) (xy 396.734793 -285.827914) (xy 396.754084 -285.782638)
			(xy 396.780387 -285.741042) (xy 396.813022 -285.704205) (xy 396.851143 -285.67308) (xy 396.893764 -285.648473)
			(xy 396.93978 -285.631021) (xy 396.987999 -285.621177) (xy 397.037174 -285.619196) (xy 397.086029 -285.625128)
			(xy 397.1333 -285.63882) (xy 397.177762 -285.659918) (xy 397.218265 -285.687874) (xy 397.253758 -285.721966)
			(xy 397.283323 -285.76131) (xy 397.306194 -285.804887) (xy 397.321778 -285.851568) (xy 397.329673 -285.900145)
			(xy 397.330168 -285.924752) (xy 397.669016 -285.924752) (xy 397.672976 -285.875698) (xy 397.684753 -285.827914)
			(xy 397.704044 -285.782638) (xy 397.730347 -285.741042) (xy 397.762982 -285.704205) (xy 397.801103 -285.67308)
			(xy 397.843724 -285.648473) (xy 397.88974 -285.631021) (xy 397.937959 -285.621177) (xy 397.987134 -285.619196)
			(xy 398.035989 -285.625128) (xy 398.08326 -285.63882) (xy 398.127722 -285.659918) (xy 398.168225 -285.687874)
			(xy 398.203718 -285.721966) (xy 398.233283 -285.76131) (xy 398.256154 -285.804887) (xy 398.271738 -285.851568)
			(xy 398.279633 -285.900145) (xy 398.280128 -285.924752) (xy 398.61923 -285.924752) (xy 398.62319 -285.875698)
			(xy 398.634967 -285.827914) (xy 398.654258 -285.782638) (xy 398.680561 -285.741042) (xy 398.713196 -285.704205)
			(xy 398.751317 -285.67308) (xy 398.793938 -285.648473) (xy 398.839954 -285.631021) (xy 398.888173 -285.621177)
			(xy 398.937348 -285.619196) (xy 398.986203 -285.625128) (xy 399.033474 -285.63882) (xy 399.077936 -285.659918)
			(xy 399.118439 -285.687874) (xy 399.153932 -285.721966) (xy 399.183497 -285.76131) (xy 399.206368 -285.804887)
			(xy 399.221952 -285.851568) (xy 399.229847 -285.900145) (xy 399.230342 -285.924752) (xy 399.56919 -285.924752)
			(xy 399.57315 -285.875698) (xy 399.584927 -285.827914) (xy 399.604218 -285.782638) (xy 399.630521 -285.741042)
			(xy 399.663156 -285.704205) (xy 399.701277 -285.67308) (xy 399.743898 -285.648473) (xy 399.789914 -285.631021)
			(xy 399.838133 -285.621177) (xy 399.887308 -285.619196) (xy 399.936163 -285.625128) (xy 399.983434 -285.63882)
			(xy 400.027896 -285.659918) (xy 400.068399 -285.687874) (xy 400.103892 -285.721966) (xy 400.133457 -285.76131)
			(xy 400.156328 -285.804887) (xy 400.171912 -285.851568) (xy 400.179807 -285.900145) (xy 400.180302 -285.924752)
			(xy 400.51915 -285.924752) (xy 400.52311 -285.875698) (xy 400.534887 -285.827914) (xy 400.554178 -285.782638)
			(xy 400.580481 -285.741042) (xy 400.613116 -285.704205) (xy 400.651237 -285.67308) (xy 400.693858 -285.648473)
			(xy 400.739874 -285.631021) (xy 400.788093 -285.621177) (xy 400.837268 -285.619196) (xy 400.886123 -285.625128)
			(xy 400.933394 -285.63882) (xy 400.977856 -285.659918) (xy 401.018359 -285.687874) (xy 401.053852 -285.721966)
			(xy 401.083417 -285.76131) (xy 401.106288 -285.804887) (xy 401.121872 -285.851568) (xy 401.129767 -285.900145)
			(xy 401.130262 -285.924752) (xy 401.46911 -285.924752) (xy 401.47307 -285.875698) (xy 401.484847 -285.827914)
			(xy 401.504138 -285.782638) (xy 401.530441 -285.741042) (xy 401.563076 -285.704205) (xy 401.601197 -285.67308)
			(xy 401.643818 -285.648473) (xy 401.689834 -285.631021) (xy 401.738053 -285.621177) (xy 401.787228 -285.619196)
			(xy 401.836083 -285.625128) (xy 401.883354 -285.63882) (xy 401.927816 -285.659918) (xy 401.968319 -285.687874)
			(xy 402.003812 -285.721966) (xy 402.033377 -285.76131) (xy 402.056248 -285.804887) (xy 402.071832 -285.851568)
			(xy 402.079727 -285.900145) (xy 402.080222 -285.924752) (xy 402.41907 -285.924752) (xy 402.42303 -285.875698)
			(xy 402.434807 -285.827914) (xy 402.454098 -285.782638) (xy 402.480401 -285.741042) (xy 402.513036 -285.704205)
			(xy 402.551157 -285.67308) (xy 402.593778 -285.648473) (xy 402.639794 -285.631021) (xy 402.688013 -285.621177)
			(xy 402.737188 -285.619196) (xy 402.786043 -285.625128) (xy 402.833314 -285.63882) (xy 402.877776 -285.659918)
			(xy 402.918279 -285.687874) (xy 402.953772 -285.721966) (xy 402.983337 -285.76131) (xy 403.006208 -285.804887)
			(xy 403.021792 -285.851568) (xy 403.029687 -285.900145) (xy 403.030182 -285.924752) (xy 403.36903 -285.924752)
			(xy 403.37299 -285.875698) (xy 403.384767 -285.827914) (xy 403.404058 -285.782638) (xy 403.430361 -285.741042)
			(xy 403.462996 -285.704205) (xy 403.501117 -285.67308) (xy 403.543738 -285.648473) (xy 403.589754 -285.631021)
			(xy 403.637973 -285.621177) (xy 403.687148 -285.619196) (xy 403.736003 -285.625128) (xy 403.783274 -285.63882)
			(xy 403.827736 -285.659918) (xy 403.868239 -285.687874) (xy 403.903732 -285.721966) (xy 403.933297 -285.76131)
			(xy 403.956168 -285.804887) (xy 403.971752 -285.851568) (xy 403.979647 -285.900145) (xy 403.980142 -285.924752)
			(xy 404.31899 -285.924752) (xy 404.32295 -285.875698) (xy 404.334727 -285.827914) (xy 404.354018 -285.782638)
			(xy 404.380321 -285.741042) (xy 404.412956 -285.704205) (xy 404.451077 -285.67308) (xy 404.493698 -285.648473)
			(xy 404.539714 -285.631021) (xy 404.587933 -285.621177) (xy 404.637108 -285.619196) (xy 404.685963 -285.625128)
			(xy 404.733234 -285.63882) (xy 404.777696 -285.659918) (xy 404.818199 -285.687874) (xy 404.853692 -285.721966)
			(xy 404.883257 -285.76131) (xy 404.906128 -285.804887) (xy 404.921712 -285.851568) (xy 404.929607 -285.900145)
			(xy 404.930102 -285.924752) (xy 405.269204 -285.924752) (xy 405.273164 -285.875698) (xy 405.284941 -285.827914)
			(xy 405.304232 -285.782638) (xy 405.330535 -285.741042) (xy 405.36317 -285.704205) (xy 405.401291 -285.67308)
			(xy 405.443912 -285.648473) (xy 405.489928 -285.631021) (xy 405.538147 -285.621177) (xy 405.587322 -285.619196)
			(xy 405.636177 -285.625128) (xy 405.683448 -285.63882) (xy 405.72791 -285.659918) (xy 405.768413 -285.687874)
			(xy 405.803906 -285.721966) (xy 405.833471 -285.76131) (xy 405.856342 -285.804887) (xy 405.871926 -285.851568)
			(xy 405.879821 -285.900145) (xy 405.880316 -285.924752) (xy 406.219164 -285.924752) (xy 406.223124 -285.875698)
			(xy 406.234901 -285.827914) (xy 406.254192 -285.782638) (xy 406.280495 -285.741042) (xy 406.31313 -285.704205)
			(xy 406.351251 -285.67308) (xy 406.393872 -285.648473) (xy 406.439888 -285.631021) (xy 406.488107 -285.621177)
			(xy 406.537282 -285.619196) (xy 406.586137 -285.625128) (xy 406.633408 -285.63882) (xy 406.67787 -285.659918)
			(xy 406.718373 -285.687874) (xy 406.753866 -285.721966) (xy 406.783431 -285.76131) (xy 406.806302 -285.804887)
			(xy 406.821886 -285.851568) (xy 406.829781 -285.900145) (xy 406.830276 -285.924752) (xy 408.119084 -285.924752)
			(xy 408.123044 -285.875698) (xy 408.134821 -285.827914) (xy 408.154112 -285.782638) (xy 408.180415 -285.741042)
			(xy 408.21305 -285.704205) (xy 408.251171 -285.67308) (xy 408.293792 -285.648473) (xy 408.339808 -285.631021)
			(xy 408.388027 -285.621177) (xy 408.437202 -285.619196) (xy 408.486057 -285.625128) (xy 408.533328 -285.63882)
			(xy 408.57779 -285.659918) (xy 408.618293 -285.687874) (xy 408.653786 -285.721966) (xy 408.683351 -285.76131)
			(xy 408.706222 -285.804887) (xy 408.721806 -285.851568) (xy 408.729701 -285.900145) (xy 408.730196 -285.924752)
			(xy 409.069044 -285.924752) (xy 409.073004 -285.875698) (xy 409.084781 -285.827914) (xy 409.104072 -285.782638)
			(xy 409.130375 -285.741042) (xy 409.16301 -285.704205) (xy 409.201131 -285.67308) (xy 409.243752 -285.648473)
			(xy 409.289768 -285.631021) (xy 409.337987 -285.621177) (xy 409.387162 -285.619196) (xy 409.436017 -285.625128)
			(xy 409.483288 -285.63882) (xy 409.52775 -285.659918) (xy 409.568253 -285.687874) (xy 409.603746 -285.721966)
			(xy 409.633311 -285.76131) (xy 409.656182 -285.804887) (xy 409.671766 -285.851568) (xy 409.679661 -285.900145)
			(xy 409.680156 -285.924752) (xy 410.019004 -285.924752) (xy 410.022964 -285.875698) (xy 410.034741 -285.827914)
			(xy 410.054032 -285.782638) (xy 410.080335 -285.741042) (xy 410.11297 -285.704205) (xy 410.151091 -285.67308)
			(xy 410.193712 -285.648473) (xy 410.239728 -285.631021) (xy 410.287947 -285.621177) (xy 410.337122 -285.619196)
			(xy 410.385977 -285.625128) (xy 410.433248 -285.63882) (xy 410.47771 -285.659918) (xy 410.518213 -285.687874)
			(xy 410.553706 -285.721966) (xy 410.583271 -285.76131) (xy 410.606142 -285.804887) (xy 410.621726 -285.851568)
			(xy 410.629621 -285.900145) (xy 410.630116 -285.924752) (xy 410.969218 -285.924752) (xy 410.973178 -285.875698)
			(xy 410.984955 -285.827914) (xy 411.004246 -285.782638) (xy 411.030549 -285.741042) (xy 411.063184 -285.704205)
			(xy 411.101305 -285.67308) (xy 411.143926 -285.648473) (xy 411.189942 -285.631021) (xy 411.238161 -285.621177)
			(xy 411.287336 -285.619196) (xy 411.336191 -285.625128) (xy 411.383462 -285.63882) (xy 411.427924 -285.659918)
			(xy 411.468427 -285.687874) (xy 411.50392 -285.721966) (xy 411.533485 -285.76131) (xy 411.556356 -285.804887)
			(xy 411.57194 -285.851568) (xy 411.579835 -285.900145) (xy 411.58033 -285.924752) (xy 411.919178 -285.924752)
			(xy 411.923138 -285.875698) (xy 411.934915 -285.827914) (xy 411.954206 -285.782638) (xy 411.980509 -285.741042)
			(xy 412.013144 -285.704205) (xy 412.051265 -285.67308) (xy 412.093886 -285.648473) (xy 412.139902 -285.631021)
			(xy 412.188121 -285.621177) (xy 412.237296 -285.619196) (xy 412.286151 -285.625128) (xy 412.333422 -285.63882)
			(xy 412.377884 -285.659918) (xy 412.418387 -285.687874) (xy 412.45388 -285.721966) (xy 412.483445 -285.76131)
			(xy 412.506316 -285.804887) (xy 412.5219 -285.851568) (xy 412.529795 -285.900145) (xy 412.53029 -285.924752)
			(xy 412.869138 -285.924752) (xy 412.873098 -285.875698) (xy 412.884875 -285.827914) (xy 412.904166 -285.782638)
			(xy 412.930469 -285.741042) (xy 412.963104 -285.704205) (xy 413.001225 -285.67308) (xy 413.043846 -285.648473)
			(xy 413.089862 -285.631021) (xy 413.138081 -285.621177) (xy 413.187256 -285.619196) (xy 413.236111 -285.625128)
			(xy 413.283382 -285.63882) (xy 413.327844 -285.659918) (xy 413.368347 -285.687874) (xy 413.40384 -285.721966)
			(xy 413.433405 -285.76131) (xy 413.456276 -285.804887) (xy 413.47186 -285.851568) (xy 413.479755 -285.900145)
			(xy 413.48025 -285.924752) (xy 413.819098 -285.924752) (xy 413.823058 -285.875698) (xy 413.834835 -285.827914)
			(xy 413.854126 -285.782638) (xy 413.880429 -285.741042) (xy 413.913064 -285.704205) (xy 413.951185 -285.67308)
			(xy 413.993806 -285.648473) (xy 414.039822 -285.631021) (xy 414.088041 -285.621177) (xy 414.137216 -285.619196)
			(xy 414.186071 -285.625128) (xy 414.233342 -285.63882) (xy 414.277804 -285.659918) (xy 414.318307 -285.687874)
			(xy 414.3538 -285.721966) (xy 414.383365 -285.76131) (xy 414.406236 -285.804887) (xy 414.42182 -285.851568)
			(xy 414.429715 -285.900145) (xy 414.43021 -285.924752) (xy 414.769058 -285.924752) (xy 414.773018 -285.875698)
			(xy 414.784795 -285.827914) (xy 414.804086 -285.782638) (xy 414.830389 -285.741042) (xy 414.863024 -285.704205)
			(xy 414.901145 -285.67308) (xy 414.943766 -285.648473) (xy 414.989782 -285.631021) (xy 415.038001 -285.621177)
			(xy 415.087176 -285.619196) (xy 415.136031 -285.625128) (xy 415.183302 -285.63882) (xy 415.227764 -285.659918)
			(xy 415.268267 -285.687874) (xy 415.30376 -285.721966) (xy 415.333325 -285.76131) (xy 415.356196 -285.804887)
			(xy 415.37178 -285.851568) (xy 415.379675 -285.900145) (xy 415.38017 -285.924752) (xy 415.719018 -285.924752)
			(xy 415.722978 -285.875698) (xy 415.734755 -285.827914) (xy 415.754046 -285.782638) (xy 415.780349 -285.741042)
			(xy 415.812984 -285.704205) (xy 415.851105 -285.67308) (xy 415.893726 -285.648473) (xy 415.939742 -285.631021)
			(xy 415.987961 -285.621177) (xy 416.037136 -285.619196) (xy 416.085991 -285.625128) (xy 416.133262 -285.63882)
			(xy 416.177724 -285.659918) (xy 416.218227 -285.687874) (xy 416.25372 -285.721966) (xy 416.283285 -285.76131)
			(xy 416.306156 -285.804887) (xy 416.32174 -285.851568) (xy 416.329635 -285.900145) (xy 416.33013 -285.924752)
			(xy 416.668978 -285.924752) (xy 416.672938 -285.875698) (xy 416.684715 -285.827914) (xy 416.704006 -285.782638)
			(xy 416.730309 -285.741042) (xy 416.762944 -285.704205) (xy 416.801065 -285.67308) (xy 416.843686 -285.648473)
			(xy 416.889702 -285.631021) (xy 416.937921 -285.621177) (xy 416.987096 -285.619196) (xy 417.035951 -285.625128)
			(xy 417.083222 -285.63882) (xy 417.127684 -285.659918) (xy 417.168187 -285.687874) (xy 417.20368 -285.721966)
			(xy 417.233245 -285.76131) (xy 417.256116 -285.804887) (xy 417.2717 -285.851568) (xy 417.279595 -285.900145)
			(xy 417.28009 -285.924752) (xy 417.279595 -285.949359) (xy 417.2717 -285.997936) (xy 417.256116 -286.044617)
			(xy 417.233245 -286.088194) (xy 417.20368 -286.127538) (xy 417.168187 -286.16163) (xy 417.127684 -286.189586)
			(xy 417.083222 -286.210684) (xy 417.035951 -286.224376) (xy 416.987096 -286.230308) (xy 416.937921 -286.228327)
			(xy 416.889702 -286.218483) (xy 416.843686 -286.201031) (xy 416.801065 -286.176424) (xy 416.762944 -286.145299)
			(xy 416.730309 -286.108462) (xy 416.704006 -286.066866) (xy 416.684715 -286.02159) (xy 416.672938 -285.973806)
			(xy 416.668978 -285.924752) (xy 416.33013 -285.924752) (xy 416.329635 -285.949359) (xy 416.32174 -285.997936)
			(xy 416.306156 -286.044617) (xy 416.283285 -286.088194) (xy 416.25372 -286.127538) (xy 416.218227 -286.16163)
			(xy 416.177724 -286.189586) (xy 416.133262 -286.210684) (xy 416.085991 -286.224376) (xy 416.037136 -286.230308)
			(xy 415.987961 -286.228327) (xy 415.939742 -286.218483) (xy 415.893726 -286.201031) (xy 415.851105 -286.176424)
			(xy 415.812984 -286.145299) (xy 415.780349 -286.108462) (xy 415.754046 -286.066866) (xy 415.734755 -286.02159)
			(xy 415.722978 -285.973806) (xy 415.719018 -285.924752) (xy 415.38017 -285.924752) (xy 415.379675 -285.949359)
			(xy 415.37178 -285.997936) (xy 415.356196 -286.044617) (xy 415.333325 -286.088194) (xy 415.30376 -286.127538)
			(xy 415.268267 -286.16163) (xy 415.227764 -286.189586) (xy 415.183302 -286.210684) (xy 415.136031 -286.224376)
			(xy 415.087176 -286.230308) (xy 415.038001 -286.228327) (xy 414.989782 -286.218483) (xy 414.943766 -286.201031)
			(xy 414.901145 -286.176424) (xy 414.863024 -286.145299) (xy 414.830389 -286.108462) (xy 414.804086 -286.066866)
			(xy 414.784795 -286.02159) (xy 414.773018 -285.973806) (xy 414.769058 -285.924752) (xy 414.43021 -285.924752)
			(xy 414.429715 -285.949359) (xy 414.42182 -285.997936) (xy 414.406236 -286.044617) (xy 414.383365 -286.088194)
			(xy 414.3538 -286.127538) (xy 414.318307 -286.16163) (xy 414.277804 -286.189586) (xy 414.233342 -286.210684)
			(xy 414.186071 -286.224376) (xy 414.137216 -286.230308) (xy 414.088041 -286.228327) (xy 414.039822 -286.218483)
			(xy 413.993806 -286.201031) (xy 413.951185 -286.176424) (xy 413.913064 -286.145299) (xy 413.880429 -286.108462)
			(xy 413.854126 -286.066866) (xy 413.834835 -286.02159) (xy 413.823058 -285.973806) (xy 413.819098 -285.924752)
			(xy 413.48025 -285.924752) (xy 413.479755 -285.949359) (xy 413.47186 -285.997936) (xy 413.456276 -286.044617)
			(xy 413.433405 -286.088194) (xy 413.40384 -286.127538) (xy 413.368347 -286.16163) (xy 413.327844 -286.189586)
			(xy 413.283382 -286.210684) (xy 413.236111 -286.224376) (xy 413.187256 -286.230308) (xy 413.138081 -286.228327)
			(xy 413.089862 -286.218483) (xy 413.043846 -286.201031) (xy 413.001225 -286.176424) (xy 412.963104 -286.145299)
			(xy 412.930469 -286.108462) (xy 412.904166 -286.066866) (xy 412.884875 -286.02159) (xy 412.873098 -285.973806)
			(xy 412.869138 -285.924752) (xy 412.53029 -285.924752) (xy 412.529795 -285.949359) (xy 412.5219 -285.997936)
			(xy 412.506316 -286.044617) (xy 412.483445 -286.088194) (xy 412.45388 -286.127538) (xy 412.418387 -286.16163)
			(xy 412.377884 -286.189586) (xy 412.333422 -286.210684) (xy 412.286151 -286.224376) (xy 412.237296 -286.230308)
			(xy 412.188121 -286.228327) (xy 412.139902 -286.218483) (xy 412.093886 -286.201031) (xy 412.051265 -286.176424)
			(xy 412.013144 -286.145299) (xy 411.980509 -286.108462) (xy 411.954206 -286.066866) (xy 411.934915 -286.02159)
			(xy 411.923138 -285.973806) (xy 411.919178 -285.924752) (xy 411.58033 -285.924752) (xy 411.579835 -285.949359)
			(xy 411.57194 -285.997936) (xy 411.556356 -286.044617) (xy 411.533485 -286.088194) (xy 411.50392 -286.127538)
			(xy 411.468427 -286.16163) (xy 411.427924 -286.189586) (xy 411.383462 -286.210684) (xy 411.336191 -286.224376)
			(xy 411.287336 -286.230308) (xy 411.238161 -286.228327) (xy 411.189942 -286.218483) (xy 411.143926 -286.201031)
			(xy 411.101305 -286.176424) (xy 411.063184 -286.145299) (xy 411.030549 -286.108462) (xy 411.004246 -286.066866)
			(xy 410.984955 -286.02159) (xy 410.973178 -285.973806) (xy 410.969218 -285.924752) (xy 410.630116 -285.924752)
			(xy 410.629621 -285.949359) (xy 410.621726 -285.997936) (xy 410.606142 -286.044617) (xy 410.583271 -286.088194)
			(xy 410.553706 -286.127538) (xy 410.518213 -286.16163) (xy 410.47771 -286.189586) (xy 410.433248 -286.210684)
			(xy 410.385977 -286.224376) (xy 410.337122 -286.230308) (xy 410.287947 -286.228327) (xy 410.239728 -286.218483)
			(xy 410.193712 -286.201031) (xy 410.151091 -286.176424) (xy 410.11297 -286.145299) (xy 410.080335 -286.108462)
			(xy 410.054032 -286.066866) (xy 410.034741 -286.02159) (xy 410.022964 -285.973806) (xy 410.019004 -285.924752)
			(xy 409.680156 -285.924752) (xy 409.679661 -285.949359) (xy 409.671766 -285.997936) (xy 409.656182 -286.044617)
			(xy 409.633311 -286.088194) (xy 409.603746 -286.127538) (xy 409.568253 -286.16163) (xy 409.52775 -286.189586)
			(xy 409.483288 -286.210684) (xy 409.436017 -286.224376) (xy 409.387162 -286.230308) (xy 409.337987 -286.228327)
			(xy 409.289768 -286.218483) (xy 409.243752 -286.201031) (xy 409.201131 -286.176424) (xy 409.16301 -286.145299)
			(xy 409.130375 -286.108462) (xy 409.104072 -286.066866) (xy 409.084781 -286.02159) (xy 409.073004 -285.973806)
			(xy 409.069044 -285.924752) (xy 408.730196 -285.924752) (xy 408.729701 -285.949359) (xy 408.721806 -285.997936)
			(xy 408.706222 -286.044617) (xy 408.683351 -286.088194) (xy 408.653786 -286.127538) (xy 408.618293 -286.16163)
			(xy 408.57779 -286.189586) (xy 408.533328 -286.210684) (xy 408.486057 -286.224376) (xy 408.437202 -286.230308)
			(xy 408.388027 -286.228327) (xy 408.339808 -286.218483) (xy 408.293792 -286.201031) (xy 408.251171 -286.176424)
			(xy 408.21305 -286.145299) (xy 408.180415 -286.108462) (xy 408.154112 -286.066866) (xy 408.134821 -286.02159)
			(xy 408.123044 -285.973806) (xy 408.119084 -285.924752) (xy 406.830276 -285.924752) (xy 406.829781 -285.949359)
			(xy 406.821886 -285.997936) (xy 406.806302 -286.044617) (xy 406.783431 -286.088194) (xy 406.753866 -286.127538)
			(xy 406.718373 -286.16163) (xy 406.67787 -286.189586) (xy 406.633408 -286.210684) (xy 406.586137 -286.224376)
			(xy 406.537282 -286.230308) (xy 406.488107 -286.228327) (xy 406.439888 -286.218483) (xy 406.393872 -286.201031)
			(xy 406.351251 -286.176424) (xy 406.31313 -286.145299) (xy 406.280495 -286.108462) (xy 406.254192 -286.066866)
			(xy 406.234901 -286.02159) (xy 406.223124 -285.973806) (xy 406.219164 -285.924752) (xy 405.880316 -285.924752)
			(xy 405.879821 -285.949359) (xy 405.871926 -285.997936) (xy 405.856342 -286.044617) (xy 405.833471 -286.088194)
			(xy 405.803906 -286.127538) (xy 405.768413 -286.16163) (xy 405.72791 -286.189586) (xy 405.683448 -286.210684)
			(xy 405.636177 -286.224376) (xy 405.587322 -286.230308) (xy 405.538147 -286.228327) (xy 405.489928 -286.218483)
			(xy 405.443912 -286.201031) (xy 405.401291 -286.176424) (xy 405.36317 -286.145299) (xy 405.330535 -286.108462)
			(xy 405.304232 -286.066866) (xy 405.284941 -286.02159) (xy 405.273164 -285.973806) (xy 405.269204 -285.924752)
			(xy 404.930102 -285.924752) (xy 404.929607 -285.949359) (xy 404.921712 -285.997936) (xy 404.906128 -286.044617)
			(xy 404.883257 -286.088194) (xy 404.853692 -286.127538) (xy 404.818199 -286.16163) (xy 404.777696 -286.189586)
			(xy 404.733234 -286.210684) (xy 404.685963 -286.224376) (xy 404.637108 -286.230308) (xy 404.587933 -286.228327)
			(xy 404.539714 -286.218483) (xy 404.493698 -286.201031) (xy 404.451077 -286.176424) (xy 404.412956 -286.145299)
			(xy 404.380321 -286.108462) (xy 404.354018 -286.066866) (xy 404.334727 -286.02159) (xy 404.32295 -285.973806)
			(xy 404.31899 -285.924752) (xy 403.980142 -285.924752) (xy 403.979647 -285.949359) (xy 403.971752 -285.997936)
			(xy 403.956168 -286.044617) (xy 403.933297 -286.088194) (xy 403.903732 -286.127538) (xy 403.868239 -286.16163)
			(xy 403.827736 -286.189586) (xy 403.783274 -286.210684) (xy 403.736003 -286.224376) (xy 403.687148 -286.230308)
			(xy 403.637973 -286.228327) (xy 403.589754 -286.218483) (xy 403.543738 -286.201031) (xy 403.501117 -286.176424)
			(xy 403.462996 -286.145299) (xy 403.430361 -286.108462) (xy 403.404058 -286.066866) (xy 403.384767 -286.02159)
			(xy 403.37299 -285.973806) (xy 403.36903 -285.924752) (xy 403.030182 -285.924752) (xy 403.029687 -285.949359)
			(xy 403.021792 -285.997936) (xy 403.006208 -286.044617) (xy 402.983337 -286.088194) (xy 402.953772 -286.127538)
			(xy 402.918279 -286.16163) (xy 402.877776 -286.189586) (xy 402.833314 -286.210684) (xy 402.786043 -286.224376)
			(xy 402.737188 -286.230308) (xy 402.688013 -286.228327) (xy 402.639794 -286.218483) (xy 402.593778 -286.201031)
			(xy 402.551157 -286.176424) (xy 402.513036 -286.145299) (xy 402.480401 -286.108462) (xy 402.454098 -286.066866)
			(xy 402.434807 -286.02159) (xy 402.42303 -285.973806) (xy 402.41907 -285.924752) (xy 402.080222 -285.924752)
			(xy 402.079727 -285.949359) (xy 402.071832 -285.997936) (xy 402.056248 -286.044617) (xy 402.033377 -286.088194)
			(xy 402.003812 -286.127538) (xy 401.968319 -286.16163) (xy 401.927816 -286.189586) (xy 401.883354 -286.210684)
			(xy 401.836083 -286.224376) (xy 401.787228 -286.230308) (xy 401.738053 -286.228327) (xy 401.689834 -286.218483)
			(xy 401.643818 -286.201031) (xy 401.601197 -286.176424) (xy 401.563076 -286.145299) (xy 401.530441 -286.108462)
			(xy 401.504138 -286.066866) (xy 401.484847 -286.02159) (xy 401.47307 -285.973806) (xy 401.46911 -285.924752)
			(xy 401.130262 -285.924752) (xy 401.129767 -285.949359) (xy 401.121872 -285.997936) (xy 401.106288 -286.044617)
			(xy 401.083417 -286.088194) (xy 401.053852 -286.127538) (xy 401.018359 -286.16163) (xy 400.977856 -286.189586)
			(xy 400.933394 -286.210684) (xy 400.886123 -286.224376) (xy 400.837268 -286.230308) (xy 400.788093 -286.228327)
			(xy 400.739874 -286.218483) (xy 400.693858 -286.201031) (xy 400.651237 -286.176424) (xy 400.613116 -286.145299)
			(xy 400.580481 -286.108462) (xy 400.554178 -286.066866) (xy 400.534887 -286.02159) (xy 400.52311 -285.973806)
			(xy 400.51915 -285.924752) (xy 400.180302 -285.924752) (xy 400.179807 -285.949359) (xy 400.171912 -285.997936)
			(xy 400.156328 -286.044617) (xy 400.133457 -286.088194) (xy 400.103892 -286.127538) (xy 400.068399 -286.16163)
			(xy 400.027896 -286.189586) (xy 399.983434 -286.210684) (xy 399.936163 -286.224376) (xy 399.887308 -286.230308)
			(xy 399.838133 -286.228327) (xy 399.789914 -286.218483) (xy 399.743898 -286.201031) (xy 399.701277 -286.176424)
			(xy 399.663156 -286.145299) (xy 399.630521 -286.108462) (xy 399.604218 -286.066866) (xy 399.584927 -286.02159)
			(xy 399.57315 -285.973806) (xy 399.56919 -285.924752) (xy 399.230342 -285.924752) (xy 399.229847 -285.949359)
			(xy 399.221952 -285.997936) (xy 399.206368 -286.044617) (xy 399.183497 -286.088194) (xy 399.153932 -286.127538)
			(xy 399.118439 -286.16163) (xy 399.077936 -286.189586) (xy 399.033474 -286.210684) (xy 398.986203 -286.224376)
			(xy 398.937348 -286.230308) (xy 398.888173 -286.228327) (xy 398.839954 -286.218483) (xy 398.793938 -286.201031)
			(xy 398.751317 -286.176424) (xy 398.713196 -286.145299) (xy 398.680561 -286.108462) (xy 398.654258 -286.066866)
			(xy 398.634967 -286.02159) (xy 398.62319 -285.973806) (xy 398.61923 -285.924752) (xy 398.280128 -285.924752)
			(xy 398.279633 -285.949359) (xy 398.271738 -285.997936) (xy 398.256154 -286.044617) (xy 398.233283 -286.088194)
			(xy 398.203718 -286.127538) (xy 398.168225 -286.16163) (xy 398.127722 -286.189586) (xy 398.08326 -286.210684)
			(xy 398.035989 -286.224376) (xy 397.987134 -286.230308) (xy 397.937959 -286.228327) (xy 397.88974 -286.218483)
			(xy 397.843724 -286.201031) (xy 397.801103 -286.176424) (xy 397.762982 -286.145299) (xy 397.730347 -286.108462)
			(xy 397.704044 -286.066866) (xy 397.684753 -286.02159) (xy 397.672976 -285.973806) (xy 397.669016 -285.924752)
			(xy 397.330168 -285.924752) (xy 397.329673 -285.949359) (xy 397.321778 -285.997936) (xy 397.306194 -286.044617)
			(xy 397.283323 -286.088194) (xy 397.253758 -286.127538) (xy 397.218265 -286.16163) (xy 397.177762 -286.189586)
			(xy 397.1333 -286.210684) (xy 397.086029 -286.224376) (xy 397.037174 -286.230308) (xy 396.987999 -286.228327)
			(xy 396.93978 -286.218483) (xy 396.893764 -286.201031) (xy 396.851143 -286.176424) (xy 396.813022 -286.145299)
			(xy 396.780387 -286.108462) (xy 396.754084 -286.066866) (xy 396.734793 -286.02159) (xy 396.723016 -285.973806)
			(xy 396.719056 -285.924752) (xy 396.380208 -285.924752) (xy 396.379713 -285.949359) (xy 396.371818 -285.997936)
			(xy 396.356234 -286.044617) (xy 396.333363 -286.088194) (xy 396.303798 -286.127538) (xy 396.268305 -286.16163)
			(xy 396.227802 -286.189586) (xy 396.18334 -286.210684) (xy 396.136069 -286.224376) (xy 396.087214 -286.230308)
			(xy 396.038039 -286.228327) (xy 395.98982 -286.218483) (xy 395.943804 -286.201031) (xy 395.901183 -286.176424)
			(xy 395.863062 -286.145299) (xy 395.830427 -286.108462) (xy 395.804124 -286.066866) (xy 395.784833 -286.02159)
			(xy 395.773056 -285.973806) (xy 395.769096 -285.924752) (xy 395.430248 -285.924752) (xy 395.429753 -285.949359)
			(xy 395.421858 -285.997936) (xy 395.406274 -286.044617) (xy 395.383403 -286.088194) (xy 395.353838 -286.127538)
			(xy 395.318345 -286.16163) (xy 395.277842 -286.189586) (xy 395.23338 -286.210684) (xy 395.186109 -286.224376)
			(xy 395.137254 -286.230308) (xy 395.088079 -286.228327) (xy 395.03986 -286.218483) (xy 394.993844 -286.201031)
			(xy 394.951223 -286.176424) (xy 394.913102 -286.145299) (xy 394.880467 -286.108462) (xy 394.854164 -286.066866)
			(xy 394.834873 -286.02159) (xy 394.823096 -285.973806) (xy 394.819136 -285.924752) (xy 394.480288 -285.924752)
			(xy 394.479793 -285.949359) (xy 394.471898 -285.997936) (xy 394.456314 -286.044617) (xy 394.433443 -286.088194)
			(xy 394.403878 -286.127538) (xy 394.368385 -286.16163) (xy 394.327882 -286.189586) (xy 394.28342 -286.210684)
			(xy 394.236149 -286.224376) (xy 394.187294 -286.230308) (xy 394.138119 -286.228327) (xy 394.0899 -286.218483)
			(xy 394.043884 -286.201031) (xy 394.001263 -286.176424) (xy 393.963142 -286.145299) (xy 393.930507 -286.108462)
			(xy 393.904204 -286.066866) (xy 393.884913 -286.02159) (xy 393.873136 -285.973806) (xy 393.869176 -285.924752)
			(xy 393.530328 -285.924752) (xy 393.529833 -285.949359) (xy 393.521938 -285.997936) (xy 393.506354 -286.044617)
			(xy 393.483483 -286.088194) (xy 393.453918 -286.127538) (xy 393.418425 -286.16163) (xy 393.377922 -286.189586)
			(xy 393.33346 -286.210684) (xy 393.286189 -286.224376) (xy 393.237334 -286.230308) (xy 393.188159 -286.228327)
			(xy 393.13994 -286.218483) (xy 393.093924 -286.201031) (xy 393.051303 -286.176424) (xy 393.013182 -286.145299)
			(xy 392.980547 -286.108462) (xy 392.954244 -286.066866) (xy 392.934953 -286.02159) (xy 392.923176 -285.973806)
			(xy 392.919216 -285.924752) (xy 389.73012 -285.924752) (xy 389.730571 -285.933079) (xy 389.725205 -285.982419)
			(xy 389.711928 -286.030242) (xy 389.69109 -286.075286) (xy 389.663239 -286.116367) (xy 389.629109 -286.1524)
			(xy 389.589599 -286.182438) (xy 389.545751 -286.205688) (xy 389.498719 -286.221539) (xy 389.449742 -286.229572)
			(xy 389.424926 -286.23006) (xy 389.41139 -286.229907) (xy 389.384426 -286.227489) (xy 389.371078 -286.225234)
			(xy 389.358886 -286.223202) (xy 389.335264 -286.230568) (xy 389.326374 -286.239458) (xy 389.31966 -286.246894)
			(xy 389.312025 -286.265393) (xy 389.312025 -286.285406) (xy 389.319659 -286.303905) (xy 389.326374 -286.31134)
			(xy 389.352028 -286.336994) (xy 389.352282 -286.336994) (xy 389.368782 -286.354151) (xy 389.396855 -286.392587)
			(xy 389.418624 -286.434914) (xy 389.433561 -286.480106) (xy 389.441306 -286.527068) (xy 389.441944 -286.550862)
			(xy 389.441944 -286.551878) (xy 389.442452 -286.570166) (xy 389.467092 -286.57207) (xy 389.515327 -286.582819)
			(xy 389.5612 -286.601195) (xy 389.603516 -286.626719) (xy 389.641169 -286.658725) (xy 389.673176 -286.696377)
			(xy 389.698701 -286.738692) (xy 389.717079 -286.784565) (xy 389.727829 -286.8328) (xy 389.729726 -286.85744)
			(xy 389.749538 -286.857948) (xy 389.750046 -286.857948) (xy 389.773738 -286.858667) (xy 389.820485 -286.866491)
			(xy 389.86546 -286.881446) (xy 389.907584 -286.903173) (xy 389.945843 -286.931149) (xy 389.962898 -286.94761)
			(xy 389.962898 -286.947864) (xy 389.983472 -286.968438) (xy 389.988552 -286.973264) (xy 389.995964 -286.979948)
			(xy 390.014397 -286.987545) (xy 390.034335 -286.987545) (xy 390.052768 -286.979948) (xy 390.06018 -286.973264)
			(xy 390.06907 -286.964374) (xy 390.076436 -286.940752) (xy 390.074404 -286.92856) (xy 390.072167 -286.915274)
			(xy 390.069749 -286.888438) (xy 390.069578 -286.874966) (xy 390.0701 -286.849711) (xy 390.078413 -286.799889)
			(xy 390.094814 -286.752115) (xy 390.118855 -286.707692) (xy 390.149879 -286.667832) (xy 390.187041 -286.633622)
			(xy 390.229327 -286.605996) (xy 390.275583 -286.585706) (xy 390.324548 -286.573306) (xy 390.374886 -286.569135)
			(xy 390.425224 -286.573306) (xy 390.474189 -286.585706) (xy 390.520445 -286.605996) (xy 390.562731 -286.633622)
			(xy 390.599893 -286.667832) (xy 390.630917 -286.707692) (xy 390.654958 -286.752115) (xy 390.671359 -286.799889)
			(xy 390.679672 -286.849711) (xy 390.680189 -286.874712) (xy 391.019042 -286.874712) (xy 391.023002 -286.825658)
			(xy 391.034779 -286.777874) (xy 391.05407 -286.732598) (xy 391.080373 -286.691002) (xy 391.113008 -286.654165)
			(xy 391.151129 -286.62304) (xy 391.19375 -286.598433) (xy 391.239766 -286.580981) (xy 391.287985 -286.571137)
			(xy 391.33716 -286.569156) (xy 391.386015 -286.575088) (xy 391.433286 -286.58878) (xy 391.477748 -286.609878)
			(xy 391.518251 -286.637834) (xy 391.553744 -286.671926) (xy 391.583309 -286.71127) (xy 391.60618 -286.754847)
			(xy 391.621764 -286.801528) (xy 391.629659 -286.850105) (xy 391.630154 -286.874712) (xy 391.969002 -286.874712)
			(xy 391.972962 -286.825658) (xy 391.984739 -286.777874) (xy 392.00403 -286.732598) (xy 392.030333 -286.691002)
			(xy 392.062968 -286.654165) (xy 392.101089 -286.62304) (xy 392.14371 -286.598433) (xy 392.189726 -286.580981)
			(xy 392.237945 -286.571137) (xy 392.28712 -286.569156) (xy 392.335975 -286.575088) (xy 392.383246 -286.58878)
			(xy 392.427708 -286.609878) (xy 392.468211 -286.637834) (xy 392.503704 -286.671926) (xy 392.533269 -286.71127)
			(xy 392.55614 -286.754847) (xy 392.571724 -286.801528) (xy 392.579619 -286.850105) (xy 392.580114 -286.874712)
			(xy 392.580109 -286.874966) (xy 392.919216 -286.874966) (xy 392.923176 -286.825912) (xy 392.934953 -286.778128)
			(xy 392.954244 -286.732852) (xy 392.980547 -286.691256) (xy 393.013182 -286.654419) (xy 393.051303 -286.623294)
			(xy 393.093924 -286.598687) (xy 393.13994 -286.581235) (xy 393.188159 -286.571391) (xy 393.237334 -286.56941)
			(xy 393.286189 -286.575342) (xy 393.33346 -286.589034) (xy 393.377922 -286.610132) (xy 393.418425 -286.638088)
			(xy 393.453918 -286.67218) (xy 393.483483 -286.711524) (xy 393.506354 -286.755101) (xy 393.521938 -286.801782)
			(xy 393.529833 -286.850359) (xy 393.530328 -286.874966) (xy 393.869176 -286.874966) (xy 393.873136 -286.825912)
			(xy 393.884913 -286.778128) (xy 393.904204 -286.732852) (xy 393.930507 -286.691256) (xy 393.963142 -286.654419)
			(xy 394.001263 -286.623294) (xy 394.043884 -286.598687) (xy 394.0899 -286.581235) (xy 394.138119 -286.571391)
			(xy 394.187294 -286.56941) (xy 394.236149 -286.575342) (xy 394.28342 -286.589034) (xy 394.327882 -286.610132)
			(xy 394.368385 -286.638088) (xy 394.403878 -286.67218) (xy 394.433443 -286.711524) (xy 394.456314 -286.755101)
			(xy 394.471898 -286.801782) (xy 394.479793 -286.850359) (xy 394.480288 -286.874966) (xy 394.819136 -286.874966)
			(xy 394.823096 -286.825912) (xy 394.834873 -286.778128) (xy 394.854164 -286.732852) (xy 394.880467 -286.691256)
			(xy 394.913102 -286.654419) (xy 394.951223 -286.623294) (xy 394.993844 -286.598687) (xy 395.03986 -286.581235)
			(xy 395.088079 -286.571391) (xy 395.137254 -286.56941) (xy 395.186109 -286.575342) (xy 395.23338 -286.589034)
			(xy 395.277842 -286.610132) (xy 395.318345 -286.638088) (xy 395.353838 -286.67218) (xy 395.383403 -286.711524)
			(xy 395.406274 -286.755101) (xy 395.421858 -286.801782) (xy 395.429753 -286.850359) (xy 395.430248 -286.874966)
			(xy 395.769096 -286.874966) (xy 395.773056 -286.825912) (xy 395.784833 -286.778128) (xy 395.804124 -286.732852)
			(xy 395.830427 -286.691256) (xy 395.863062 -286.654419) (xy 395.901183 -286.623294) (xy 395.943804 -286.598687)
			(xy 395.98982 -286.581235) (xy 396.038039 -286.571391) (xy 396.087214 -286.56941) (xy 396.136069 -286.575342)
			(xy 396.18334 -286.589034) (xy 396.227802 -286.610132) (xy 396.268305 -286.638088) (xy 396.303798 -286.67218)
			(xy 396.333363 -286.711524) (xy 396.356234 -286.755101) (xy 396.371818 -286.801782) (xy 396.379713 -286.850359)
			(xy 396.380208 -286.874966) (xy 396.719056 -286.874966) (xy 396.723016 -286.825912) (xy 396.734793 -286.778128)
			(xy 396.754084 -286.732852) (xy 396.780387 -286.691256) (xy 396.813022 -286.654419) (xy 396.851143 -286.623294)
			(xy 396.893764 -286.598687) (xy 396.93978 -286.581235) (xy 396.987999 -286.571391) (xy 397.037174 -286.56941)
			(xy 397.086029 -286.575342) (xy 397.1333 -286.589034) (xy 397.177762 -286.610132) (xy 397.218265 -286.638088)
			(xy 397.253758 -286.67218) (xy 397.283323 -286.711524) (xy 397.306194 -286.755101) (xy 397.321778 -286.801782)
			(xy 397.329673 -286.850359) (xy 397.330168 -286.874966) (xy 397.669016 -286.874966) (xy 397.672976 -286.825912)
			(xy 397.684753 -286.778128) (xy 397.704044 -286.732852) (xy 397.730347 -286.691256) (xy 397.762982 -286.654419)
			(xy 397.801103 -286.623294) (xy 397.843724 -286.598687) (xy 397.88974 -286.581235) (xy 397.937959 -286.571391)
			(xy 397.987134 -286.56941) (xy 398.035989 -286.575342) (xy 398.08326 -286.589034) (xy 398.127722 -286.610132)
			(xy 398.168225 -286.638088) (xy 398.203718 -286.67218) (xy 398.233283 -286.711524) (xy 398.256154 -286.755101)
			(xy 398.271738 -286.801782) (xy 398.279633 -286.850359) (xy 398.280128 -286.874966) (xy 398.61923 -286.874966)
			(xy 398.62319 -286.825912) (xy 398.634967 -286.778128) (xy 398.654258 -286.732852) (xy 398.680561 -286.691256)
			(xy 398.713196 -286.654419) (xy 398.751317 -286.623294) (xy 398.793938 -286.598687) (xy 398.839954 -286.581235)
			(xy 398.888173 -286.571391) (xy 398.937348 -286.56941) (xy 398.986203 -286.575342) (xy 399.033474 -286.589034)
			(xy 399.077936 -286.610132) (xy 399.118439 -286.638088) (xy 399.153932 -286.67218) (xy 399.183497 -286.711524)
			(xy 399.206368 -286.755101) (xy 399.221952 -286.801782) (xy 399.229847 -286.850359) (xy 399.230342 -286.874966)
			(xy 399.56919 -286.874966) (xy 399.57315 -286.825912) (xy 399.584927 -286.778128) (xy 399.604218 -286.732852)
			(xy 399.630521 -286.691256) (xy 399.663156 -286.654419) (xy 399.701277 -286.623294) (xy 399.743898 -286.598687)
			(xy 399.789914 -286.581235) (xy 399.838133 -286.571391) (xy 399.887308 -286.56941) (xy 399.936163 -286.575342)
			(xy 399.983434 -286.589034) (xy 400.027896 -286.610132) (xy 400.068399 -286.638088) (xy 400.103892 -286.67218)
			(xy 400.133457 -286.711524) (xy 400.156328 -286.755101) (xy 400.171912 -286.801782) (xy 400.179807 -286.850359)
			(xy 400.180302 -286.874966) (xy 400.51915 -286.874966) (xy 400.52311 -286.825912) (xy 400.534887 -286.778128)
			(xy 400.554178 -286.732852) (xy 400.580481 -286.691256) (xy 400.613116 -286.654419) (xy 400.651237 -286.623294)
			(xy 400.693858 -286.598687) (xy 400.739874 -286.581235) (xy 400.788093 -286.571391) (xy 400.837268 -286.56941)
			(xy 400.886123 -286.575342) (xy 400.933394 -286.589034) (xy 400.977856 -286.610132) (xy 401.018359 -286.638088)
			(xy 401.053852 -286.67218) (xy 401.083417 -286.711524) (xy 401.106288 -286.755101) (xy 401.121872 -286.801782)
			(xy 401.129767 -286.850359) (xy 401.130262 -286.874966) (xy 401.46911 -286.874966) (xy 401.47307 -286.825912)
			(xy 401.484847 -286.778128) (xy 401.504138 -286.732852) (xy 401.530441 -286.691256) (xy 401.563076 -286.654419)
			(xy 401.601197 -286.623294) (xy 401.643818 -286.598687) (xy 401.689834 -286.581235) (xy 401.738053 -286.571391)
			(xy 401.787228 -286.56941) (xy 401.836083 -286.575342) (xy 401.883354 -286.589034) (xy 401.927816 -286.610132)
			(xy 401.968319 -286.638088) (xy 402.003812 -286.67218) (xy 402.033377 -286.711524) (xy 402.056248 -286.755101)
			(xy 402.071832 -286.801782) (xy 402.079727 -286.850359) (xy 402.080222 -286.874966) (xy 402.41907 -286.874966)
			(xy 402.42303 -286.825912) (xy 402.434807 -286.778128) (xy 402.454098 -286.732852) (xy 402.480401 -286.691256)
			(xy 402.513036 -286.654419) (xy 402.551157 -286.623294) (xy 402.593778 -286.598687) (xy 402.639794 -286.581235)
			(xy 402.688013 -286.571391) (xy 402.737188 -286.56941) (xy 402.786043 -286.575342) (xy 402.833314 -286.589034)
			(xy 402.877776 -286.610132) (xy 402.918279 -286.638088) (xy 402.953772 -286.67218) (xy 402.983337 -286.711524)
			(xy 403.006208 -286.755101) (xy 403.021792 -286.801782) (xy 403.029687 -286.850359) (xy 403.030182 -286.874966)
			(xy 403.36903 -286.874966) (xy 403.37299 -286.825912) (xy 403.384767 -286.778128) (xy 403.404058 -286.732852)
			(xy 403.430361 -286.691256) (xy 403.462996 -286.654419) (xy 403.501117 -286.623294) (xy 403.543738 -286.598687)
			(xy 403.589754 -286.581235) (xy 403.637973 -286.571391) (xy 403.687148 -286.56941) (xy 403.736003 -286.575342)
			(xy 403.783274 -286.589034) (xy 403.827736 -286.610132) (xy 403.868239 -286.638088) (xy 403.903732 -286.67218)
			(xy 403.933297 -286.711524) (xy 403.956168 -286.755101) (xy 403.971752 -286.801782) (xy 403.979647 -286.850359)
			(xy 403.980142 -286.874966) (xy 404.31899 -286.874966) (xy 404.32295 -286.825912) (xy 404.334727 -286.778128)
			(xy 404.354018 -286.732852) (xy 404.380321 -286.691256) (xy 404.412956 -286.654419) (xy 404.451077 -286.623294)
			(xy 404.493698 -286.598687) (xy 404.539714 -286.581235) (xy 404.587933 -286.571391) (xy 404.637108 -286.56941)
			(xy 404.685963 -286.575342) (xy 404.733234 -286.589034) (xy 404.777696 -286.610132) (xy 404.818199 -286.638088)
			(xy 404.853692 -286.67218) (xy 404.883257 -286.711524) (xy 404.906128 -286.755101) (xy 404.921712 -286.801782)
			(xy 404.929607 -286.850359) (xy 404.930102 -286.874966) (xy 405.269204 -286.874966) (xy 405.273164 -286.825912)
			(xy 405.284941 -286.778128) (xy 405.304232 -286.732852) (xy 405.330535 -286.691256) (xy 405.36317 -286.654419)
			(xy 405.401291 -286.623294) (xy 405.443912 -286.598687) (xy 405.489928 -286.581235) (xy 405.538147 -286.571391)
			(xy 405.587322 -286.56941) (xy 405.636177 -286.575342) (xy 405.683448 -286.589034) (xy 405.72791 -286.610132)
			(xy 405.768413 -286.638088) (xy 405.803906 -286.67218) (xy 405.833471 -286.711524) (xy 405.856342 -286.755101)
			(xy 405.871926 -286.801782) (xy 405.879821 -286.850359) (xy 405.880316 -286.874966) (xy 406.219164 -286.874966)
			(xy 406.223124 -286.825912) (xy 406.234901 -286.778128) (xy 406.254192 -286.732852) (xy 406.280495 -286.691256)
			(xy 406.31313 -286.654419) (xy 406.351251 -286.623294) (xy 406.393872 -286.598687) (xy 406.439888 -286.581235)
			(xy 406.488107 -286.571391) (xy 406.537282 -286.56941) (xy 406.586137 -286.575342) (xy 406.633408 -286.589034)
			(xy 406.67787 -286.610132) (xy 406.718373 -286.638088) (xy 406.753866 -286.67218) (xy 406.783431 -286.711524)
			(xy 406.806302 -286.755101) (xy 406.821886 -286.801782) (xy 406.829781 -286.850359) (xy 406.830276 -286.874966)
			(xy 408.119084 -286.874966) (xy 408.123044 -286.825912) (xy 408.134821 -286.778128) (xy 408.154112 -286.732852)
			(xy 408.180415 -286.691256) (xy 408.21305 -286.654419) (xy 408.251171 -286.623294) (xy 408.293792 -286.598687)
			(xy 408.339808 -286.581235) (xy 408.388027 -286.571391) (xy 408.437202 -286.56941) (xy 408.486057 -286.575342)
			(xy 408.533328 -286.589034) (xy 408.57779 -286.610132) (xy 408.618293 -286.638088) (xy 408.653786 -286.67218)
			(xy 408.683351 -286.711524) (xy 408.706222 -286.755101) (xy 408.721806 -286.801782) (xy 408.729701 -286.850359)
			(xy 408.730196 -286.874966) (xy 409.069044 -286.874966) (xy 409.073004 -286.825912) (xy 409.084781 -286.778128)
			(xy 409.104072 -286.732852) (xy 409.130375 -286.691256) (xy 409.16301 -286.654419) (xy 409.201131 -286.623294)
			(xy 409.243752 -286.598687) (xy 409.289768 -286.581235) (xy 409.337987 -286.571391) (xy 409.387162 -286.56941)
			(xy 409.436017 -286.575342) (xy 409.483288 -286.589034) (xy 409.52775 -286.610132) (xy 409.568253 -286.638088)
			(xy 409.603746 -286.67218) (xy 409.633311 -286.711524) (xy 409.656182 -286.755101) (xy 409.671766 -286.801782)
			(xy 409.679661 -286.850359) (xy 409.680156 -286.874966) (xy 410.019004 -286.874966) (xy 410.022964 -286.825912)
			(xy 410.034741 -286.778128) (xy 410.054032 -286.732852) (xy 410.080335 -286.691256) (xy 410.11297 -286.654419)
			(xy 410.151091 -286.623294) (xy 410.193712 -286.598687) (xy 410.239728 -286.581235) (xy 410.287947 -286.571391)
			(xy 410.337122 -286.56941) (xy 410.385977 -286.575342) (xy 410.433248 -286.589034) (xy 410.47771 -286.610132)
			(xy 410.518213 -286.638088) (xy 410.553706 -286.67218) (xy 410.583271 -286.711524) (xy 410.606142 -286.755101)
			(xy 410.621726 -286.801782) (xy 410.629621 -286.850359) (xy 410.630116 -286.874966) (xy 410.969218 -286.874966)
			(xy 410.973178 -286.825912) (xy 410.984955 -286.778128) (xy 411.004246 -286.732852) (xy 411.030549 -286.691256)
			(xy 411.063184 -286.654419) (xy 411.101305 -286.623294) (xy 411.143926 -286.598687) (xy 411.189942 -286.581235)
			(xy 411.238161 -286.571391) (xy 411.287336 -286.56941) (xy 411.336191 -286.575342) (xy 411.383462 -286.589034)
			(xy 411.427924 -286.610132) (xy 411.468427 -286.638088) (xy 411.50392 -286.67218) (xy 411.533485 -286.711524)
			(xy 411.556356 -286.755101) (xy 411.57194 -286.801782) (xy 411.579835 -286.850359) (xy 411.58033 -286.874966)
			(xy 411.919178 -286.874966) (xy 411.923138 -286.825912) (xy 411.934915 -286.778128) (xy 411.954206 -286.732852)
			(xy 411.980509 -286.691256) (xy 412.013144 -286.654419) (xy 412.051265 -286.623294) (xy 412.093886 -286.598687)
			(xy 412.139902 -286.581235) (xy 412.188121 -286.571391) (xy 412.237296 -286.56941) (xy 412.286151 -286.575342)
			(xy 412.333422 -286.589034) (xy 412.377884 -286.610132) (xy 412.418387 -286.638088) (xy 412.45388 -286.67218)
			(xy 412.483445 -286.711524) (xy 412.506316 -286.755101) (xy 412.5219 -286.801782) (xy 412.529795 -286.850359)
			(xy 412.53029 -286.874966) (xy 412.869138 -286.874966) (xy 412.873098 -286.825912) (xy 412.884875 -286.778128)
			(xy 412.904166 -286.732852) (xy 412.930469 -286.691256) (xy 412.963104 -286.654419) (xy 413.001225 -286.623294)
			(xy 413.043846 -286.598687) (xy 413.089862 -286.581235) (xy 413.138081 -286.571391) (xy 413.187256 -286.56941)
			(xy 413.236111 -286.575342) (xy 413.283382 -286.589034) (xy 413.327844 -286.610132) (xy 413.368347 -286.638088)
			(xy 413.40384 -286.67218) (xy 413.433405 -286.711524) (xy 413.456276 -286.755101) (xy 413.47186 -286.801782)
			(xy 413.479755 -286.850359) (xy 413.48025 -286.874966) (xy 413.819098 -286.874966) (xy 413.823058 -286.825912)
			(xy 413.834835 -286.778128) (xy 413.854126 -286.732852) (xy 413.880429 -286.691256) (xy 413.913064 -286.654419)
			(xy 413.951185 -286.623294) (xy 413.993806 -286.598687) (xy 414.039822 -286.581235) (xy 414.088041 -286.571391)
			(xy 414.137216 -286.56941) (xy 414.186071 -286.575342) (xy 414.233342 -286.589034) (xy 414.277804 -286.610132)
			(xy 414.318307 -286.638088) (xy 414.3538 -286.67218) (xy 414.383365 -286.711524) (xy 414.406236 -286.755101)
			(xy 414.42182 -286.801782) (xy 414.429715 -286.850359) (xy 414.43021 -286.874966) (xy 414.769058 -286.874966)
			(xy 414.773018 -286.825912) (xy 414.784795 -286.778128) (xy 414.804086 -286.732852) (xy 414.830389 -286.691256)
			(xy 414.863024 -286.654419) (xy 414.901145 -286.623294) (xy 414.943766 -286.598687) (xy 414.989782 -286.581235)
			(xy 415.038001 -286.571391) (xy 415.087176 -286.56941) (xy 415.136031 -286.575342) (xy 415.183302 -286.589034)
			(xy 415.227764 -286.610132) (xy 415.268267 -286.638088) (xy 415.30376 -286.67218) (xy 415.333325 -286.711524)
			(xy 415.356196 -286.755101) (xy 415.37178 -286.801782) (xy 415.379675 -286.850359) (xy 415.38017 -286.874966)
			(xy 415.719018 -286.874966) (xy 415.722978 -286.825912) (xy 415.734755 -286.778128) (xy 415.754046 -286.732852)
			(xy 415.780349 -286.691256) (xy 415.812984 -286.654419) (xy 415.851105 -286.623294) (xy 415.893726 -286.598687)
			(xy 415.939742 -286.581235) (xy 415.987961 -286.571391) (xy 416.037136 -286.56941) (xy 416.085991 -286.575342)
			(xy 416.133262 -286.589034) (xy 416.177724 -286.610132) (xy 416.218227 -286.638088) (xy 416.25372 -286.67218)
			(xy 416.283285 -286.711524) (xy 416.306156 -286.755101) (xy 416.32174 -286.801782) (xy 416.329635 -286.850359)
			(xy 416.33013 -286.874966) (xy 416.668978 -286.874966) (xy 416.672938 -286.825912) (xy 416.684715 -286.778128)
			(xy 416.704006 -286.732852) (xy 416.730309 -286.691256) (xy 416.762944 -286.654419) (xy 416.801065 -286.623294)
			(xy 416.843686 -286.598687) (xy 416.889702 -286.581235) (xy 416.937921 -286.571391) (xy 416.987096 -286.56941)
			(xy 417.035951 -286.575342) (xy 417.083222 -286.589034) (xy 417.127684 -286.610132) (xy 417.168187 -286.638088)
			(xy 417.20368 -286.67218) (xy 417.233245 -286.711524) (xy 417.256116 -286.755101) (xy 417.2717 -286.801782)
			(xy 417.279595 -286.850359) (xy 417.28009 -286.874966) (xy 417.279595 -286.899573) (xy 417.2717 -286.94815)
			(xy 417.256116 -286.994831) (xy 417.233245 -287.038408) (xy 417.20368 -287.077752) (xy 417.168187 -287.111844)
			(xy 417.127684 -287.1398) (xy 417.083222 -287.160898) (xy 417.035951 -287.17459) (xy 416.987096 -287.180522)
			(xy 416.937921 -287.178541) (xy 416.889702 -287.168697) (xy 416.843686 -287.151245) (xy 416.801065 -287.126638)
			(xy 416.762944 -287.095513) (xy 416.730309 -287.058676) (xy 416.704006 -287.01708) (xy 416.684715 -286.971804)
			(xy 416.672938 -286.92402) (xy 416.668978 -286.874966) (xy 416.33013 -286.874966) (xy 416.329635 -286.899573)
			(xy 416.32174 -286.94815) (xy 416.306156 -286.994831) (xy 416.283285 -287.038408) (xy 416.25372 -287.077752)
			(xy 416.218227 -287.111844) (xy 416.177724 -287.1398) (xy 416.133262 -287.160898) (xy 416.085991 -287.17459)
			(xy 416.037136 -287.180522) (xy 415.987961 -287.178541) (xy 415.939742 -287.168697) (xy 415.893726 -287.151245)
			(xy 415.851105 -287.126638) (xy 415.812984 -287.095513) (xy 415.780349 -287.058676) (xy 415.754046 -287.01708)
			(xy 415.734755 -286.971804) (xy 415.722978 -286.92402) (xy 415.719018 -286.874966) (xy 415.38017 -286.874966)
			(xy 415.379675 -286.899573) (xy 415.37178 -286.94815) (xy 415.356196 -286.994831) (xy 415.333325 -287.038408)
			(xy 415.30376 -287.077752) (xy 415.268267 -287.111844) (xy 415.227764 -287.1398) (xy 415.183302 -287.160898)
			(xy 415.136031 -287.17459) (xy 415.087176 -287.180522) (xy 415.038001 -287.178541) (xy 414.989782 -287.168697)
			(xy 414.943766 -287.151245) (xy 414.901145 -287.126638) (xy 414.863024 -287.095513) (xy 414.830389 -287.058676)
			(xy 414.804086 -287.01708) (xy 414.784795 -286.971804) (xy 414.773018 -286.92402) (xy 414.769058 -286.874966)
			(xy 414.43021 -286.874966) (xy 414.429715 -286.899573) (xy 414.42182 -286.94815) (xy 414.406236 -286.994831)
			(xy 414.383365 -287.038408) (xy 414.3538 -287.077752) (xy 414.318307 -287.111844) (xy 414.277804 -287.1398)
			(xy 414.233342 -287.160898) (xy 414.186071 -287.17459) (xy 414.137216 -287.180522) (xy 414.088041 -287.178541)
			(xy 414.039822 -287.168697) (xy 413.993806 -287.151245) (xy 413.951185 -287.126638) (xy 413.913064 -287.095513)
			(xy 413.880429 -287.058676) (xy 413.854126 -287.01708) (xy 413.834835 -286.971804) (xy 413.823058 -286.92402)
			(xy 413.819098 -286.874966) (xy 413.48025 -286.874966) (xy 413.479755 -286.899573) (xy 413.47186 -286.94815)
			(xy 413.456276 -286.994831) (xy 413.433405 -287.038408) (xy 413.40384 -287.077752) (xy 413.368347 -287.111844)
			(xy 413.327844 -287.1398) (xy 413.283382 -287.160898) (xy 413.236111 -287.17459) (xy 413.187256 -287.180522)
			(xy 413.138081 -287.178541) (xy 413.089862 -287.168697) (xy 413.043846 -287.151245) (xy 413.001225 -287.126638)
			(xy 412.963104 -287.095513) (xy 412.930469 -287.058676) (xy 412.904166 -287.01708) (xy 412.884875 -286.971804)
			(xy 412.873098 -286.92402) (xy 412.869138 -286.874966) (xy 412.53029 -286.874966) (xy 412.529795 -286.899573)
			(xy 412.5219 -286.94815) (xy 412.506316 -286.994831) (xy 412.483445 -287.038408) (xy 412.45388 -287.077752)
			(xy 412.418387 -287.111844) (xy 412.377884 -287.1398) (xy 412.333422 -287.160898) (xy 412.286151 -287.17459)
			(xy 412.237296 -287.180522) (xy 412.188121 -287.178541) (xy 412.139902 -287.168697) (xy 412.093886 -287.151245)
			(xy 412.051265 -287.126638) (xy 412.013144 -287.095513) (xy 411.980509 -287.058676) (xy 411.954206 -287.01708)
			(xy 411.934915 -286.971804) (xy 411.923138 -286.92402) (xy 411.919178 -286.874966) (xy 411.58033 -286.874966)
			(xy 411.579835 -286.899573) (xy 411.57194 -286.94815) (xy 411.556356 -286.994831) (xy 411.533485 -287.038408)
			(xy 411.50392 -287.077752) (xy 411.468427 -287.111844) (xy 411.427924 -287.1398) (xy 411.383462 -287.160898)
			(xy 411.336191 -287.17459) (xy 411.287336 -287.180522) (xy 411.238161 -287.178541) (xy 411.189942 -287.168697)
			(xy 411.143926 -287.151245) (xy 411.101305 -287.126638) (xy 411.063184 -287.095513) (xy 411.030549 -287.058676)
			(xy 411.004246 -287.01708) (xy 410.984955 -286.971804) (xy 410.973178 -286.92402) (xy 410.969218 -286.874966)
			(xy 410.630116 -286.874966) (xy 410.629621 -286.899573) (xy 410.621726 -286.94815) (xy 410.606142 -286.994831)
			(xy 410.583271 -287.038408) (xy 410.553706 -287.077752) (xy 410.518213 -287.111844) (xy 410.47771 -287.1398)
			(xy 410.433248 -287.160898) (xy 410.385977 -287.17459) (xy 410.337122 -287.180522) (xy 410.287947 -287.178541)
			(xy 410.239728 -287.168697) (xy 410.193712 -287.151245) (xy 410.151091 -287.126638) (xy 410.11297 -287.095513)
			(xy 410.080335 -287.058676) (xy 410.054032 -287.01708) (xy 410.034741 -286.971804) (xy 410.022964 -286.92402)
			(xy 410.019004 -286.874966) (xy 409.680156 -286.874966) (xy 409.679661 -286.899573) (xy 409.671766 -286.94815)
			(xy 409.656182 -286.994831) (xy 409.633311 -287.038408) (xy 409.603746 -287.077752) (xy 409.568253 -287.111844)
			(xy 409.52775 -287.1398) (xy 409.483288 -287.160898) (xy 409.436017 -287.17459) (xy 409.387162 -287.180522)
			(xy 409.337987 -287.178541) (xy 409.289768 -287.168697) (xy 409.243752 -287.151245) (xy 409.201131 -287.126638)
			(xy 409.16301 -287.095513) (xy 409.130375 -287.058676) (xy 409.104072 -287.01708) (xy 409.084781 -286.971804)
			(xy 409.073004 -286.92402) (xy 409.069044 -286.874966) (xy 408.730196 -286.874966) (xy 408.729701 -286.899573)
			(xy 408.721806 -286.94815) (xy 408.706222 -286.994831) (xy 408.683351 -287.038408) (xy 408.653786 -287.077752)
			(xy 408.618293 -287.111844) (xy 408.57779 -287.1398) (xy 408.533328 -287.160898) (xy 408.486057 -287.17459)
			(xy 408.437202 -287.180522) (xy 408.388027 -287.178541) (xy 408.339808 -287.168697) (xy 408.293792 -287.151245)
			(xy 408.251171 -287.126638) (xy 408.21305 -287.095513) (xy 408.180415 -287.058676) (xy 408.154112 -287.01708)
			(xy 408.134821 -286.971804) (xy 408.123044 -286.92402) (xy 408.119084 -286.874966) (xy 406.830276 -286.874966)
			(xy 406.829781 -286.899573) (xy 406.821886 -286.94815) (xy 406.806302 -286.994831) (xy 406.783431 -287.038408)
			(xy 406.753866 -287.077752) (xy 406.718373 -287.111844) (xy 406.67787 -287.1398) (xy 406.633408 -287.160898)
			(xy 406.586137 -287.17459) (xy 406.537282 -287.180522) (xy 406.488107 -287.178541) (xy 406.439888 -287.168697)
			(xy 406.393872 -287.151245) (xy 406.351251 -287.126638) (xy 406.31313 -287.095513) (xy 406.280495 -287.058676)
			(xy 406.254192 -287.01708) (xy 406.234901 -286.971804) (xy 406.223124 -286.92402) (xy 406.219164 -286.874966)
			(xy 405.880316 -286.874966) (xy 405.879821 -286.899573) (xy 405.871926 -286.94815) (xy 405.856342 -286.994831)
			(xy 405.833471 -287.038408) (xy 405.803906 -287.077752) (xy 405.768413 -287.111844) (xy 405.72791 -287.1398)
			(xy 405.683448 -287.160898) (xy 405.636177 -287.17459) (xy 405.587322 -287.180522) (xy 405.538147 -287.178541)
			(xy 405.489928 -287.168697) (xy 405.443912 -287.151245) (xy 405.401291 -287.126638) (xy 405.36317 -287.095513)
			(xy 405.330535 -287.058676) (xy 405.304232 -287.01708) (xy 405.284941 -286.971804) (xy 405.273164 -286.92402)
			(xy 405.269204 -286.874966) (xy 404.930102 -286.874966) (xy 404.929607 -286.899573) (xy 404.921712 -286.94815)
			(xy 404.906128 -286.994831) (xy 404.883257 -287.038408) (xy 404.853692 -287.077752) (xy 404.818199 -287.111844)
			(xy 404.777696 -287.1398) (xy 404.733234 -287.160898) (xy 404.685963 -287.17459) (xy 404.637108 -287.180522)
			(xy 404.587933 -287.178541) (xy 404.539714 -287.168697) (xy 404.493698 -287.151245) (xy 404.451077 -287.126638)
			(xy 404.412956 -287.095513) (xy 404.380321 -287.058676) (xy 404.354018 -287.01708) (xy 404.334727 -286.971804)
			(xy 404.32295 -286.92402) (xy 404.31899 -286.874966) (xy 403.980142 -286.874966) (xy 403.979647 -286.899573)
			(xy 403.971752 -286.94815) (xy 403.956168 -286.994831) (xy 403.933297 -287.038408) (xy 403.903732 -287.077752)
			(xy 403.868239 -287.111844) (xy 403.827736 -287.1398) (xy 403.783274 -287.160898) (xy 403.736003 -287.17459)
			(xy 403.687148 -287.180522) (xy 403.637973 -287.178541) (xy 403.589754 -287.168697) (xy 403.543738 -287.151245)
			(xy 403.501117 -287.126638) (xy 403.462996 -287.095513) (xy 403.430361 -287.058676) (xy 403.404058 -287.01708)
			(xy 403.384767 -286.971804) (xy 403.37299 -286.92402) (xy 403.36903 -286.874966) (xy 403.030182 -286.874966)
			(xy 403.029687 -286.899573) (xy 403.021792 -286.94815) (xy 403.006208 -286.994831) (xy 402.983337 -287.038408)
			(xy 402.953772 -287.077752) (xy 402.918279 -287.111844) (xy 402.877776 -287.1398) (xy 402.833314 -287.160898)
			(xy 402.786043 -287.17459) (xy 402.737188 -287.180522) (xy 402.688013 -287.178541) (xy 402.639794 -287.168697)
			(xy 402.593778 -287.151245) (xy 402.551157 -287.126638) (xy 402.513036 -287.095513) (xy 402.480401 -287.058676)
			(xy 402.454098 -287.01708) (xy 402.434807 -286.971804) (xy 402.42303 -286.92402) (xy 402.41907 -286.874966)
			(xy 402.080222 -286.874966) (xy 402.079727 -286.899573) (xy 402.071832 -286.94815) (xy 402.056248 -286.994831)
			(xy 402.033377 -287.038408) (xy 402.003812 -287.077752) (xy 401.968319 -287.111844) (xy 401.927816 -287.1398)
			(xy 401.883354 -287.160898) (xy 401.836083 -287.17459) (xy 401.787228 -287.180522) (xy 401.738053 -287.178541)
			(xy 401.689834 -287.168697) (xy 401.643818 -287.151245) (xy 401.601197 -287.126638) (xy 401.563076 -287.095513)
			(xy 401.530441 -287.058676) (xy 401.504138 -287.01708) (xy 401.484847 -286.971804) (xy 401.47307 -286.92402)
			(xy 401.46911 -286.874966) (xy 401.130262 -286.874966) (xy 401.129767 -286.899573) (xy 401.121872 -286.94815)
			(xy 401.106288 -286.994831) (xy 401.083417 -287.038408) (xy 401.053852 -287.077752) (xy 401.018359 -287.111844)
			(xy 400.977856 -287.1398) (xy 400.933394 -287.160898) (xy 400.886123 -287.17459) (xy 400.837268 -287.180522)
			(xy 400.788093 -287.178541) (xy 400.739874 -287.168697) (xy 400.693858 -287.151245) (xy 400.651237 -287.126638)
			(xy 400.613116 -287.095513) (xy 400.580481 -287.058676) (xy 400.554178 -287.01708) (xy 400.534887 -286.971804)
			(xy 400.52311 -286.92402) (xy 400.51915 -286.874966) (xy 400.180302 -286.874966) (xy 400.179807 -286.899573)
			(xy 400.171912 -286.94815) (xy 400.156328 -286.994831) (xy 400.133457 -287.038408) (xy 400.103892 -287.077752)
			(xy 400.068399 -287.111844) (xy 400.027896 -287.1398) (xy 399.983434 -287.160898) (xy 399.936163 -287.17459)
			(xy 399.887308 -287.180522) (xy 399.838133 -287.178541) (xy 399.789914 -287.168697) (xy 399.743898 -287.151245)
			(xy 399.701277 -287.126638) (xy 399.663156 -287.095513) (xy 399.630521 -287.058676) (xy 399.604218 -287.01708)
			(xy 399.584927 -286.971804) (xy 399.57315 -286.92402) (xy 399.56919 -286.874966) (xy 399.230342 -286.874966)
			(xy 399.229847 -286.899573) (xy 399.221952 -286.94815) (xy 399.206368 -286.994831) (xy 399.183497 -287.038408)
			(xy 399.153932 -287.077752) (xy 399.118439 -287.111844) (xy 399.077936 -287.1398) (xy 399.033474 -287.160898)
			(xy 398.986203 -287.17459) (xy 398.937348 -287.180522) (xy 398.888173 -287.178541) (xy 398.839954 -287.168697)
			(xy 398.793938 -287.151245) (xy 398.751317 -287.126638) (xy 398.713196 -287.095513) (xy 398.680561 -287.058676)
			(xy 398.654258 -287.01708) (xy 398.634967 -286.971804) (xy 398.62319 -286.92402) (xy 398.61923 -286.874966)
			(xy 398.280128 -286.874966) (xy 398.279633 -286.899573) (xy 398.271738 -286.94815) (xy 398.256154 -286.994831)
			(xy 398.233283 -287.038408) (xy 398.203718 -287.077752) (xy 398.168225 -287.111844) (xy 398.127722 -287.1398)
			(xy 398.08326 -287.160898) (xy 398.035989 -287.17459) (xy 397.987134 -287.180522) (xy 397.937959 -287.178541)
			(xy 397.88974 -287.168697) (xy 397.843724 -287.151245) (xy 397.801103 -287.126638) (xy 397.762982 -287.095513)
			(xy 397.730347 -287.058676) (xy 397.704044 -287.01708) (xy 397.684753 -286.971804) (xy 397.672976 -286.92402)
			(xy 397.669016 -286.874966) (xy 397.330168 -286.874966) (xy 397.329673 -286.899573) (xy 397.321778 -286.94815)
			(xy 397.306194 -286.994831) (xy 397.283323 -287.038408) (xy 397.253758 -287.077752) (xy 397.218265 -287.111844)
			(xy 397.177762 -287.1398) (xy 397.1333 -287.160898) (xy 397.086029 -287.17459) (xy 397.037174 -287.180522)
			(xy 396.987999 -287.178541) (xy 396.93978 -287.168697) (xy 396.893764 -287.151245) (xy 396.851143 -287.126638)
			(xy 396.813022 -287.095513) (xy 396.780387 -287.058676) (xy 396.754084 -287.01708) (xy 396.734793 -286.971804)
			(xy 396.723016 -286.92402) (xy 396.719056 -286.874966) (xy 396.380208 -286.874966) (xy 396.379713 -286.899573)
			(xy 396.371818 -286.94815) (xy 396.356234 -286.994831) (xy 396.333363 -287.038408) (xy 396.303798 -287.077752)
			(xy 396.268305 -287.111844) (xy 396.227802 -287.1398) (xy 396.18334 -287.160898) (xy 396.136069 -287.17459)
			(xy 396.087214 -287.180522) (xy 396.038039 -287.178541) (xy 395.98982 -287.168697) (xy 395.943804 -287.151245)
			(xy 395.901183 -287.126638) (xy 395.863062 -287.095513) (xy 395.830427 -287.058676) (xy 395.804124 -287.01708)
			(xy 395.784833 -286.971804) (xy 395.773056 -286.92402) (xy 395.769096 -286.874966) (xy 395.430248 -286.874966)
			(xy 395.429753 -286.899573) (xy 395.421858 -286.94815) (xy 395.406274 -286.994831) (xy 395.383403 -287.038408)
			(xy 395.353838 -287.077752) (xy 395.318345 -287.111844) (xy 395.277842 -287.1398) (xy 395.23338 -287.160898)
			(xy 395.186109 -287.17459) (xy 395.137254 -287.180522) (xy 395.088079 -287.178541) (xy 395.03986 -287.168697)
			(xy 394.993844 -287.151245) (xy 394.951223 -287.126638) (xy 394.913102 -287.095513) (xy 394.880467 -287.058676)
			(xy 394.854164 -287.01708) (xy 394.834873 -286.971804) (xy 394.823096 -286.92402) (xy 394.819136 -286.874966)
			(xy 394.480288 -286.874966) (xy 394.479793 -286.899573) (xy 394.471898 -286.94815) (xy 394.456314 -286.994831)
			(xy 394.433443 -287.038408) (xy 394.403878 -287.077752) (xy 394.368385 -287.111844) (xy 394.327882 -287.1398)
			(xy 394.28342 -287.160898) (xy 394.236149 -287.17459) (xy 394.187294 -287.180522) (xy 394.138119 -287.178541)
			(xy 394.0899 -287.168697) (xy 394.043884 -287.151245) (xy 394.001263 -287.126638) (xy 393.963142 -287.095513)
			(xy 393.930507 -287.058676) (xy 393.904204 -287.01708) (xy 393.884913 -286.971804) (xy 393.873136 -286.92402)
			(xy 393.869176 -286.874966) (xy 393.530328 -286.874966) (xy 393.529833 -286.899573) (xy 393.521938 -286.94815)
			(xy 393.506354 -286.994831) (xy 393.483483 -287.038408) (xy 393.453918 -287.077752) (xy 393.418425 -287.111844)
			(xy 393.377922 -287.1398) (xy 393.33346 -287.160898) (xy 393.286189 -287.17459) (xy 393.237334 -287.180522)
			(xy 393.188159 -287.178541) (xy 393.13994 -287.168697) (xy 393.093924 -287.151245) (xy 393.051303 -287.126638)
			(xy 393.013182 -287.095513) (xy 392.980547 -287.058676) (xy 392.954244 -287.01708) (xy 392.934953 -286.971804)
			(xy 392.923176 -286.92402) (xy 392.919216 -286.874966) (xy 392.580109 -286.874966) (xy 392.579619 -286.899319)
			(xy 392.571724 -286.947896) (xy 392.55614 -286.994577) (xy 392.533269 -287.038154) (xy 392.503704 -287.077498)
			(xy 392.468211 -287.11159) (xy 392.427708 -287.139546) (xy 392.383246 -287.160644) (xy 392.335975 -287.174336)
			(xy 392.28712 -287.180268) (xy 392.237945 -287.178287) (xy 392.189726 -287.168443) (xy 392.14371 -287.150991)
			(xy 392.101089 -287.126384) (xy 392.062968 -287.095259) (xy 392.030333 -287.058422) (xy 392.00403 -287.016826)
			(xy 391.984739 -286.97155) (xy 391.972962 -286.923766) (xy 391.969002 -286.874712) (xy 391.630154 -286.874712)
			(xy 391.629659 -286.899319) (xy 391.621764 -286.947896) (xy 391.60618 -286.994577) (xy 391.583309 -287.038154)
			(xy 391.553744 -287.077498) (xy 391.518251 -287.11159) (xy 391.477748 -287.139546) (xy 391.433286 -287.160644)
			(xy 391.386015 -287.174336) (xy 391.33716 -287.180268) (xy 391.287985 -287.178287) (xy 391.239766 -287.168443)
			(xy 391.19375 -287.150991) (xy 391.151129 -287.126384) (xy 391.113008 -287.095259) (xy 391.080373 -287.058422)
			(xy 391.05407 -287.016826) (xy 391.034779 -286.97155) (xy 391.023002 -286.923766) (xy 391.019042 -286.874712)
			(xy 390.680189 -286.874712) (xy 390.680194 -286.874966) (xy 390.679745 -286.899054) (xy 390.672156 -286.94663)
			(xy 390.657191 -286.992423) (xy 390.635222 -287.0353) (xy 390.606794 -287.074195) (xy 390.572612 -287.108146)
			(xy 390.533524 -287.136308) (xy 390.490499 -287.157985) (xy 390.444605 -287.172637) (xy 390.42086 -287.176718)
			(xy 390.420606 -287.176718) (xy 390.411463 -287.178545) (xy 390.395319 -287.187852) (xy 390.383541 -287.202293)
			(xy 390.38022 -287.211008) (xy 390.351772 -287.297368) (xy 390.349154 -287.306397) (xy 390.350119 -287.325163)
			(xy 390.357801 -287.342311) (xy 390.364218 -287.349184) (xy 390.83996 -287.824926) (xy 392.919216 -287.824926)
			(xy 392.923176 -287.775872) (xy 392.934953 -287.728088) (xy 392.954244 -287.682812) (xy 392.980547 -287.641216)
			(xy 393.013182 -287.604379) (xy 393.051303 -287.573254) (xy 393.093924 -287.548647) (xy 393.13994 -287.531195)
			(xy 393.188159 -287.521351) (xy 393.237334 -287.51937) (xy 393.286189 -287.525302) (xy 393.33346 -287.538994)
			(xy 393.377922 -287.560092) (xy 393.418425 -287.588048) (xy 393.453918 -287.62214) (xy 393.483483 -287.661484)
			(xy 393.506354 -287.705061) (xy 393.521938 -287.751742) (xy 393.529833 -287.800319) (xy 393.530328 -287.824926)
			(xy 393.869176 -287.824926) (xy 393.873136 -287.775872) (xy 393.884913 -287.728088) (xy 393.904204 -287.682812)
			(xy 393.930507 -287.641216) (xy 393.963142 -287.604379) (xy 394.001263 -287.573254) (xy 394.043884 -287.548647)
			(xy 394.0899 -287.531195) (xy 394.138119 -287.521351) (xy 394.187294 -287.51937) (xy 394.236149 -287.525302)
			(xy 394.28342 -287.538994) (xy 394.327882 -287.560092) (xy 394.368385 -287.588048) (xy 394.403878 -287.62214)
			(xy 394.433443 -287.661484) (xy 394.456314 -287.705061) (xy 394.471898 -287.751742) (xy 394.479793 -287.800319)
			(xy 394.480288 -287.824926) (xy 394.819136 -287.824926) (xy 394.823096 -287.775872) (xy 394.834873 -287.728088)
			(xy 394.854164 -287.682812) (xy 394.880467 -287.641216) (xy 394.913102 -287.604379) (xy 394.951223 -287.573254)
			(xy 394.993844 -287.548647) (xy 395.03986 -287.531195) (xy 395.088079 -287.521351) (xy 395.137254 -287.51937)
			(xy 395.186109 -287.525302) (xy 395.23338 -287.538994) (xy 395.277842 -287.560092) (xy 395.318345 -287.588048)
			(xy 395.353838 -287.62214) (xy 395.383403 -287.661484) (xy 395.406274 -287.705061) (xy 395.421858 -287.751742)
			(xy 395.429753 -287.800319) (xy 395.430248 -287.824926) (xy 395.769096 -287.824926) (xy 395.773056 -287.775872)
			(xy 395.784833 -287.728088) (xy 395.804124 -287.682812) (xy 395.830427 -287.641216) (xy 395.863062 -287.604379)
			(xy 395.901183 -287.573254) (xy 395.943804 -287.548647) (xy 395.98982 -287.531195) (xy 396.038039 -287.521351)
			(xy 396.087214 -287.51937) (xy 396.136069 -287.525302) (xy 396.18334 -287.538994) (xy 396.227802 -287.560092)
			(xy 396.268305 -287.588048) (xy 396.303798 -287.62214) (xy 396.333363 -287.661484) (xy 396.356234 -287.705061)
			(xy 396.371818 -287.751742) (xy 396.379713 -287.800319) (xy 396.380208 -287.824926) (xy 396.719056 -287.824926)
			(xy 396.723016 -287.775872) (xy 396.734793 -287.728088) (xy 396.754084 -287.682812) (xy 396.780387 -287.641216)
			(xy 396.813022 -287.604379) (xy 396.851143 -287.573254) (xy 396.893764 -287.548647) (xy 396.93978 -287.531195)
			(xy 396.987999 -287.521351) (xy 397.037174 -287.51937) (xy 397.086029 -287.525302) (xy 397.1333 -287.538994)
			(xy 397.177762 -287.560092) (xy 397.218265 -287.588048) (xy 397.253758 -287.62214) (xy 397.283323 -287.661484)
			(xy 397.306194 -287.705061) (xy 397.321778 -287.751742) (xy 397.329673 -287.800319) (xy 397.330168 -287.824926)
			(xy 397.669016 -287.824926) (xy 397.672976 -287.775872) (xy 397.684753 -287.728088) (xy 397.704044 -287.682812)
			(xy 397.730347 -287.641216) (xy 397.762982 -287.604379) (xy 397.801103 -287.573254) (xy 397.843724 -287.548647)
			(xy 397.88974 -287.531195) (xy 397.937959 -287.521351) (xy 397.987134 -287.51937) (xy 398.035989 -287.525302)
			(xy 398.08326 -287.538994) (xy 398.127722 -287.560092) (xy 398.168225 -287.588048) (xy 398.203718 -287.62214)
			(xy 398.233283 -287.661484) (xy 398.256154 -287.705061) (xy 398.271738 -287.751742) (xy 398.279633 -287.800319)
			(xy 398.280128 -287.824926) (xy 398.61923 -287.824926) (xy 398.62319 -287.775872) (xy 398.634967 -287.728088)
			(xy 398.654258 -287.682812) (xy 398.680561 -287.641216) (xy 398.713196 -287.604379) (xy 398.751317 -287.573254)
			(xy 398.793938 -287.548647) (xy 398.839954 -287.531195) (xy 398.888173 -287.521351) (xy 398.937348 -287.51937)
			(xy 398.986203 -287.525302) (xy 399.033474 -287.538994) (xy 399.077936 -287.560092) (xy 399.118439 -287.588048)
			(xy 399.153932 -287.62214) (xy 399.183497 -287.661484) (xy 399.206368 -287.705061) (xy 399.221952 -287.751742)
			(xy 399.229847 -287.800319) (xy 399.230342 -287.824926) (xy 399.56919 -287.824926) (xy 399.57315 -287.775872)
			(xy 399.584927 -287.728088) (xy 399.604218 -287.682812) (xy 399.630521 -287.641216) (xy 399.663156 -287.604379)
			(xy 399.701277 -287.573254) (xy 399.743898 -287.548647) (xy 399.789914 -287.531195) (xy 399.838133 -287.521351)
			(xy 399.887308 -287.51937) (xy 399.936163 -287.525302) (xy 399.983434 -287.538994) (xy 400.027896 -287.560092)
			(xy 400.068399 -287.588048) (xy 400.103892 -287.62214) (xy 400.133457 -287.661484) (xy 400.156328 -287.705061)
			(xy 400.171912 -287.751742) (xy 400.179807 -287.800319) (xy 400.180302 -287.824926) (xy 400.51915 -287.824926)
			(xy 400.52311 -287.775872) (xy 400.534887 -287.728088) (xy 400.554178 -287.682812) (xy 400.580481 -287.641216)
			(xy 400.613116 -287.604379) (xy 400.651237 -287.573254) (xy 400.693858 -287.548647) (xy 400.739874 -287.531195)
			(xy 400.788093 -287.521351) (xy 400.837268 -287.51937) (xy 400.886123 -287.525302) (xy 400.933394 -287.538994)
			(xy 400.977856 -287.560092) (xy 401.018359 -287.588048) (xy 401.053852 -287.62214) (xy 401.083417 -287.661484)
			(xy 401.106288 -287.705061) (xy 401.121872 -287.751742) (xy 401.129767 -287.800319) (xy 401.130262 -287.824926)
			(xy 401.46911 -287.824926) (xy 401.47307 -287.775872) (xy 401.484847 -287.728088) (xy 401.504138 -287.682812)
			(xy 401.530441 -287.641216) (xy 401.563076 -287.604379) (xy 401.601197 -287.573254) (xy 401.643818 -287.548647)
			(xy 401.689834 -287.531195) (xy 401.738053 -287.521351) (xy 401.787228 -287.51937) (xy 401.836083 -287.525302)
			(xy 401.883354 -287.538994) (xy 401.927816 -287.560092) (xy 401.968319 -287.588048) (xy 402.003812 -287.62214)
			(xy 402.033377 -287.661484) (xy 402.056248 -287.705061) (xy 402.071832 -287.751742) (xy 402.079727 -287.800319)
			(xy 402.080222 -287.824926) (xy 402.41907 -287.824926) (xy 402.42303 -287.775872) (xy 402.434807 -287.728088)
			(xy 402.454098 -287.682812) (xy 402.480401 -287.641216) (xy 402.513036 -287.604379) (xy 402.551157 -287.573254)
			(xy 402.593778 -287.548647) (xy 402.639794 -287.531195) (xy 402.688013 -287.521351) (xy 402.737188 -287.51937)
			(xy 402.786043 -287.525302) (xy 402.833314 -287.538994) (xy 402.877776 -287.560092) (xy 402.918279 -287.588048)
			(xy 402.953772 -287.62214) (xy 402.983337 -287.661484) (xy 403.006208 -287.705061) (xy 403.021792 -287.751742)
			(xy 403.029687 -287.800319) (xy 403.030182 -287.824926) (xy 403.36903 -287.824926) (xy 403.37299 -287.775872)
			(xy 403.384767 -287.728088) (xy 403.404058 -287.682812) (xy 403.430361 -287.641216) (xy 403.462996 -287.604379)
			(xy 403.501117 -287.573254) (xy 403.543738 -287.548647) (xy 403.589754 -287.531195) (xy 403.637973 -287.521351)
			(xy 403.687148 -287.51937) (xy 403.736003 -287.525302) (xy 403.783274 -287.538994) (xy 403.827736 -287.560092)
			(xy 403.868239 -287.588048) (xy 403.903732 -287.62214) (xy 403.933297 -287.661484) (xy 403.956168 -287.705061)
			(xy 403.971752 -287.751742) (xy 403.979647 -287.800319) (xy 403.980142 -287.824926) (xy 404.31899 -287.824926)
			(xy 404.32295 -287.775872) (xy 404.334727 -287.728088) (xy 404.354018 -287.682812) (xy 404.380321 -287.641216)
			(xy 404.412956 -287.604379) (xy 404.451077 -287.573254) (xy 404.493698 -287.548647) (xy 404.539714 -287.531195)
			(xy 404.587933 -287.521351) (xy 404.637108 -287.51937) (xy 404.685963 -287.525302) (xy 404.733234 -287.538994)
			(xy 404.777696 -287.560092) (xy 404.818199 -287.588048) (xy 404.853692 -287.62214) (xy 404.883257 -287.661484)
			(xy 404.906128 -287.705061) (xy 404.921712 -287.751742) (xy 404.929607 -287.800319) (xy 404.930102 -287.824926)
			(xy 405.269204 -287.824926) (xy 405.273164 -287.775872) (xy 405.284941 -287.728088) (xy 405.304232 -287.682812)
			(xy 405.330535 -287.641216) (xy 405.36317 -287.604379) (xy 405.401291 -287.573254) (xy 405.443912 -287.548647)
			(xy 405.489928 -287.531195) (xy 405.538147 -287.521351) (xy 405.587322 -287.51937) (xy 405.636177 -287.525302)
			(xy 405.683448 -287.538994) (xy 405.72791 -287.560092) (xy 405.768413 -287.588048) (xy 405.803906 -287.62214)
			(xy 405.833471 -287.661484) (xy 405.853664 -287.699958) (xy 406.244056 -287.699958) (xy 406.248016 -287.650904)
			(xy 406.259793 -287.60312) (xy 406.279084 -287.557844) (xy 406.305387 -287.516248) (xy 406.338022 -287.479411)
			(xy 406.376143 -287.448286) (xy 406.418764 -287.423679) (xy 406.46478 -287.406227) (xy 406.512999 -287.396383)
			(xy 406.562174 -287.394402) (xy 406.611029 -287.400334) (xy 406.6583 -287.414026) (xy 406.702762 -287.435124)
			(xy 406.743265 -287.46308) (xy 406.778758 -287.497172) (xy 406.808323 -287.536516) (xy 406.831194 -287.580093)
			(xy 406.846778 -287.626774) (xy 406.854673 -287.675351) (xy 406.855168 -287.699958) (xy 406.854673 -287.724565)
			(xy 406.846778 -287.773142) (xy 406.831194 -287.819823) (xy 406.808323 -287.8634) (xy 406.780928 -287.899856)
			(xy 408.119084 -287.899856) (xy 408.123044 -287.850802) (xy 408.134821 -287.803018) (xy 408.154112 -287.757742)
			(xy 408.180415 -287.716146) (xy 408.21305 -287.679309) (xy 408.251171 -287.648184) (xy 408.293792 -287.623577)
			(xy 408.339808 -287.606125) (xy 408.388027 -287.596281) (xy 408.437202 -287.5943) (xy 408.486057 -287.600232)
			(xy 408.533328 -287.613924) (xy 408.57779 -287.635022) (xy 408.618293 -287.662978) (xy 408.653786 -287.69707)
			(xy 408.683351 -287.736414) (xy 408.706222 -287.779991) (xy 408.721223 -287.824926) (xy 409.069044 -287.824926)
			(xy 409.073004 -287.775872) (xy 409.084781 -287.728088) (xy 409.104072 -287.682812) (xy 409.130375 -287.641216)
			(xy 409.16301 -287.604379) (xy 409.201131 -287.573254) (xy 409.243752 -287.548647) (xy 409.289768 -287.531195)
			(xy 409.337987 -287.521351) (xy 409.387162 -287.51937) (xy 409.436017 -287.525302) (xy 409.483288 -287.538994)
			(xy 409.52775 -287.560092) (xy 409.568253 -287.588048) (xy 409.603746 -287.62214) (xy 409.633311 -287.661484)
			(xy 409.656182 -287.705061) (xy 409.671766 -287.751742) (xy 409.679661 -287.800319) (xy 409.680156 -287.824926)
			(xy 410.019004 -287.824926) (xy 410.022964 -287.775872) (xy 410.034741 -287.728088) (xy 410.054032 -287.682812)
			(xy 410.080335 -287.641216) (xy 410.11297 -287.604379) (xy 410.151091 -287.573254) (xy 410.193712 -287.548647)
			(xy 410.239728 -287.531195) (xy 410.287947 -287.521351) (xy 410.337122 -287.51937) (xy 410.385977 -287.525302)
			(xy 410.433248 -287.538994) (xy 410.47771 -287.560092) (xy 410.518213 -287.588048) (xy 410.553706 -287.62214)
			(xy 410.583271 -287.661484) (xy 410.606142 -287.705061) (xy 410.621726 -287.751742) (xy 410.629621 -287.800319)
			(xy 410.630116 -287.824926) (xy 410.969218 -287.824926) (xy 410.973178 -287.775872) (xy 410.984955 -287.728088)
			(xy 411.004246 -287.682812) (xy 411.030549 -287.641216) (xy 411.063184 -287.604379) (xy 411.101305 -287.573254)
			(xy 411.143926 -287.548647) (xy 411.189942 -287.531195) (xy 411.238161 -287.521351) (xy 411.287336 -287.51937)
			(xy 411.336191 -287.525302) (xy 411.383462 -287.538994) (xy 411.427924 -287.560092) (xy 411.468427 -287.588048)
			(xy 411.50392 -287.62214) (xy 411.533485 -287.661484) (xy 411.556356 -287.705061) (xy 411.57194 -287.751742)
			(xy 411.579835 -287.800319) (xy 411.58033 -287.824926) (xy 411.919178 -287.824926) (xy 411.923138 -287.775872)
			(xy 411.934915 -287.728088) (xy 411.954206 -287.682812) (xy 411.980509 -287.641216) (xy 412.013144 -287.604379)
			(xy 412.051265 -287.573254) (xy 412.093886 -287.548647) (xy 412.139902 -287.531195) (xy 412.188121 -287.521351)
			(xy 412.237296 -287.51937) (xy 412.286151 -287.525302) (xy 412.333422 -287.538994) (xy 412.377884 -287.560092)
			(xy 412.418387 -287.588048) (xy 412.45388 -287.62214) (xy 412.483445 -287.661484) (xy 412.506316 -287.705061)
			(xy 412.5219 -287.751742) (xy 412.529795 -287.800319) (xy 412.53029 -287.824926) (xy 412.869138 -287.824926)
			(xy 412.873098 -287.775872) (xy 412.884875 -287.728088) (xy 412.904166 -287.682812) (xy 412.930469 -287.641216)
			(xy 412.963104 -287.604379) (xy 413.001225 -287.573254) (xy 413.043846 -287.548647) (xy 413.089862 -287.531195)
			(xy 413.138081 -287.521351) (xy 413.187256 -287.51937) (xy 413.236111 -287.525302) (xy 413.283382 -287.538994)
			(xy 413.327844 -287.560092) (xy 413.368347 -287.588048) (xy 413.40384 -287.62214) (xy 413.433405 -287.661484)
			(xy 413.456276 -287.705061) (xy 413.47186 -287.751742) (xy 413.479755 -287.800319) (xy 413.48025 -287.824926)
			(xy 413.819098 -287.824926) (xy 413.823058 -287.775872) (xy 413.834835 -287.728088) (xy 413.854126 -287.682812)
			(xy 413.880429 -287.641216) (xy 413.913064 -287.604379) (xy 413.951185 -287.573254) (xy 413.993806 -287.548647)
			(xy 414.039822 -287.531195) (xy 414.088041 -287.521351) (xy 414.137216 -287.51937) (xy 414.186071 -287.525302)
			(xy 414.233342 -287.538994) (xy 414.277804 -287.560092) (xy 414.318307 -287.588048) (xy 414.3538 -287.62214)
			(xy 414.383365 -287.661484) (xy 414.406236 -287.705061) (xy 414.42182 -287.751742) (xy 414.429715 -287.800319)
			(xy 414.43021 -287.824926) (xy 414.769058 -287.824926) (xy 414.773018 -287.775872) (xy 414.784795 -287.728088)
			(xy 414.804086 -287.682812) (xy 414.830389 -287.641216) (xy 414.863024 -287.604379) (xy 414.901145 -287.573254)
			(xy 414.943766 -287.548647) (xy 414.989782 -287.531195) (xy 415.038001 -287.521351) (xy 415.087176 -287.51937)
			(xy 415.136031 -287.525302) (xy 415.183302 -287.538994) (xy 415.227764 -287.560092) (xy 415.268267 -287.588048)
			(xy 415.30376 -287.62214) (xy 415.333325 -287.661484) (xy 415.356196 -287.705061) (xy 415.37178 -287.751742)
			(xy 415.379675 -287.800319) (xy 415.38017 -287.824926) (xy 415.719018 -287.824926) (xy 415.722978 -287.775872)
			(xy 415.734755 -287.728088) (xy 415.754046 -287.682812) (xy 415.780349 -287.641216) (xy 415.812984 -287.604379)
			(xy 415.851105 -287.573254) (xy 415.893726 -287.548647) (xy 415.939742 -287.531195) (xy 415.987961 -287.521351)
			(xy 416.037136 -287.51937) (xy 416.085991 -287.525302) (xy 416.133262 -287.538994) (xy 416.177724 -287.560092)
			(xy 416.218227 -287.588048) (xy 416.25372 -287.62214) (xy 416.283285 -287.661484) (xy 416.306156 -287.705061)
			(xy 416.32174 -287.751742) (xy 416.329635 -287.800319) (xy 416.33013 -287.824926) (xy 416.668978 -287.824926)
			(xy 416.672938 -287.775872) (xy 416.684715 -287.728088) (xy 416.704006 -287.682812) (xy 416.730309 -287.641216)
			(xy 416.762944 -287.604379) (xy 416.801065 -287.573254) (xy 416.843686 -287.548647) (xy 416.889702 -287.531195)
			(xy 416.937921 -287.521351) (xy 416.987096 -287.51937) (xy 417.035951 -287.525302) (xy 417.083222 -287.538994)
			(xy 417.127684 -287.560092) (xy 417.168187 -287.588048) (xy 417.20368 -287.62214) (xy 417.233245 -287.661484)
			(xy 417.256116 -287.705061) (xy 417.2717 -287.751742) (xy 417.279595 -287.800319) (xy 417.28009 -287.824926)
			(xy 417.279595 -287.849533) (xy 417.2717 -287.89811) (xy 417.256116 -287.944791) (xy 417.233245 -287.988368)
			(xy 417.20368 -288.027712) (xy 417.168187 -288.061804) (xy 417.127684 -288.08976) (xy 417.083222 -288.110858)
			(xy 417.035951 -288.12455) (xy 416.987096 -288.130482) (xy 416.937921 -288.128501) (xy 416.889702 -288.118657)
			(xy 416.843686 -288.101205) (xy 416.801065 -288.076598) (xy 416.762944 -288.045473) (xy 416.730309 -288.008636)
			(xy 416.704006 -287.96704) (xy 416.684715 -287.921764) (xy 416.672938 -287.87398) (xy 416.668978 -287.824926)
			(xy 416.33013 -287.824926) (xy 416.329635 -287.849533) (xy 416.32174 -287.89811) (xy 416.306156 -287.944791)
			(xy 416.283285 -287.988368) (xy 416.25372 -288.027712) (xy 416.218227 -288.061804) (xy 416.177724 -288.08976)
			(xy 416.133262 -288.110858) (xy 416.085991 -288.12455) (xy 416.037136 -288.130482) (xy 415.987961 -288.128501)
			(xy 415.939742 -288.118657) (xy 415.893726 -288.101205) (xy 415.851105 -288.076598) (xy 415.812984 -288.045473)
			(xy 415.780349 -288.008636) (xy 415.754046 -287.96704) (xy 415.734755 -287.921764) (xy 415.722978 -287.87398)
			(xy 415.719018 -287.824926) (xy 415.38017 -287.824926) (xy 415.379675 -287.849533) (xy 415.37178 -287.89811)
			(xy 415.356196 -287.944791) (xy 415.333325 -287.988368) (xy 415.30376 -288.027712) (xy 415.268267 -288.061804)
			(xy 415.227764 -288.08976) (xy 415.183302 -288.110858) (xy 415.136031 -288.12455) (xy 415.087176 -288.130482)
			(xy 415.038001 -288.128501) (xy 414.989782 -288.118657) (xy 414.943766 -288.101205) (xy 414.901145 -288.076598)
			(xy 414.863024 -288.045473) (xy 414.830389 -288.008636) (xy 414.804086 -287.96704) (xy 414.784795 -287.921764)
			(xy 414.773018 -287.87398) (xy 414.769058 -287.824926) (xy 414.43021 -287.824926) (xy 414.429715 -287.849533)
			(xy 414.42182 -287.89811) (xy 414.406236 -287.944791) (xy 414.383365 -287.988368) (xy 414.3538 -288.027712)
			(xy 414.318307 -288.061804) (xy 414.277804 -288.08976) (xy 414.233342 -288.110858) (xy 414.186071 -288.12455)
			(xy 414.137216 -288.130482) (xy 414.088041 -288.128501) (xy 414.039822 -288.118657) (xy 413.993806 -288.101205)
			(xy 413.951185 -288.076598) (xy 413.913064 -288.045473) (xy 413.880429 -288.008636) (xy 413.854126 -287.96704)
			(xy 413.834835 -287.921764) (xy 413.823058 -287.87398) (xy 413.819098 -287.824926) (xy 413.48025 -287.824926)
			(xy 413.479755 -287.849533) (xy 413.47186 -287.89811) (xy 413.456276 -287.944791) (xy 413.433405 -287.988368)
			(xy 413.40384 -288.027712) (xy 413.368347 -288.061804) (xy 413.327844 -288.08976) (xy 413.283382 -288.110858)
			(xy 413.236111 -288.12455) (xy 413.187256 -288.130482) (xy 413.138081 -288.128501) (xy 413.089862 -288.118657)
			(xy 413.043846 -288.101205) (xy 413.001225 -288.076598) (xy 412.963104 -288.045473) (xy 412.930469 -288.008636)
			(xy 412.904166 -287.96704) (xy 412.884875 -287.921764) (xy 412.873098 -287.87398) (xy 412.869138 -287.824926)
			(xy 412.53029 -287.824926) (xy 412.529795 -287.849533) (xy 412.5219 -287.89811) (xy 412.506316 -287.944791)
			(xy 412.483445 -287.988368) (xy 412.45388 -288.027712) (xy 412.418387 -288.061804) (xy 412.377884 -288.08976)
			(xy 412.333422 -288.110858) (xy 412.286151 -288.12455) (xy 412.237296 -288.130482) (xy 412.188121 -288.128501)
			(xy 412.139902 -288.118657) (xy 412.093886 -288.101205) (xy 412.051265 -288.076598) (xy 412.013144 -288.045473)
			(xy 411.980509 -288.008636) (xy 411.954206 -287.96704) (xy 411.934915 -287.921764) (xy 411.923138 -287.87398)
			(xy 411.919178 -287.824926) (xy 411.58033 -287.824926) (xy 411.579835 -287.849533) (xy 411.57194 -287.89811)
			(xy 411.556356 -287.944791) (xy 411.533485 -287.988368) (xy 411.50392 -288.027712) (xy 411.468427 -288.061804)
			(xy 411.427924 -288.08976) (xy 411.383462 -288.110858) (xy 411.336191 -288.12455) (xy 411.287336 -288.130482)
			(xy 411.238161 -288.128501) (xy 411.189942 -288.118657) (xy 411.143926 -288.101205) (xy 411.101305 -288.076598)
			(xy 411.063184 -288.045473) (xy 411.030549 -288.008636) (xy 411.004246 -287.96704) (xy 410.984955 -287.921764)
			(xy 410.973178 -287.87398) (xy 410.969218 -287.824926) (xy 410.630116 -287.824926) (xy 410.629621 -287.849533)
			(xy 410.621726 -287.89811) (xy 410.606142 -287.944791) (xy 410.583271 -287.988368) (xy 410.553706 -288.027712)
			(xy 410.518213 -288.061804) (xy 410.47771 -288.08976) (xy 410.433248 -288.110858) (xy 410.385977 -288.12455)
			(xy 410.337122 -288.130482) (xy 410.287947 -288.128501) (xy 410.239728 -288.118657) (xy 410.193712 -288.101205)
			(xy 410.151091 -288.076598) (xy 410.11297 -288.045473) (xy 410.080335 -288.008636) (xy 410.054032 -287.96704)
			(xy 410.034741 -287.921764) (xy 410.022964 -287.87398) (xy 410.019004 -287.824926) (xy 409.680156 -287.824926)
			(xy 409.679661 -287.849533) (xy 409.671766 -287.89811) (xy 409.656182 -287.944791) (xy 409.633311 -287.988368)
			(xy 409.603746 -288.027712) (xy 409.568253 -288.061804) (xy 409.52775 -288.08976) (xy 409.483288 -288.110858)
			(xy 409.436017 -288.12455) (xy 409.387162 -288.130482) (xy 409.337987 -288.128501) (xy 409.289768 -288.118657)
			(xy 409.243752 -288.101205) (xy 409.201131 -288.076598) (xy 409.16301 -288.045473) (xy 409.130375 -288.008636)
			(xy 409.104072 -287.96704) (xy 409.084781 -287.921764) (xy 409.073004 -287.87398) (xy 409.069044 -287.824926)
			(xy 408.721223 -287.824926) (xy 408.721806 -287.826672) (xy 408.729701 -287.875249) (xy 408.730196 -287.899856)
			(xy 408.729701 -287.924463) (xy 408.721806 -287.97304) (xy 408.706222 -288.019721) (xy 408.683351 -288.063298)
			(xy 408.653786 -288.102642) (xy 408.618293 -288.136734) (xy 408.57779 -288.16469) (xy 408.533328 -288.185788)
			(xy 408.486057 -288.19948) (xy 408.437202 -288.205412) (xy 408.388027 -288.203431) (xy 408.339808 -288.193587)
			(xy 408.293792 -288.176135) (xy 408.251171 -288.151528) (xy 408.21305 -288.120403) (xy 408.180415 -288.083566)
			(xy 408.154112 -288.04197) (xy 408.134821 -287.996694) (xy 408.123044 -287.94891) (xy 408.119084 -287.899856)
			(xy 406.780928 -287.899856) (xy 406.778758 -287.902744) (xy 406.743265 -287.936836) (xy 406.702762 -287.964792)
			(xy 406.6583 -287.98589) (xy 406.611029 -287.999582) (xy 406.562174 -288.005514) (xy 406.512999 -288.003533)
			(xy 406.46478 -287.993689) (xy 406.418764 -287.976237) (xy 406.376143 -287.95163) (xy 406.338022 -287.920505)
			(xy 406.305387 -287.883668) (xy 406.279084 -287.842072) (xy 406.259793 -287.796796) (xy 406.248016 -287.749012)
			(xy 406.244056 -287.699958) (xy 405.853664 -287.699958) (xy 405.856342 -287.705061) (xy 405.871926 -287.751742)
			(xy 405.879821 -287.800319) (xy 405.880316 -287.824926) (xy 405.879821 -287.849533) (xy 405.871926 -287.89811)
			(xy 405.856342 -287.944791) (xy 405.833471 -287.988368) (xy 405.803906 -288.027712) (xy 405.768413 -288.061804)
			(xy 405.72791 -288.08976) (xy 405.683448 -288.110858) (xy 405.636177 -288.12455) (xy 405.587322 -288.130482)
			(xy 405.538147 -288.128501) (xy 405.489928 -288.118657) (xy 405.443912 -288.101205) (xy 405.401291 -288.076598)
			(xy 405.36317 -288.045473) (xy 405.330535 -288.008636) (xy 405.304232 -287.96704) (xy 405.284941 -287.921764)
			(xy 405.273164 -287.87398) (xy 405.269204 -287.824926) (xy 404.930102 -287.824926) (xy 404.929607 -287.849533)
			(xy 404.921712 -287.89811) (xy 404.906128 -287.944791) (xy 404.883257 -287.988368) (xy 404.853692 -288.027712)
			(xy 404.818199 -288.061804) (xy 404.777696 -288.08976) (xy 404.733234 -288.110858) (xy 404.685963 -288.12455)
			(xy 404.637108 -288.130482) (xy 404.587933 -288.128501) (xy 404.539714 -288.118657) (xy 404.493698 -288.101205)
			(xy 404.451077 -288.076598) (xy 404.412956 -288.045473) (xy 404.380321 -288.008636) (xy 404.354018 -287.96704)
			(xy 404.334727 -287.921764) (xy 404.32295 -287.87398) (xy 404.31899 -287.824926) (xy 403.980142 -287.824926)
			(xy 403.979647 -287.849533) (xy 403.971752 -287.89811) (xy 403.956168 -287.944791) (xy 403.933297 -287.988368)
			(xy 403.903732 -288.027712) (xy 403.868239 -288.061804) (xy 403.827736 -288.08976) (xy 403.783274 -288.110858)
			(xy 403.736003 -288.12455) (xy 403.687148 -288.130482) (xy 403.637973 -288.128501) (xy 403.589754 -288.118657)
			(xy 403.543738 -288.101205) (xy 403.501117 -288.076598) (xy 403.462996 -288.045473) (xy 403.430361 -288.008636)
			(xy 403.404058 -287.96704) (xy 403.384767 -287.921764) (xy 403.37299 -287.87398) (xy 403.36903 -287.824926)
			(xy 403.030182 -287.824926) (xy 403.029687 -287.849533) (xy 403.021792 -287.89811) (xy 403.006208 -287.944791)
			(xy 402.983337 -287.988368) (xy 402.953772 -288.027712) (xy 402.918279 -288.061804) (xy 402.877776 -288.08976)
			(xy 402.833314 -288.110858) (xy 402.786043 -288.12455) (xy 402.737188 -288.130482) (xy 402.688013 -288.128501)
			(xy 402.639794 -288.118657) (xy 402.593778 -288.101205) (xy 402.551157 -288.076598) (xy 402.513036 -288.045473)
			(xy 402.480401 -288.008636) (xy 402.454098 -287.96704) (xy 402.434807 -287.921764) (xy 402.42303 -287.87398)
			(xy 402.41907 -287.824926) (xy 402.080222 -287.824926) (xy 402.079727 -287.849533) (xy 402.071832 -287.89811)
			(xy 402.056248 -287.944791) (xy 402.033377 -287.988368) (xy 402.003812 -288.027712) (xy 401.968319 -288.061804)
			(xy 401.927816 -288.08976) (xy 401.883354 -288.110858) (xy 401.836083 -288.12455) (xy 401.787228 -288.130482)
			(xy 401.738053 -288.128501) (xy 401.689834 -288.118657) (xy 401.643818 -288.101205) (xy 401.601197 -288.076598)
			(xy 401.563076 -288.045473) (xy 401.530441 -288.008636) (xy 401.504138 -287.96704) (xy 401.484847 -287.921764)
			(xy 401.47307 -287.87398) (xy 401.46911 -287.824926) (xy 401.130262 -287.824926) (xy 401.129767 -287.849533)
			(xy 401.121872 -287.89811) (xy 401.106288 -287.944791) (xy 401.083417 -287.988368) (xy 401.053852 -288.027712)
			(xy 401.018359 -288.061804) (xy 400.977856 -288.08976) (xy 400.933394 -288.110858) (xy 400.886123 -288.12455)
			(xy 400.837268 -288.130482) (xy 400.788093 -288.128501) (xy 400.739874 -288.118657) (xy 400.693858 -288.101205)
			(xy 400.651237 -288.076598) (xy 400.613116 -288.045473) (xy 400.580481 -288.008636) (xy 400.554178 -287.96704)
			(xy 400.534887 -287.921764) (xy 400.52311 -287.87398) (xy 400.51915 -287.824926) (xy 400.180302 -287.824926)
			(xy 400.179807 -287.849533) (xy 400.171912 -287.89811) (xy 400.156328 -287.944791) (xy 400.133457 -287.988368)
			(xy 400.103892 -288.027712) (xy 400.068399 -288.061804) (xy 400.027896 -288.08976) (xy 399.983434 -288.110858)
			(xy 399.936163 -288.12455) (xy 399.887308 -288.130482) (xy 399.838133 -288.128501) (xy 399.789914 -288.118657)
			(xy 399.743898 -288.101205) (xy 399.701277 -288.076598) (xy 399.663156 -288.045473) (xy 399.630521 -288.008636)
			(xy 399.604218 -287.96704) (xy 399.584927 -287.921764) (xy 399.57315 -287.87398) (xy 399.56919 -287.824926)
			(xy 399.230342 -287.824926) (xy 399.229847 -287.849533) (xy 399.221952 -287.89811) (xy 399.206368 -287.944791)
			(xy 399.183497 -287.988368) (xy 399.153932 -288.027712) (xy 399.118439 -288.061804) (xy 399.077936 -288.08976)
			(xy 399.033474 -288.110858) (xy 398.986203 -288.12455) (xy 398.937348 -288.130482) (xy 398.888173 -288.128501)
			(xy 398.839954 -288.118657) (xy 398.793938 -288.101205) (xy 398.751317 -288.076598) (xy 398.713196 -288.045473)
			(xy 398.680561 -288.008636) (xy 398.654258 -287.96704) (xy 398.634967 -287.921764) (xy 398.62319 -287.87398)
			(xy 398.61923 -287.824926) (xy 398.280128 -287.824926) (xy 398.279633 -287.849533) (xy 398.271738 -287.89811)
			(xy 398.256154 -287.944791) (xy 398.233283 -287.988368) (xy 398.203718 -288.027712) (xy 398.168225 -288.061804)
			(xy 398.127722 -288.08976) (xy 398.08326 -288.110858) (xy 398.035989 -288.12455) (xy 397.987134 -288.130482)
			(xy 397.937959 -288.128501) (xy 397.88974 -288.118657) (xy 397.843724 -288.101205) (xy 397.801103 -288.076598)
			(xy 397.762982 -288.045473) (xy 397.730347 -288.008636) (xy 397.704044 -287.96704) (xy 397.684753 -287.921764)
			(xy 397.672976 -287.87398) (xy 397.669016 -287.824926) (xy 397.330168 -287.824926) (xy 397.329673 -287.849533)
			(xy 397.321778 -287.89811) (xy 397.306194 -287.944791) (xy 397.283323 -287.988368) (xy 397.253758 -288.027712)
			(xy 397.218265 -288.061804) (xy 397.177762 -288.08976) (xy 397.1333 -288.110858) (xy 397.086029 -288.12455)
			(xy 397.037174 -288.130482) (xy 396.987999 -288.128501) (xy 396.93978 -288.118657) (xy 396.893764 -288.101205)
			(xy 396.851143 -288.076598) (xy 396.813022 -288.045473) (xy 396.780387 -288.008636) (xy 396.754084 -287.96704)
			(xy 396.734793 -287.921764) (xy 396.723016 -287.87398) (xy 396.719056 -287.824926) (xy 396.380208 -287.824926)
			(xy 396.379713 -287.849533) (xy 396.371818 -287.89811) (xy 396.356234 -287.944791) (xy 396.333363 -287.988368)
			(xy 396.303798 -288.027712) (xy 396.268305 -288.061804) (xy 396.227802 -288.08976) (xy 396.18334 -288.110858)
			(xy 396.136069 -288.12455) (xy 396.087214 -288.130482) (xy 396.038039 -288.128501) (xy 395.98982 -288.118657)
			(xy 395.943804 -288.101205) (xy 395.901183 -288.076598) (xy 395.863062 -288.045473) (xy 395.830427 -288.008636)
			(xy 395.804124 -287.96704) (xy 395.784833 -287.921764) (xy 395.773056 -287.87398) (xy 395.769096 -287.824926)
			(xy 395.430248 -287.824926) (xy 395.429753 -287.849533) (xy 395.421858 -287.89811) (xy 395.406274 -287.944791)
			(xy 395.383403 -287.988368) (xy 395.353838 -288.027712) (xy 395.318345 -288.061804) (xy 395.277842 -288.08976)
			(xy 395.23338 -288.110858) (xy 395.186109 -288.12455) (xy 395.137254 -288.130482) (xy 395.088079 -288.128501)
			(xy 395.03986 -288.118657) (xy 394.993844 -288.101205) (xy 394.951223 -288.076598) (xy 394.913102 -288.045473)
			(xy 394.880467 -288.008636) (xy 394.854164 -287.96704) (xy 394.834873 -287.921764) (xy 394.823096 -287.87398)
			(xy 394.819136 -287.824926) (xy 394.480288 -287.824926) (xy 394.479793 -287.849533) (xy 394.471898 -287.89811)
			(xy 394.456314 -287.944791) (xy 394.433443 -287.988368) (xy 394.403878 -288.027712) (xy 394.368385 -288.061804)
			(xy 394.327882 -288.08976) (xy 394.28342 -288.110858) (xy 394.236149 -288.12455) (xy 394.187294 -288.130482)
			(xy 394.138119 -288.128501) (xy 394.0899 -288.118657) (xy 394.043884 -288.101205) (xy 394.001263 -288.076598)
			(xy 393.963142 -288.045473) (xy 393.930507 -288.008636) (xy 393.904204 -287.96704) (xy 393.884913 -287.921764)
			(xy 393.873136 -287.87398) (xy 393.869176 -287.824926) (xy 393.530328 -287.824926) (xy 393.529833 -287.849533)
			(xy 393.521938 -287.89811) (xy 393.506354 -287.944791) (xy 393.483483 -287.988368) (xy 393.453918 -288.027712)
			(xy 393.418425 -288.061804) (xy 393.377922 -288.08976) (xy 393.33346 -288.110858) (xy 393.286189 -288.12455)
			(xy 393.237334 -288.130482) (xy 393.188159 -288.128501) (xy 393.13994 -288.118657) (xy 393.093924 -288.101205)
			(xy 393.051303 -288.076598) (xy 393.013182 -288.045473) (xy 392.980547 -288.008636) (xy 392.954244 -287.96704)
			(xy 392.934953 -287.921764) (xy 392.923176 -287.87398) (xy 392.919216 -287.824926) (xy 390.83996 -287.824926)
			(xy 391.251948 -288.236914) (xy 391.252202 -288.236914) (xy 391.268715 -288.254059) (xy 391.296785 -288.292499)
			(xy 391.318551 -288.334829) (xy 391.333486 -288.380023) (xy 391.341228 -288.426987) (xy 391.341864 -288.450782)
			(xy 391.341864 -288.451798) (xy 391.342372 -288.470086) (xy 391.367016 -288.471954) (xy 391.415252 -288.482707)
			(xy 391.461128 -288.501088) (xy 391.503444 -288.526617) (xy 391.541097 -288.558627) (xy 391.573103 -288.596283)
			(xy 391.598627 -288.638603) (xy 391.617003 -288.68448) (xy 391.627751 -288.732718) (xy 391.629646 -288.75736)
			(xy 391.649458 -288.757868) (xy 391.649966 -288.757868) (xy 391.673657 -288.758598) (xy 391.720402 -288.766422)
			(xy 391.765377 -288.781376) (xy 391.807501 -288.8031) (xy 391.845762 -288.831072) (xy 391.862818 -288.84753)
			(xy 391.862818 -288.847784) (xy 391.880852 -288.865818) (xy 391.888273 -288.872632) (xy 391.906856 -288.880366)
			(xy 391.91692 -288.880804) (xy 391.923016 -288.880804) (xy 391.933024 -288.880325) (xy 391.951516 -288.872661)
			(xy 391.965668 -288.858506) (xy 391.973328 -288.840012) (xy 391.973816 -288.830004) (xy 391.973816 -288.82594)
			(xy 391.973054 -288.82213) (xy 391.971365 -288.810392) (xy 391.969582 -288.786744) (xy 391.969498 -288.774886)
			(xy 391.97002 -288.749631) (xy 391.978333 -288.699809) (xy 391.994734 -288.652035) (xy 392.018775 -288.607612)
			(xy 392.049799 -288.567752) (xy 392.086961 -288.533542) (xy 392.129247 -288.505916) (xy 392.175503 -288.485626)
			(xy 392.224468 -288.473226) (xy 392.274806 -288.469055) (xy 392.325144 -288.473226) (xy 392.374109 -288.485626)
			(xy 392.420365 -288.505916) (xy 392.462651 -288.533542) (xy 392.499813 -288.567752) (xy 392.530837 -288.607612)
			(xy 392.554878 -288.652035) (xy 392.571279 -288.699809) (xy 392.579592 -288.749631) (xy 392.580114 -288.774886)
			(xy 392.580114 -288.778188) (xy 392.58046 -288.788236) (xy 392.588065 -288.806832) (xy 392.594846 -288.814256)
			(xy 392.645392 -288.865818) (xy 392.652852 -288.872685) (xy 392.671582 -288.880411) (xy 392.681714 -288.880804)
			(xy 392.818112 -288.880804) (xy 392.828248 -288.880423) (xy 392.846983 -288.872699) (xy 392.854434 -288.865818)
			(xy 392.90498 -288.814256) (xy 392.911686 -288.806785) (xy 392.919268 -288.788218) (xy 392.919712 -288.778188)
			(xy 392.919712 -288.774886) (xy 392.920234 -288.749631) (xy 392.928547 -288.699809) (xy 392.944948 -288.652035)
			(xy 392.968989 -288.607612) (xy 393.000013 -288.567752) (xy 393.037175 -288.533542) (xy 393.079461 -288.505916)
			(xy 393.125717 -288.485626) (xy 393.174682 -288.473226) (xy 393.22502 -288.469055) (xy 393.275358 -288.473226)
			(xy 393.324323 -288.485626) (xy 393.370579 -288.505916) (xy 393.412865 -288.533542) (xy 393.450027 -288.567752)
			(xy 393.481051 -288.607612) (xy 393.505092 -288.652035) (xy 393.521493 -288.699809) (xy 393.529806 -288.749631)
			(xy 393.530328 -288.774886) (xy 393.530328 -288.778188) (xy 393.53067 -288.788236) (xy 393.538278 -288.806833)
			(xy 393.54506 -288.814256) (xy 393.595606 -288.865818) (xy 393.603061 -288.872692) (xy 393.621795 -288.880414)
			(xy 393.631928 -288.880804) (xy 393.768072 -288.880804) (xy 393.778211 -288.880455) (xy 393.796946 -288.872708)
			(xy 393.804394 -288.865818) (xy 393.85494 -288.814256) (xy 393.861641 -288.80678) (xy 393.869227 -288.788217)
			(xy 393.869672 -288.778188) (xy 393.869672 -288.774886) (xy 393.870194 -288.749631) (xy 393.878507 -288.699809)
			(xy 393.894908 -288.652035) (xy 393.918949 -288.607612) (xy 393.949973 -288.567752) (xy 393.987135 -288.533542)
			(xy 394.029421 -288.505916) (xy 394.075677 -288.485626) (xy 394.124642 -288.473226) (xy 394.17498 -288.469055)
			(xy 394.225318 -288.473226) (xy 394.274283 -288.485626) (xy 394.320539 -288.505916) (xy 394.362825 -288.533542)
			(xy 394.399987 -288.567752) (xy 394.431011 -288.607612) (xy 394.455052 -288.652035) (xy 394.471453 -288.699809)
			(xy 394.479766 -288.749631) (xy 394.480288 -288.774886) (xy 394.480288 -288.778188) (xy 394.480614 -288.788238)
			(xy 394.488231 -288.806835) (xy 394.49502 -288.814256) (xy 394.545566 -288.865818) (xy 394.553035 -288.872674)
			(xy 394.571758 -288.880406) (xy 394.581888 -288.880804) (xy 394.718032 -288.880804) (xy 394.728169 -288.880434)
			(xy 394.746904 -288.872702) (xy 394.754354 -288.865818) (xy 394.8049 -288.814256) (xy 394.811609 -288.806787)
			(xy 394.819189 -288.788218) (xy 394.819632 -288.778188) (xy 394.819632 -288.774886) (xy 394.820154 -288.749631)
			(xy 394.828467 -288.699809) (xy 394.844868 -288.652035) (xy 394.868909 -288.607612) (xy 394.899933 -288.567752)
			(xy 394.937095 -288.533542) (xy 394.979381 -288.505916) (xy 395.025637 -288.485626) (xy 395.074602 -288.473226)
			(xy 395.12494 -288.469055) (xy 395.175278 -288.473226) (xy 395.224243 -288.485626) (xy 395.270499 -288.505916)
			(xy 395.312785 -288.533542) (xy 395.349947 -288.567752) (xy 395.380971 -288.607612) (xy 395.405012 -288.652035)
			(xy 395.421413 -288.699809) (xy 395.429726 -288.749631) (xy 395.430248 -288.774886) (xy 395.430248 -288.778188)
			(xy 395.430585 -288.788237) (xy 395.438196 -288.806833) (xy 395.44498 -288.814256) (xy 395.495526 -288.865818)
			(xy 395.502974 -288.8727) (xy 395.521713 -288.880418) (xy 395.531848 -288.880804) (xy 395.667992 -288.880804)
			(xy 395.678132 -288.880466) (xy 395.696867 -288.872712) (xy 395.704314 -288.865818) (xy 395.75486 -288.814256)
			(xy 395.761563 -288.806783) (xy 395.769147 -288.788217) (xy 395.769592 -288.778188) (xy 395.769592 -288.774886)
			(xy 395.770114 -288.749631) (xy 395.778427 -288.699809) (xy 395.794828 -288.652035) (xy 395.818869 -288.607612)
			(xy 395.849893 -288.567752) (xy 395.887055 -288.533542) (xy 395.929341 -288.505916) (xy 395.975597 -288.485626)
			(xy 396.024562 -288.473226) (xy 396.0749 -288.469055) (xy 396.125238 -288.473226) (xy 396.174203 -288.485626)
			(xy 396.220459 -288.505916) (xy 396.262745 -288.533542) (xy 396.299907 -288.567752) (xy 396.330931 -288.607612)
			(xy 396.354972 -288.652035) (xy 396.371373 -288.699809) (xy 396.379686 -288.749631) (xy 396.380208 -288.774886)
			(xy 396.719056 -288.774886) (xy 396.723016 -288.725832) (xy 396.734793 -288.678048) (xy 396.754084 -288.632772)
			(xy 396.780387 -288.591176) (xy 396.813022 -288.554339) (xy 396.851143 -288.523214) (xy 396.893764 -288.498607)
			(xy 396.93978 -288.481155) (xy 396.987999 -288.471311) (xy 397.037174 -288.46933) (xy 397.086029 -288.475262)
			(xy 397.1333 -288.488954) (xy 397.177762 -288.510052) (xy 397.218265 -288.538008) (xy 397.253758 -288.5721)
			(xy 397.283323 -288.611444) (xy 397.306194 -288.655021) (xy 397.321778 -288.701702) (xy 397.329673 -288.750279)
			(xy 397.330168 -288.774886) (xy 397.669016 -288.774886) (xy 397.672976 -288.725832) (xy 397.684753 -288.678048)
			(xy 397.704044 -288.632772) (xy 397.730347 -288.591176) (xy 397.762982 -288.554339) (xy 397.801103 -288.523214)
			(xy 397.843724 -288.498607) (xy 397.88974 -288.481155) (xy 397.937959 -288.471311) (xy 397.987134 -288.46933)
			(xy 398.035989 -288.475262) (xy 398.08326 -288.488954) (xy 398.127722 -288.510052) (xy 398.168225 -288.538008)
			(xy 398.203718 -288.5721) (xy 398.233283 -288.611444) (xy 398.256154 -288.655021) (xy 398.271738 -288.701702)
			(xy 398.279633 -288.750279) (xy 398.280128 -288.774886) (xy 398.61923 -288.774886) (xy 398.62319 -288.725832)
			(xy 398.634967 -288.678048) (xy 398.654258 -288.632772) (xy 398.680561 -288.591176) (xy 398.713196 -288.554339)
			(xy 398.751317 -288.523214) (xy 398.793938 -288.498607) (xy 398.839954 -288.481155) (xy 398.888173 -288.471311)
			(xy 398.937348 -288.46933) (xy 398.986203 -288.475262) (xy 399.033474 -288.488954) (xy 399.077936 -288.510052)
			(xy 399.118439 -288.538008) (xy 399.153932 -288.5721) (xy 399.183497 -288.611444) (xy 399.206368 -288.655021)
			(xy 399.221952 -288.701702) (xy 399.229847 -288.750279) (xy 399.230342 -288.774886) (xy 399.56919 -288.774886)
			(xy 399.57315 -288.725832) (xy 399.584927 -288.678048) (xy 399.604218 -288.632772) (xy 399.630521 -288.591176)
			(xy 399.663156 -288.554339) (xy 399.701277 -288.523214) (xy 399.743898 -288.498607) (xy 399.789914 -288.481155)
			(xy 399.838133 -288.471311) (xy 399.887308 -288.46933) (xy 399.936163 -288.475262) (xy 399.983434 -288.488954)
			(xy 400.027896 -288.510052) (xy 400.068399 -288.538008) (xy 400.103892 -288.5721) (xy 400.133457 -288.611444)
			(xy 400.156328 -288.655021) (xy 400.171912 -288.701702) (xy 400.179807 -288.750279) (xy 400.180302 -288.774886)
			(xy 400.51915 -288.774886) (xy 400.52311 -288.725832) (xy 400.534887 -288.678048) (xy 400.554178 -288.632772)
			(xy 400.580481 -288.591176) (xy 400.613116 -288.554339) (xy 400.651237 -288.523214) (xy 400.693858 -288.498607)
			(xy 400.739874 -288.481155) (xy 400.788093 -288.471311) (xy 400.837268 -288.46933) (xy 400.886123 -288.475262)
			(xy 400.933394 -288.488954) (xy 400.977856 -288.510052) (xy 401.018359 -288.538008) (xy 401.053852 -288.5721)
			(xy 401.083417 -288.611444) (xy 401.106288 -288.655021) (xy 401.121872 -288.701702) (xy 401.129767 -288.750279)
			(xy 401.130262 -288.774886) (xy 401.46911 -288.774886) (xy 401.47307 -288.725832) (xy 401.484847 -288.678048)
			(xy 401.504138 -288.632772) (xy 401.530441 -288.591176) (xy 401.563076 -288.554339) (xy 401.601197 -288.523214)
			(xy 401.643818 -288.498607) (xy 401.689834 -288.481155) (xy 401.738053 -288.471311) (xy 401.787228 -288.46933)
			(xy 401.836083 -288.475262) (xy 401.883354 -288.488954) (xy 401.927816 -288.510052) (xy 401.968319 -288.538008)
			(xy 402.003812 -288.5721) (xy 402.033377 -288.611444) (xy 402.056248 -288.655021) (xy 402.071832 -288.701702)
			(xy 402.079727 -288.750279) (xy 402.080222 -288.774886) (xy 402.41907 -288.774886) (xy 402.42303 -288.725832)
			(xy 402.434807 -288.678048) (xy 402.454098 -288.632772) (xy 402.480401 -288.591176) (xy 402.513036 -288.554339)
			(xy 402.551157 -288.523214) (xy 402.593778 -288.498607) (xy 402.639794 -288.481155) (xy 402.688013 -288.471311)
			(xy 402.737188 -288.46933) (xy 402.786043 -288.475262) (xy 402.833314 -288.488954) (xy 402.877776 -288.510052)
			(xy 402.918279 -288.538008) (xy 402.953772 -288.5721) (xy 402.983337 -288.611444) (xy 403.006208 -288.655021)
			(xy 403.021792 -288.701702) (xy 403.029687 -288.750279) (xy 403.030182 -288.774886) (xy 403.36903 -288.774886)
			(xy 403.37299 -288.725832) (xy 403.384767 -288.678048) (xy 403.404058 -288.632772) (xy 403.430361 -288.591176)
			(xy 403.462996 -288.554339) (xy 403.501117 -288.523214) (xy 403.543738 -288.498607) (xy 403.589754 -288.481155)
			(xy 403.637973 -288.471311) (xy 403.687148 -288.46933) (xy 403.736003 -288.475262) (xy 403.783274 -288.488954)
			(xy 403.827736 -288.510052) (xy 403.868239 -288.538008) (xy 403.903732 -288.5721) (xy 403.933297 -288.611444)
			(xy 403.956168 -288.655021) (xy 403.971752 -288.701702) (xy 403.979647 -288.750279) (xy 403.980142 -288.774886)
			(xy 404.31899 -288.774886) (xy 404.32295 -288.725832) (xy 404.334727 -288.678048) (xy 404.354018 -288.632772)
			(xy 404.380321 -288.591176) (xy 404.412956 -288.554339) (xy 404.451077 -288.523214) (xy 404.493698 -288.498607)
			(xy 404.539714 -288.481155) (xy 404.587933 -288.471311) (xy 404.637108 -288.46933) (xy 404.685963 -288.475262)
			(xy 404.733234 -288.488954) (xy 404.777696 -288.510052) (xy 404.818199 -288.538008) (xy 404.853692 -288.5721)
			(xy 404.883257 -288.611444) (xy 404.906128 -288.655021) (xy 404.921712 -288.701702) (xy 404.929607 -288.750279)
			(xy 404.930102 -288.774886) (xy 405.269204 -288.774886) (xy 405.273164 -288.725832) (xy 405.284941 -288.678048)
			(xy 405.304232 -288.632772) (xy 405.330535 -288.591176) (xy 405.36317 -288.554339) (xy 405.401291 -288.523214)
			(xy 405.443912 -288.498607) (xy 405.489928 -288.481155) (xy 405.538147 -288.471311) (xy 405.587322 -288.46933)
			(xy 405.636177 -288.475262) (xy 405.683448 -288.488954) (xy 405.72791 -288.510052) (xy 405.768413 -288.538008)
			(xy 405.803906 -288.5721) (xy 405.833471 -288.611444) (xy 405.856342 -288.655021) (xy 405.871926 -288.701702)
			(xy 405.879821 -288.750279) (xy 405.880316 -288.774886) (xy 406.219164 -288.774886) (xy 406.223124 -288.725832)
			(xy 406.234901 -288.678048) (xy 406.254192 -288.632772) (xy 406.280495 -288.591176) (xy 406.31313 -288.554339)
			(xy 406.351251 -288.523214) (xy 406.393872 -288.498607) (xy 406.439888 -288.481155) (xy 406.488107 -288.471311)
			(xy 406.537282 -288.46933) (xy 406.586137 -288.475262) (xy 406.633408 -288.488954) (xy 406.67787 -288.510052)
			(xy 406.718373 -288.538008) (xy 406.753866 -288.5721) (xy 406.783431 -288.611444) (xy 406.806302 -288.655021)
			(xy 406.821886 -288.701702) (xy 406.829781 -288.750279) (xy 406.830276 -288.774886) (xy 408.119084 -288.774886)
			(xy 408.123044 -288.725832) (xy 408.134821 -288.678048) (xy 408.154112 -288.632772) (xy 408.180415 -288.591176)
			(xy 408.21305 -288.554339) (xy 408.251171 -288.523214) (xy 408.293792 -288.498607) (xy 408.339808 -288.481155)
			(xy 408.388027 -288.471311) (xy 408.437202 -288.46933) (xy 408.486057 -288.475262) (xy 408.533328 -288.488954)
			(xy 408.57779 -288.510052) (xy 408.618293 -288.538008) (xy 408.653786 -288.5721) (xy 408.683351 -288.611444)
			(xy 408.706222 -288.655021) (xy 408.721806 -288.701702) (xy 408.729701 -288.750279) (xy 408.730196 -288.774886)
			(xy 409.069044 -288.774886) (xy 409.073004 -288.725832) (xy 409.084781 -288.678048) (xy 409.104072 -288.632772)
			(xy 409.130375 -288.591176) (xy 409.16301 -288.554339) (xy 409.201131 -288.523214) (xy 409.243752 -288.498607)
			(xy 409.289768 -288.481155) (xy 409.337987 -288.471311) (xy 409.387162 -288.46933) (xy 409.436017 -288.475262)
			(xy 409.483288 -288.488954) (xy 409.52775 -288.510052) (xy 409.568253 -288.538008) (xy 409.603746 -288.5721)
			(xy 409.633311 -288.611444) (xy 409.656182 -288.655021) (xy 409.671766 -288.701702) (xy 409.679661 -288.750279)
			(xy 409.680156 -288.774886) (xy 410.019004 -288.774886) (xy 410.022964 -288.725832) (xy 410.034741 -288.678048)
			(xy 410.054032 -288.632772) (xy 410.080335 -288.591176) (xy 410.11297 -288.554339) (xy 410.151091 -288.523214)
			(xy 410.193712 -288.498607) (xy 410.239728 -288.481155) (xy 410.287947 -288.471311) (xy 410.337122 -288.46933)
			(xy 410.385977 -288.475262) (xy 410.433248 -288.488954) (xy 410.47771 -288.510052) (xy 410.518213 -288.538008)
			(xy 410.553706 -288.5721) (xy 410.583271 -288.611444) (xy 410.606142 -288.655021) (xy 410.621726 -288.701702)
			(xy 410.629621 -288.750279) (xy 410.630116 -288.774886) (xy 410.969218 -288.774886) (xy 410.973178 -288.725832)
			(xy 410.984955 -288.678048) (xy 411.004246 -288.632772) (xy 411.030549 -288.591176) (xy 411.063184 -288.554339)
			(xy 411.101305 -288.523214) (xy 411.143926 -288.498607) (xy 411.189942 -288.481155) (xy 411.238161 -288.471311)
			(xy 411.287336 -288.46933) (xy 411.336191 -288.475262) (xy 411.383462 -288.488954) (xy 411.427924 -288.510052)
			(xy 411.468427 -288.538008) (xy 411.50392 -288.5721) (xy 411.533485 -288.611444) (xy 411.556356 -288.655021)
			(xy 411.57194 -288.701702) (xy 411.579835 -288.750279) (xy 411.58033 -288.774886) (xy 411.919178 -288.774886)
			(xy 411.923138 -288.725832) (xy 411.934915 -288.678048) (xy 411.954206 -288.632772) (xy 411.980509 -288.591176)
			(xy 412.013144 -288.554339) (xy 412.051265 -288.523214) (xy 412.093886 -288.498607) (xy 412.139902 -288.481155)
			(xy 412.188121 -288.471311) (xy 412.237296 -288.46933) (xy 412.286151 -288.475262) (xy 412.333422 -288.488954)
			(xy 412.377884 -288.510052) (xy 412.418387 -288.538008) (xy 412.45388 -288.5721) (xy 412.483445 -288.611444)
			(xy 412.506316 -288.655021) (xy 412.5219 -288.701702) (xy 412.529795 -288.750279) (xy 412.53029 -288.774886)
			(xy 412.869138 -288.774886) (xy 412.873098 -288.725832) (xy 412.884875 -288.678048) (xy 412.904166 -288.632772)
			(xy 412.930469 -288.591176) (xy 412.963104 -288.554339) (xy 413.001225 -288.523214) (xy 413.043846 -288.498607)
			(xy 413.089862 -288.481155) (xy 413.138081 -288.471311) (xy 413.187256 -288.46933) (xy 413.236111 -288.475262)
			(xy 413.283382 -288.488954) (xy 413.327844 -288.510052) (xy 413.368347 -288.538008) (xy 413.40384 -288.5721)
			(xy 413.433405 -288.611444) (xy 413.456276 -288.655021) (xy 413.47186 -288.701702) (xy 413.479755 -288.750279)
			(xy 413.48025 -288.774886) (xy 413.819098 -288.774886) (xy 413.823058 -288.725832) (xy 413.834835 -288.678048)
			(xy 413.854126 -288.632772) (xy 413.880429 -288.591176) (xy 413.913064 -288.554339) (xy 413.951185 -288.523214)
			(xy 413.993806 -288.498607) (xy 414.039822 -288.481155) (xy 414.088041 -288.471311) (xy 414.137216 -288.46933)
			(xy 414.186071 -288.475262) (xy 414.233342 -288.488954) (xy 414.277804 -288.510052) (xy 414.318307 -288.538008)
			(xy 414.3538 -288.5721) (xy 414.383365 -288.611444) (xy 414.406236 -288.655021) (xy 414.42182 -288.701702)
			(xy 414.429715 -288.750279) (xy 414.43021 -288.774886) (xy 414.769058 -288.774886) (xy 414.773018 -288.725832)
			(xy 414.784795 -288.678048) (xy 414.804086 -288.632772) (xy 414.830389 -288.591176) (xy 414.863024 -288.554339)
			(xy 414.901145 -288.523214) (xy 414.943766 -288.498607) (xy 414.989782 -288.481155) (xy 415.038001 -288.471311)
			(xy 415.087176 -288.46933) (xy 415.136031 -288.475262) (xy 415.183302 -288.488954) (xy 415.227764 -288.510052)
			(xy 415.268267 -288.538008) (xy 415.30376 -288.5721) (xy 415.333325 -288.611444) (xy 415.356196 -288.655021)
			(xy 415.37178 -288.701702) (xy 415.379675 -288.750279) (xy 415.38017 -288.774886) (xy 415.719018 -288.774886)
			(xy 415.722978 -288.725832) (xy 415.734755 -288.678048) (xy 415.754046 -288.632772) (xy 415.780349 -288.591176)
			(xy 415.812984 -288.554339) (xy 415.851105 -288.523214) (xy 415.893726 -288.498607) (xy 415.939742 -288.481155)
			(xy 415.987961 -288.471311) (xy 416.037136 -288.46933) (xy 416.085991 -288.475262) (xy 416.133262 -288.488954)
			(xy 416.177724 -288.510052) (xy 416.218227 -288.538008) (xy 416.25372 -288.5721) (xy 416.283285 -288.611444)
			(xy 416.306156 -288.655021) (xy 416.32174 -288.701702) (xy 416.329635 -288.750279) (xy 416.33013 -288.774886)
			(xy 416.668978 -288.774886) (xy 416.672938 -288.725832) (xy 416.684715 -288.678048) (xy 416.704006 -288.632772)
			(xy 416.730309 -288.591176) (xy 416.762944 -288.554339) (xy 416.801065 -288.523214) (xy 416.843686 -288.498607)
			(xy 416.889702 -288.481155) (xy 416.937921 -288.471311) (xy 416.987096 -288.46933) (xy 417.035951 -288.475262)
			(xy 417.083222 -288.488954) (xy 417.127684 -288.510052) (xy 417.168187 -288.538008) (xy 417.20368 -288.5721)
			(xy 417.233245 -288.611444) (xy 417.256116 -288.655021) (xy 417.2717 -288.701702) (xy 417.279595 -288.750279)
			(xy 417.28009 -288.774886) (xy 417.279595 -288.799493) (xy 417.2717 -288.84807) (xy 417.256116 -288.894751)
			(xy 417.233245 -288.938328) (xy 417.20368 -288.977672) (xy 417.168187 -289.011764) (xy 417.127684 -289.03972)
			(xy 417.083222 -289.060818) (xy 417.035951 -289.07451) (xy 416.987096 -289.080442) (xy 416.937921 -289.078461)
			(xy 416.889702 -289.068617) (xy 416.843686 -289.051165) (xy 416.801065 -289.026558) (xy 416.762944 -288.995433)
			(xy 416.730309 -288.958596) (xy 416.704006 -288.917) (xy 416.684715 -288.871724) (xy 416.672938 -288.82394)
			(xy 416.668978 -288.774886) (xy 416.33013 -288.774886) (xy 416.329635 -288.799493) (xy 416.32174 -288.84807)
			(xy 416.306156 -288.894751) (xy 416.283285 -288.938328) (xy 416.25372 -288.977672) (xy 416.218227 -289.011764)
			(xy 416.177724 -289.03972) (xy 416.133262 -289.060818) (xy 416.085991 -289.07451) (xy 416.037136 -289.080442)
			(xy 415.987961 -289.078461) (xy 415.939742 -289.068617) (xy 415.893726 -289.051165) (xy 415.851105 -289.026558)
			(xy 415.812984 -288.995433) (xy 415.780349 -288.958596) (xy 415.754046 -288.917) (xy 415.734755 -288.871724)
			(xy 415.722978 -288.82394) (xy 415.719018 -288.774886) (xy 415.38017 -288.774886) (xy 415.379675 -288.799493)
			(xy 415.37178 -288.84807) (xy 415.356196 -288.894751) (xy 415.333325 -288.938328) (xy 415.30376 -288.977672)
			(xy 415.268267 -289.011764) (xy 415.227764 -289.03972) (xy 415.183302 -289.060818) (xy 415.136031 -289.07451)
			(xy 415.087176 -289.080442) (xy 415.038001 -289.078461) (xy 414.989782 -289.068617) (xy 414.943766 -289.051165)
			(xy 414.901145 -289.026558) (xy 414.863024 -288.995433) (xy 414.830389 -288.958596) (xy 414.804086 -288.917)
			(xy 414.784795 -288.871724) (xy 414.773018 -288.82394) (xy 414.769058 -288.774886) (xy 414.43021 -288.774886)
			(xy 414.429715 -288.799493) (xy 414.42182 -288.84807) (xy 414.406236 -288.894751) (xy 414.383365 -288.938328)
			(xy 414.3538 -288.977672) (xy 414.318307 -289.011764) (xy 414.277804 -289.03972) (xy 414.233342 -289.060818)
			(xy 414.186071 -289.07451) (xy 414.137216 -289.080442) (xy 414.088041 -289.078461) (xy 414.039822 -289.068617)
			(xy 413.993806 -289.051165) (xy 413.951185 -289.026558) (xy 413.913064 -288.995433) (xy 413.880429 -288.958596)
			(xy 413.854126 -288.917) (xy 413.834835 -288.871724) (xy 413.823058 -288.82394) (xy 413.819098 -288.774886)
			(xy 413.48025 -288.774886) (xy 413.479755 -288.799493) (xy 413.47186 -288.84807) (xy 413.456276 -288.894751)
			(xy 413.433405 -288.938328) (xy 413.40384 -288.977672) (xy 413.368347 -289.011764) (xy 413.327844 -289.03972)
			(xy 413.283382 -289.060818) (xy 413.236111 -289.07451) (xy 413.187256 -289.080442) (xy 413.138081 -289.078461)
			(xy 413.089862 -289.068617) (xy 413.043846 -289.051165) (xy 413.001225 -289.026558) (xy 412.963104 -288.995433)
			(xy 412.930469 -288.958596) (xy 412.904166 -288.917) (xy 412.884875 -288.871724) (xy 412.873098 -288.82394)
			(xy 412.869138 -288.774886) (xy 412.53029 -288.774886) (xy 412.529795 -288.799493) (xy 412.5219 -288.84807)
			(xy 412.506316 -288.894751) (xy 412.483445 -288.938328) (xy 412.45388 -288.977672) (xy 412.418387 -289.011764)
			(xy 412.377884 -289.03972) (xy 412.333422 -289.060818) (xy 412.286151 -289.07451) (xy 412.237296 -289.080442)
			(xy 412.188121 -289.078461) (xy 412.139902 -289.068617) (xy 412.093886 -289.051165) (xy 412.051265 -289.026558)
			(xy 412.013144 -288.995433) (xy 411.980509 -288.958596) (xy 411.954206 -288.917) (xy 411.934915 -288.871724)
			(xy 411.923138 -288.82394) (xy 411.919178 -288.774886) (xy 411.58033 -288.774886) (xy 411.579835 -288.799493)
			(xy 411.57194 -288.84807) (xy 411.556356 -288.894751) (xy 411.533485 -288.938328) (xy 411.50392 -288.977672)
			(xy 411.468427 -289.011764) (xy 411.427924 -289.03972) (xy 411.383462 -289.060818) (xy 411.336191 -289.07451)
			(xy 411.287336 -289.080442) (xy 411.238161 -289.078461) (xy 411.189942 -289.068617) (xy 411.143926 -289.051165)
			(xy 411.101305 -289.026558) (xy 411.063184 -288.995433) (xy 411.030549 -288.958596) (xy 411.004246 -288.917)
			(xy 410.984955 -288.871724) (xy 410.973178 -288.82394) (xy 410.969218 -288.774886) (xy 410.630116 -288.774886)
			(xy 410.629621 -288.799493) (xy 410.621726 -288.84807) (xy 410.606142 -288.894751) (xy 410.583271 -288.938328)
			(xy 410.553706 -288.977672) (xy 410.518213 -289.011764) (xy 410.47771 -289.03972) (xy 410.433248 -289.060818)
			(xy 410.385977 -289.07451) (xy 410.337122 -289.080442) (xy 410.287947 -289.078461) (xy 410.239728 -289.068617)
			(xy 410.193712 -289.051165) (xy 410.151091 -289.026558) (xy 410.11297 -288.995433) (xy 410.080335 -288.958596)
			(xy 410.054032 -288.917) (xy 410.034741 -288.871724) (xy 410.022964 -288.82394) (xy 410.019004 -288.774886)
			(xy 409.680156 -288.774886) (xy 409.679661 -288.799493) (xy 409.671766 -288.84807) (xy 409.656182 -288.894751)
			(xy 409.633311 -288.938328) (xy 409.603746 -288.977672) (xy 409.568253 -289.011764) (xy 409.52775 -289.03972)
			(xy 409.483288 -289.060818) (xy 409.436017 -289.07451) (xy 409.387162 -289.080442) (xy 409.337987 -289.078461)
			(xy 409.289768 -289.068617) (xy 409.243752 -289.051165) (xy 409.201131 -289.026558) (xy 409.16301 -288.995433)
			(xy 409.130375 -288.958596) (xy 409.104072 -288.917) (xy 409.084781 -288.871724) (xy 409.073004 -288.82394)
			(xy 409.069044 -288.774886) (xy 408.730196 -288.774886) (xy 408.729701 -288.799493) (xy 408.721806 -288.84807)
			(xy 408.706222 -288.894751) (xy 408.683351 -288.938328) (xy 408.653786 -288.977672) (xy 408.618293 -289.011764)
			(xy 408.57779 -289.03972) (xy 408.533328 -289.060818) (xy 408.486057 -289.07451) (xy 408.437202 -289.080442)
			(xy 408.388027 -289.078461) (xy 408.339808 -289.068617) (xy 408.293792 -289.051165) (xy 408.251171 -289.026558)
			(xy 408.21305 -288.995433) (xy 408.180415 -288.958596) (xy 408.154112 -288.917) (xy 408.134821 -288.871724)
			(xy 408.123044 -288.82394) (xy 408.119084 -288.774886) (xy 406.830276 -288.774886) (xy 406.829781 -288.799493)
			(xy 406.821886 -288.84807) (xy 406.806302 -288.894751) (xy 406.783431 -288.938328) (xy 406.753866 -288.977672)
			(xy 406.718373 -289.011764) (xy 406.67787 -289.03972) (xy 406.633408 -289.060818) (xy 406.586137 -289.07451)
			(xy 406.537282 -289.080442) (xy 406.488107 -289.078461) (xy 406.439888 -289.068617) (xy 406.393872 -289.051165)
			(xy 406.351251 -289.026558) (xy 406.31313 -288.995433) (xy 406.280495 -288.958596) (xy 406.254192 -288.917)
			(xy 406.234901 -288.871724) (xy 406.223124 -288.82394) (xy 406.219164 -288.774886) (xy 405.880316 -288.774886)
			(xy 405.879821 -288.799493) (xy 405.871926 -288.84807) (xy 405.856342 -288.894751) (xy 405.833471 -288.938328)
			(xy 405.803906 -288.977672) (xy 405.768413 -289.011764) (xy 405.72791 -289.03972) (xy 405.683448 -289.060818)
			(xy 405.636177 -289.07451) (xy 405.587322 -289.080442) (xy 405.538147 -289.078461) (xy 405.489928 -289.068617)
			(xy 405.443912 -289.051165) (xy 405.401291 -289.026558) (xy 405.36317 -288.995433) (xy 405.330535 -288.958596)
			(xy 405.304232 -288.917) (xy 405.284941 -288.871724) (xy 405.273164 -288.82394) (xy 405.269204 -288.774886)
			(xy 404.930102 -288.774886) (xy 404.929607 -288.799493) (xy 404.921712 -288.84807) (xy 404.906128 -288.894751)
			(xy 404.883257 -288.938328) (xy 404.853692 -288.977672) (xy 404.818199 -289.011764) (xy 404.777696 -289.03972)
			(xy 404.733234 -289.060818) (xy 404.685963 -289.07451) (xy 404.637108 -289.080442) (xy 404.587933 -289.078461)
			(xy 404.539714 -289.068617) (xy 404.493698 -289.051165) (xy 404.451077 -289.026558) (xy 404.412956 -288.995433)
			(xy 404.380321 -288.958596) (xy 404.354018 -288.917) (xy 404.334727 -288.871724) (xy 404.32295 -288.82394)
			(xy 404.31899 -288.774886) (xy 403.980142 -288.774886) (xy 403.979647 -288.799493) (xy 403.971752 -288.84807)
			(xy 403.956168 -288.894751) (xy 403.933297 -288.938328) (xy 403.903732 -288.977672) (xy 403.868239 -289.011764)
			(xy 403.827736 -289.03972) (xy 403.783274 -289.060818) (xy 403.736003 -289.07451) (xy 403.687148 -289.080442)
			(xy 403.637973 -289.078461) (xy 403.589754 -289.068617) (xy 403.543738 -289.051165) (xy 403.501117 -289.026558)
			(xy 403.462996 -288.995433) (xy 403.430361 -288.958596) (xy 403.404058 -288.917) (xy 403.384767 -288.871724)
			(xy 403.37299 -288.82394) (xy 403.36903 -288.774886) (xy 403.030182 -288.774886) (xy 403.029687 -288.799493)
			(xy 403.021792 -288.84807) (xy 403.006208 -288.894751) (xy 402.983337 -288.938328) (xy 402.953772 -288.977672)
			(xy 402.918279 -289.011764) (xy 402.877776 -289.03972) (xy 402.833314 -289.060818) (xy 402.786043 -289.07451)
			(xy 402.737188 -289.080442) (xy 402.688013 -289.078461) (xy 402.639794 -289.068617) (xy 402.593778 -289.051165)
			(xy 402.551157 -289.026558) (xy 402.513036 -288.995433) (xy 402.480401 -288.958596) (xy 402.454098 -288.917)
			(xy 402.434807 -288.871724) (xy 402.42303 -288.82394) (xy 402.41907 -288.774886) (xy 402.080222 -288.774886)
			(xy 402.079727 -288.799493) (xy 402.071832 -288.84807) (xy 402.056248 -288.894751) (xy 402.033377 -288.938328)
			(xy 402.003812 -288.977672) (xy 401.968319 -289.011764) (xy 401.927816 -289.03972) (xy 401.883354 -289.060818)
			(xy 401.836083 -289.07451) (xy 401.787228 -289.080442) (xy 401.738053 -289.078461) (xy 401.689834 -289.068617)
			(xy 401.643818 -289.051165) (xy 401.601197 -289.026558) (xy 401.563076 -288.995433) (xy 401.530441 -288.958596)
			(xy 401.504138 -288.917) (xy 401.484847 -288.871724) (xy 401.47307 -288.82394) (xy 401.46911 -288.774886)
			(xy 401.130262 -288.774886) (xy 401.129767 -288.799493) (xy 401.121872 -288.84807) (xy 401.106288 -288.894751)
			(xy 401.083417 -288.938328) (xy 401.053852 -288.977672) (xy 401.018359 -289.011764) (xy 400.977856 -289.03972)
			(xy 400.933394 -289.060818) (xy 400.886123 -289.07451) (xy 400.837268 -289.080442) (xy 400.788093 -289.078461)
			(xy 400.739874 -289.068617) (xy 400.693858 -289.051165) (xy 400.651237 -289.026558) (xy 400.613116 -288.995433)
			(xy 400.580481 -288.958596) (xy 400.554178 -288.917) (xy 400.534887 -288.871724) (xy 400.52311 -288.82394)
			(xy 400.51915 -288.774886) (xy 400.180302 -288.774886) (xy 400.179807 -288.799493) (xy 400.171912 -288.84807)
			(xy 400.156328 -288.894751) (xy 400.133457 -288.938328) (xy 400.103892 -288.977672) (xy 400.068399 -289.011764)
			(xy 400.027896 -289.03972) (xy 399.983434 -289.060818) (xy 399.936163 -289.07451) (xy 399.887308 -289.080442)
			(xy 399.838133 -289.078461) (xy 399.789914 -289.068617) (xy 399.743898 -289.051165) (xy 399.701277 -289.026558)
			(xy 399.663156 -288.995433) (xy 399.630521 -288.958596) (xy 399.604218 -288.917) (xy 399.584927 -288.871724)
			(xy 399.57315 -288.82394) (xy 399.56919 -288.774886) (xy 399.230342 -288.774886) (xy 399.229847 -288.799493)
			(xy 399.221952 -288.84807) (xy 399.206368 -288.894751) (xy 399.183497 -288.938328) (xy 399.153932 -288.977672)
			(xy 399.118439 -289.011764) (xy 399.077936 -289.03972) (xy 399.033474 -289.060818) (xy 398.986203 -289.07451)
			(xy 398.937348 -289.080442) (xy 398.888173 -289.078461) (xy 398.839954 -289.068617) (xy 398.793938 -289.051165)
			(xy 398.751317 -289.026558) (xy 398.713196 -288.995433) (xy 398.680561 -288.958596) (xy 398.654258 -288.917)
			(xy 398.634967 -288.871724) (xy 398.62319 -288.82394) (xy 398.61923 -288.774886) (xy 398.280128 -288.774886)
			(xy 398.279633 -288.799493) (xy 398.271738 -288.84807) (xy 398.256154 -288.894751) (xy 398.233283 -288.938328)
			(xy 398.203718 -288.977672) (xy 398.168225 -289.011764) (xy 398.127722 -289.03972) (xy 398.08326 -289.060818)
			(xy 398.035989 -289.07451) (xy 397.987134 -289.080442) (xy 397.937959 -289.078461) (xy 397.88974 -289.068617)
			(xy 397.843724 -289.051165) (xy 397.801103 -289.026558) (xy 397.762982 -288.995433) (xy 397.730347 -288.958596)
			(xy 397.704044 -288.917) (xy 397.684753 -288.871724) (xy 397.672976 -288.82394) (xy 397.669016 -288.774886)
			(xy 397.330168 -288.774886) (xy 397.329673 -288.799493) (xy 397.321778 -288.84807) (xy 397.306194 -288.894751)
			(xy 397.283323 -288.938328) (xy 397.253758 -288.977672) (xy 397.218265 -289.011764) (xy 397.177762 -289.03972)
			(xy 397.1333 -289.060818) (xy 397.086029 -289.07451) (xy 397.037174 -289.080442) (xy 396.987999 -289.078461)
			(xy 396.93978 -289.068617) (xy 396.893764 -289.051165) (xy 396.851143 -289.026558) (xy 396.813022 -288.995433)
			(xy 396.780387 -288.958596) (xy 396.754084 -288.917) (xy 396.734793 -288.871724) (xy 396.723016 -288.82394)
			(xy 396.719056 -288.774886) (xy 396.380208 -288.774886) (xy 396.379759 -288.798106) (xy 396.372715 -288.844009)
			(xy 396.358802 -288.888316) (xy 396.338341 -288.930007) (xy 396.311804 -288.968118) (xy 396.279803 -289.001773)
			(xy 396.243075 -289.030195) (xy 396.222982 -289.04184) (xy 396.222728 -289.04184) (xy 396.2146 -289.046893)
			(xy 396.2026 -289.061789) (xy 396.19936 -289.070796) (xy 396.17523 -289.146996) (xy 396.1765 -289.165792)
			(xy 396.178532 -289.17011) (xy 396.17904 -289.171634) (xy 396.191584 -289.198114) (xy 396.20745 -289.254511)
			(xy 396.210536 -289.283648) (xy 396.211669 -289.300872) (xy 396.210526 -289.335372) (xy 396.20825 -289.352482)
			(xy 396.200122 -289.4076) (xy 396.199094 -289.417763) (xy 396.204217 -289.437517) (xy 396.216625 -289.453719)
			(xy 396.225268 -289.459162) (xy 396.245768 -289.471268) (xy 396.28307 -289.500851) (xy 396.315316 -289.535875)
			(xy 396.3289 -289.555428) (xy 396.347442 -289.549078) (xy 396.37023 -289.542434) (xy 396.417183 -289.535482)
			(xy 396.464646 -289.535873) (xy 396.511478 -289.543598) (xy 396.556552 -289.558471) (xy 396.598785 -289.580135)
			(xy 396.63716 -289.608068) (xy 396.654274 -289.624516) (xy 396.683738 -289.653726) (xy 396.688056 -289.658298)
			(xy 396.694152 -289.664394) (xy 396.737586 -289.621214) (xy 396.741396 -289.611308) (xy 396.751534 -289.587396)
			(xy 396.778736 -289.543157) (xy 396.813026 -289.504153) (xy 396.853417 -289.471509) (xy 396.898747 -289.446165)
			(xy 396.947709 -289.428849) (xy 396.998893 -289.420061) (xy 397.02486 -289.419538) (xy 397.050124 -289.419936)
			(xy 397.099963 -289.428246) (xy 397.147754 -289.444648) (xy 397.192194 -289.468692) (xy 397.232069 -289.499723)
			(xy 397.266292 -289.536895) (xy 397.29393 -289.579194) (xy 397.314228 -289.625464) (xy 397.326633 -289.674445)
			(xy 397.330806 -289.7248) (xy 397.330802 -289.724846) (xy 397.669016 -289.724846) (xy 397.672976 -289.675792)
			(xy 397.684753 -289.628008) (xy 397.704044 -289.582732) (xy 397.730347 -289.541136) (xy 397.762982 -289.504299)
			(xy 397.801103 -289.473174) (xy 397.843724 -289.448567) (xy 397.88974 -289.431115) (xy 397.937959 -289.421271)
			(xy 397.987134 -289.41929) (xy 398.035989 -289.425222) (xy 398.08326 -289.438914) (xy 398.127722 -289.460012)
			(xy 398.168225 -289.487968) (xy 398.203718 -289.52206) (xy 398.233283 -289.561404) (xy 398.256154 -289.604981)
			(xy 398.271738 -289.651662) (xy 398.279633 -289.700239) (xy 398.280128 -289.724846) (xy 398.61923 -289.724846)
			(xy 398.62319 -289.675792) (xy 398.634967 -289.628008) (xy 398.654258 -289.582732) (xy 398.680561 -289.541136)
			(xy 398.713196 -289.504299) (xy 398.751317 -289.473174) (xy 398.793938 -289.448567) (xy 398.839954 -289.431115)
			(xy 398.888173 -289.421271) (xy 398.937348 -289.41929) (xy 398.986203 -289.425222) (xy 399.033474 -289.438914)
			(xy 399.077936 -289.460012) (xy 399.118439 -289.487968) (xy 399.153932 -289.52206) (xy 399.183497 -289.561404)
			(xy 399.206368 -289.604981) (xy 399.221952 -289.651662) (xy 399.229847 -289.700239) (xy 399.230342 -289.724846)
			(xy 399.56919 -289.724846) (xy 399.57315 -289.675792) (xy 399.584927 -289.628008) (xy 399.604218 -289.582732)
			(xy 399.630521 -289.541136) (xy 399.663156 -289.504299) (xy 399.701277 -289.473174) (xy 399.743898 -289.448567)
			(xy 399.789914 -289.431115) (xy 399.838133 -289.421271) (xy 399.887308 -289.41929) (xy 399.936163 -289.425222)
			(xy 399.983434 -289.438914) (xy 400.027896 -289.460012) (xy 400.068399 -289.487968) (xy 400.103892 -289.52206)
			(xy 400.133457 -289.561404) (xy 400.156328 -289.604981) (xy 400.171912 -289.651662) (xy 400.179807 -289.700239)
			(xy 400.180302 -289.724846) (xy 400.51915 -289.724846) (xy 400.52311 -289.675792) (xy 400.534887 -289.628008)
			(xy 400.554178 -289.582732) (xy 400.580481 -289.541136) (xy 400.613116 -289.504299) (xy 400.651237 -289.473174)
			(xy 400.693858 -289.448567) (xy 400.739874 -289.431115) (xy 400.788093 -289.421271) (xy 400.837268 -289.41929)
			(xy 400.886123 -289.425222) (xy 400.933394 -289.438914) (xy 400.977856 -289.460012) (xy 401.018359 -289.487968)
			(xy 401.053852 -289.52206) (xy 401.083417 -289.561404) (xy 401.106288 -289.604981) (xy 401.121872 -289.651662)
			(xy 401.129767 -289.700239) (xy 401.130262 -289.724846) (xy 401.46911 -289.724846) (xy 401.47307 -289.675792)
			(xy 401.484847 -289.628008) (xy 401.504138 -289.582732) (xy 401.530441 -289.541136) (xy 401.563076 -289.504299)
			(xy 401.601197 -289.473174) (xy 401.643818 -289.448567) (xy 401.689834 -289.431115) (xy 401.738053 -289.421271)
			(xy 401.787228 -289.41929) (xy 401.836083 -289.425222) (xy 401.883354 -289.438914) (xy 401.927816 -289.460012)
			(xy 401.968319 -289.487968) (xy 402.003812 -289.52206) (xy 402.033377 -289.561404) (xy 402.056248 -289.604981)
			(xy 402.071832 -289.651662) (xy 402.079727 -289.700239) (xy 402.080222 -289.724846) (xy 402.41907 -289.724846)
			(xy 402.42303 -289.675792) (xy 402.434807 -289.628008) (xy 402.454098 -289.582732) (xy 402.480401 -289.541136)
			(xy 402.513036 -289.504299) (xy 402.551157 -289.473174) (xy 402.593778 -289.448567) (xy 402.639794 -289.431115)
			(xy 402.688013 -289.421271) (xy 402.737188 -289.41929) (xy 402.786043 -289.425222) (xy 402.833314 -289.438914)
			(xy 402.877776 -289.460012) (xy 402.918279 -289.487968) (xy 402.953772 -289.52206) (xy 402.983337 -289.561404)
			(xy 403.006208 -289.604981) (xy 403.021792 -289.651662) (xy 403.029687 -289.700239) (xy 403.030182 -289.724846)
			(xy 403.36903 -289.724846) (xy 403.37299 -289.675792) (xy 403.384767 -289.628008) (xy 403.404058 -289.582732)
			(xy 403.430361 -289.541136) (xy 403.462996 -289.504299) (xy 403.501117 -289.473174) (xy 403.543738 -289.448567)
			(xy 403.589754 -289.431115) (xy 403.637973 -289.421271) (xy 403.687148 -289.41929) (xy 403.736003 -289.425222)
			(xy 403.783274 -289.438914) (xy 403.827736 -289.460012) (xy 403.868239 -289.487968) (xy 403.903732 -289.52206)
			(xy 403.933297 -289.561404) (xy 403.956168 -289.604981) (xy 403.971752 -289.651662) (xy 403.979647 -289.700239)
			(xy 403.980142 -289.724846) (xy 404.31899 -289.724846) (xy 404.32295 -289.675792) (xy 404.334727 -289.628008)
			(xy 404.354018 -289.582732) (xy 404.380321 -289.541136) (xy 404.412956 -289.504299) (xy 404.451077 -289.473174)
			(xy 404.493698 -289.448567) (xy 404.539714 -289.431115) (xy 404.587933 -289.421271) (xy 404.637108 -289.41929)
			(xy 404.685963 -289.425222) (xy 404.733234 -289.438914) (xy 404.777696 -289.460012) (xy 404.818199 -289.487968)
			(xy 404.853692 -289.52206) (xy 404.883257 -289.561404) (xy 404.906128 -289.604981) (xy 404.921712 -289.651662)
			(xy 404.929607 -289.700239) (xy 404.930102 -289.724846) (xy 405.269204 -289.724846) (xy 405.273164 -289.675792)
			(xy 405.284941 -289.628008) (xy 405.304232 -289.582732) (xy 405.330535 -289.541136) (xy 405.36317 -289.504299)
			(xy 405.401291 -289.473174) (xy 405.443912 -289.448567) (xy 405.489928 -289.431115) (xy 405.538147 -289.421271)
			(xy 405.587322 -289.41929) (xy 405.636177 -289.425222) (xy 405.683448 -289.438914) (xy 405.72791 -289.460012)
			(xy 405.768413 -289.487968) (xy 405.803906 -289.52206) (xy 405.833471 -289.561404) (xy 405.856342 -289.604981)
			(xy 405.871926 -289.651662) (xy 405.879821 -289.700239) (xy 405.880316 -289.724846) (xy 406.219164 -289.724846)
			(xy 406.223124 -289.675792) (xy 406.234901 -289.628008) (xy 406.254192 -289.582732) (xy 406.280495 -289.541136)
			(xy 406.31313 -289.504299) (xy 406.351251 -289.473174) (xy 406.393872 -289.448567) (xy 406.439888 -289.431115)
			(xy 406.488107 -289.421271) (xy 406.537282 -289.41929) (xy 406.586137 -289.425222) (xy 406.633408 -289.438914)
			(xy 406.67787 -289.460012) (xy 406.718373 -289.487968) (xy 406.753866 -289.52206) (xy 406.783431 -289.561404)
			(xy 406.806302 -289.604981) (xy 406.821886 -289.651662) (xy 406.829781 -289.700239) (xy 406.830276 -289.724846)
			(xy 408.119084 -289.724846) (xy 408.123044 -289.675792) (xy 408.134821 -289.628008) (xy 408.154112 -289.582732)
			(xy 408.180415 -289.541136) (xy 408.21305 -289.504299) (xy 408.251171 -289.473174) (xy 408.293792 -289.448567)
			(xy 408.339808 -289.431115) (xy 408.388027 -289.421271) (xy 408.437202 -289.41929) (xy 408.486057 -289.425222)
			(xy 408.533328 -289.438914) (xy 408.57779 -289.460012) (xy 408.618293 -289.487968) (xy 408.653786 -289.52206)
			(xy 408.683351 -289.561404) (xy 408.706222 -289.604981) (xy 408.721806 -289.651662) (xy 408.729701 -289.700239)
			(xy 408.730196 -289.724846) (xy 409.069044 -289.724846) (xy 409.073004 -289.675792) (xy 409.084781 -289.628008)
			(xy 409.104072 -289.582732) (xy 409.130375 -289.541136) (xy 409.16301 -289.504299) (xy 409.201131 -289.473174)
			(xy 409.243752 -289.448567) (xy 409.289768 -289.431115) (xy 409.337987 -289.421271) (xy 409.387162 -289.41929)
			(xy 409.436017 -289.425222) (xy 409.483288 -289.438914) (xy 409.52775 -289.460012) (xy 409.568253 -289.487968)
			(xy 409.603746 -289.52206) (xy 409.633311 -289.561404) (xy 409.656182 -289.604981) (xy 409.671766 -289.651662)
			(xy 409.679661 -289.700239) (xy 409.680156 -289.724846) (xy 410.019004 -289.724846) (xy 410.022964 -289.675792)
			(xy 410.034741 -289.628008) (xy 410.054032 -289.582732) (xy 410.080335 -289.541136) (xy 410.11297 -289.504299)
			(xy 410.151091 -289.473174) (xy 410.193712 -289.448567) (xy 410.239728 -289.431115) (xy 410.287947 -289.421271)
			(xy 410.337122 -289.41929) (xy 410.385977 -289.425222) (xy 410.433248 -289.438914) (xy 410.47771 -289.460012)
			(xy 410.518213 -289.487968) (xy 410.553706 -289.52206) (xy 410.583271 -289.561404) (xy 410.606142 -289.604981)
			(xy 410.621726 -289.651662) (xy 410.629621 -289.700239) (xy 410.630116 -289.724846) (xy 410.969218 -289.724846)
			(xy 410.973178 -289.675792) (xy 410.984955 -289.628008) (xy 411.004246 -289.582732) (xy 411.030549 -289.541136)
			(xy 411.063184 -289.504299) (xy 411.101305 -289.473174) (xy 411.143926 -289.448567) (xy 411.189942 -289.431115)
			(xy 411.238161 -289.421271) (xy 411.287336 -289.41929) (xy 411.336191 -289.425222) (xy 411.383462 -289.438914)
			(xy 411.427924 -289.460012) (xy 411.468427 -289.487968) (xy 411.50392 -289.52206) (xy 411.533485 -289.561404)
			(xy 411.556356 -289.604981) (xy 411.57194 -289.651662) (xy 411.579835 -289.700239) (xy 411.58033 -289.724846)
			(xy 411.919178 -289.724846) (xy 411.923138 -289.675792) (xy 411.934915 -289.628008) (xy 411.954206 -289.582732)
			(xy 411.980509 -289.541136) (xy 412.013144 -289.504299) (xy 412.051265 -289.473174) (xy 412.093886 -289.448567)
			(xy 412.139902 -289.431115) (xy 412.188121 -289.421271) (xy 412.237296 -289.41929) (xy 412.286151 -289.425222)
			(xy 412.333422 -289.438914) (xy 412.377884 -289.460012) (xy 412.418387 -289.487968) (xy 412.45388 -289.52206)
			(xy 412.483445 -289.561404) (xy 412.506316 -289.604981) (xy 412.5219 -289.651662) (xy 412.529795 -289.700239)
			(xy 412.53029 -289.724846) (xy 412.869138 -289.724846) (xy 412.873098 -289.675792) (xy 412.884875 -289.628008)
			(xy 412.904166 -289.582732) (xy 412.930469 -289.541136) (xy 412.963104 -289.504299) (xy 413.001225 -289.473174)
			(xy 413.043846 -289.448567) (xy 413.089862 -289.431115) (xy 413.138081 -289.421271) (xy 413.187256 -289.41929)
			(xy 413.236111 -289.425222) (xy 413.283382 -289.438914) (xy 413.327844 -289.460012) (xy 413.368347 -289.487968)
			(xy 413.40384 -289.52206) (xy 413.433405 -289.561404) (xy 413.456276 -289.604981) (xy 413.47186 -289.651662)
			(xy 413.479755 -289.700239) (xy 413.48025 -289.724846) (xy 413.819098 -289.724846) (xy 413.823058 -289.675792)
			(xy 413.834835 -289.628008) (xy 413.854126 -289.582732) (xy 413.880429 -289.541136) (xy 413.913064 -289.504299)
			(xy 413.951185 -289.473174) (xy 413.993806 -289.448567) (xy 414.039822 -289.431115) (xy 414.088041 -289.421271)
			(xy 414.137216 -289.41929) (xy 414.186071 -289.425222) (xy 414.233342 -289.438914) (xy 414.277804 -289.460012)
			(xy 414.318307 -289.487968) (xy 414.3538 -289.52206) (xy 414.383365 -289.561404) (xy 414.406236 -289.604981)
			(xy 414.42182 -289.651662) (xy 414.429715 -289.700239) (xy 414.43021 -289.724846) (xy 414.769058 -289.724846)
			(xy 414.773018 -289.675792) (xy 414.784795 -289.628008) (xy 414.804086 -289.582732) (xy 414.830389 -289.541136)
			(xy 414.863024 -289.504299) (xy 414.901145 -289.473174) (xy 414.943766 -289.448567) (xy 414.989782 -289.431115)
			(xy 415.038001 -289.421271) (xy 415.087176 -289.41929) (xy 415.136031 -289.425222) (xy 415.183302 -289.438914)
			(xy 415.227764 -289.460012) (xy 415.268267 -289.487968) (xy 415.30376 -289.52206) (xy 415.333325 -289.561404)
			(xy 415.356196 -289.604981) (xy 415.37178 -289.651662) (xy 415.379675 -289.700239) (xy 415.38017 -289.724846)
			(xy 415.719018 -289.724846) (xy 415.722978 -289.675792) (xy 415.734755 -289.628008) (xy 415.754046 -289.582732)
			(xy 415.780349 -289.541136) (xy 415.812984 -289.504299) (xy 415.851105 -289.473174) (xy 415.893726 -289.448567)
			(xy 415.939742 -289.431115) (xy 415.987961 -289.421271) (xy 416.037136 -289.41929) (xy 416.085991 -289.425222)
			(xy 416.133262 -289.438914) (xy 416.177724 -289.460012) (xy 416.218227 -289.487968) (xy 416.25372 -289.52206)
			(xy 416.283285 -289.561404) (xy 416.306156 -289.604981) (xy 416.32174 -289.651662) (xy 416.329635 -289.700239)
			(xy 416.33013 -289.724846) (xy 416.668978 -289.724846) (xy 416.672938 -289.675792) (xy 416.684715 -289.628008)
			(xy 416.704006 -289.582732) (xy 416.730309 -289.541136) (xy 416.762944 -289.504299) (xy 416.801065 -289.473174)
			(xy 416.843686 -289.448567) (xy 416.889702 -289.431115) (xy 416.937921 -289.421271) (xy 416.987096 -289.41929)
			(xy 417.035951 -289.425222) (xy 417.083222 -289.438914) (xy 417.127684 -289.460012) (xy 417.168187 -289.487968)
			(xy 417.20368 -289.52206) (xy 417.233245 -289.561404) (xy 417.256116 -289.604981) (xy 417.2717 -289.651662)
			(xy 417.279595 -289.700239) (xy 417.28009 -289.724846) (xy 417.279595 -289.749453) (xy 417.2717 -289.79803)
			(xy 417.256116 -289.844711) (xy 417.233245 -289.888288) (xy 417.20368 -289.927632) (xy 417.168187 -289.961724)
			(xy 417.127684 -289.98968) (xy 417.083222 -290.010778) (xy 417.035951 -290.02447) (xy 416.987096 -290.030402)
			(xy 416.937921 -290.028421) (xy 416.889702 -290.018577) (xy 416.843686 -290.001125) (xy 416.801065 -289.976518)
			(xy 416.762944 -289.945393) (xy 416.730309 -289.908556) (xy 416.704006 -289.86696) (xy 416.684715 -289.821684)
			(xy 416.672938 -289.7739) (xy 416.668978 -289.724846) (xy 416.33013 -289.724846) (xy 416.329635 -289.749453)
			(xy 416.32174 -289.79803) (xy 416.306156 -289.844711) (xy 416.283285 -289.888288) (xy 416.25372 -289.927632)
			(xy 416.218227 -289.961724) (xy 416.177724 -289.98968) (xy 416.133262 -290.010778) (xy 416.085991 -290.02447)
			(xy 416.037136 -290.030402) (xy 415.987961 -290.028421) (xy 415.939742 -290.018577) (xy 415.893726 -290.001125)
			(xy 415.851105 -289.976518) (xy 415.812984 -289.945393) (xy 415.780349 -289.908556) (xy 415.754046 -289.86696)
			(xy 415.734755 -289.821684) (xy 415.722978 -289.7739) (xy 415.719018 -289.724846) (xy 415.38017 -289.724846)
			(xy 415.379675 -289.749453) (xy 415.37178 -289.79803) (xy 415.356196 -289.844711) (xy 415.333325 -289.888288)
			(xy 415.30376 -289.927632) (xy 415.268267 -289.961724) (xy 415.227764 -289.98968) (xy 415.183302 -290.010778)
			(xy 415.136031 -290.02447) (xy 415.087176 -290.030402) (xy 415.038001 -290.028421) (xy 414.989782 -290.018577)
			(xy 414.943766 -290.001125) (xy 414.901145 -289.976518) (xy 414.863024 -289.945393) (xy 414.830389 -289.908556)
			(xy 414.804086 -289.86696) (xy 414.784795 -289.821684) (xy 414.773018 -289.7739) (xy 414.769058 -289.724846)
			(xy 414.43021 -289.724846) (xy 414.429715 -289.749453) (xy 414.42182 -289.79803) (xy 414.406236 -289.844711)
			(xy 414.383365 -289.888288) (xy 414.3538 -289.927632) (xy 414.318307 -289.961724) (xy 414.277804 -289.98968)
			(xy 414.233342 -290.010778) (xy 414.186071 -290.02447) (xy 414.137216 -290.030402) (xy 414.088041 -290.028421)
			(xy 414.039822 -290.018577) (xy 413.993806 -290.001125) (xy 413.951185 -289.976518) (xy 413.913064 -289.945393)
			(xy 413.880429 -289.908556) (xy 413.854126 -289.86696) (xy 413.834835 -289.821684) (xy 413.823058 -289.7739)
			(xy 413.819098 -289.724846) (xy 413.48025 -289.724846) (xy 413.479755 -289.749453) (xy 413.47186 -289.79803)
			(xy 413.456276 -289.844711) (xy 413.433405 -289.888288) (xy 413.40384 -289.927632) (xy 413.368347 -289.961724)
			(xy 413.327844 -289.98968) (xy 413.283382 -290.010778) (xy 413.236111 -290.02447) (xy 413.187256 -290.030402)
			(xy 413.138081 -290.028421) (xy 413.089862 -290.018577) (xy 413.043846 -290.001125) (xy 413.001225 -289.976518)
			(xy 412.963104 -289.945393) (xy 412.930469 -289.908556) (xy 412.904166 -289.86696) (xy 412.884875 -289.821684)
			(xy 412.873098 -289.7739) (xy 412.869138 -289.724846) (xy 412.53029 -289.724846) (xy 412.529795 -289.749453)
			(xy 412.5219 -289.79803) (xy 412.506316 -289.844711) (xy 412.483445 -289.888288) (xy 412.45388 -289.927632)
			(xy 412.418387 -289.961724) (xy 412.377884 -289.98968) (xy 412.333422 -290.010778) (xy 412.286151 -290.02447)
			(xy 412.237296 -290.030402) (xy 412.188121 -290.028421) (xy 412.139902 -290.018577) (xy 412.093886 -290.001125)
			(xy 412.051265 -289.976518) (xy 412.013144 -289.945393) (xy 411.980509 -289.908556) (xy 411.954206 -289.86696)
			(xy 411.934915 -289.821684) (xy 411.923138 -289.7739) (xy 411.919178 -289.724846) (xy 411.58033 -289.724846)
			(xy 411.579835 -289.749453) (xy 411.57194 -289.79803) (xy 411.556356 -289.844711) (xy 411.533485 -289.888288)
			(xy 411.50392 -289.927632) (xy 411.468427 -289.961724) (xy 411.427924 -289.98968) (xy 411.383462 -290.010778)
			(xy 411.336191 -290.02447) (xy 411.287336 -290.030402) (xy 411.238161 -290.028421) (xy 411.189942 -290.018577)
			(xy 411.143926 -290.001125) (xy 411.101305 -289.976518) (xy 411.063184 -289.945393) (xy 411.030549 -289.908556)
			(xy 411.004246 -289.86696) (xy 410.984955 -289.821684) (xy 410.973178 -289.7739) (xy 410.969218 -289.724846)
			(xy 410.630116 -289.724846) (xy 410.629621 -289.749453) (xy 410.621726 -289.79803) (xy 410.606142 -289.844711)
			(xy 410.583271 -289.888288) (xy 410.553706 -289.927632) (xy 410.518213 -289.961724) (xy 410.47771 -289.98968)
			(xy 410.433248 -290.010778) (xy 410.385977 -290.02447) (xy 410.337122 -290.030402) (xy 410.287947 -290.028421)
			(xy 410.239728 -290.018577) (xy 410.193712 -290.001125) (xy 410.151091 -289.976518) (xy 410.11297 -289.945393)
			(xy 410.080335 -289.908556) (xy 410.054032 -289.86696) (xy 410.034741 -289.821684) (xy 410.022964 -289.7739)
			(xy 410.019004 -289.724846) (xy 409.680156 -289.724846) (xy 409.679661 -289.749453) (xy 409.671766 -289.79803)
			(xy 409.656182 -289.844711) (xy 409.633311 -289.888288) (xy 409.603746 -289.927632) (xy 409.568253 -289.961724)
			(xy 409.52775 -289.98968) (xy 409.483288 -290.010778) (xy 409.436017 -290.02447) (xy 409.387162 -290.030402)
			(xy 409.337987 -290.028421) (xy 409.289768 -290.018577) (xy 409.243752 -290.001125) (xy 409.201131 -289.976518)
			(xy 409.16301 -289.945393) (xy 409.130375 -289.908556) (xy 409.104072 -289.86696) (xy 409.084781 -289.821684)
			(xy 409.073004 -289.7739) (xy 409.069044 -289.724846) (xy 408.730196 -289.724846) (xy 408.729701 -289.749453)
			(xy 408.721806 -289.79803) (xy 408.706222 -289.844711) (xy 408.683351 -289.888288) (xy 408.653786 -289.927632)
			(xy 408.618293 -289.961724) (xy 408.57779 -289.98968) (xy 408.533328 -290.010778) (xy 408.486057 -290.02447)
			(xy 408.437202 -290.030402) (xy 408.388027 -290.028421) (xy 408.339808 -290.018577) (xy 408.293792 -290.001125)
			(xy 408.251171 -289.976518) (xy 408.21305 -289.945393) (xy 408.180415 -289.908556) (xy 408.154112 -289.86696)
			(xy 408.134821 -289.821684) (xy 408.123044 -289.7739) (xy 408.119084 -289.724846) (xy 406.830276 -289.724846)
			(xy 406.829781 -289.749453) (xy 406.821886 -289.79803) (xy 406.806302 -289.844711) (xy 406.783431 -289.888288)
			(xy 406.753866 -289.927632) (xy 406.718373 -289.961724) (xy 406.67787 -289.98968) (xy 406.633408 -290.010778)
			(xy 406.586137 -290.02447) (xy 406.537282 -290.030402) (xy 406.488107 -290.028421) (xy 406.439888 -290.018577)
			(xy 406.393872 -290.001125) (xy 406.351251 -289.976518) (xy 406.31313 -289.945393) (xy 406.280495 -289.908556)
			(xy 406.254192 -289.86696) (xy 406.234901 -289.821684) (xy 406.223124 -289.7739) (xy 406.219164 -289.724846)
			(xy 405.880316 -289.724846) (xy 405.879821 -289.749453) (xy 405.871926 -289.79803) (xy 405.856342 -289.844711)
			(xy 405.833471 -289.888288) (xy 405.803906 -289.927632) (xy 405.768413 -289.961724) (xy 405.72791 -289.98968)
			(xy 405.683448 -290.010778) (xy 405.636177 -290.02447) (xy 405.587322 -290.030402) (xy 405.538147 -290.028421)
			(xy 405.489928 -290.018577) (xy 405.443912 -290.001125) (xy 405.401291 -289.976518) (xy 405.36317 -289.945393)
			(xy 405.330535 -289.908556) (xy 405.304232 -289.86696) (xy 405.284941 -289.821684) (xy 405.273164 -289.7739)
			(xy 405.269204 -289.724846) (xy 404.930102 -289.724846) (xy 404.929607 -289.749453) (xy 404.921712 -289.79803)
			(xy 404.906128 -289.844711) (xy 404.883257 -289.888288) (xy 404.853692 -289.927632) (xy 404.818199 -289.961724)
			(xy 404.777696 -289.98968) (xy 404.733234 -290.010778) (xy 404.685963 -290.02447) (xy 404.637108 -290.030402)
			(xy 404.587933 -290.028421) (xy 404.539714 -290.018577) (xy 404.493698 -290.001125) (xy 404.451077 -289.976518)
			(xy 404.412956 -289.945393) (xy 404.380321 -289.908556) (xy 404.354018 -289.86696) (xy 404.334727 -289.821684)
			(xy 404.32295 -289.7739) (xy 404.31899 -289.724846) (xy 403.980142 -289.724846) (xy 403.979647 -289.749453)
			(xy 403.971752 -289.79803) (xy 403.956168 -289.844711) (xy 403.933297 -289.888288) (xy 403.903732 -289.927632)
			(xy 403.868239 -289.961724) (xy 403.827736 -289.98968) (xy 403.783274 -290.010778) (xy 403.736003 -290.02447)
			(xy 403.687148 -290.030402) (xy 403.637973 -290.028421) (xy 403.589754 -290.018577) (xy 403.543738 -290.001125)
			(xy 403.501117 -289.976518) (xy 403.462996 -289.945393) (xy 403.430361 -289.908556) (xy 403.404058 -289.86696)
			(xy 403.384767 -289.821684) (xy 403.37299 -289.7739) (xy 403.36903 -289.724846) (xy 403.030182 -289.724846)
			(xy 403.029687 -289.749453) (xy 403.021792 -289.79803) (xy 403.006208 -289.844711) (xy 402.983337 -289.888288)
			(xy 402.953772 -289.927632) (xy 402.918279 -289.961724) (xy 402.877776 -289.98968) (xy 402.833314 -290.010778)
			(xy 402.786043 -290.02447) (xy 402.737188 -290.030402) (xy 402.688013 -290.028421) (xy 402.639794 -290.018577)
			(xy 402.593778 -290.001125) (xy 402.551157 -289.976518) (xy 402.513036 -289.945393) (xy 402.480401 -289.908556)
			(xy 402.454098 -289.86696) (xy 402.434807 -289.821684) (xy 402.42303 -289.7739) (xy 402.41907 -289.724846)
			(xy 402.080222 -289.724846) (xy 402.079727 -289.749453) (xy 402.071832 -289.79803) (xy 402.056248 -289.844711)
			(xy 402.033377 -289.888288) (xy 402.003812 -289.927632) (xy 401.968319 -289.961724) (xy 401.927816 -289.98968)
			(xy 401.883354 -290.010778) (xy 401.836083 -290.02447) (xy 401.787228 -290.030402) (xy 401.738053 -290.028421)
			(xy 401.689834 -290.018577) (xy 401.643818 -290.001125) (xy 401.601197 -289.976518) (xy 401.563076 -289.945393)
			(xy 401.530441 -289.908556) (xy 401.504138 -289.86696) (xy 401.484847 -289.821684) (xy 401.47307 -289.7739)
			(xy 401.46911 -289.724846) (xy 401.130262 -289.724846) (xy 401.129767 -289.749453) (xy 401.121872 -289.79803)
			(xy 401.106288 -289.844711) (xy 401.083417 -289.888288) (xy 401.053852 -289.927632) (xy 401.018359 -289.961724)
			(xy 400.977856 -289.98968) (xy 400.933394 -290.010778) (xy 400.886123 -290.02447) (xy 400.837268 -290.030402)
			(xy 400.788093 -290.028421) (xy 400.739874 -290.018577) (xy 400.693858 -290.001125) (xy 400.651237 -289.976518)
			(xy 400.613116 -289.945393) (xy 400.580481 -289.908556) (xy 400.554178 -289.86696) (xy 400.534887 -289.821684)
			(xy 400.52311 -289.7739) (xy 400.51915 -289.724846) (xy 400.180302 -289.724846) (xy 400.179807 -289.749453)
			(xy 400.171912 -289.79803) (xy 400.156328 -289.844711) (xy 400.133457 -289.888288) (xy 400.103892 -289.927632)
			(xy 400.068399 -289.961724) (xy 400.027896 -289.98968) (xy 399.983434 -290.010778) (xy 399.936163 -290.02447)
			(xy 399.887308 -290.030402) (xy 399.838133 -290.028421) (xy 399.789914 -290.018577) (xy 399.743898 -290.001125)
			(xy 399.701277 -289.976518) (xy 399.663156 -289.945393) (xy 399.630521 -289.908556) (xy 399.604218 -289.86696)
			(xy 399.584927 -289.821684) (xy 399.57315 -289.7739) (xy 399.56919 -289.724846) (xy 399.230342 -289.724846)
			(xy 399.229847 -289.749453) (xy 399.221952 -289.79803) (xy 399.206368 -289.844711) (xy 399.183497 -289.888288)
			(xy 399.153932 -289.927632) (xy 399.118439 -289.961724) (xy 399.077936 -289.98968) (xy 399.033474 -290.010778)
			(xy 398.986203 -290.02447) (xy 398.937348 -290.030402) (xy 398.888173 -290.028421) (xy 398.839954 -290.018577)
			(xy 398.793938 -290.001125) (xy 398.751317 -289.976518) (xy 398.713196 -289.945393) (xy 398.680561 -289.908556)
			(xy 398.654258 -289.86696) (xy 398.634967 -289.821684) (xy 398.62319 -289.7739) (xy 398.61923 -289.724846)
			(xy 398.280128 -289.724846) (xy 398.279633 -289.749453) (xy 398.271738 -289.79803) (xy 398.256154 -289.844711)
			(xy 398.233283 -289.888288) (xy 398.203718 -289.927632) (xy 398.168225 -289.961724) (xy 398.127722 -289.98968)
			(xy 398.08326 -290.010778) (xy 398.035989 -290.02447) (xy 397.987134 -290.030402) (xy 397.937959 -290.028421)
			(xy 397.88974 -290.018577) (xy 397.843724 -290.001125) (xy 397.801103 -289.976518) (xy 397.762982 -289.945393)
			(xy 397.730347 -289.908556) (xy 397.704044 -289.86696) (xy 397.684753 -289.821684) (xy 397.672976 -289.7739)
			(xy 397.669016 -289.724846) (xy 397.330802 -289.724846) (xy 397.326633 -289.775155) (xy 397.314228 -289.824135)
			(xy 397.29393 -289.870406) (xy 397.266292 -289.912705) (xy 397.232069 -289.949877) (xy 397.192194 -289.980908)
			(xy 397.147754 -290.004952) (xy 397.099963 -290.021354) (xy 397.050124 -290.029664) (xy 397.02486 -290.030154)
			(xy 396.996023 -290.029465) (xy 396.939382 -290.018596) (xy 396.912338 -290.008564) (xy 396.912084 -290.008564)
			(xy 396.900295 -290.004791) (xy 396.875739 -290.007581) (xy 396.865094 -290.013898) (xy 396.795498 -290.060888)
			(xy 396.785557 -290.06846) (xy 396.773971 -290.090569) (xy 396.7734 -290.103052) (xy 396.7734 -290.2966)
			(xy 396.773943 -290.309087) (xy 396.78555 -290.331194) (xy 396.795498 -290.338764) (xy 396.865094 -290.385754)
			(xy 396.875674 -290.392253) (xy 396.900317 -290.395052) (xy 396.912084 -290.391088) (xy 396.912338 -290.391088)
			(xy 396.939382 -290.381055) (xy 396.996023 -290.370188) (xy 397.02486 -290.369498) (xy 397.05012 -290.369976)
			(xy 397.099953 -290.378285) (xy 397.147738 -290.394684) (xy 397.192172 -290.418725) (xy 397.232042 -290.449753)
			(xy 397.266261 -290.48692) (xy 397.293895 -290.529213) (xy 397.314191 -290.575477) (xy 397.326594 -290.624452)
			(xy 397.330766 -290.6748) (xy 397.330766 -290.674806) (xy 397.669016 -290.674806) (xy 397.672976 -290.625752)
			(xy 397.684753 -290.577968) (xy 397.704044 -290.532692) (xy 397.730347 -290.491096) (xy 397.762982 -290.454259)
			(xy 397.801103 -290.423134) (xy 397.843724 -290.398527) (xy 397.88974 -290.381075) (xy 397.937959 -290.371231)
			(xy 397.987134 -290.36925) (xy 398.035989 -290.375182) (xy 398.08326 -290.388874) (xy 398.127722 -290.409972)
			(xy 398.168225 -290.437928) (xy 398.203718 -290.47202) (xy 398.233283 -290.511364) (xy 398.256154 -290.554941)
			(xy 398.271738 -290.601622) (xy 398.279633 -290.650199) (xy 398.280128 -290.674806) (xy 416.668978 -290.674806)
			(xy 416.672938 -290.625752) (xy 416.684715 -290.577968) (xy 416.704006 -290.532692) (xy 416.730309 -290.491096)
			(xy 416.762944 -290.454259) (xy 416.801065 -290.423134) (xy 416.843686 -290.398527) (xy 416.889702 -290.381075)
			(xy 416.937921 -290.371231) (xy 416.987096 -290.36925) (xy 417.035951 -290.375182) (xy 417.083222 -290.388874)
			(xy 417.127684 -290.409972) (xy 417.168187 -290.437928) (xy 417.20368 -290.47202) (xy 417.233245 -290.511364)
			(xy 417.256116 -290.554941) (xy 417.2717 -290.601622) (xy 417.279595 -290.650199) (xy 417.28009 -290.674806)
			(xy 417.279595 -290.699413) (xy 417.2717 -290.74799) (xy 417.256116 -290.794671) (xy 417.233245 -290.838248)
			(xy 417.20368 -290.877592) (xy 417.168187 -290.911684) (xy 417.127684 -290.93964) (xy 417.083222 -290.960738)
			(xy 417.035951 -290.97443) (xy 416.987096 -290.980362) (xy 416.937921 -290.978381) (xy 416.889702 -290.968537)
			(xy 416.843686 -290.951085) (xy 416.801065 -290.926478) (xy 416.762944 -290.895353) (xy 416.730309 -290.858516)
			(xy 416.704006 -290.81692) (xy 416.684715 -290.771644) (xy 416.672938 -290.72386) (xy 416.668978 -290.674806)
			(xy 398.280128 -290.674806) (xy 398.279633 -290.699413) (xy 398.271738 -290.74799) (xy 398.256154 -290.794671)
			(xy 398.233283 -290.838248) (xy 398.203718 -290.877592) (xy 398.168225 -290.911684) (xy 398.127722 -290.93964)
			(xy 398.08326 -290.960738) (xy 398.035989 -290.97443) (xy 397.987134 -290.980362) (xy 397.937959 -290.978381)
			(xy 397.88974 -290.968537) (xy 397.843724 -290.951085) (xy 397.801103 -290.926478) (xy 397.762982 -290.895353)
			(xy 397.730347 -290.858516) (xy 397.704044 -290.81692) (xy 397.684753 -290.771644) (xy 397.672976 -290.72386)
			(xy 397.669016 -290.674806) (xy 397.330766 -290.674806) (xy 397.326594 -290.725148) (xy 397.314191 -290.774123)
			(xy 397.293895 -290.820387) (xy 397.266261 -290.86268) (xy 397.232042 -290.899847) (xy 397.192172 -290.930875)
			(xy 397.147738 -290.954916) (xy 397.099953 -290.971315) (xy 397.05012 -290.979624) (xy 397.02486 -290.980114)
			(xy 396.996023 -290.979427) (xy 396.939382 -290.968557) (xy 396.912338 -290.958524) (xy 396.912084 -290.958524)
			(xy 396.900294 -290.954757) (xy 396.87574 -290.957545) (xy 396.865094 -290.963858) (xy 396.795498 -291.010848)
			(xy 396.785575 -291.018439) (xy 396.77398 -291.040533) (xy 396.7734 -291.053012) (xy 396.7734 -291.24656)
			(xy 396.773967 -291.259044) (xy 396.785557 -291.281151) (xy 396.795498 -291.288724) (xy 396.865094 -291.335714)
			(xy 396.875673 -291.342214) (xy 396.900316 -291.345009) (xy 396.912084 -291.341048) (xy 396.912338 -291.341048)
			(xy 396.939381 -291.331013) (xy 396.996023 -291.320148) (xy 397.02486 -291.319458) (xy 397.050117 -291.320015)
			(xy 397.099943 -291.328324) (xy 397.147722 -291.344721) (xy 397.19215 -291.368759) (xy 397.232015 -291.399782)
			(xy 397.266229 -291.436944) (xy 397.29386 -291.479232) (xy 397.314153 -291.52549) (xy 397.326554 -291.574459)
			(xy 397.330723 -291.624766) (xy 397.669016 -291.624766) (xy 397.672976 -291.575712) (xy 397.684753 -291.527928)
			(xy 397.704044 -291.482652) (xy 397.730347 -291.441056) (xy 397.762982 -291.404219) (xy 397.801103 -291.373094)
			(xy 397.843724 -291.348487) (xy 397.88974 -291.331035) (xy 397.937959 -291.321191) (xy 397.987134 -291.31921)
			(xy 398.035989 -291.325142) (xy 398.08326 -291.338834) (xy 398.127722 -291.359932) (xy 398.168225 -291.387888)
			(xy 398.203718 -291.42198) (xy 398.233283 -291.461324) (xy 398.256154 -291.504901) (xy 398.271738 -291.551582)
			(xy 398.279633 -291.600159) (xy 398.280128 -291.624766) (xy 398.61923 -291.624766) (xy 398.62319 -291.575712)
			(xy 398.634967 -291.527928) (xy 398.654258 -291.482652) (xy 398.680561 -291.441056) (xy 398.713196 -291.404219)
			(xy 398.751317 -291.373094) (xy 398.793938 -291.348487) (xy 398.839954 -291.331035) (xy 398.888173 -291.321191)
			(xy 398.937348 -291.31921) (xy 398.986203 -291.325142) (xy 399.033474 -291.338834) (xy 399.077936 -291.359932)
			(xy 399.118439 -291.387888) (xy 399.153932 -291.42198) (xy 399.183497 -291.461324) (xy 399.206368 -291.504901)
			(xy 399.221952 -291.551582) (xy 399.229847 -291.600159) (xy 399.230342 -291.624766) (xy 399.56919 -291.624766)
			(xy 399.57315 -291.575712) (xy 399.584927 -291.527928) (xy 399.604218 -291.482652) (xy 399.630521 -291.441056)
			(xy 399.663156 -291.404219) (xy 399.701277 -291.373094) (xy 399.743898 -291.348487) (xy 399.789914 -291.331035)
			(xy 399.838133 -291.321191) (xy 399.887308 -291.31921) (xy 399.936163 -291.325142) (xy 399.983434 -291.338834)
			(xy 400.027896 -291.359932) (xy 400.068399 -291.387888) (xy 400.103892 -291.42198) (xy 400.133457 -291.461324)
			(xy 400.156328 -291.504901) (xy 400.171912 -291.551582) (xy 400.179807 -291.600159) (xy 400.180302 -291.624766)
			(xy 400.51915 -291.624766) (xy 400.52311 -291.575712) (xy 400.534887 -291.527928) (xy 400.554178 -291.482652)
			(xy 400.580481 -291.441056) (xy 400.613116 -291.404219) (xy 400.651237 -291.373094) (xy 400.693858 -291.348487)
			(xy 400.739874 -291.331035) (xy 400.788093 -291.321191) (xy 400.837268 -291.31921) (xy 400.886123 -291.325142)
			(xy 400.933394 -291.338834) (xy 400.977856 -291.359932) (xy 401.018359 -291.387888) (xy 401.053852 -291.42198)
			(xy 401.083417 -291.461324) (xy 401.106288 -291.504901) (xy 401.121872 -291.551582) (xy 401.129767 -291.600159)
			(xy 401.130262 -291.624766) (xy 401.46911 -291.624766) (xy 401.47307 -291.575712) (xy 401.484847 -291.527928)
			(xy 401.504138 -291.482652) (xy 401.530441 -291.441056) (xy 401.563076 -291.404219) (xy 401.601197 -291.373094)
			(xy 401.643818 -291.348487) (xy 401.689834 -291.331035) (xy 401.738053 -291.321191) (xy 401.787228 -291.31921)
			(xy 401.836083 -291.325142) (xy 401.883354 -291.338834) (xy 401.927816 -291.359932) (xy 401.968319 -291.387888)
			(xy 402.003812 -291.42198) (xy 402.033377 -291.461324) (xy 402.056248 -291.504901) (xy 402.071832 -291.551582)
			(xy 402.079727 -291.600159) (xy 402.080222 -291.624766) (xy 402.41907 -291.624766) (xy 402.42303 -291.575712)
			(xy 402.434807 -291.527928) (xy 402.454098 -291.482652) (xy 402.480401 -291.441056) (xy 402.513036 -291.404219)
			(xy 402.551157 -291.373094) (xy 402.593778 -291.348487) (xy 402.639794 -291.331035) (xy 402.688013 -291.321191)
			(xy 402.737188 -291.31921) (xy 402.786043 -291.325142) (xy 402.833314 -291.338834) (xy 402.877776 -291.359932)
			(xy 402.918279 -291.387888) (xy 402.953772 -291.42198) (xy 402.983337 -291.461324) (xy 403.006208 -291.504901)
			(xy 403.021792 -291.551582) (xy 403.029687 -291.600159) (xy 403.030182 -291.624766) (xy 403.36903 -291.624766)
			(xy 403.37299 -291.575712) (xy 403.384767 -291.527928) (xy 403.404058 -291.482652) (xy 403.430361 -291.441056)
			(xy 403.462996 -291.404219) (xy 403.501117 -291.373094) (xy 403.543738 -291.348487) (xy 403.589754 -291.331035)
			(xy 403.637973 -291.321191) (xy 403.687148 -291.31921) (xy 403.736003 -291.325142) (xy 403.783274 -291.338834)
			(xy 403.827736 -291.359932) (xy 403.868239 -291.387888) (xy 403.903732 -291.42198) (xy 403.933297 -291.461324)
			(xy 403.956168 -291.504901) (xy 403.971752 -291.551582) (xy 403.979647 -291.600159) (xy 403.980142 -291.624766)
			(xy 404.31899 -291.624766) (xy 404.32295 -291.575712) (xy 404.334727 -291.527928) (xy 404.354018 -291.482652)
			(xy 404.380321 -291.441056) (xy 404.412956 -291.404219) (xy 404.451077 -291.373094) (xy 404.493698 -291.348487)
			(xy 404.539714 -291.331035) (xy 404.587933 -291.321191) (xy 404.637108 -291.31921) (xy 404.685963 -291.325142)
			(xy 404.733234 -291.338834) (xy 404.777696 -291.359932) (xy 404.818199 -291.387888) (xy 404.853692 -291.42198)
			(xy 404.883257 -291.461324) (xy 404.906128 -291.504901) (xy 404.921712 -291.551582) (xy 404.929607 -291.600159)
			(xy 404.930102 -291.624766) (xy 405.269204 -291.624766) (xy 405.273164 -291.575712) (xy 405.284941 -291.527928)
			(xy 405.304232 -291.482652) (xy 405.330535 -291.441056) (xy 405.36317 -291.404219) (xy 405.401291 -291.373094)
			(xy 405.443912 -291.348487) (xy 405.489928 -291.331035) (xy 405.538147 -291.321191) (xy 405.587322 -291.31921)
			(xy 405.636177 -291.325142) (xy 405.683448 -291.338834) (xy 405.72791 -291.359932) (xy 405.768413 -291.387888)
			(xy 405.803906 -291.42198) (xy 405.833471 -291.461324) (xy 405.856342 -291.504901) (xy 405.871926 -291.551582)
			(xy 405.879821 -291.600159) (xy 405.880316 -291.624766) (xy 406.219164 -291.624766) (xy 406.223124 -291.575712)
			(xy 406.234901 -291.527928) (xy 406.254192 -291.482652) (xy 406.280495 -291.441056) (xy 406.31313 -291.404219)
			(xy 406.351251 -291.373094) (xy 406.393872 -291.348487) (xy 406.439888 -291.331035) (xy 406.488107 -291.321191)
			(xy 406.537282 -291.31921) (xy 406.586137 -291.325142) (xy 406.633408 -291.338834) (xy 406.67787 -291.359932)
			(xy 406.718373 -291.387888) (xy 406.753866 -291.42198) (xy 406.783431 -291.461324) (xy 406.806302 -291.504901)
			(xy 406.821886 -291.551582) (xy 406.829781 -291.600159) (xy 406.830276 -291.624766) (xy 408.119084 -291.624766)
			(xy 408.123044 -291.575712) (xy 408.134821 -291.527928) (xy 408.154112 -291.482652) (xy 408.180415 -291.441056)
			(xy 408.21305 -291.404219) (xy 408.251171 -291.373094) (xy 408.293792 -291.348487) (xy 408.339808 -291.331035)
			(xy 408.388027 -291.321191) (xy 408.437202 -291.31921) (xy 408.486057 -291.325142) (xy 408.533328 -291.338834)
			(xy 408.57779 -291.359932) (xy 408.618293 -291.387888) (xy 408.653786 -291.42198) (xy 408.683351 -291.461324)
			(xy 408.706222 -291.504901) (xy 408.721806 -291.551582) (xy 408.729701 -291.600159) (xy 408.730196 -291.624766)
			(xy 409.069044 -291.624766) (xy 409.073004 -291.575712) (xy 409.084781 -291.527928) (xy 409.104072 -291.482652)
			(xy 409.130375 -291.441056) (xy 409.16301 -291.404219) (xy 409.201131 -291.373094) (xy 409.243752 -291.348487)
			(xy 409.289768 -291.331035) (xy 409.337987 -291.321191) (xy 409.387162 -291.31921) (xy 409.436017 -291.325142)
			(xy 409.483288 -291.338834) (xy 409.52775 -291.359932) (xy 409.568253 -291.387888) (xy 409.603746 -291.42198)
			(xy 409.633311 -291.461324) (xy 409.656182 -291.504901) (xy 409.671766 -291.551582) (xy 409.679661 -291.600159)
			(xy 409.680156 -291.624766) (xy 410.019004 -291.624766) (xy 410.022964 -291.575712) (xy 410.034741 -291.527928)
			(xy 410.054032 -291.482652) (xy 410.080335 -291.441056) (xy 410.11297 -291.404219) (xy 410.151091 -291.373094)
			(xy 410.193712 -291.348487) (xy 410.239728 -291.331035) (xy 410.287947 -291.321191) (xy 410.337122 -291.31921)
			(xy 410.385977 -291.325142) (xy 410.433248 -291.338834) (xy 410.47771 -291.359932) (xy 410.518213 -291.387888)
			(xy 410.553706 -291.42198) (xy 410.583271 -291.461324) (xy 410.606142 -291.504901) (xy 410.621726 -291.551582)
			(xy 410.629621 -291.600159) (xy 410.630116 -291.624766) (xy 410.969218 -291.624766) (xy 410.973178 -291.575712)
			(xy 410.984955 -291.527928) (xy 411.004246 -291.482652) (xy 411.030549 -291.441056) (xy 411.063184 -291.404219)
			(xy 411.101305 -291.373094) (xy 411.143926 -291.348487) (xy 411.189942 -291.331035) (xy 411.238161 -291.321191)
			(xy 411.287336 -291.31921) (xy 411.336191 -291.325142) (xy 411.383462 -291.338834) (xy 411.427924 -291.359932)
			(xy 411.468427 -291.387888) (xy 411.50392 -291.42198) (xy 411.533485 -291.461324) (xy 411.556356 -291.504901)
			(xy 411.57194 -291.551582) (xy 411.579835 -291.600159) (xy 411.58033 -291.624766) (xy 411.919178 -291.624766)
			(xy 411.923138 -291.575712) (xy 411.934915 -291.527928) (xy 411.954206 -291.482652) (xy 411.980509 -291.441056)
			(xy 412.013144 -291.404219) (xy 412.051265 -291.373094) (xy 412.093886 -291.348487) (xy 412.139902 -291.331035)
			(xy 412.188121 -291.321191) (xy 412.237296 -291.31921) (xy 412.286151 -291.325142) (xy 412.333422 -291.338834)
			(xy 412.377884 -291.359932) (xy 412.418387 -291.387888) (xy 412.45388 -291.42198) (xy 412.483445 -291.461324)
			(xy 412.506316 -291.504901) (xy 412.5219 -291.551582) (xy 412.529795 -291.600159) (xy 412.53029 -291.624766)
			(xy 412.869138 -291.624766) (xy 412.873098 -291.575712) (xy 412.884875 -291.527928) (xy 412.904166 -291.482652)
			(xy 412.930469 -291.441056) (xy 412.963104 -291.404219) (xy 413.001225 -291.373094) (xy 413.043846 -291.348487)
			(xy 413.089862 -291.331035) (xy 413.138081 -291.321191) (xy 413.187256 -291.31921) (xy 413.236111 -291.325142)
			(xy 413.283382 -291.338834) (xy 413.327844 -291.359932) (xy 413.368347 -291.387888) (xy 413.40384 -291.42198)
			(xy 413.433405 -291.461324) (xy 413.456276 -291.504901) (xy 413.47186 -291.551582) (xy 413.479755 -291.600159)
			(xy 413.48025 -291.624766) (xy 413.819098 -291.624766) (xy 413.823058 -291.575712) (xy 413.834835 -291.527928)
			(xy 413.854126 -291.482652) (xy 413.880429 -291.441056) (xy 413.913064 -291.404219) (xy 413.951185 -291.373094)
			(xy 413.993806 -291.348487) (xy 414.039822 -291.331035) (xy 414.088041 -291.321191) (xy 414.137216 -291.31921)
			(xy 414.186071 -291.325142) (xy 414.233342 -291.338834) (xy 414.277804 -291.359932) (xy 414.318307 -291.387888)
			(xy 414.3538 -291.42198) (xy 414.383365 -291.461324) (xy 414.406236 -291.504901) (xy 414.42182 -291.551582)
			(xy 414.429715 -291.600159) (xy 414.43021 -291.624766) (xy 414.769058 -291.624766) (xy 414.773018 -291.575712)
			(xy 414.784795 -291.527928) (xy 414.804086 -291.482652) (xy 414.830389 -291.441056) (xy 414.863024 -291.404219)
			(xy 414.901145 -291.373094) (xy 414.943766 -291.348487) (xy 414.989782 -291.331035) (xy 415.038001 -291.321191)
			(xy 415.087176 -291.31921) (xy 415.136031 -291.325142) (xy 415.183302 -291.338834) (xy 415.227764 -291.359932)
			(xy 415.268267 -291.387888) (xy 415.30376 -291.42198) (xy 415.333325 -291.461324) (xy 415.356196 -291.504901)
			(xy 415.37178 -291.551582) (xy 415.379675 -291.600159) (xy 415.38017 -291.624766) (xy 415.719018 -291.624766)
			(xy 415.722978 -291.575712) (xy 415.734755 -291.527928) (xy 415.754046 -291.482652) (xy 415.780349 -291.441056)
			(xy 415.812984 -291.404219) (xy 415.851105 -291.373094) (xy 415.893726 -291.348487) (xy 415.939742 -291.331035)
			(xy 415.987961 -291.321191) (xy 416.037136 -291.31921) (xy 416.085991 -291.325142) (xy 416.133262 -291.338834)
			(xy 416.177724 -291.359932) (xy 416.218227 -291.387888) (xy 416.25372 -291.42198) (xy 416.283285 -291.461324)
			(xy 416.306156 -291.504901) (xy 416.32174 -291.551582) (xy 416.329635 -291.600159) (xy 416.33013 -291.624766)
			(xy 416.668978 -291.624766) (xy 416.672938 -291.575712) (xy 416.684715 -291.527928) (xy 416.704006 -291.482652)
			(xy 416.730309 -291.441056) (xy 416.762944 -291.404219) (xy 416.801065 -291.373094) (xy 416.843686 -291.348487)
			(xy 416.889702 -291.331035) (xy 416.937921 -291.321191) (xy 416.987096 -291.31921) (xy 417.035951 -291.325142)
			(xy 417.083222 -291.338834) (xy 417.127684 -291.359932) (xy 417.168187 -291.387888) (xy 417.20368 -291.42198)
			(xy 417.233245 -291.461324) (xy 417.256116 -291.504901) (xy 417.2717 -291.551582) (xy 417.279595 -291.600159)
			(xy 417.28009 -291.624766) (xy 417.279595 -291.649373) (xy 417.2717 -291.69795) (xy 417.256116 -291.744631)
			(xy 417.233245 -291.788208) (xy 417.20368 -291.827552) (xy 417.168187 -291.861644) (xy 417.127684 -291.8896)
			(xy 417.083222 -291.910698) (xy 417.035951 -291.92439) (xy 416.987096 -291.930322) (xy 416.937921 -291.928341)
			(xy 416.889702 -291.918497) (xy 416.843686 -291.901045) (xy 416.801065 -291.876438) (xy 416.762944 -291.845313)
			(xy 416.730309 -291.808476) (xy 416.704006 -291.76688) (xy 416.684715 -291.721604) (xy 416.672938 -291.67382)
			(xy 416.668978 -291.624766) (xy 416.33013 -291.624766) (xy 416.329635 -291.649373) (xy 416.32174 -291.69795)
			(xy 416.306156 -291.744631) (xy 416.283285 -291.788208) (xy 416.25372 -291.827552) (xy 416.218227 -291.861644)
			(xy 416.177724 -291.8896) (xy 416.133262 -291.910698) (xy 416.085991 -291.92439) (xy 416.037136 -291.930322)
			(xy 415.987961 -291.928341) (xy 415.939742 -291.918497) (xy 415.893726 -291.901045) (xy 415.851105 -291.876438)
			(xy 415.812984 -291.845313) (xy 415.780349 -291.808476) (xy 415.754046 -291.76688) (xy 415.734755 -291.721604)
			(xy 415.722978 -291.67382) (xy 415.719018 -291.624766) (xy 415.38017 -291.624766) (xy 415.379675 -291.649373)
			(xy 415.37178 -291.69795) (xy 415.356196 -291.744631) (xy 415.333325 -291.788208) (xy 415.30376 -291.827552)
			(xy 415.268267 -291.861644) (xy 415.227764 -291.8896) (xy 415.183302 -291.910698) (xy 415.136031 -291.92439)
			(xy 415.087176 -291.930322) (xy 415.038001 -291.928341) (xy 414.989782 -291.918497) (xy 414.943766 -291.901045)
			(xy 414.901145 -291.876438) (xy 414.863024 -291.845313) (xy 414.830389 -291.808476) (xy 414.804086 -291.76688)
			(xy 414.784795 -291.721604) (xy 414.773018 -291.67382) (xy 414.769058 -291.624766) (xy 414.43021 -291.624766)
			(xy 414.429715 -291.649373) (xy 414.42182 -291.69795) (xy 414.406236 -291.744631) (xy 414.383365 -291.788208)
			(xy 414.3538 -291.827552) (xy 414.318307 -291.861644) (xy 414.277804 -291.8896) (xy 414.233342 -291.910698)
			(xy 414.186071 -291.92439) (xy 414.137216 -291.930322) (xy 414.088041 -291.928341) (xy 414.039822 -291.918497)
			(xy 413.993806 -291.901045) (xy 413.951185 -291.876438) (xy 413.913064 -291.845313) (xy 413.880429 -291.808476)
			(xy 413.854126 -291.76688) (xy 413.834835 -291.721604) (xy 413.823058 -291.67382) (xy 413.819098 -291.624766)
			(xy 413.48025 -291.624766) (xy 413.479755 -291.649373) (xy 413.47186 -291.69795) (xy 413.456276 -291.744631)
			(xy 413.433405 -291.788208) (xy 413.40384 -291.827552) (xy 413.368347 -291.861644) (xy 413.327844 -291.8896)
			(xy 413.283382 -291.910698) (xy 413.236111 -291.92439) (xy 413.187256 -291.930322) (xy 413.138081 -291.928341)
			(xy 413.089862 -291.918497) (xy 413.043846 -291.901045) (xy 413.001225 -291.876438) (xy 412.963104 -291.845313)
			(xy 412.930469 -291.808476) (xy 412.904166 -291.76688) (xy 412.884875 -291.721604) (xy 412.873098 -291.67382)
			(xy 412.869138 -291.624766) (xy 412.53029 -291.624766) (xy 412.529795 -291.649373) (xy 412.5219 -291.69795)
			(xy 412.506316 -291.744631) (xy 412.483445 -291.788208) (xy 412.45388 -291.827552) (xy 412.418387 -291.861644)
			(xy 412.377884 -291.8896) (xy 412.333422 -291.910698) (xy 412.286151 -291.92439) (xy 412.237296 -291.930322)
			(xy 412.188121 -291.928341) (xy 412.139902 -291.918497) (xy 412.093886 -291.901045) (xy 412.051265 -291.876438)
			(xy 412.013144 -291.845313) (xy 411.980509 -291.808476) (xy 411.954206 -291.76688) (xy 411.934915 -291.721604)
			(xy 411.923138 -291.67382) (xy 411.919178 -291.624766) (xy 411.58033 -291.624766) (xy 411.579835 -291.649373)
			(xy 411.57194 -291.69795) (xy 411.556356 -291.744631) (xy 411.533485 -291.788208) (xy 411.50392 -291.827552)
			(xy 411.468427 -291.861644) (xy 411.427924 -291.8896) (xy 411.383462 -291.910698) (xy 411.336191 -291.92439)
			(xy 411.287336 -291.930322) (xy 411.238161 -291.928341) (xy 411.189942 -291.918497) (xy 411.143926 -291.901045)
			(xy 411.101305 -291.876438) (xy 411.063184 -291.845313) (xy 411.030549 -291.808476) (xy 411.004246 -291.76688)
			(xy 410.984955 -291.721604) (xy 410.973178 -291.67382) (xy 410.969218 -291.624766) (xy 410.630116 -291.624766)
			(xy 410.629621 -291.649373) (xy 410.621726 -291.69795) (xy 410.606142 -291.744631) (xy 410.583271 -291.788208)
			(xy 410.553706 -291.827552) (xy 410.518213 -291.861644) (xy 410.47771 -291.8896) (xy 410.433248 -291.910698)
			(xy 410.385977 -291.92439) (xy 410.337122 -291.930322) (xy 410.287947 -291.928341) (xy 410.239728 -291.918497)
			(xy 410.193712 -291.901045) (xy 410.151091 -291.876438) (xy 410.11297 -291.845313) (xy 410.080335 -291.808476)
			(xy 410.054032 -291.76688) (xy 410.034741 -291.721604) (xy 410.022964 -291.67382) (xy 410.019004 -291.624766)
			(xy 409.680156 -291.624766) (xy 409.679661 -291.649373) (xy 409.671766 -291.69795) (xy 409.656182 -291.744631)
			(xy 409.633311 -291.788208) (xy 409.603746 -291.827552) (xy 409.568253 -291.861644) (xy 409.52775 -291.8896)
			(xy 409.483288 -291.910698) (xy 409.436017 -291.92439) (xy 409.387162 -291.930322) (xy 409.337987 -291.928341)
			(xy 409.289768 -291.918497) (xy 409.243752 -291.901045) (xy 409.201131 -291.876438) (xy 409.16301 -291.845313)
			(xy 409.130375 -291.808476) (xy 409.104072 -291.76688) (xy 409.084781 -291.721604) (xy 409.073004 -291.67382)
			(xy 409.069044 -291.624766) (xy 408.730196 -291.624766) (xy 408.729701 -291.649373) (xy 408.721806 -291.69795)
			(xy 408.706222 -291.744631) (xy 408.683351 -291.788208) (xy 408.653786 -291.827552) (xy 408.618293 -291.861644)
			(xy 408.57779 -291.8896) (xy 408.533328 -291.910698) (xy 408.486057 -291.92439) (xy 408.437202 -291.930322)
			(xy 408.388027 -291.928341) (xy 408.339808 -291.918497) (xy 408.293792 -291.901045) (xy 408.251171 -291.876438)
			(xy 408.21305 -291.845313) (xy 408.180415 -291.808476) (xy 408.154112 -291.76688) (xy 408.134821 -291.721604)
			(xy 408.123044 -291.67382) (xy 408.119084 -291.624766) (xy 406.830276 -291.624766) (xy 406.829781 -291.649373)
			(xy 406.821886 -291.69795) (xy 406.806302 -291.744631) (xy 406.783431 -291.788208) (xy 406.753866 -291.827552)
			(xy 406.718373 -291.861644) (xy 406.67787 -291.8896) (xy 406.633408 -291.910698) (xy 406.586137 -291.92439)
			(xy 406.537282 -291.930322) (xy 406.488107 -291.928341) (xy 406.439888 -291.918497) (xy 406.393872 -291.901045)
			(xy 406.351251 -291.876438) (xy 406.31313 -291.845313) (xy 406.280495 -291.808476) (xy 406.254192 -291.76688)
			(xy 406.234901 -291.721604) (xy 406.223124 -291.67382) (xy 406.219164 -291.624766) (xy 405.880316 -291.624766)
			(xy 405.879821 -291.649373) (xy 405.871926 -291.69795) (xy 405.856342 -291.744631) (xy 405.833471 -291.788208)
			(xy 405.803906 -291.827552) (xy 405.768413 -291.861644) (xy 405.72791 -291.8896) (xy 405.683448 -291.910698)
			(xy 405.636177 -291.92439) (xy 405.587322 -291.930322) (xy 405.538147 -291.928341) (xy 405.489928 -291.918497)
			(xy 405.443912 -291.901045) (xy 405.401291 -291.876438) (xy 405.36317 -291.845313) (xy 405.330535 -291.808476)
			(xy 405.304232 -291.76688) (xy 405.284941 -291.721604) (xy 405.273164 -291.67382) (xy 405.269204 -291.624766)
			(xy 404.930102 -291.624766) (xy 404.929607 -291.649373) (xy 404.921712 -291.69795) (xy 404.906128 -291.744631)
			(xy 404.883257 -291.788208) (xy 404.853692 -291.827552) (xy 404.818199 -291.861644) (xy 404.777696 -291.8896)
			(xy 404.733234 -291.910698) (xy 404.685963 -291.92439) (xy 404.637108 -291.930322) (xy 404.587933 -291.928341)
			(xy 404.539714 -291.918497) (xy 404.493698 -291.901045) (xy 404.451077 -291.876438) (xy 404.412956 -291.845313)
			(xy 404.380321 -291.808476) (xy 404.354018 -291.76688) (xy 404.334727 -291.721604) (xy 404.32295 -291.67382)
			(xy 404.31899 -291.624766) (xy 403.980142 -291.624766) (xy 403.979647 -291.649373) (xy 403.971752 -291.69795)
			(xy 403.956168 -291.744631) (xy 403.933297 -291.788208) (xy 403.903732 -291.827552) (xy 403.868239 -291.861644)
			(xy 403.827736 -291.8896) (xy 403.783274 -291.910698) (xy 403.736003 -291.92439) (xy 403.687148 -291.930322)
			(xy 403.637973 -291.928341) (xy 403.589754 -291.918497) (xy 403.543738 -291.901045) (xy 403.501117 -291.876438)
			(xy 403.462996 -291.845313) (xy 403.430361 -291.808476) (xy 403.404058 -291.76688) (xy 403.384767 -291.721604)
			(xy 403.37299 -291.67382) (xy 403.36903 -291.624766) (xy 403.030182 -291.624766) (xy 403.029687 -291.649373)
			(xy 403.021792 -291.69795) (xy 403.006208 -291.744631) (xy 402.983337 -291.788208) (xy 402.953772 -291.827552)
			(xy 402.918279 -291.861644) (xy 402.877776 -291.8896) (xy 402.833314 -291.910698) (xy 402.786043 -291.92439)
			(xy 402.737188 -291.930322) (xy 402.688013 -291.928341) (xy 402.639794 -291.918497) (xy 402.593778 -291.901045)
			(xy 402.551157 -291.876438) (xy 402.513036 -291.845313) (xy 402.480401 -291.808476) (xy 402.454098 -291.76688)
			(xy 402.434807 -291.721604) (xy 402.42303 -291.67382) (xy 402.41907 -291.624766) (xy 402.080222 -291.624766)
			(xy 402.079727 -291.649373) (xy 402.071832 -291.69795) (xy 402.056248 -291.744631) (xy 402.033377 -291.788208)
			(xy 402.003812 -291.827552) (xy 401.968319 -291.861644) (xy 401.927816 -291.8896) (xy 401.883354 -291.910698)
			(xy 401.836083 -291.92439) (xy 401.787228 -291.930322) (xy 401.738053 -291.928341) (xy 401.689834 -291.918497)
			(xy 401.643818 -291.901045) (xy 401.601197 -291.876438) (xy 401.563076 -291.845313) (xy 401.530441 -291.808476)
			(xy 401.504138 -291.76688) (xy 401.484847 -291.721604) (xy 401.47307 -291.67382) (xy 401.46911 -291.624766)
			(xy 401.130262 -291.624766) (xy 401.129767 -291.649373) (xy 401.121872 -291.69795) (xy 401.106288 -291.744631)
			(xy 401.083417 -291.788208) (xy 401.053852 -291.827552) (xy 401.018359 -291.861644) (xy 400.977856 -291.8896)
			(xy 400.933394 -291.910698) (xy 400.886123 -291.92439) (xy 400.837268 -291.930322) (xy 400.788093 -291.928341)
			(xy 400.739874 -291.918497) (xy 400.693858 -291.901045) (xy 400.651237 -291.876438) (xy 400.613116 -291.845313)
			(xy 400.580481 -291.808476) (xy 400.554178 -291.76688) (xy 400.534887 -291.721604) (xy 400.52311 -291.67382)
			(xy 400.51915 -291.624766) (xy 400.180302 -291.624766) (xy 400.179807 -291.649373) (xy 400.171912 -291.69795)
			(xy 400.156328 -291.744631) (xy 400.133457 -291.788208) (xy 400.103892 -291.827552) (xy 400.068399 -291.861644)
			(xy 400.027896 -291.8896) (xy 399.983434 -291.910698) (xy 399.936163 -291.92439) (xy 399.887308 -291.930322)
			(xy 399.838133 -291.928341) (xy 399.789914 -291.918497) (xy 399.743898 -291.901045) (xy 399.701277 -291.876438)
			(xy 399.663156 -291.845313) (xy 399.630521 -291.808476) (xy 399.604218 -291.76688) (xy 399.584927 -291.721604)
			(xy 399.57315 -291.67382) (xy 399.56919 -291.624766) (xy 399.230342 -291.624766) (xy 399.229847 -291.649373)
			(xy 399.221952 -291.69795) (xy 399.206368 -291.744631) (xy 399.183497 -291.788208) (xy 399.153932 -291.827552)
			(xy 399.118439 -291.861644) (xy 399.077936 -291.8896) (xy 399.033474 -291.910698) (xy 398.986203 -291.92439)
			(xy 398.937348 -291.930322) (xy 398.888173 -291.928341) (xy 398.839954 -291.918497) (xy 398.793938 -291.901045)
			(xy 398.751317 -291.876438) (xy 398.713196 -291.845313) (xy 398.680561 -291.808476) (xy 398.654258 -291.76688)
			(xy 398.634967 -291.721604) (xy 398.62319 -291.67382) (xy 398.61923 -291.624766) (xy 398.280128 -291.624766)
			(xy 398.279633 -291.649373) (xy 398.271738 -291.69795) (xy 398.256154 -291.744631) (xy 398.233283 -291.788208)
			(xy 398.203718 -291.827552) (xy 398.168225 -291.861644) (xy 398.127722 -291.8896) (xy 398.08326 -291.910698)
			(xy 398.035989 -291.92439) (xy 397.987134 -291.930322) (xy 397.937959 -291.928341) (xy 397.88974 -291.918497)
			(xy 397.843724 -291.901045) (xy 397.801103 -291.876438) (xy 397.762982 -291.845313) (xy 397.730347 -291.808476)
			(xy 397.704044 -291.76688) (xy 397.684753 -291.721604) (xy 397.672976 -291.67382) (xy 397.669016 -291.624766)
			(xy 397.330723 -291.624766) (xy 397.330726 -291.6248) (xy 397.326554 -291.675141) (xy 397.314153 -291.72411)
			(xy 397.29386 -291.770368) (xy 397.266229 -291.812656) (xy 397.232015 -291.849818) (xy 397.19215 -291.880841)
			(xy 397.147722 -291.904879) (xy 397.099943 -291.921276) (xy 397.050117 -291.929585) (xy 397.02486 -291.930074)
			(xy 397.001466 -291.929634) (xy 396.955227 -291.922477) (xy 396.910626 -291.908337) (xy 396.889478 -291.898324)
			(xy 396.889224 -291.898324) (xy 396.879702 -291.894176) (xy 396.858981 -291.89312) (xy 396.849092 -291.896292)
			(xy 396.76959 -291.926264) (xy 396.75435 -291.94125) (xy 396.75308 -291.944044) (xy 396.75308 -291.944552)
			(xy 396.74863 -291.955696) (xy 396.738204 -291.977312) (xy 396.732252 -291.987732) (xy 396.722 -292.004899)
			(xy 396.697657 -292.036622) (xy 396.683738 -292.050978) (xy 396.594838 -292.139878) (xy 396.577583 -292.156572)
			(xy 396.538765 -292.184824) (xy 396.496005 -292.206655) (xy 396.450356 -292.221527) (xy 396.402943 -292.229075)
			(xy 396.378938 -292.22954) (xy 396.274798 -292.22954) (xy 396.264772 -292.229919) (xy 396.246247 -292.237597)
			(xy 396.232073 -292.251782) (xy 396.224411 -292.270313) (xy 396.223998 -292.28034) (xy 396.223998 -292.29304)
			(xy 396.235682 -292.315138) (xy 396.246096 -292.32225) (xy 396.266405 -292.336546) (xy 396.302484 -292.370677)
			(xy 396.332558 -292.410201) (xy 396.355833 -292.454073) (xy 396.371696 -292.501137) (xy 396.379727 -292.550148)
			(xy 396.380203 -292.574726) (xy 396.719056 -292.574726) (xy 396.723016 -292.525672) (xy 396.734793 -292.477888)
			(xy 396.754084 -292.432612) (xy 396.780387 -292.391016) (xy 396.813022 -292.354179) (xy 396.851143 -292.323054)
			(xy 396.893764 -292.298447) (xy 396.93978 -292.280995) (xy 396.987999 -292.271151) (xy 397.037174 -292.26917)
			(xy 397.086029 -292.275102) (xy 397.1333 -292.288794) (xy 397.177762 -292.309892) (xy 397.218265 -292.337848)
			(xy 397.253758 -292.37194) (xy 397.283323 -292.411284) (xy 397.306194 -292.454861) (xy 397.321778 -292.501542)
			(xy 397.329673 -292.550119) (xy 397.330168 -292.574726) (xy 397.669016 -292.574726) (xy 397.672976 -292.525672)
			(xy 397.684753 -292.477888) (xy 397.704044 -292.432612) (xy 397.730347 -292.391016) (xy 397.762982 -292.354179)
			(xy 397.801103 -292.323054) (xy 397.843724 -292.298447) (xy 397.88974 -292.280995) (xy 397.937959 -292.271151)
			(xy 397.987134 -292.26917) (xy 398.035989 -292.275102) (xy 398.08326 -292.288794) (xy 398.127722 -292.309892)
			(xy 398.168225 -292.337848) (xy 398.203718 -292.37194) (xy 398.233283 -292.411284) (xy 398.256154 -292.454861)
			(xy 398.271738 -292.501542) (xy 398.279633 -292.550119) (xy 398.280128 -292.574726) (xy 416.668978 -292.574726)
			(xy 416.672938 -292.525672) (xy 416.684715 -292.477888) (xy 416.704006 -292.432612) (xy 416.730309 -292.391016)
			(xy 416.762944 -292.354179) (xy 416.801065 -292.323054) (xy 416.843686 -292.298447) (xy 416.889702 -292.280995)
			(xy 416.937921 -292.271151) (xy 416.987096 -292.26917) (xy 417.035951 -292.275102) (xy 417.083222 -292.288794)
			(xy 417.127684 -292.309892) (xy 417.168187 -292.337848) (xy 417.20368 -292.37194) (xy 417.233245 -292.411284)
			(xy 417.256116 -292.454861) (xy 417.2717 -292.501542) (xy 417.279595 -292.550119) (xy 417.28009 -292.574726)
			(xy 417.279595 -292.599333) (xy 417.2717 -292.64791) (xy 417.256116 -292.694591) (xy 417.233245 -292.738168)
			(xy 417.20368 -292.777512) (xy 417.168187 -292.811604) (xy 417.127684 -292.83956) (xy 417.083222 -292.860658)
			(xy 417.035951 -292.87435) (xy 416.987096 -292.880282) (xy 416.937921 -292.878301) (xy 416.889702 -292.868457)
			(xy 416.843686 -292.851005) (xy 416.801065 -292.826398) (xy 416.762944 -292.795273) (xy 416.730309 -292.758436)
			(xy 416.704006 -292.71684) (xy 416.684715 -292.671564) (xy 416.672938 -292.62378) (xy 416.668978 -292.574726)
			(xy 398.280128 -292.574726) (xy 398.279633 -292.599333) (xy 398.271738 -292.64791) (xy 398.256154 -292.694591)
			(xy 398.233283 -292.738168) (xy 398.203718 -292.777512) (xy 398.168225 -292.811604) (xy 398.127722 -292.83956)
			(xy 398.08326 -292.860658) (xy 398.035989 -292.87435) (xy 397.987134 -292.880282) (xy 397.937959 -292.878301)
			(xy 397.88974 -292.868457) (xy 397.843724 -292.851005) (xy 397.801103 -292.826398) (xy 397.762982 -292.795273)
			(xy 397.730347 -292.758436) (xy 397.704044 -292.71684) (xy 397.684753 -292.671564) (xy 397.672976 -292.62378)
			(xy 397.669016 -292.574726) (xy 397.330168 -292.574726) (xy 397.329673 -292.599333) (xy 397.321778 -292.64791)
			(xy 397.306194 -292.694591) (xy 397.283323 -292.738168) (xy 397.253758 -292.777512) (xy 397.218265 -292.811604)
			(xy 397.177762 -292.83956) (xy 397.1333 -292.860658) (xy 397.086029 -292.87435) (xy 397.037174 -292.880282)
			(xy 396.987999 -292.878301) (xy 396.93978 -292.868457) (xy 396.893764 -292.851005) (xy 396.851143 -292.826398)
			(xy 396.813022 -292.795273) (xy 396.780387 -292.758436) (xy 396.754084 -292.71684) (xy 396.734793 -292.671564)
			(xy 396.723016 -292.62378) (xy 396.719056 -292.574726) (xy 396.380203 -292.574726) (xy 396.380208 -292.57498)
			(xy 396.379743 -292.598973) (xy 396.37224 -292.646367) (xy 396.357414 -292.692005) (xy 396.335631 -292.734761)
			(xy 396.307428 -292.773583) (xy 396.273498 -292.807515) (xy 396.234678 -292.83572) (xy 396.191923 -292.857506)
			(xy 396.146287 -292.872335) (xy 396.098893 -292.879842) (xy 396.0749 -292.880288) (xy 396.053383 -292.879915)
			(xy 396.010775 -292.873865) (xy 395.969445 -292.861873) (xy 395.949678 -292.853364) (xy 395.941855 -292.850183)
			(xy 395.925037 -292.848728) (xy 395.908661 -292.852829) (xy 395.901418 -292.857174) (xy 395.82979 -292.903402)
			(xy 395.819479 -292.910913) (xy 395.807365 -292.933333) (xy 395.806676 -292.946074) (xy 395.806676 -293.153846)
			(xy 395.806949 -293.162309) (xy 395.812435 -293.17832) (xy 395.822857 -293.191656) (xy 395.82979 -293.196518)
			(xy 395.91234 -293.249858) (xy 395.93774 -293.25189) (xy 395.949678 -293.246556) (xy 395.969456 -293.238079)
			(xy 396.010786 -293.226101) (xy 396.053385 -293.220024) (xy 396.0749 -293.219632) (xy 396.100159 -293.220074)
			(xy 396.149987 -293.228389) (xy 396.197767 -293.244791) (xy 396.242196 -293.268835) (xy 396.282061 -293.299863)
			(xy 396.316275 -293.33703) (xy 396.343906 -293.379321) (xy 396.364198 -293.425584) (xy 396.376599 -293.474555)
			(xy 396.380771 -293.5249) (xy 396.380768 -293.52494) (xy 396.719056 -293.52494) (xy 396.723016 -293.475886)
			(xy 396.734793 -293.428102) (xy 396.754084 -293.382826) (xy 396.780387 -293.34123) (xy 396.813022 -293.304393)
			(xy 396.851143 -293.273268) (xy 396.893764 -293.248661) (xy 396.93978 -293.231209) (xy 396.987999 -293.221365)
			(xy 397.037174 -293.219384) (xy 397.086029 -293.225316) (xy 397.1333 -293.239008) (xy 397.177762 -293.260106)
			(xy 397.218265 -293.288062) (xy 397.253758 -293.322154) (xy 397.283323 -293.361498) (xy 397.306194 -293.405075)
			(xy 397.321778 -293.451756) (xy 397.329673 -293.500333) (xy 397.330168 -293.52494) (xy 397.669016 -293.52494)
			(xy 397.672976 -293.475886) (xy 397.684753 -293.428102) (xy 397.704044 -293.382826) (xy 397.730347 -293.34123)
			(xy 397.762982 -293.304393) (xy 397.801103 -293.273268) (xy 397.843724 -293.248661) (xy 397.88974 -293.231209)
			(xy 397.937959 -293.221365) (xy 397.987134 -293.219384) (xy 398.035989 -293.225316) (xy 398.08326 -293.239008)
			(xy 398.127722 -293.260106) (xy 398.168225 -293.288062) (xy 398.203718 -293.322154) (xy 398.233283 -293.361498)
			(xy 398.256154 -293.405075) (xy 398.271738 -293.451756) (xy 398.279633 -293.500333) (xy 398.280128 -293.52494)
			(xy 398.61923 -293.52494) (xy 398.62319 -293.475886) (xy 398.634967 -293.428102) (xy 398.654258 -293.382826)
			(xy 398.680561 -293.34123) (xy 398.713196 -293.304393) (xy 398.751317 -293.273268) (xy 398.793938 -293.248661)
			(xy 398.839954 -293.231209) (xy 398.888173 -293.221365) (xy 398.937348 -293.219384) (xy 398.986203 -293.225316)
			(xy 399.033474 -293.239008) (xy 399.077936 -293.260106) (xy 399.118439 -293.288062) (xy 399.153932 -293.322154)
			(xy 399.183497 -293.361498) (xy 399.206368 -293.405075) (xy 399.221952 -293.451756) (xy 399.229847 -293.500333)
			(xy 399.230342 -293.52494) (xy 399.56919 -293.52494) (xy 399.57315 -293.475886) (xy 399.584927 -293.428102)
			(xy 399.604218 -293.382826) (xy 399.630521 -293.34123) (xy 399.663156 -293.304393) (xy 399.701277 -293.273268)
			(xy 399.743898 -293.248661) (xy 399.789914 -293.231209) (xy 399.838133 -293.221365) (xy 399.887308 -293.219384)
			(xy 399.936163 -293.225316) (xy 399.983434 -293.239008) (xy 400.027896 -293.260106) (xy 400.068399 -293.288062)
			(xy 400.103892 -293.322154) (xy 400.133457 -293.361498) (xy 400.156328 -293.405075) (xy 400.171912 -293.451756)
			(xy 400.179807 -293.500333) (xy 400.180302 -293.52494) (xy 400.51915 -293.52494) (xy 400.52311 -293.475886)
			(xy 400.534887 -293.428102) (xy 400.554178 -293.382826) (xy 400.580481 -293.34123) (xy 400.613116 -293.304393)
			(xy 400.651237 -293.273268) (xy 400.693858 -293.248661) (xy 400.739874 -293.231209) (xy 400.788093 -293.221365)
			(xy 400.837268 -293.219384) (xy 400.886123 -293.225316) (xy 400.933394 -293.239008) (xy 400.977856 -293.260106)
			(xy 401.018359 -293.288062) (xy 401.053852 -293.322154) (xy 401.083417 -293.361498) (xy 401.106288 -293.405075)
			(xy 401.121872 -293.451756) (xy 401.129767 -293.500333) (xy 401.130262 -293.52494) (xy 401.46911 -293.52494)
			(xy 401.47307 -293.475886) (xy 401.484847 -293.428102) (xy 401.504138 -293.382826) (xy 401.530441 -293.34123)
			(xy 401.563076 -293.304393) (xy 401.601197 -293.273268) (xy 401.643818 -293.248661) (xy 401.689834 -293.231209)
			(xy 401.738053 -293.221365) (xy 401.787228 -293.219384) (xy 401.836083 -293.225316) (xy 401.883354 -293.239008)
			(xy 401.927816 -293.260106) (xy 401.968319 -293.288062) (xy 402.003812 -293.322154) (xy 402.033377 -293.361498)
			(xy 402.056248 -293.405075) (xy 402.071832 -293.451756) (xy 402.079727 -293.500333) (xy 402.080222 -293.52494)
			(xy 402.41907 -293.52494) (xy 402.42303 -293.475886) (xy 402.434807 -293.428102) (xy 402.454098 -293.382826)
			(xy 402.480401 -293.34123) (xy 402.513036 -293.304393) (xy 402.551157 -293.273268) (xy 402.593778 -293.248661)
			(xy 402.639794 -293.231209) (xy 402.688013 -293.221365) (xy 402.737188 -293.219384) (xy 402.786043 -293.225316)
			(xy 402.833314 -293.239008) (xy 402.877776 -293.260106) (xy 402.918279 -293.288062) (xy 402.953772 -293.322154)
			(xy 402.983337 -293.361498) (xy 403.006208 -293.405075) (xy 403.021792 -293.451756) (xy 403.029687 -293.500333)
			(xy 403.030182 -293.52494) (xy 403.36903 -293.52494) (xy 403.37299 -293.475886) (xy 403.384767 -293.428102)
			(xy 403.404058 -293.382826) (xy 403.430361 -293.34123) (xy 403.462996 -293.304393) (xy 403.501117 -293.273268)
			(xy 403.543738 -293.248661) (xy 403.589754 -293.231209) (xy 403.637973 -293.221365) (xy 403.687148 -293.219384)
			(xy 403.736003 -293.225316) (xy 403.783274 -293.239008) (xy 403.827736 -293.260106) (xy 403.868239 -293.288062)
			(xy 403.903732 -293.322154) (xy 403.933297 -293.361498) (xy 403.956168 -293.405075) (xy 403.971752 -293.451756)
			(xy 403.979647 -293.500333) (xy 403.980142 -293.52494) (xy 404.31899 -293.52494) (xy 404.32295 -293.475886)
			(xy 404.334727 -293.428102) (xy 404.354018 -293.382826) (xy 404.380321 -293.34123) (xy 404.412956 -293.304393)
			(xy 404.451077 -293.273268) (xy 404.493698 -293.248661) (xy 404.539714 -293.231209) (xy 404.587933 -293.221365)
			(xy 404.637108 -293.219384) (xy 404.685963 -293.225316) (xy 404.733234 -293.239008) (xy 404.777696 -293.260106)
			(xy 404.818199 -293.288062) (xy 404.853692 -293.322154) (xy 404.883257 -293.361498) (xy 404.906128 -293.405075)
			(xy 404.921712 -293.451756) (xy 404.929607 -293.500333) (xy 404.930102 -293.52494) (xy 405.269204 -293.52494)
			(xy 405.273164 -293.475886) (xy 405.284941 -293.428102) (xy 405.304232 -293.382826) (xy 405.330535 -293.34123)
			(xy 405.36317 -293.304393) (xy 405.401291 -293.273268) (xy 405.443912 -293.248661) (xy 405.489928 -293.231209)
			(xy 405.538147 -293.221365) (xy 405.587322 -293.219384) (xy 405.636177 -293.225316) (xy 405.683448 -293.239008)
			(xy 405.72791 -293.260106) (xy 405.768413 -293.288062) (xy 405.803906 -293.322154) (xy 405.833471 -293.361498)
			(xy 405.856342 -293.405075) (xy 405.871926 -293.451756) (xy 405.879821 -293.500333) (xy 405.880316 -293.52494)
			(xy 406.219164 -293.52494) (xy 406.223124 -293.475886) (xy 406.234901 -293.428102) (xy 406.254192 -293.382826)
			(xy 406.280495 -293.34123) (xy 406.31313 -293.304393) (xy 406.351251 -293.273268) (xy 406.393872 -293.248661)
			(xy 406.439888 -293.231209) (xy 406.488107 -293.221365) (xy 406.537282 -293.219384) (xy 406.586137 -293.225316)
			(xy 406.633408 -293.239008) (xy 406.67787 -293.260106) (xy 406.718373 -293.288062) (xy 406.753866 -293.322154)
			(xy 406.783431 -293.361498) (xy 406.806302 -293.405075) (xy 406.821886 -293.451756) (xy 406.829781 -293.500333)
			(xy 406.830276 -293.52494) (xy 408.119084 -293.52494) (xy 408.123044 -293.475886) (xy 408.134821 -293.428102)
			(xy 408.154112 -293.382826) (xy 408.180415 -293.34123) (xy 408.21305 -293.304393) (xy 408.251171 -293.273268)
			(xy 408.293792 -293.248661) (xy 408.339808 -293.231209) (xy 408.388027 -293.221365) (xy 408.437202 -293.219384)
			(xy 408.486057 -293.225316) (xy 408.533328 -293.239008) (xy 408.57779 -293.260106) (xy 408.618293 -293.288062)
			(xy 408.653786 -293.322154) (xy 408.683351 -293.361498) (xy 408.706222 -293.405075) (xy 408.721806 -293.451756)
			(xy 408.729701 -293.500333) (xy 408.730196 -293.52494) (xy 409.069044 -293.52494) (xy 409.073004 -293.475886)
			(xy 409.084781 -293.428102) (xy 409.104072 -293.382826) (xy 409.130375 -293.34123) (xy 409.16301 -293.304393)
			(xy 409.201131 -293.273268) (xy 409.243752 -293.248661) (xy 409.289768 -293.231209) (xy 409.337987 -293.221365)
			(xy 409.387162 -293.219384) (xy 409.436017 -293.225316) (xy 409.483288 -293.239008) (xy 409.52775 -293.260106)
			(xy 409.568253 -293.288062) (xy 409.603746 -293.322154) (xy 409.633311 -293.361498) (xy 409.656182 -293.405075)
			(xy 409.671766 -293.451756) (xy 409.679661 -293.500333) (xy 409.680156 -293.52494) (xy 410.019004 -293.52494)
			(xy 410.022964 -293.475886) (xy 410.034741 -293.428102) (xy 410.054032 -293.382826) (xy 410.080335 -293.34123)
			(xy 410.11297 -293.304393) (xy 410.151091 -293.273268) (xy 410.193712 -293.248661) (xy 410.239728 -293.231209)
			(xy 410.287947 -293.221365) (xy 410.337122 -293.219384) (xy 410.385977 -293.225316) (xy 410.433248 -293.239008)
			(xy 410.47771 -293.260106) (xy 410.518213 -293.288062) (xy 410.553706 -293.322154) (xy 410.583271 -293.361498)
			(xy 410.606142 -293.405075) (xy 410.621726 -293.451756) (xy 410.629621 -293.500333) (xy 410.630116 -293.52494)
			(xy 410.969218 -293.52494) (xy 410.973178 -293.475886) (xy 410.984955 -293.428102) (xy 411.004246 -293.382826)
			(xy 411.030549 -293.34123) (xy 411.063184 -293.304393) (xy 411.101305 -293.273268) (xy 411.143926 -293.248661)
			(xy 411.189942 -293.231209) (xy 411.238161 -293.221365) (xy 411.287336 -293.219384) (xy 411.336191 -293.225316)
			(xy 411.383462 -293.239008) (xy 411.427924 -293.260106) (xy 411.468427 -293.288062) (xy 411.50392 -293.322154)
			(xy 411.533485 -293.361498) (xy 411.556356 -293.405075) (xy 411.57194 -293.451756) (xy 411.579835 -293.500333)
			(xy 411.58033 -293.52494) (xy 411.919178 -293.52494) (xy 411.923138 -293.475886) (xy 411.934915 -293.428102)
			(xy 411.954206 -293.382826) (xy 411.980509 -293.34123) (xy 412.013144 -293.304393) (xy 412.051265 -293.273268)
			(xy 412.093886 -293.248661) (xy 412.139902 -293.231209) (xy 412.188121 -293.221365) (xy 412.237296 -293.219384)
			(xy 412.286151 -293.225316) (xy 412.333422 -293.239008) (xy 412.377884 -293.260106) (xy 412.418387 -293.288062)
			(xy 412.45388 -293.322154) (xy 412.483445 -293.361498) (xy 412.506316 -293.405075) (xy 412.5219 -293.451756)
			(xy 412.529795 -293.500333) (xy 412.53029 -293.52494) (xy 412.869138 -293.52494) (xy 412.873098 -293.475886)
			(xy 412.884875 -293.428102) (xy 412.904166 -293.382826) (xy 412.930469 -293.34123) (xy 412.963104 -293.304393)
			(xy 413.001225 -293.273268) (xy 413.043846 -293.248661) (xy 413.089862 -293.231209) (xy 413.138081 -293.221365)
			(xy 413.187256 -293.219384) (xy 413.236111 -293.225316) (xy 413.283382 -293.239008) (xy 413.327844 -293.260106)
			(xy 413.368347 -293.288062) (xy 413.40384 -293.322154) (xy 413.433405 -293.361498) (xy 413.456276 -293.405075)
			(xy 413.47186 -293.451756) (xy 413.479755 -293.500333) (xy 413.48025 -293.52494) (xy 413.819098 -293.52494)
			(xy 413.823058 -293.475886) (xy 413.834835 -293.428102) (xy 413.854126 -293.382826) (xy 413.880429 -293.34123)
			(xy 413.913064 -293.304393) (xy 413.951185 -293.273268) (xy 413.993806 -293.248661) (xy 414.039822 -293.231209)
			(xy 414.088041 -293.221365) (xy 414.137216 -293.219384) (xy 414.186071 -293.225316) (xy 414.233342 -293.239008)
			(xy 414.277804 -293.260106) (xy 414.318307 -293.288062) (xy 414.3538 -293.322154) (xy 414.383365 -293.361498)
			(xy 414.406236 -293.405075) (xy 414.42182 -293.451756) (xy 414.429715 -293.500333) (xy 414.43021 -293.52494)
			(xy 414.769058 -293.52494) (xy 414.773018 -293.475886) (xy 414.784795 -293.428102) (xy 414.804086 -293.382826)
			(xy 414.830389 -293.34123) (xy 414.863024 -293.304393) (xy 414.901145 -293.273268) (xy 414.943766 -293.248661)
			(xy 414.989782 -293.231209) (xy 415.038001 -293.221365) (xy 415.087176 -293.219384) (xy 415.136031 -293.225316)
			(xy 415.183302 -293.239008) (xy 415.227764 -293.260106) (xy 415.268267 -293.288062) (xy 415.30376 -293.322154)
			(xy 415.333325 -293.361498) (xy 415.356196 -293.405075) (xy 415.37178 -293.451756) (xy 415.379675 -293.500333)
			(xy 415.38017 -293.52494) (xy 415.719018 -293.52494) (xy 415.722978 -293.475886) (xy 415.734755 -293.428102)
			(xy 415.754046 -293.382826) (xy 415.780349 -293.34123) (xy 415.812984 -293.304393) (xy 415.851105 -293.273268)
			(xy 415.893726 -293.248661) (xy 415.939742 -293.231209) (xy 415.987961 -293.221365) (xy 416.037136 -293.219384)
			(xy 416.085991 -293.225316) (xy 416.133262 -293.239008) (xy 416.177724 -293.260106) (xy 416.218227 -293.288062)
			(xy 416.25372 -293.322154) (xy 416.283285 -293.361498) (xy 416.306156 -293.405075) (xy 416.32174 -293.451756)
			(xy 416.329635 -293.500333) (xy 416.33013 -293.52494) (xy 416.668978 -293.52494) (xy 416.672938 -293.475886)
			(xy 416.684715 -293.428102) (xy 416.704006 -293.382826) (xy 416.730309 -293.34123) (xy 416.762944 -293.304393)
			(xy 416.801065 -293.273268) (xy 416.843686 -293.248661) (xy 416.889702 -293.231209) (xy 416.937921 -293.221365)
			(xy 416.987096 -293.219384) (xy 417.035951 -293.225316) (xy 417.083222 -293.239008) (xy 417.127684 -293.260106)
			(xy 417.168187 -293.288062) (xy 417.20368 -293.322154) (xy 417.233245 -293.361498) (xy 417.256116 -293.405075)
			(xy 417.2717 -293.451756) (xy 417.279595 -293.500333) (xy 417.28009 -293.52494) (xy 417.279595 -293.549547)
			(xy 417.2717 -293.598124) (xy 417.256116 -293.644805) (xy 417.233245 -293.688382) (xy 417.20368 -293.727726)
			(xy 417.168187 -293.761818) (xy 417.127684 -293.789774) (xy 417.083222 -293.810872) (xy 417.035951 -293.824564)
			(xy 416.987096 -293.830496) (xy 416.937921 -293.828515) (xy 416.889702 -293.818671) (xy 416.843686 -293.801219)
			(xy 416.801065 -293.776612) (xy 416.762944 -293.745487) (xy 416.730309 -293.70865) (xy 416.704006 -293.667054)
			(xy 416.684715 -293.621778) (xy 416.672938 -293.573994) (xy 416.668978 -293.52494) (xy 416.33013 -293.52494)
			(xy 416.329635 -293.549547) (xy 416.32174 -293.598124) (xy 416.306156 -293.644805) (xy 416.283285 -293.688382)
			(xy 416.25372 -293.727726) (xy 416.218227 -293.761818) (xy 416.177724 -293.789774) (xy 416.133262 -293.810872)
			(xy 416.085991 -293.824564) (xy 416.037136 -293.830496) (xy 415.987961 -293.828515) (xy 415.939742 -293.818671)
			(xy 415.893726 -293.801219) (xy 415.851105 -293.776612) (xy 415.812984 -293.745487) (xy 415.780349 -293.70865)
			(xy 415.754046 -293.667054) (xy 415.734755 -293.621778) (xy 415.722978 -293.573994) (xy 415.719018 -293.52494)
			(xy 415.38017 -293.52494) (xy 415.379675 -293.549547) (xy 415.37178 -293.598124) (xy 415.356196 -293.644805)
			(xy 415.333325 -293.688382) (xy 415.30376 -293.727726) (xy 415.268267 -293.761818) (xy 415.227764 -293.789774)
			(xy 415.183302 -293.810872) (xy 415.136031 -293.824564) (xy 415.087176 -293.830496) (xy 415.038001 -293.828515)
			(xy 414.989782 -293.818671) (xy 414.943766 -293.801219) (xy 414.901145 -293.776612) (xy 414.863024 -293.745487)
			(xy 414.830389 -293.70865) (xy 414.804086 -293.667054) (xy 414.784795 -293.621778) (xy 414.773018 -293.573994)
			(xy 414.769058 -293.52494) (xy 414.43021 -293.52494) (xy 414.429715 -293.549547) (xy 414.42182 -293.598124)
			(xy 414.406236 -293.644805) (xy 414.383365 -293.688382) (xy 414.3538 -293.727726) (xy 414.318307 -293.761818)
			(xy 414.277804 -293.789774) (xy 414.233342 -293.810872) (xy 414.186071 -293.824564) (xy 414.137216 -293.830496)
			(xy 414.088041 -293.828515) (xy 414.039822 -293.818671) (xy 413.993806 -293.801219) (xy 413.951185 -293.776612)
			(xy 413.913064 -293.745487) (xy 413.880429 -293.70865) (xy 413.854126 -293.667054) (xy 413.834835 -293.621778)
			(xy 413.823058 -293.573994) (xy 413.819098 -293.52494) (xy 413.48025 -293.52494) (xy 413.479755 -293.549547)
			(xy 413.47186 -293.598124) (xy 413.456276 -293.644805) (xy 413.433405 -293.688382) (xy 413.40384 -293.727726)
			(xy 413.368347 -293.761818) (xy 413.327844 -293.789774) (xy 413.283382 -293.810872) (xy 413.236111 -293.824564)
			(xy 413.187256 -293.830496) (xy 413.138081 -293.828515) (xy 413.089862 -293.818671) (xy 413.043846 -293.801219)
			(xy 413.001225 -293.776612) (xy 412.963104 -293.745487) (xy 412.930469 -293.70865) (xy 412.904166 -293.667054)
			(xy 412.884875 -293.621778) (xy 412.873098 -293.573994) (xy 412.869138 -293.52494) (xy 412.53029 -293.52494)
			(xy 412.529795 -293.549547) (xy 412.5219 -293.598124) (xy 412.506316 -293.644805) (xy 412.483445 -293.688382)
			(xy 412.45388 -293.727726) (xy 412.418387 -293.761818) (xy 412.377884 -293.789774) (xy 412.333422 -293.810872)
			(xy 412.286151 -293.824564) (xy 412.237296 -293.830496) (xy 412.188121 -293.828515) (xy 412.139902 -293.818671)
			(xy 412.093886 -293.801219) (xy 412.051265 -293.776612) (xy 412.013144 -293.745487) (xy 411.980509 -293.70865)
			(xy 411.954206 -293.667054) (xy 411.934915 -293.621778) (xy 411.923138 -293.573994) (xy 411.919178 -293.52494)
			(xy 411.58033 -293.52494) (xy 411.579835 -293.549547) (xy 411.57194 -293.598124) (xy 411.556356 -293.644805)
			(xy 411.533485 -293.688382) (xy 411.50392 -293.727726) (xy 411.468427 -293.761818) (xy 411.427924 -293.789774)
			(xy 411.383462 -293.810872) (xy 411.336191 -293.824564) (xy 411.287336 -293.830496) (xy 411.238161 -293.828515)
			(xy 411.189942 -293.818671) (xy 411.143926 -293.801219) (xy 411.101305 -293.776612) (xy 411.063184 -293.745487)
			(xy 411.030549 -293.70865) (xy 411.004246 -293.667054) (xy 410.984955 -293.621778) (xy 410.973178 -293.573994)
			(xy 410.969218 -293.52494) (xy 410.630116 -293.52494) (xy 410.629621 -293.549547) (xy 410.621726 -293.598124)
			(xy 410.606142 -293.644805) (xy 410.583271 -293.688382) (xy 410.553706 -293.727726) (xy 410.518213 -293.761818)
			(xy 410.47771 -293.789774) (xy 410.433248 -293.810872) (xy 410.385977 -293.824564) (xy 410.337122 -293.830496)
			(xy 410.287947 -293.828515) (xy 410.239728 -293.818671) (xy 410.193712 -293.801219) (xy 410.151091 -293.776612)
			(xy 410.11297 -293.745487) (xy 410.080335 -293.70865) (xy 410.054032 -293.667054) (xy 410.034741 -293.621778)
			(xy 410.022964 -293.573994) (xy 410.019004 -293.52494) (xy 409.680156 -293.52494) (xy 409.679661 -293.549547)
			(xy 409.671766 -293.598124) (xy 409.656182 -293.644805) (xy 409.633311 -293.688382) (xy 409.603746 -293.727726)
			(xy 409.568253 -293.761818) (xy 409.52775 -293.789774) (xy 409.483288 -293.810872) (xy 409.436017 -293.824564)
			(xy 409.387162 -293.830496) (xy 409.337987 -293.828515) (xy 409.289768 -293.818671) (xy 409.243752 -293.801219)
			(xy 409.201131 -293.776612) (xy 409.16301 -293.745487) (xy 409.130375 -293.70865) (xy 409.104072 -293.667054)
			(xy 409.084781 -293.621778) (xy 409.073004 -293.573994) (xy 409.069044 -293.52494) (xy 408.730196 -293.52494)
			(xy 408.729701 -293.549547) (xy 408.721806 -293.598124) (xy 408.706222 -293.644805) (xy 408.683351 -293.688382)
			(xy 408.653786 -293.727726) (xy 408.618293 -293.761818) (xy 408.57779 -293.789774) (xy 408.533328 -293.810872)
			(xy 408.486057 -293.824564) (xy 408.437202 -293.830496) (xy 408.388027 -293.828515) (xy 408.339808 -293.818671)
			(xy 408.293792 -293.801219) (xy 408.251171 -293.776612) (xy 408.21305 -293.745487) (xy 408.180415 -293.70865)
			(xy 408.154112 -293.667054) (xy 408.134821 -293.621778) (xy 408.123044 -293.573994) (xy 408.119084 -293.52494)
			(xy 406.830276 -293.52494) (xy 406.829781 -293.549547) (xy 406.821886 -293.598124) (xy 406.806302 -293.644805)
			(xy 406.783431 -293.688382) (xy 406.753866 -293.727726) (xy 406.718373 -293.761818) (xy 406.67787 -293.789774)
			(xy 406.633408 -293.810872) (xy 406.586137 -293.824564) (xy 406.537282 -293.830496) (xy 406.488107 -293.828515)
			(xy 406.439888 -293.818671) (xy 406.393872 -293.801219) (xy 406.351251 -293.776612) (xy 406.31313 -293.745487)
			(xy 406.280495 -293.70865) (xy 406.254192 -293.667054) (xy 406.234901 -293.621778) (xy 406.223124 -293.573994)
			(xy 406.219164 -293.52494) (xy 405.880316 -293.52494) (xy 405.879821 -293.549547) (xy 405.871926 -293.598124)
			(xy 405.856342 -293.644805) (xy 405.833471 -293.688382) (xy 405.803906 -293.727726) (xy 405.768413 -293.761818)
			(xy 405.72791 -293.789774) (xy 405.683448 -293.810872) (xy 405.636177 -293.824564) (xy 405.587322 -293.830496)
			(xy 405.538147 -293.828515) (xy 405.489928 -293.818671) (xy 405.443912 -293.801219) (xy 405.401291 -293.776612)
			(xy 405.36317 -293.745487) (xy 405.330535 -293.70865) (xy 405.304232 -293.667054) (xy 405.284941 -293.621778)
			(xy 405.273164 -293.573994) (xy 405.269204 -293.52494) (xy 404.930102 -293.52494) (xy 404.929607 -293.549547)
			(xy 404.921712 -293.598124) (xy 404.906128 -293.644805) (xy 404.883257 -293.688382) (xy 404.853692 -293.727726)
			(xy 404.818199 -293.761818) (xy 404.777696 -293.789774) (xy 404.733234 -293.810872) (xy 404.685963 -293.824564)
			(xy 404.637108 -293.830496) (xy 404.587933 -293.828515) (xy 404.539714 -293.818671) (xy 404.493698 -293.801219)
			(xy 404.451077 -293.776612) (xy 404.412956 -293.745487) (xy 404.380321 -293.70865) (xy 404.354018 -293.667054)
			(xy 404.334727 -293.621778) (xy 404.32295 -293.573994) (xy 404.31899 -293.52494) (xy 403.980142 -293.52494)
			(xy 403.979647 -293.549547) (xy 403.971752 -293.598124) (xy 403.956168 -293.644805) (xy 403.933297 -293.688382)
			(xy 403.903732 -293.727726) (xy 403.868239 -293.761818) (xy 403.827736 -293.789774) (xy 403.783274 -293.810872)
			(xy 403.736003 -293.824564) (xy 403.687148 -293.830496) (xy 403.637973 -293.828515) (xy 403.589754 -293.818671)
			(xy 403.543738 -293.801219) (xy 403.501117 -293.776612) (xy 403.462996 -293.745487) (xy 403.430361 -293.70865)
			(xy 403.404058 -293.667054) (xy 403.384767 -293.621778) (xy 403.37299 -293.573994) (xy 403.36903 -293.52494)
			(xy 403.030182 -293.52494) (xy 403.029687 -293.549547) (xy 403.021792 -293.598124) (xy 403.006208 -293.644805)
			(xy 402.983337 -293.688382) (xy 402.953772 -293.727726) (xy 402.918279 -293.761818) (xy 402.877776 -293.789774)
			(xy 402.833314 -293.810872) (xy 402.786043 -293.824564) (xy 402.737188 -293.830496) (xy 402.688013 -293.828515)
			(xy 402.639794 -293.818671) (xy 402.593778 -293.801219) (xy 402.551157 -293.776612) (xy 402.513036 -293.745487)
			(xy 402.480401 -293.70865) (xy 402.454098 -293.667054) (xy 402.434807 -293.621778) (xy 402.42303 -293.573994)
			(xy 402.41907 -293.52494) (xy 402.080222 -293.52494) (xy 402.079727 -293.549547) (xy 402.071832 -293.598124)
			(xy 402.056248 -293.644805) (xy 402.033377 -293.688382) (xy 402.003812 -293.727726) (xy 401.968319 -293.761818)
			(xy 401.927816 -293.789774) (xy 401.883354 -293.810872) (xy 401.836083 -293.824564) (xy 401.787228 -293.830496)
			(xy 401.738053 -293.828515) (xy 401.689834 -293.818671) (xy 401.643818 -293.801219) (xy 401.601197 -293.776612)
			(xy 401.563076 -293.745487) (xy 401.530441 -293.70865) (xy 401.504138 -293.667054) (xy 401.484847 -293.621778)
			(xy 401.47307 -293.573994) (xy 401.46911 -293.52494) (xy 401.130262 -293.52494) (xy 401.129767 -293.549547)
			(xy 401.121872 -293.598124) (xy 401.106288 -293.644805) (xy 401.083417 -293.688382) (xy 401.053852 -293.727726)
			(xy 401.018359 -293.761818) (xy 400.977856 -293.789774) (xy 400.933394 -293.810872) (xy 400.886123 -293.824564)
			(xy 400.837268 -293.830496) (xy 400.788093 -293.828515) (xy 400.739874 -293.818671) (xy 400.693858 -293.801219)
			(xy 400.651237 -293.776612) (xy 400.613116 -293.745487) (xy 400.580481 -293.70865) (xy 400.554178 -293.667054)
			(xy 400.534887 -293.621778) (xy 400.52311 -293.573994) (xy 400.51915 -293.52494) (xy 400.180302 -293.52494)
			(xy 400.179807 -293.549547) (xy 400.171912 -293.598124) (xy 400.156328 -293.644805) (xy 400.133457 -293.688382)
			(xy 400.103892 -293.727726) (xy 400.068399 -293.761818) (xy 400.027896 -293.789774) (xy 399.983434 -293.810872)
			(xy 399.936163 -293.824564) (xy 399.887308 -293.830496) (xy 399.838133 -293.828515) (xy 399.789914 -293.818671)
			(xy 399.743898 -293.801219) (xy 399.701277 -293.776612) (xy 399.663156 -293.745487) (xy 399.630521 -293.70865)
			(xy 399.604218 -293.667054) (xy 399.584927 -293.621778) (xy 399.57315 -293.573994) (xy 399.56919 -293.52494)
			(xy 399.230342 -293.52494) (xy 399.229847 -293.549547) (xy 399.221952 -293.598124) (xy 399.206368 -293.644805)
			(xy 399.183497 -293.688382) (xy 399.153932 -293.727726) (xy 399.118439 -293.761818) (xy 399.077936 -293.789774)
			(xy 399.033474 -293.810872) (xy 398.986203 -293.824564) (xy 398.937348 -293.830496) (xy 398.888173 -293.828515)
			(xy 398.839954 -293.818671) (xy 398.793938 -293.801219) (xy 398.751317 -293.776612) (xy 398.713196 -293.745487)
			(xy 398.680561 -293.70865) (xy 398.654258 -293.667054) (xy 398.634967 -293.621778) (xy 398.62319 -293.573994)
			(xy 398.61923 -293.52494) (xy 398.280128 -293.52494) (xy 398.279633 -293.549547) (xy 398.271738 -293.598124)
			(xy 398.256154 -293.644805) (xy 398.233283 -293.688382) (xy 398.203718 -293.727726) (xy 398.168225 -293.761818)
			(xy 398.127722 -293.789774) (xy 398.08326 -293.810872) (xy 398.035989 -293.824564) (xy 397.987134 -293.830496)
			(xy 397.937959 -293.828515) (xy 397.88974 -293.818671) (xy 397.843724 -293.801219) (xy 397.801103 -293.776612)
			(xy 397.762982 -293.745487) (xy 397.730347 -293.70865) (xy 397.704044 -293.667054) (xy 397.684753 -293.621778)
			(xy 397.672976 -293.573994) (xy 397.669016 -293.52494) (xy 397.330168 -293.52494) (xy 397.329673 -293.549547)
			(xy 397.321778 -293.598124) (xy 397.306194 -293.644805) (xy 397.283323 -293.688382) (xy 397.253758 -293.727726)
			(xy 397.218265 -293.761818) (xy 397.177762 -293.789774) (xy 397.1333 -293.810872) (xy 397.086029 -293.824564)
			(xy 397.037174 -293.830496) (xy 396.987999 -293.828515) (xy 396.93978 -293.818671) (xy 396.893764 -293.801219)
			(xy 396.851143 -293.776612) (xy 396.813022 -293.745487) (xy 396.780387 -293.70865) (xy 396.754084 -293.667054)
			(xy 396.734793 -293.621778) (xy 396.723016 -293.573994) (xy 396.719056 -293.52494) (xy 396.380768 -293.52494)
			(xy 396.376599 -293.575245) (xy 396.364198 -293.624216) (xy 396.343906 -293.670479) (xy 396.316275 -293.71277)
			(xy 396.282061 -293.749937) (xy 396.242196 -293.780965) (xy 396.197767 -293.805009) (xy 396.149987 -293.821411)
			(xy 396.100159 -293.829726) (xy 396.0749 -293.830248) (xy 396.050546 -293.829836) (xy 396.002457 -293.822103)
			(xy 395.956205 -293.806833) (xy 395.912965 -293.784413) (xy 395.873832 -293.755413) (xy 395.8398 -293.720567)
			(xy 395.811732 -293.68076) (xy 395.790341 -293.637002) (xy 395.7828 -293.61384) (xy 395.779498 -293.602918)
			(xy 395.764512 -293.586154) (xy 395.670532 -293.547292) (xy 395.647672 -293.548562) (xy 395.637766 -293.553896)
			(xy 395.623034 -293.561262) (xy 395.611858 -293.566596) (xy 395.596872 -293.586154) (xy 395.580362 -293.680388)
			(xy 395.578922 -293.692495) (xy 395.586239 -293.715716) (xy 395.594332 -293.724838) (xy 395.648434 -293.77894)
			(xy 395.665108 -293.796212) (xy 395.693356 -293.835027) (xy 395.715184 -293.877784) (xy 395.730056 -293.923428)
			(xy 395.737605 -293.970837) (xy 395.738096 -293.99484) (xy 395.738096 -294.142922) (xy 395.73851 -294.152223)
			(xy 395.745082 -294.169619) (xy 395.757455 -294.183502) (xy 395.765528 -294.188134) (xy 395.845538 -294.229536)
			(xy 395.853967 -294.233413) (xy 395.872393 -294.235449) (xy 395.890333 -294.230776) (xy 395.898116 -294.225726)
			(xy 395.89837 -294.225726) (xy 395.91783 -294.212478) (xy 395.959978 -294.191505) (xy 396.004842 -294.177242)
			(xy 396.051362 -294.170026) (xy 396.0749 -294.169592) (xy 396.100155 -294.170114) (xy 396.149977 -294.178427)
			(xy 396.197751 -294.194828) (xy 396.242174 -294.218869) (xy 396.282034 -294.249893) (xy 396.316244 -294.287055)
			(xy 396.34387 -294.329341) (xy 396.36416 -294.375597) (xy 396.37656 -294.424562) (xy 396.380731 -294.4749)
			(xy 396.719056 -294.4749) (xy 396.723016 -294.425846) (xy 396.734793 -294.378062) (xy 396.754084 -294.332786)
			(xy 396.780387 -294.29119) (xy 396.813022 -294.254353) (xy 396.851143 -294.223228) (xy 396.893764 -294.198621)
			(xy 396.93978 -294.181169) (xy 396.987999 -294.171325) (xy 397.037174 -294.169344) (xy 397.086029 -294.175276)
			(xy 397.1333 -294.188968) (xy 397.177762 -294.210066) (xy 397.218265 -294.238022) (xy 397.253758 -294.272114)
			(xy 397.283323 -294.311458) (xy 397.306194 -294.355035) (xy 397.321778 -294.401716) (xy 397.329673 -294.450293)
			(xy 397.330168 -294.4749) (xy 397.669016 -294.4749) (xy 397.672976 -294.425846) (xy 397.684753 -294.378062)
			(xy 397.704044 -294.332786) (xy 397.730347 -294.29119) (xy 397.762982 -294.254353) (xy 397.801103 -294.223228)
			(xy 397.843724 -294.198621) (xy 397.88974 -294.181169) (xy 397.937959 -294.171325) (xy 397.987134 -294.169344)
			(xy 398.035989 -294.175276) (xy 398.08326 -294.188968) (xy 398.127722 -294.210066) (xy 398.168225 -294.238022)
			(xy 398.203718 -294.272114) (xy 398.233283 -294.311458) (xy 398.256154 -294.355035) (xy 398.271738 -294.401716)
			(xy 398.279633 -294.450293) (xy 398.280128 -294.4749) (xy 398.61923 -294.4749) (xy 398.62319 -294.425846)
			(xy 398.634967 -294.378062) (xy 398.654258 -294.332786) (xy 398.680561 -294.29119) (xy 398.713196 -294.254353)
			(xy 398.751317 -294.223228) (xy 398.793938 -294.198621) (xy 398.839954 -294.181169) (xy 398.888173 -294.171325)
			(xy 398.937348 -294.169344) (xy 398.986203 -294.175276) (xy 399.033474 -294.188968) (xy 399.077936 -294.210066)
			(xy 399.118439 -294.238022) (xy 399.153932 -294.272114) (xy 399.183497 -294.311458) (xy 399.206368 -294.355035)
			(xy 399.221952 -294.401716) (xy 399.229847 -294.450293) (xy 399.230342 -294.4749) (xy 399.56919 -294.4749)
			(xy 399.57315 -294.425846) (xy 399.584927 -294.378062) (xy 399.604218 -294.332786) (xy 399.630521 -294.29119)
			(xy 399.663156 -294.254353) (xy 399.701277 -294.223228) (xy 399.743898 -294.198621) (xy 399.789914 -294.181169)
			(xy 399.838133 -294.171325) (xy 399.887308 -294.169344) (xy 399.936163 -294.175276) (xy 399.983434 -294.188968)
			(xy 400.027896 -294.210066) (xy 400.068399 -294.238022) (xy 400.103892 -294.272114) (xy 400.133457 -294.311458)
			(xy 400.156328 -294.355035) (xy 400.171912 -294.401716) (xy 400.179807 -294.450293) (xy 400.180302 -294.4749)
			(xy 400.51915 -294.4749) (xy 400.52311 -294.425846) (xy 400.534887 -294.378062) (xy 400.554178 -294.332786)
			(xy 400.580481 -294.29119) (xy 400.613116 -294.254353) (xy 400.651237 -294.223228) (xy 400.693858 -294.198621)
			(xy 400.739874 -294.181169) (xy 400.788093 -294.171325) (xy 400.837268 -294.169344) (xy 400.886123 -294.175276)
			(xy 400.933394 -294.188968) (xy 400.977856 -294.210066) (xy 401.018359 -294.238022) (xy 401.053852 -294.272114)
			(xy 401.083417 -294.311458) (xy 401.106288 -294.355035) (xy 401.121872 -294.401716) (xy 401.129767 -294.450293)
			(xy 401.130262 -294.4749) (xy 401.46911 -294.4749) (xy 401.47307 -294.425846) (xy 401.484847 -294.378062)
			(xy 401.504138 -294.332786) (xy 401.530441 -294.29119) (xy 401.563076 -294.254353) (xy 401.601197 -294.223228)
			(xy 401.643818 -294.198621) (xy 401.689834 -294.181169) (xy 401.738053 -294.171325) (xy 401.787228 -294.169344)
			(xy 401.836083 -294.175276) (xy 401.883354 -294.188968) (xy 401.927816 -294.210066) (xy 401.968319 -294.238022)
			(xy 402.003812 -294.272114) (xy 402.033377 -294.311458) (xy 402.056248 -294.355035) (xy 402.071832 -294.401716)
			(xy 402.079727 -294.450293) (xy 402.080222 -294.4749) (xy 402.41907 -294.4749) (xy 402.42303 -294.425846)
			(xy 402.434807 -294.378062) (xy 402.454098 -294.332786) (xy 402.480401 -294.29119) (xy 402.513036 -294.254353)
			(xy 402.551157 -294.223228) (xy 402.593778 -294.198621) (xy 402.639794 -294.181169) (xy 402.688013 -294.171325)
			(xy 402.737188 -294.169344) (xy 402.786043 -294.175276) (xy 402.833314 -294.188968) (xy 402.877776 -294.210066)
			(xy 402.918279 -294.238022) (xy 402.953772 -294.272114) (xy 402.983337 -294.311458) (xy 403.006208 -294.355035)
			(xy 403.021792 -294.401716) (xy 403.029687 -294.450293) (xy 403.030182 -294.4749) (xy 403.36903 -294.4749)
			(xy 403.37299 -294.425846) (xy 403.384767 -294.378062) (xy 403.404058 -294.332786) (xy 403.430361 -294.29119)
			(xy 403.462996 -294.254353) (xy 403.501117 -294.223228) (xy 403.543738 -294.198621) (xy 403.589754 -294.181169)
			(xy 403.637973 -294.171325) (xy 403.687148 -294.169344) (xy 403.736003 -294.175276) (xy 403.783274 -294.188968)
			(xy 403.827736 -294.210066) (xy 403.868239 -294.238022) (xy 403.903732 -294.272114) (xy 403.933297 -294.311458)
			(xy 403.956168 -294.355035) (xy 403.971752 -294.401716) (xy 403.979647 -294.450293) (xy 403.980142 -294.4749)
			(xy 404.31899 -294.4749) (xy 404.32295 -294.425846) (xy 404.334727 -294.378062) (xy 404.354018 -294.332786)
			(xy 404.380321 -294.29119) (xy 404.412956 -294.254353) (xy 404.451077 -294.223228) (xy 404.493698 -294.198621)
			(xy 404.539714 -294.181169) (xy 404.587933 -294.171325) (xy 404.637108 -294.169344) (xy 404.685963 -294.175276)
			(xy 404.733234 -294.188968) (xy 404.777696 -294.210066) (xy 404.818199 -294.238022) (xy 404.853692 -294.272114)
			(xy 404.883257 -294.311458) (xy 404.906128 -294.355035) (xy 404.921712 -294.401716) (xy 404.929607 -294.450293)
			(xy 404.930102 -294.4749) (xy 405.269204 -294.4749) (xy 405.273164 -294.425846) (xy 405.284941 -294.378062)
			(xy 405.304232 -294.332786) (xy 405.330535 -294.29119) (xy 405.36317 -294.254353) (xy 405.401291 -294.223228)
			(xy 405.443912 -294.198621) (xy 405.489928 -294.181169) (xy 405.538147 -294.171325) (xy 405.587322 -294.169344)
			(xy 405.636177 -294.175276) (xy 405.683448 -294.188968) (xy 405.72791 -294.210066) (xy 405.768413 -294.238022)
			(xy 405.803906 -294.272114) (xy 405.833471 -294.311458) (xy 405.856342 -294.355035) (xy 405.871926 -294.401716)
			(xy 405.879821 -294.450293) (xy 405.880316 -294.4749) (xy 406.219164 -294.4749) (xy 406.223124 -294.425846)
			(xy 406.234901 -294.378062) (xy 406.254192 -294.332786) (xy 406.280495 -294.29119) (xy 406.31313 -294.254353)
			(xy 406.351251 -294.223228) (xy 406.393872 -294.198621) (xy 406.439888 -294.181169) (xy 406.488107 -294.171325)
			(xy 406.537282 -294.169344) (xy 406.586137 -294.175276) (xy 406.633408 -294.188968) (xy 406.67787 -294.210066)
			(xy 406.718373 -294.238022) (xy 406.753866 -294.272114) (xy 406.783431 -294.311458) (xy 406.806302 -294.355035)
			(xy 406.821886 -294.401716) (xy 406.829781 -294.450293) (xy 406.830276 -294.4749) (xy 408.119084 -294.4749)
			(xy 408.123044 -294.425846) (xy 408.134821 -294.378062) (xy 408.154112 -294.332786) (xy 408.180415 -294.29119)
			(xy 408.21305 -294.254353) (xy 408.251171 -294.223228) (xy 408.293792 -294.198621) (xy 408.339808 -294.181169)
			(xy 408.388027 -294.171325) (xy 408.437202 -294.169344) (xy 408.486057 -294.175276) (xy 408.533328 -294.188968)
			(xy 408.57779 -294.210066) (xy 408.618293 -294.238022) (xy 408.653786 -294.272114) (xy 408.683351 -294.311458)
			(xy 408.706222 -294.355035) (xy 408.721806 -294.401716) (xy 408.729701 -294.450293) (xy 408.730196 -294.4749)
			(xy 409.069044 -294.4749) (xy 409.073004 -294.425846) (xy 409.084781 -294.378062) (xy 409.104072 -294.332786)
			(xy 409.130375 -294.29119) (xy 409.16301 -294.254353) (xy 409.201131 -294.223228) (xy 409.243752 -294.198621)
			(xy 409.289768 -294.181169) (xy 409.337987 -294.171325) (xy 409.387162 -294.169344) (xy 409.436017 -294.175276)
			(xy 409.483288 -294.188968) (xy 409.52775 -294.210066) (xy 409.568253 -294.238022) (xy 409.603746 -294.272114)
			(xy 409.633311 -294.311458) (xy 409.656182 -294.355035) (xy 409.671766 -294.401716) (xy 409.679661 -294.450293)
			(xy 409.680156 -294.4749) (xy 410.019004 -294.4749) (xy 410.022964 -294.425846) (xy 410.034741 -294.378062)
			(xy 410.054032 -294.332786) (xy 410.080335 -294.29119) (xy 410.11297 -294.254353) (xy 410.151091 -294.223228)
			(xy 410.193712 -294.198621) (xy 410.239728 -294.181169) (xy 410.287947 -294.171325) (xy 410.337122 -294.169344)
			(xy 410.385977 -294.175276) (xy 410.433248 -294.188968) (xy 410.47771 -294.210066) (xy 410.518213 -294.238022)
			(xy 410.553706 -294.272114) (xy 410.583271 -294.311458) (xy 410.606142 -294.355035) (xy 410.621726 -294.401716)
			(xy 410.629621 -294.450293) (xy 410.630116 -294.4749) (xy 410.969218 -294.4749) (xy 410.973178 -294.425846)
			(xy 410.984955 -294.378062) (xy 411.004246 -294.332786) (xy 411.030549 -294.29119) (xy 411.063184 -294.254353)
			(xy 411.101305 -294.223228) (xy 411.143926 -294.198621) (xy 411.189942 -294.181169) (xy 411.238161 -294.171325)
			(xy 411.287336 -294.169344) (xy 411.336191 -294.175276) (xy 411.383462 -294.188968) (xy 411.427924 -294.210066)
			(xy 411.468427 -294.238022) (xy 411.50392 -294.272114) (xy 411.533485 -294.311458) (xy 411.556356 -294.355035)
			(xy 411.57194 -294.401716) (xy 411.579835 -294.450293) (xy 411.58033 -294.4749) (xy 411.919178 -294.4749)
			(xy 411.923138 -294.425846) (xy 411.934915 -294.378062) (xy 411.954206 -294.332786) (xy 411.980509 -294.29119)
			(xy 412.013144 -294.254353) (xy 412.051265 -294.223228) (xy 412.093886 -294.198621) (xy 412.139902 -294.181169)
			(xy 412.188121 -294.171325) (xy 412.237296 -294.169344) (xy 412.286151 -294.175276) (xy 412.333422 -294.188968)
			(xy 412.377884 -294.210066) (xy 412.418387 -294.238022) (xy 412.45388 -294.272114) (xy 412.483445 -294.311458)
			(xy 412.506316 -294.355035) (xy 412.5219 -294.401716) (xy 412.529795 -294.450293) (xy 412.53029 -294.4749)
			(xy 412.869138 -294.4749) (xy 412.873098 -294.425846) (xy 412.884875 -294.378062) (xy 412.904166 -294.332786)
			(xy 412.930469 -294.29119) (xy 412.963104 -294.254353) (xy 413.001225 -294.223228) (xy 413.043846 -294.198621)
			(xy 413.089862 -294.181169) (xy 413.138081 -294.171325) (xy 413.187256 -294.169344) (xy 413.236111 -294.175276)
			(xy 413.283382 -294.188968) (xy 413.327844 -294.210066) (xy 413.368347 -294.238022) (xy 413.40384 -294.272114)
			(xy 413.433405 -294.311458) (xy 413.456276 -294.355035) (xy 413.47186 -294.401716) (xy 413.479755 -294.450293)
			(xy 413.48025 -294.4749) (xy 413.819098 -294.4749) (xy 413.823058 -294.425846) (xy 413.834835 -294.378062)
			(xy 413.854126 -294.332786) (xy 413.880429 -294.29119) (xy 413.913064 -294.254353) (xy 413.951185 -294.223228)
			(xy 413.993806 -294.198621) (xy 414.039822 -294.181169) (xy 414.088041 -294.171325) (xy 414.137216 -294.169344)
			(xy 414.186071 -294.175276) (xy 414.233342 -294.188968) (xy 414.277804 -294.210066) (xy 414.318307 -294.238022)
			(xy 414.3538 -294.272114) (xy 414.383365 -294.311458) (xy 414.406236 -294.355035) (xy 414.42182 -294.401716)
			(xy 414.429715 -294.450293) (xy 414.43021 -294.4749) (xy 414.429715 -294.499507) (xy 414.42182 -294.548084)
			(xy 414.406236 -294.594765) (xy 414.383365 -294.638342) (xy 414.3538 -294.677686) (xy 414.318307 -294.711778)
			(xy 414.277804 -294.739734) (xy 414.233342 -294.760832) (xy 414.186071 -294.774524) (xy 414.137216 -294.780456)
			(xy 414.088041 -294.778475) (xy 414.039822 -294.768631) (xy 413.993806 -294.751179) (xy 413.951185 -294.726572)
			(xy 413.913064 -294.695447) (xy 413.880429 -294.65861) (xy 413.854126 -294.617014) (xy 413.834835 -294.571738)
			(xy 413.823058 -294.523954) (xy 413.819098 -294.4749) (xy 413.48025 -294.4749) (xy 413.479755 -294.499507)
			(xy 413.47186 -294.548084) (xy 413.456276 -294.594765) (xy 413.433405 -294.638342) (xy 413.40384 -294.677686)
			(xy 413.368347 -294.711778) (xy 413.327844 -294.739734) (xy 413.283382 -294.760832) (xy 413.236111 -294.774524)
			(xy 413.187256 -294.780456) (xy 413.138081 -294.778475) (xy 413.089862 -294.768631) (xy 413.043846 -294.751179)
			(xy 413.001225 -294.726572) (xy 412.963104 -294.695447) (xy 412.930469 -294.65861) (xy 412.904166 -294.617014)
			(xy 412.884875 -294.571738) (xy 412.873098 -294.523954) (xy 412.869138 -294.4749) (xy 412.53029 -294.4749)
			(xy 412.529795 -294.499507) (xy 412.5219 -294.548084) (xy 412.506316 -294.594765) (xy 412.483445 -294.638342)
			(xy 412.45388 -294.677686) (xy 412.418387 -294.711778) (xy 412.377884 -294.739734) (xy 412.333422 -294.760832)
			(xy 412.286151 -294.774524) (xy 412.237296 -294.780456) (xy 412.188121 -294.778475) (xy 412.139902 -294.768631)
			(xy 412.093886 -294.751179) (xy 412.051265 -294.726572) (xy 412.013144 -294.695447) (xy 411.980509 -294.65861)
			(xy 411.954206 -294.617014) (xy 411.934915 -294.571738) (xy 411.923138 -294.523954) (xy 411.919178 -294.4749)
			(xy 411.58033 -294.4749) (xy 411.579835 -294.499507) (xy 411.57194 -294.548084) (xy 411.556356 -294.594765)
			(xy 411.533485 -294.638342) (xy 411.50392 -294.677686) (xy 411.468427 -294.711778) (xy 411.427924 -294.739734)
			(xy 411.383462 -294.760832) (xy 411.336191 -294.774524) (xy 411.287336 -294.780456) (xy 411.238161 -294.778475)
			(xy 411.189942 -294.768631) (xy 411.143926 -294.751179) (xy 411.101305 -294.726572) (xy 411.063184 -294.695447)
			(xy 411.030549 -294.65861) (xy 411.004246 -294.617014) (xy 410.984955 -294.571738) (xy 410.973178 -294.523954)
			(xy 410.969218 -294.4749) (xy 410.630116 -294.4749) (xy 410.629621 -294.499507) (xy 410.621726 -294.548084)
			(xy 410.606142 -294.594765) (xy 410.583271 -294.638342) (xy 410.553706 -294.677686) (xy 410.518213 -294.711778)
			(xy 410.47771 -294.739734) (xy 410.433248 -294.760832) (xy 410.385977 -294.774524) (xy 410.337122 -294.780456)
			(xy 410.287947 -294.778475) (xy 410.239728 -294.768631) (xy 410.193712 -294.751179) (xy 410.151091 -294.726572)
			(xy 410.11297 -294.695447) (xy 410.080335 -294.65861) (xy 410.054032 -294.617014) (xy 410.034741 -294.571738)
			(xy 410.022964 -294.523954) (xy 410.019004 -294.4749) (xy 409.680156 -294.4749) (xy 409.679661 -294.499507)
			(xy 409.671766 -294.548084) (xy 409.656182 -294.594765) (xy 409.633311 -294.638342) (xy 409.603746 -294.677686)
			(xy 409.568253 -294.711778) (xy 409.52775 -294.739734) (xy 409.483288 -294.760832) (xy 409.436017 -294.774524)
			(xy 409.387162 -294.780456) (xy 409.337987 -294.778475) (xy 409.289768 -294.768631) (xy 409.243752 -294.751179)
			(xy 409.201131 -294.726572) (xy 409.16301 -294.695447) (xy 409.130375 -294.65861) (xy 409.104072 -294.617014)
			(xy 409.084781 -294.571738) (xy 409.073004 -294.523954) (xy 409.069044 -294.4749) (xy 408.730196 -294.4749)
			(xy 408.729701 -294.499507) (xy 408.721806 -294.548084) (xy 408.706222 -294.594765) (xy 408.683351 -294.638342)
			(xy 408.653786 -294.677686) (xy 408.618293 -294.711778) (xy 408.57779 -294.739734) (xy 408.533328 -294.760832)
			(xy 408.486057 -294.774524) (xy 408.437202 -294.780456) (xy 408.388027 -294.778475) (xy 408.339808 -294.768631)
			(xy 408.293792 -294.751179) (xy 408.251171 -294.726572) (xy 408.21305 -294.695447) (xy 408.180415 -294.65861)
			(xy 408.154112 -294.617014) (xy 408.134821 -294.571738) (xy 408.123044 -294.523954) (xy 408.119084 -294.4749)
			(xy 406.830276 -294.4749) (xy 406.829781 -294.499507) (xy 406.821886 -294.548084) (xy 406.806302 -294.594765)
			(xy 406.783431 -294.638342) (xy 406.753866 -294.677686) (xy 406.718373 -294.711778) (xy 406.67787 -294.739734)
			(xy 406.633408 -294.760832) (xy 406.586137 -294.774524) (xy 406.537282 -294.780456) (xy 406.488107 -294.778475)
			(xy 406.439888 -294.768631) (xy 406.393872 -294.751179) (xy 406.351251 -294.726572) (xy 406.31313 -294.695447)
			(xy 406.280495 -294.65861) (xy 406.254192 -294.617014) (xy 406.234901 -294.571738) (xy 406.223124 -294.523954)
			(xy 406.219164 -294.4749) (xy 405.880316 -294.4749) (xy 405.879821 -294.499507) (xy 405.871926 -294.548084)
			(xy 405.856342 -294.594765) (xy 405.833471 -294.638342) (xy 405.803906 -294.677686) (xy 405.768413 -294.711778)
			(xy 405.72791 -294.739734) (xy 405.683448 -294.760832) (xy 405.636177 -294.774524) (xy 405.587322 -294.780456)
			(xy 405.538147 -294.778475) (xy 405.489928 -294.768631) (xy 405.443912 -294.751179) (xy 405.401291 -294.726572)
			(xy 405.36317 -294.695447) (xy 405.330535 -294.65861) (xy 405.304232 -294.617014) (xy 405.284941 -294.571738)
			(xy 405.273164 -294.523954) (xy 405.269204 -294.4749) (xy 404.930102 -294.4749) (xy 404.929607 -294.499507)
			(xy 404.921712 -294.548084) (xy 404.906128 -294.594765) (xy 404.883257 -294.638342) (xy 404.853692 -294.677686)
			(xy 404.818199 -294.711778) (xy 404.777696 -294.739734) (xy 404.733234 -294.760832) (xy 404.685963 -294.774524)
			(xy 404.637108 -294.780456) (xy 404.587933 -294.778475) (xy 404.539714 -294.768631) (xy 404.493698 -294.751179)
			(xy 404.451077 -294.726572) (xy 404.412956 -294.695447) (xy 404.380321 -294.65861) (xy 404.354018 -294.617014)
			(xy 404.334727 -294.571738) (xy 404.32295 -294.523954) (xy 404.31899 -294.4749) (xy 403.980142 -294.4749)
			(xy 403.979647 -294.499507) (xy 403.971752 -294.548084) (xy 403.956168 -294.594765) (xy 403.933297 -294.638342)
			(xy 403.903732 -294.677686) (xy 403.868239 -294.711778) (xy 403.827736 -294.739734) (xy 403.783274 -294.760832)
			(xy 403.736003 -294.774524) (xy 403.687148 -294.780456) (xy 403.637973 -294.778475) (xy 403.589754 -294.768631)
			(xy 403.543738 -294.751179) (xy 403.501117 -294.726572) (xy 403.462996 -294.695447) (xy 403.430361 -294.65861)
			(xy 403.404058 -294.617014) (xy 403.384767 -294.571738) (xy 403.37299 -294.523954) (xy 403.36903 -294.4749)
			(xy 403.030182 -294.4749) (xy 403.029687 -294.499507) (xy 403.021792 -294.548084) (xy 403.006208 -294.594765)
			(xy 402.983337 -294.638342) (xy 402.953772 -294.677686) (xy 402.918279 -294.711778) (xy 402.877776 -294.739734)
			(xy 402.833314 -294.760832) (xy 402.786043 -294.774524) (xy 402.737188 -294.780456) (xy 402.688013 -294.778475)
			(xy 402.639794 -294.768631) (xy 402.593778 -294.751179) (xy 402.551157 -294.726572) (xy 402.513036 -294.695447)
			(xy 402.480401 -294.65861) (xy 402.454098 -294.617014) (xy 402.434807 -294.571738) (xy 402.42303 -294.523954)
			(xy 402.41907 -294.4749) (xy 402.080222 -294.4749) (xy 402.079727 -294.499507) (xy 402.071832 -294.548084)
			(xy 402.056248 -294.594765) (xy 402.033377 -294.638342) (xy 402.003812 -294.677686) (xy 401.968319 -294.711778)
			(xy 401.927816 -294.739734) (xy 401.883354 -294.760832) (xy 401.836083 -294.774524) (xy 401.787228 -294.780456)
			(xy 401.738053 -294.778475) (xy 401.689834 -294.768631) (xy 401.643818 -294.751179) (xy 401.601197 -294.726572)
			(xy 401.563076 -294.695447) (xy 401.530441 -294.65861) (xy 401.504138 -294.617014) (xy 401.484847 -294.571738)
			(xy 401.47307 -294.523954) (xy 401.46911 -294.4749) (xy 401.130262 -294.4749) (xy 401.129767 -294.499507)
			(xy 401.121872 -294.548084) (xy 401.106288 -294.594765) (xy 401.083417 -294.638342) (xy 401.053852 -294.677686)
			(xy 401.018359 -294.711778) (xy 400.977856 -294.739734) (xy 400.933394 -294.760832) (xy 400.886123 -294.774524)
			(xy 400.837268 -294.780456) (xy 400.788093 -294.778475) (xy 400.739874 -294.768631) (xy 400.693858 -294.751179)
			(xy 400.651237 -294.726572) (xy 400.613116 -294.695447) (xy 400.580481 -294.65861) (xy 400.554178 -294.617014)
			(xy 400.534887 -294.571738) (xy 400.52311 -294.523954) (xy 400.51915 -294.4749) (xy 400.180302 -294.4749)
			(xy 400.179807 -294.499507) (xy 400.171912 -294.548084) (xy 400.156328 -294.594765) (xy 400.133457 -294.638342)
			(xy 400.103892 -294.677686) (xy 400.068399 -294.711778) (xy 400.027896 -294.739734) (xy 399.983434 -294.760832)
			(xy 399.936163 -294.774524) (xy 399.887308 -294.780456) (xy 399.838133 -294.778475) (xy 399.789914 -294.768631)
			(xy 399.743898 -294.751179) (xy 399.701277 -294.726572) (xy 399.663156 -294.695447) (xy 399.630521 -294.65861)
			(xy 399.604218 -294.617014) (xy 399.584927 -294.571738) (xy 399.57315 -294.523954) (xy 399.56919 -294.4749)
			(xy 399.230342 -294.4749) (xy 399.229847 -294.499507) (xy 399.221952 -294.548084) (xy 399.206368 -294.594765)
			(xy 399.183497 -294.638342) (xy 399.153932 -294.677686) (xy 399.118439 -294.711778) (xy 399.077936 -294.739734)
			(xy 399.033474 -294.760832) (xy 398.986203 -294.774524) (xy 398.937348 -294.780456) (xy 398.888173 -294.778475)
			(xy 398.839954 -294.768631) (xy 398.793938 -294.751179) (xy 398.751317 -294.726572) (xy 398.713196 -294.695447)
			(xy 398.680561 -294.65861) (xy 398.654258 -294.617014) (xy 398.634967 -294.571738) (xy 398.62319 -294.523954)
			(xy 398.61923 -294.4749) (xy 398.280128 -294.4749) (xy 398.279633 -294.499507) (xy 398.271738 -294.548084)
			(xy 398.256154 -294.594765) (xy 398.233283 -294.638342) (xy 398.203718 -294.677686) (xy 398.168225 -294.711778)
			(xy 398.127722 -294.739734) (xy 398.08326 -294.760832) (xy 398.035989 -294.774524) (xy 397.987134 -294.780456)
			(xy 397.937959 -294.778475) (xy 397.88974 -294.768631) (xy 397.843724 -294.751179) (xy 397.801103 -294.726572)
			(xy 397.762982 -294.695447) (xy 397.730347 -294.65861) (xy 397.704044 -294.617014) (xy 397.684753 -294.571738)
			(xy 397.672976 -294.523954) (xy 397.669016 -294.4749) (xy 397.330168 -294.4749) (xy 397.329673 -294.499507)
			(xy 397.321778 -294.548084) (xy 397.306194 -294.594765) (xy 397.283323 -294.638342) (xy 397.253758 -294.677686)
			(xy 397.218265 -294.711778) (xy 397.177762 -294.739734) (xy 397.1333 -294.760832) (xy 397.086029 -294.774524)
			(xy 397.037174 -294.780456) (xy 396.987999 -294.778475) (xy 396.93978 -294.768631) (xy 396.893764 -294.751179)
			(xy 396.851143 -294.726572) (xy 396.813022 -294.695447) (xy 396.780387 -294.65861) (xy 396.754084 -294.617014)
			(xy 396.734793 -294.571738) (xy 396.723016 -294.523954) (xy 396.719056 -294.4749) (xy 396.380731 -294.4749)
			(xy 396.37656 -294.525238) (xy 396.36416 -294.574203) (xy 396.34387 -294.620459) (xy 396.316244 -294.662745)
			(xy 396.282034 -294.699907) (xy 396.242174 -294.730931) (xy 396.197751 -294.754972) (xy 396.149977 -294.771373)
			(xy 396.100155 -294.779686) (xy 396.0749 -294.780208) (xy 396.051362 -294.779766) (xy 396.004841 -294.772557)
			(xy 395.959978 -294.758295) (xy 395.917834 -294.737317) (xy 395.89837 -294.724074) (xy 395.898116 -294.724074)
			(xy 395.890334 -294.719029) (xy 395.872394 -294.714382) (xy 395.853973 -294.716406) (xy 395.845538 -294.720264)
			(xy 395.765528 -294.761666) (xy 395.757497 -294.766355) (xy 395.745147 -294.780234) (xy 395.73852 -294.79759)
			(xy 395.738096 -294.806878) (xy 395.738096 -295.598088) (xy 395.737641 -295.622093) (xy 395.730095 -295.669507)
			(xy 395.715218 -295.715154) (xy 395.693379 -295.75791) (xy 395.665114 -295.796719) (xy 395.648434 -295.813988)
			(xy 395.410182 -296.05224) (xy 395.39291 -296.068861) (xy 395.354125 -296.097025) (xy 395.311418 -296.118789)
			(xy 395.265838 -296.13362) (xy 395.218502 -296.141155) (xy 395.194536 -296.141648) (xy 395.111732 -296.141648)
			(xy 395.10062 -296.142203) (xy 395.080461 -296.151549) (xy 395.07287 -296.159682) (xy 395.066172 -296.168354)
			(xy 395.060252 -296.189428) (xy 395.06144 -296.200322) (xy 395.072616 -296.271188) (xy 395.073416 -296.277186)
			(xy 395.072518 -296.289251) (xy 395.070838 -296.295064) (xy 395.052296 -296.351706) (xy 395.051788 -296.353484)
			(xy 395.050341 -296.358763) (xy 395.048815 -296.369601) (xy 395.048743 -296.37482) (xy 395.769096 -296.37482)
			(xy 395.773056 -296.325766) (xy 395.784833 -296.277982) (xy 395.804124 -296.232706) (xy 395.830427 -296.19111)
			(xy 395.863062 -296.154273) (xy 395.901183 -296.123148) (xy 395.943804 -296.098541) (xy 395.98982 -296.081089)
			(xy 396.038039 -296.071245) (xy 396.087214 -296.069264) (xy 396.136069 -296.075196) (xy 396.18334 -296.088888)
			(xy 396.227802 -296.109986) (xy 396.268305 -296.137942) (xy 396.303798 -296.172034) (xy 396.333363 -296.211378)
			(xy 396.356234 -296.254955) (xy 396.371818 -296.301636) (xy 396.379713 -296.350213) (xy 396.380208 -296.37482)
			(xy 396.719056 -296.37482) (xy 396.723016 -296.325766) (xy 396.734793 -296.277982) (xy 396.754084 -296.232706)
			(xy 396.780387 -296.19111) (xy 396.813022 -296.154273) (xy 396.851143 -296.123148) (xy 396.893764 -296.098541)
			(xy 396.93978 -296.081089) (xy 396.987999 -296.071245) (xy 397.037174 -296.069264) (xy 397.086029 -296.075196)
			(xy 397.1333 -296.088888) (xy 397.177762 -296.109986) (xy 397.218265 -296.137942) (xy 397.253758 -296.172034)
			(xy 397.283323 -296.211378) (xy 397.306194 -296.254955) (xy 397.321778 -296.301636) (xy 397.329673 -296.350213)
			(xy 397.330168 -296.37482) (xy 397.669016 -296.37482) (xy 397.672976 -296.325766) (xy 397.684753 -296.277982)
			(xy 397.704044 -296.232706) (xy 397.730347 -296.19111) (xy 397.762982 -296.154273) (xy 397.801103 -296.123148)
			(xy 397.843724 -296.098541) (xy 397.88974 -296.081089) (xy 397.937959 -296.071245) (xy 397.987134 -296.069264)
			(xy 398.035989 -296.075196) (xy 398.08326 -296.088888) (xy 398.127722 -296.109986) (xy 398.168225 -296.137942)
			(xy 398.203718 -296.172034) (xy 398.233283 -296.211378) (xy 398.256154 -296.254955) (xy 398.271738 -296.301636)
			(xy 398.279633 -296.350213) (xy 398.280128 -296.37482) (xy 398.61923 -296.37482) (xy 398.62319 -296.325766)
			(xy 398.634967 -296.277982) (xy 398.654258 -296.232706) (xy 398.680561 -296.19111) (xy 398.713196 -296.154273)
			(xy 398.751317 -296.123148) (xy 398.793938 -296.098541) (xy 398.839954 -296.081089) (xy 398.888173 -296.071245)
			(xy 398.937348 -296.069264) (xy 398.986203 -296.075196) (xy 399.033474 -296.088888) (xy 399.077936 -296.109986)
			(xy 399.118439 -296.137942) (xy 399.153932 -296.172034) (xy 399.183497 -296.211378) (xy 399.206368 -296.254955)
			(xy 399.221952 -296.301636) (xy 399.229847 -296.350213) (xy 399.230342 -296.37482) (xy 399.56919 -296.37482)
			(xy 399.57315 -296.325766) (xy 399.584927 -296.277982) (xy 399.604218 -296.232706) (xy 399.630521 -296.19111)
			(xy 399.663156 -296.154273) (xy 399.701277 -296.123148) (xy 399.743898 -296.098541) (xy 399.789914 -296.081089)
			(xy 399.838133 -296.071245) (xy 399.887308 -296.069264) (xy 399.936163 -296.075196) (xy 399.983434 -296.088888)
			(xy 400.027896 -296.109986) (xy 400.068399 -296.137942) (xy 400.103892 -296.172034) (xy 400.133457 -296.211378)
			(xy 400.156328 -296.254955) (xy 400.171912 -296.301636) (xy 400.179807 -296.350213) (xy 400.180302 -296.37482)
			(xy 400.51915 -296.37482) (xy 400.52311 -296.325766) (xy 400.534887 -296.277982) (xy 400.554178 -296.232706)
			(xy 400.580481 -296.19111) (xy 400.613116 -296.154273) (xy 400.651237 -296.123148) (xy 400.693858 -296.098541)
			(xy 400.739874 -296.081089) (xy 400.788093 -296.071245) (xy 400.837268 -296.069264) (xy 400.886123 -296.075196)
			(xy 400.933394 -296.088888) (xy 400.977856 -296.109986) (xy 401.018359 -296.137942) (xy 401.053852 -296.172034)
			(xy 401.083417 -296.211378) (xy 401.106288 -296.254955) (xy 401.121872 -296.301636) (xy 401.129767 -296.350213)
			(xy 401.130262 -296.37482) (xy 401.46911 -296.37482) (xy 401.47307 -296.325766) (xy 401.484847 -296.277982)
			(xy 401.504138 -296.232706) (xy 401.530441 -296.19111) (xy 401.563076 -296.154273) (xy 401.601197 -296.123148)
			(xy 401.643818 -296.098541) (xy 401.689834 -296.081089) (xy 401.738053 -296.071245) (xy 401.787228 -296.069264)
			(xy 401.836083 -296.075196) (xy 401.883354 -296.088888) (xy 401.927816 -296.109986) (xy 401.968319 -296.137942)
			(xy 402.003812 -296.172034) (xy 402.033377 -296.211378) (xy 402.056248 -296.254955) (xy 402.071832 -296.301636)
			(xy 402.079727 -296.350213) (xy 402.080222 -296.37482) (xy 402.41907 -296.37482) (xy 402.42303 -296.325766)
			(xy 402.434807 -296.277982) (xy 402.454098 -296.232706) (xy 402.480401 -296.19111) (xy 402.513036 -296.154273)
			(xy 402.551157 -296.123148) (xy 402.593778 -296.098541) (xy 402.639794 -296.081089) (xy 402.688013 -296.071245)
			(xy 402.737188 -296.069264) (xy 402.786043 -296.075196) (xy 402.833314 -296.088888) (xy 402.877776 -296.109986)
			(xy 402.918279 -296.137942) (xy 402.953772 -296.172034) (xy 402.983337 -296.211378) (xy 403.006208 -296.254955)
			(xy 403.021792 -296.301636) (xy 403.029687 -296.350213) (xy 403.030182 -296.37482) (xy 403.36903 -296.37482)
			(xy 403.37299 -296.325766) (xy 403.384767 -296.277982) (xy 403.404058 -296.232706) (xy 403.430361 -296.19111)
			(xy 403.462996 -296.154273) (xy 403.501117 -296.123148) (xy 403.543738 -296.098541) (xy 403.589754 -296.081089)
			(xy 403.637973 -296.071245) (xy 403.687148 -296.069264) (xy 403.736003 -296.075196) (xy 403.783274 -296.088888)
			(xy 403.827736 -296.109986) (xy 403.868239 -296.137942) (xy 403.903732 -296.172034) (xy 403.933297 -296.211378)
			(xy 403.956168 -296.254955) (xy 403.971752 -296.301636) (xy 403.979647 -296.350213) (xy 403.980142 -296.37482)
			(xy 404.319244 -296.37482) (xy 404.323204 -296.325766) (xy 404.334981 -296.277982) (xy 404.354272 -296.232706)
			(xy 404.380575 -296.19111) (xy 404.41321 -296.154273) (xy 404.451331 -296.123148) (xy 404.493952 -296.098541)
			(xy 404.539968 -296.081089) (xy 404.588187 -296.071245) (xy 404.637362 -296.069264) (xy 404.686217 -296.075196)
			(xy 404.733488 -296.088888) (xy 404.77795 -296.109986) (xy 404.818453 -296.137942) (xy 404.853946 -296.172034)
			(xy 404.883511 -296.211378) (xy 404.906382 -296.254955) (xy 404.921966 -296.301636) (xy 404.929861 -296.350213)
			(xy 404.930356 -296.37482) (xy 405.269204 -296.37482) (xy 405.273164 -296.325766) (xy 405.284941 -296.277982)
			(xy 405.304232 -296.232706) (xy 405.330535 -296.19111) (xy 405.36317 -296.154273) (xy 405.401291 -296.123148)
			(xy 405.443912 -296.098541) (xy 405.489928 -296.081089) (xy 405.538147 -296.071245) (xy 405.587322 -296.069264)
			(xy 405.636177 -296.075196) (xy 405.683448 -296.088888) (xy 405.72791 -296.109986) (xy 405.768413 -296.137942)
			(xy 405.803906 -296.172034) (xy 405.833471 -296.211378) (xy 405.856342 -296.254955) (xy 405.871926 -296.301636)
			(xy 405.879821 -296.350213) (xy 405.880316 -296.37482) (xy 406.219164 -296.37482) (xy 406.223124 -296.325766)
			(xy 406.234901 -296.277982) (xy 406.254192 -296.232706) (xy 406.280495 -296.19111) (xy 406.31313 -296.154273)
			(xy 406.351251 -296.123148) (xy 406.393872 -296.098541) (xy 406.439888 -296.081089) (xy 406.488107 -296.071245)
			(xy 406.537282 -296.069264) (xy 406.586137 -296.075196) (xy 406.633408 -296.088888) (xy 406.67787 -296.109986)
			(xy 406.718373 -296.137942) (xy 406.753866 -296.172034) (xy 406.783431 -296.211378) (xy 406.806302 -296.254955)
			(xy 406.821886 -296.301636) (xy 406.829781 -296.350213) (xy 406.830276 -296.37482) (xy 408.119084 -296.37482)
			(xy 408.123044 -296.325766) (xy 408.134821 -296.277982) (xy 408.154112 -296.232706) (xy 408.180415 -296.19111)
			(xy 408.21305 -296.154273) (xy 408.251171 -296.123148) (xy 408.293792 -296.098541) (xy 408.339808 -296.081089)
			(xy 408.388027 -296.071245) (xy 408.437202 -296.069264) (xy 408.486057 -296.075196) (xy 408.533328 -296.088888)
			(xy 408.57779 -296.109986) (xy 408.618293 -296.137942) (xy 408.653786 -296.172034) (xy 408.683351 -296.211378)
			(xy 408.706222 -296.254955) (xy 408.721806 -296.301636) (xy 408.729701 -296.350213) (xy 408.730196 -296.37482)
			(xy 409.069044 -296.37482) (xy 409.073004 -296.325766) (xy 409.084781 -296.277982) (xy 409.104072 -296.232706)
			(xy 409.130375 -296.19111) (xy 409.16301 -296.154273) (xy 409.201131 -296.123148) (xy 409.243752 -296.098541)
			(xy 409.289768 -296.081089) (xy 409.337987 -296.071245) (xy 409.387162 -296.069264) (xy 409.436017 -296.075196)
			(xy 409.483288 -296.088888) (xy 409.52775 -296.109986) (xy 409.568253 -296.137942) (xy 409.603746 -296.172034)
			(xy 409.633311 -296.211378) (xy 409.656182 -296.254955) (xy 409.671766 -296.301636) (xy 409.679661 -296.350213)
			(xy 409.680156 -296.37482) (xy 410.019004 -296.37482) (xy 410.022964 -296.325766) (xy 410.034741 -296.277982)
			(xy 410.054032 -296.232706) (xy 410.080335 -296.19111) (xy 410.11297 -296.154273) (xy 410.151091 -296.123148)
			(xy 410.193712 -296.098541) (xy 410.239728 -296.081089) (xy 410.287947 -296.071245) (xy 410.337122 -296.069264)
			(xy 410.385977 -296.075196) (xy 410.433248 -296.088888) (xy 410.47771 -296.109986) (xy 410.518213 -296.137942)
			(xy 410.553706 -296.172034) (xy 410.583271 -296.211378) (xy 410.606142 -296.254955) (xy 410.621726 -296.301636)
			(xy 410.629621 -296.350213) (xy 410.630116 -296.37482) (xy 410.969218 -296.37482) (xy 410.973178 -296.325766)
			(xy 410.984955 -296.277982) (xy 411.004246 -296.232706) (xy 411.030549 -296.19111) (xy 411.063184 -296.154273)
			(xy 411.101305 -296.123148) (xy 411.143926 -296.098541) (xy 411.189942 -296.081089) (xy 411.238161 -296.071245)
			(xy 411.287336 -296.069264) (xy 411.336191 -296.075196) (xy 411.383462 -296.088888) (xy 411.427924 -296.109986)
			(xy 411.468427 -296.137942) (xy 411.50392 -296.172034) (xy 411.533485 -296.211378) (xy 411.556356 -296.254955)
			(xy 411.57194 -296.301636) (xy 411.579835 -296.350213) (xy 411.58033 -296.37482) (xy 411.919178 -296.37482)
			(xy 411.923138 -296.325766) (xy 411.934915 -296.277982) (xy 411.954206 -296.232706) (xy 411.980509 -296.19111)
			(xy 412.013144 -296.154273) (xy 412.051265 -296.123148) (xy 412.093886 -296.098541) (xy 412.139902 -296.081089)
			(xy 412.188121 -296.071245) (xy 412.237296 -296.069264) (xy 412.286151 -296.075196) (xy 412.333422 -296.088888)
			(xy 412.377884 -296.109986) (xy 412.418387 -296.137942) (xy 412.45388 -296.172034) (xy 412.483445 -296.211378)
			(xy 412.506316 -296.254955) (xy 412.5219 -296.301636) (xy 412.529795 -296.350213) (xy 412.53029 -296.37482)
			(xy 412.869138 -296.37482) (xy 412.873098 -296.325766) (xy 412.884875 -296.277982) (xy 412.904166 -296.232706)
			(xy 412.930469 -296.19111) (xy 412.963104 -296.154273) (xy 413.001225 -296.123148) (xy 413.043846 -296.098541)
			(xy 413.089862 -296.081089) (xy 413.138081 -296.071245) (xy 413.187256 -296.069264) (xy 413.236111 -296.075196)
			(xy 413.283382 -296.088888) (xy 413.327844 -296.109986) (xy 413.368347 -296.137942) (xy 413.40384 -296.172034)
			(xy 413.433405 -296.211378) (xy 413.456276 -296.254955) (xy 413.47186 -296.301636) (xy 413.479755 -296.350213)
			(xy 413.48025 -296.37482) (xy 413.819098 -296.37482) (xy 413.823058 -296.325766) (xy 413.834835 -296.277982)
			(xy 413.854126 -296.232706) (xy 413.880429 -296.19111) (xy 413.913064 -296.154273) (xy 413.951185 -296.123148)
			(xy 413.993806 -296.098541) (xy 414.039822 -296.081089) (xy 414.088041 -296.071245) (xy 414.137216 -296.069264)
			(xy 414.186071 -296.075196) (xy 414.233342 -296.088888) (xy 414.277804 -296.109986) (xy 414.318307 -296.137942)
			(xy 414.3538 -296.172034) (xy 414.383365 -296.211378) (xy 414.406236 -296.254955) (xy 414.42182 -296.301636)
			(xy 414.429715 -296.350213) (xy 414.43021 -296.37482) (xy 414.769058 -296.37482) (xy 414.773018 -296.325766)
			(xy 414.784795 -296.277982) (xy 414.804086 -296.232706) (xy 414.830389 -296.19111) (xy 414.863024 -296.154273)
			(xy 414.901145 -296.123148) (xy 414.943766 -296.098541) (xy 414.989782 -296.081089) (xy 415.038001 -296.071245)
			(xy 415.087176 -296.069264) (xy 415.136031 -296.075196) (xy 415.183302 -296.088888) (xy 415.227764 -296.109986)
			(xy 415.268267 -296.137942) (xy 415.30376 -296.172034) (xy 415.333325 -296.211378) (xy 415.356196 -296.254955)
			(xy 415.37178 -296.301636) (xy 415.379675 -296.350213) (xy 415.38017 -296.37482) (xy 415.379675 -296.399427)
			(xy 415.37178 -296.448004) (xy 415.356196 -296.494685) (xy 415.333325 -296.538262) (xy 415.30376 -296.577606)
			(xy 415.268267 -296.611698) (xy 415.227764 -296.639654) (xy 415.183302 -296.660752) (xy 415.136031 -296.674444)
			(xy 415.087176 -296.680376) (xy 415.038001 -296.678395) (xy 414.989782 -296.668551) (xy 414.943766 -296.651099)
			(xy 414.901145 -296.626492) (xy 414.863024 -296.595367) (xy 414.830389 -296.55853) (xy 414.804086 -296.516934)
			(xy 414.784795 -296.471658) (xy 414.773018 -296.423874) (xy 414.769058 -296.37482) (xy 414.43021 -296.37482)
			(xy 414.429715 -296.399427) (xy 414.42182 -296.448004) (xy 414.406236 -296.494685) (xy 414.383365 -296.538262)
			(xy 414.3538 -296.577606) (xy 414.318307 -296.611698) (xy 414.277804 -296.639654) (xy 414.233342 -296.660752)
			(xy 414.186071 -296.674444) (xy 414.137216 -296.680376) (xy 414.088041 -296.678395) (xy 414.039822 -296.668551)
			(xy 413.993806 -296.651099) (xy 413.951185 -296.626492) (xy 413.913064 -296.595367) (xy 413.880429 -296.55853)
			(xy 413.854126 -296.516934) (xy 413.834835 -296.471658) (xy 413.823058 -296.423874) (xy 413.819098 -296.37482)
			(xy 413.48025 -296.37482) (xy 413.479755 -296.399427) (xy 413.47186 -296.448004) (xy 413.456276 -296.494685)
			(xy 413.433405 -296.538262) (xy 413.40384 -296.577606) (xy 413.368347 -296.611698) (xy 413.327844 -296.639654)
			(xy 413.283382 -296.660752) (xy 413.236111 -296.674444) (xy 413.187256 -296.680376) (xy 413.138081 -296.678395)
			(xy 413.089862 -296.668551) (xy 413.043846 -296.651099) (xy 413.001225 -296.626492) (xy 412.963104 -296.595367)
			(xy 412.930469 -296.55853) (xy 412.904166 -296.516934) (xy 412.884875 -296.471658) (xy 412.873098 -296.423874)
			(xy 412.869138 -296.37482) (xy 412.53029 -296.37482) (xy 412.529795 -296.399427) (xy 412.5219 -296.448004)
			(xy 412.506316 -296.494685) (xy 412.483445 -296.538262) (xy 412.45388 -296.577606) (xy 412.418387 -296.611698)
			(xy 412.377884 -296.639654) (xy 412.333422 -296.660752) (xy 412.286151 -296.674444) (xy 412.237296 -296.680376)
			(xy 412.188121 -296.678395) (xy 412.139902 -296.668551) (xy 412.093886 -296.651099) (xy 412.051265 -296.626492)
			(xy 412.013144 -296.595367) (xy 411.980509 -296.55853) (xy 411.954206 -296.516934) (xy 411.934915 -296.471658)
			(xy 411.923138 -296.423874) (xy 411.919178 -296.37482) (xy 411.58033 -296.37482) (xy 411.579835 -296.399427)
			(xy 411.57194 -296.448004) (xy 411.556356 -296.494685) (xy 411.533485 -296.538262) (xy 411.50392 -296.577606)
			(xy 411.468427 -296.611698) (xy 411.427924 -296.639654) (xy 411.383462 -296.660752) (xy 411.336191 -296.674444)
			(xy 411.287336 -296.680376) (xy 411.238161 -296.678395) (xy 411.189942 -296.668551) (xy 411.143926 -296.651099)
			(xy 411.101305 -296.626492) (xy 411.063184 -296.595367) (xy 411.030549 -296.55853) (xy 411.004246 -296.516934)
			(xy 410.984955 -296.471658) (xy 410.973178 -296.423874) (xy 410.969218 -296.37482) (xy 410.630116 -296.37482)
			(xy 410.629621 -296.399427) (xy 410.621726 -296.448004) (xy 410.606142 -296.494685) (xy 410.583271 -296.538262)
			(xy 410.553706 -296.577606) (xy 410.518213 -296.611698) (xy 410.47771 -296.639654) (xy 410.433248 -296.660752)
			(xy 410.385977 -296.674444) (xy 410.337122 -296.680376) (xy 410.287947 -296.678395) (xy 410.239728 -296.668551)
			(xy 410.193712 -296.651099) (xy 410.151091 -296.626492) (xy 410.11297 -296.595367) (xy 410.080335 -296.55853)
			(xy 410.054032 -296.516934) (xy 410.034741 -296.471658) (xy 410.022964 -296.423874) (xy 410.019004 -296.37482)
			(xy 409.680156 -296.37482) (xy 409.679661 -296.399427) (xy 409.671766 -296.448004) (xy 409.656182 -296.494685)
			(xy 409.633311 -296.538262) (xy 409.603746 -296.577606) (xy 409.568253 -296.611698) (xy 409.52775 -296.639654)
			(xy 409.483288 -296.660752) (xy 409.436017 -296.674444) (xy 409.387162 -296.680376) (xy 409.337987 -296.678395)
			(xy 409.289768 -296.668551) (xy 409.243752 -296.651099) (xy 409.201131 -296.626492) (xy 409.16301 -296.595367)
			(xy 409.130375 -296.55853) (xy 409.104072 -296.516934) (xy 409.084781 -296.471658) (xy 409.073004 -296.423874)
			(xy 409.069044 -296.37482) (xy 408.730196 -296.37482) (xy 408.729701 -296.399427) (xy 408.721806 -296.448004)
			(xy 408.706222 -296.494685) (xy 408.683351 -296.538262) (xy 408.653786 -296.577606) (xy 408.618293 -296.611698)
			(xy 408.57779 -296.639654) (xy 408.533328 -296.660752) (xy 408.486057 -296.674444) (xy 408.437202 -296.680376)
			(xy 408.388027 -296.678395) (xy 408.339808 -296.668551) (xy 408.293792 -296.651099) (xy 408.251171 -296.626492)
			(xy 408.21305 -296.595367) (xy 408.180415 -296.55853) (xy 408.154112 -296.516934) (xy 408.134821 -296.471658)
			(xy 408.123044 -296.423874) (xy 408.119084 -296.37482) (xy 406.830276 -296.37482) (xy 406.829781 -296.399427)
			(xy 406.821886 -296.448004) (xy 406.806302 -296.494685) (xy 406.783431 -296.538262) (xy 406.753866 -296.577606)
			(xy 406.718373 -296.611698) (xy 406.67787 -296.639654) (xy 406.633408 -296.660752) (xy 406.586137 -296.674444)
			(xy 406.537282 -296.680376) (xy 406.488107 -296.678395) (xy 406.439888 -296.668551) (xy 406.393872 -296.651099)
			(xy 406.351251 -296.626492) (xy 406.31313 -296.595367) (xy 406.280495 -296.55853) (xy 406.254192 -296.516934)
			(xy 406.234901 -296.471658) (xy 406.223124 -296.423874) (xy 406.219164 -296.37482) (xy 405.880316 -296.37482)
			(xy 405.879821 -296.399427) (xy 405.871926 -296.448004) (xy 405.856342 -296.494685) (xy 405.833471 -296.538262)
			(xy 405.803906 -296.577606) (xy 405.768413 -296.611698) (xy 405.72791 -296.639654) (xy 405.683448 -296.660752)
			(xy 405.636177 -296.674444) (xy 405.587322 -296.680376) (xy 405.538147 -296.678395) (xy 405.489928 -296.668551)
			(xy 405.443912 -296.651099) (xy 405.401291 -296.626492) (xy 405.36317 -296.595367) (xy 405.330535 -296.55853)
			(xy 405.304232 -296.516934) (xy 405.284941 -296.471658) (xy 405.273164 -296.423874) (xy 405.269204 -296.37482)
			(xy 404.930356 -296.37482) (xy 404.929861 -296.399427) (xy 404.921966 -296.448004) (xy 404.906382 -296.494685)
			(xy 404.883511 -296.538262) (xy 404.853946 -296.577606) (xy 404.818453 -296.611698) (xy 404.77795 -296.639654)
			(xy 404.733488 -296.660752) (xy 404.686217 -296.674444) (xy 404.637362 -296.680376) (xy 404.588187 -296.678395)
			(xy 404.539968 -296.668551) (xy 404.493952 -296.651099) (xy 404.451331 -296.626492) (xy 404.41321 -296.595367)
			(xy 404.380575 -296.55853) (xy 404.354272 -296.516934) (xy 404.334981 -296.471658) (xy 404.323204 -296.423874)
			(xy 404.319244 -296.37482) (xy 403.980142 -296.37482) (xy 403.979647 -296.399427) (xy 403.971752 -296.448004)
			(xy 403.956168 -296.494685) (xy 403.933297 -296.538262) (xy 403.903732 -296.577606) (xy 403.868239 -296.611698)
			(xy 403.827736 -296.639654) (xy 403.783274 -296.660752) (xy 403.736003 -296.674444) (xy 403.687148 -296.680376)
			(xy 403.637973 -296.678395) (xy 403.589754 -296.668551) (xy 403.543738 -296.651099) (xy 403.501117 -296.626492)
			(xy 403.462996 -296.595367) (xy 403.430361 -296.55853) (xy 403.404058 -296.516934) (xy 403.384767 -296.471658)
			(xy 403.37299 -296.423874) (xy 403.36903 -296.37482) (xy 403.030182 -296.37482) (xy 403.029687 -296.399427)
			(xy 403.021792 -296.448004) (xy 403.006208 -296.494685) (xy 402.983337 -296.538262) (xy 402.953772 -296.577606)
			(xy 402.918279 -296.611698) (xy 402.877776 -296.639654) (xy 402.833314 -296.660752) (xy 402.786043 -296.674444)
			(xy 402.737188 -296.680376) (xy 402.688013 -296.678395) (xy 402.639794 -296.668551) (xy 402.593778 -296.651099)
			(xy 402.551157 -296.626492) (xy 402.513036 -296.595367) (xy 402.480401 -296.55853) (xy 402.454098 -296.516934)
			(xy 402.434807 -296.471658) (xy 402.42303 -296.423874) (xy 402.41907 -296.37482) (xy 402.080222 -296.37482)
			(xy 402.079727 -296.399427) (xy 402.071832 -296.448004) (xy 402.056248 -296.494685) (xy 402.033377 -296.538262)
			(xy 402.003812 -296.577606) (xy 401.968319 -296.611698) (xy 401.927816 -296.639654) (xy 401.883354 -296.660752)
			(xy 401.836083 -296.674444) (xy 401.787228 -296.680376) (xy 401.738053 -296.678395) (xy 401.689834 -296.668551)
			(xy 401.643818 -296.651099) (xy 401.601197 -296.626492) (xy 401.563076 -296.595367) (xy 401.530441 -296.55853)
			(xy 401.504138 -296.516934) (xy 401.484847 -296.471658) (xy 401.47307 -296.423874) (xy 401.46911 -296.37482)
			(xy 401.130262 -296.37482) (xy 401.129767 -296.399427) (xy 401.121872 -296.448004) (xy 401.106288 -296.494685)
			(xy 401.083417 -296.538262) (xy 401.053852 -296.577606) (xy 401.018359 -296.611698) (xy 400.977856 -296.639654)
			(xy 400.933394 -296.660752) (xy 400.886123 -296.674444) (xy 400.837268 -296.680376) (xy 400.788093 -296.678395)
			(xy 400.739874 -296.668551) (xy 400.693858 -296.651099) (xy 400.651237 -296.626492) (xy 400.613116 -296.595367)
			(xy 400.580481 -296.55853) (xy 400.554178 -296.516934) (xy 400.534887 -296.471658) (xy 400.52311 -296.423874)
			(xy 400.51915 -296.37482) (xy 400.180302 -296.37482) (xy 400.179807 -296.399427) (xy 400.171912 -296.448004)
			(xy 400.156328 -296.494685) (xy 400.133457 -296.538262) (xy 400.103892 -296.577606) (xy 400.068399 -296.611698)
			(xy 400.027896 -296.639654) (xy 399.983434 -296.660752) (xy 399.936163 -296.674444) (xy 399.887308 -296.680376)
			(xy 399.838133 -296.678395) (xy 399.789914 -296.668551) (xy 399.743898 -296.651099) (xy 399.701277 -296.626492)
			(xy 399.663156 -296.595367) (xy 399.630521 -296.55853) (xy 399.604218 -296.516934) (xy 399.584927 -296.471658)
			(xy 399.57315 -296.423874) (xy 399.56919 -296.37482) (xy 399.230342 -296.37482) (xy 399.229847 -296.399427)
			(xy 399.221952 -296.448004) (xy 399.206368 -296.494685) (xy 399.183497 -296.538262) (xy 399.153932 -296.577606)
			(xy 399.118439 -296.611698) (xy 399.077936 -296.639654) (xy 399.033474 -296.660752) (xy 398.986203 -296.674444)
			(xy 398.937348 -296.680376) (xy 398.888173 -296.678395) (xy 398.839954 -296.668551) (xy 398.793938 -296.651099)
			(xy 398.751317 -296.626492) (xy 398.713196 -296.595367) (xy 398.680561 -296.55853) (xy 398.654258 -296.516934)
			(xy 398.634967 -296.471658) (xy 398.62319 -296.423874) (xy 398.61923 -296.37482) (xy 398.280128 -296.37482)
			(xy 398.279633 -296.399427) (xy 398.271738 -296.448004) (xy 398.256154 -296.494685) (xy 398.233283 -296.538262)
			(xy 398.203718 -296.577606) (xy 398.168225 -296.611698) (xy 398.127722 -296.639654) (xy 398.08326 -296.660752)
			(xy 398.035989 -296.674444) (xy 397.987134 -296.680376) (xy 397.937959 -296.678395) (xy 397.88974 -296.668551)
			(xy 397.843724 -296.651099) (xy 397.801103 -296.626492) (xy 397.762982 -296.595367) (xy 397.730347 -296.55853)
			(xy 397.704044 -296.516934) (xy 397.684753 -296.471658) (xy 397.672976 -296.423874) (xy 397.669016 -296.37482)
			(xy 397.330168 -296.37482) (xy 397.329673 -296.399427) (xy 397.321778 -296.448004) (xy 397.306194 -296.494685)
			(xy 397.283323 -296.538262) (xy 397.253758 -296.577606) (xy 397.218265 -296.611698) (xy 397.177762 -296.639654)
			(xy 397.1333 -296.660752) (xy 397.086029 -296.674444) (xy 397.037174 -296.680376) (xy 396.987999 -296.678395)
			(xy 396.93978 -296.668551) (xy 396.893764 -296.651099) (xy 396.851143 -296.626492) (xy 396.813022 -296.595367)
			(xy 396.780387 -296.55853) (xy 396.754084 -296.516934) (xy 396.734793 -296.471658) (xy 396.723016 -296.423874)
			(xy 396.719056 -296.37482) (xy 396.380208 -296.37482) (xy 396.379713 -296.399427) (xy 396.371818 -296.448004)
			(xy 396.356234 -296.494685) (xy 396.333363 -296.538262) (xy 396.303798 -296.577606) (xy 396.268305 -296.611698)
			(xy 396.227802 -296.639654) (xy 396.18334 -296.660752) (xy 396.136069 -296.674444) (xy 396.087214 -296.680376)
			(xy 396.038039 -296.678395) (xy 395.98982 -296.668551) (xy 395.943804 -296.651099) (xy 395.901183 -296.626492)
			(xy 395.863062 -296.595367) (xy 395.830427 -296.55853) (xy 395.804124 -296.516934) (xy 395.784833 -296.471658)
			(xy 395.773056 -296.423874) (xy 395.769096 -296.37482) (xy 395.048743 -296.37482) (xy 395.04874 -296.375074)
			(xy 395.049189 -296.387047) (xy 395.056658 -296.409802) (xy 395.07078 -296.429143) (xy 395.09018 -296.443186)
			(xy 395.112965 -296.450561) (xy 395.12494 -296.45102) (xy 395.125194 -296.45102) (xy 395.135257 -296.450655)
			(xy 395.154682 -296.445381) (xy 395.163548 -296.440606) (xy 395.164056 -296.440098) (xy 395.223238 -296.405554)
			(xy 395.229032 -296.402377) (xy 395.241779 -296.398911) (xy 395.248384 -296.398696) (xy 395.385036 -296.397426)
			(xy 395.391752 -296.397538) (xy 395.404755 -296.400885) (xy 395.41069 -296.40403) (xy 395.547088 -296.481754)
			(xy 395.570072 -296.495493) (xy 395.611252 -296.529715) (xy 395.645822 -296.570603) (xy 395.672721 -296.616899)
			(xy 395.691122 -296.667181) (xy 395.700459 -296.719904) (xy 395.701012 -296.746676) (xy 395.701012 -297.022266)
			(xy 395.70139 -297.032084) (xy 395.708762 -297.050284) (xy 395.722436 -297.064376) (xy 395.731238 -297.068748)
			(xy 395.816074 -297.10634) (xy 395.825152 -297.109856) (xy 395.844594 -297.110481) (xy 395.862883 -297.103854)
			(xy 395.87043 -297.097704) (xy 395.870684 -297.097704) (xy 395.887584 -297.083034) (xy 395.924889 -297.058313)
			(xy 395.9654 -297.039295) (xy 396.00825 -297.026386) (xy 396.052524 -297.019862) (xy 396.0749 -297.019472)
			(xy 396.100154 -297.020033) (xy 396.149972 -297.028347) (xy 396.197743 -297.044746) (xy 396.242163 -297.068785)
			(xy 396.28202 -297.099808) (xy 396.316228 -297.136967) (xy 396.343853 -297.17925) (xy 396.364141 -297.225503)
			(xy 396.37654 -297.274465) (xy 396.380709 -297.32478) (xy 396.719056 -297.32478) (xy 396.723016 -297.275726)
			(xy 396.734793 -297.227942) (xy 396.754084 -297.182666) (xy 396.780387 -297.14107) (xy 396.813022 -297.104233)
			(xy 396.851143 -297.073108) (xy 396.893764 -297.048501) (xy 396.93978 -297.031049) (xy 396.987999 -297.021205)
			(xy 397.037174 -297.019224) (xy 397.086029 -297.025156) (xy 397.1333 -297.038848) (xy 397.177762 -297.059946)
			(xy 397.218265 -297.087902) (xy 397.253758 -297.121994) (xy 397.283323 -297.161338) (xy 397.306194 -297.204915)
			(xy 397.321778 -297.251596) (xy 397.329673 -297.300173) (xy 397.330168 -297.32478) (xy 397.669016 -297.32478)
			(xy 397.672976 -297.275726) (xy 397.684753 -297.227942) (xy 397.704044 -297.182666) (xy 397.730347 -297.14107)
			(xy 397.762982 -297.104233) (xy 397.801103 -297.073108) (xy 397.843724 -297.048501) (xy 397.88974 -297.031049)
			(xy 397.937959 -297.021205) (xy 397.987134 -297.019224) (xy 398.035989 -297.025156) (xy 398.08326 -297.038848)
			(xy 398.127722 -297.059946) (xy 398.168225 -297.087902) (xy 398.203718 -297.121994) (xy 398.233283 -297.161338)
			(xy 398.256154 -297.204915) (xy 398.271738 -297.251596) (xy 398.279633 -297.300173) (xy 398.280128 -297.32478)
			(xy 398.61923 -297.32478) (xy 398.62319 -297.275726) (xy 398.634967 -297.227942) (xy 398.654258 -297.182666)
			(xy 398.680561 -297.14107) (xy 398.713196 -297.104233) (xy 398.751317 -297.073108) (xy 398.793938 -297.048501)
			(xy 398.839954 -297.031049) (xy 398.888173 -297.021205) (xy 398.937348 -297.019224) (xy 398.986203 -297.025156)
			(xy 399.033474 -297.038848) (xy 399.077936 -297.059946) (xy 399.118439 -297.087902) (xy 399.153932 -297.121994)
			(xy 399.183497 -297.161338) (xy 399.206368 -297.204915) (xy 399.221952 -297.251596) (xy 399.229847 -297.300173)
			(xy 399.230342 -297.32478) (xy 399.56919 -297.32478) (xy 399.57315 -297.275726) (xy 399.584927 -297.227942)
			(xy 399.604218 -297.182666) (xy 399.630521 -297.14107) (xy 399.663156 -297.104233) (xy 399.701277 -297.073108)
			(xy 399.743898 -297.048501) (xy 399.789914 -297.031049) (xy 399.838133 -297.021205) (xy 399.887308 -297.019224)
			(xy 399.936163 -297.025156) (xy 399.983434 -297.038848) (xy 400.027896 -297.059946) (xy 400.068399 -297.087902)
			(xy 400.103892 -297.121994) (xy 400.133457 -297.161338) (xy 400.156328 -297.204915) (xy 400.171912 -297.251596)
			(xy 400.179807 -297.300173) (xy 400.180302 -297.32478) (xy 400.51915 -297.32478) (xy 400.52311 -297.275726)
			(xy 400.534887 -297.227942) (xy 400.554178 -297.182666) (xy 400.580481 -297.14107) (xy 400.613116 -297.104233)
			(xy 400.651237 -297.073108) (xy 400.693858 -297.048501) (xy 400.739874 -297.031049) (xy 400.788093 -297.021205)
			(xy 400.837268 -297.019224) (xy 400.886123 -297.025156) (xy 400.933394 -297.038848) (xy 400.977856 -297.059946)
			(xy 401.018359 -297.087902) (xy 401.053852 -297.121994) (xy 401.083417 -297.161338) (xy 401.106288 -297.204915)
			(xy 401.121872 -297.251596) (xy 401.129767 -297.300173) (xy 401.130262 -297.32478) (xy 401.46911 -297.32478)
			(xy 401.47307 -297.275726) (xy 401.484847 -297.227942) (xy 401.504138 -297.182666) (xy 401.530441 -297.14107)
			(xy 401.563076 -297.104233) (xy 401.601197 -297.073108) (xy 401.643818 -297.048501) (xy 401.689834 -297.031049)
			(xy 401.738053 -297.021205) (xy 401.787228 -297.019224) (xy 401.836083 -297.025156) (xy 401.883354 -297.038848)
			(xy 401.927816 -297.059946) (xy 401.968319 -297.087902) (xy 402.003812 -297.121994) (xy 402.033377 -297.161338)
			(xy 402.056248 -297.204915) (xy 402.071832 -297.251596) (xy 402.079727 -297.300173) (xy 402.080222 -297.32478)
			(xy 402.41907 -297.32478) (xy 402.42303 -297.275726) (xy 402.434807 -297.227942) (xy 402.454098 -297.182666)
			(xy 402.480401 -297.14107) (xy 402.513036 -297.104233) (xy 402.551157 -297.073108) (xy 402.593778 -297.048501)
			(xy 402.639794 -297.031049) (xy 402.688013 -297.021205) (xy 402.737188 -297.019224) (xy 402.786043 -297.025156)
			(xy 402.833314 -297.038848) (xy 402.877776 -297.059946) (xy 402.918279 -297.087902) (xy 402.953772 -297.121994)
			(xy 402.983337 -297.161338) (xy 403.006208 -297.204915) (xy 403.021792 -297.251596) (xy 403.029687 -297.300173)
			(xy 403.030182 -297.32478) (xy 403.36903 -297.32478) (xy 403.37299 -297.275726) (xy 403.384767 -297.227942)
			(xy 403.404058 -297.182666) (xy 403.430361 -297.14107) (xy 403.462996 -297.104233) (xy 403.501117 -297.073108)
			(xy 403.543738 -297.048501) (xy 403.589754 -297.031049) (xy 403.637973 -297.021205) (xy 403.687148 -297.019224)
			(xy 403.736003 -297.025156) (xy 403.783274 -297.038848) (xy 403.827736 -297.059946) (xy 403.868239 -297.087902)
			(xy 403.903732 -297.121994) (xy 403.933297 -297.161338) (xy 403.956168 -297.204915) (xy 403.971752 -297.251596)
			(xy 403.979647 -297.300173) (xy 403.980142 -297.32478) (xy 404.31899 -297.32478) (xy 404.32295 -297.275726)
			(xy 404.334727 -297.227942) (xy 404.354018 -297.182666) (xy 404.380321 -297.14107) (xy 404.412956 -297.104233)
			(xy 404.451077 -297.073108) (xy 404.493698 -297.048501) (xy 404.539714 -297.031049) (xy 404.587933 -297.021205)
			(xy 404.637108 -297.019224) (xy 404.685963 -297.025156) (xy 404.733234 -297.038848) (xy 404.777696 -297.059946)
			(xy 404.818199 -297.087902) (xy 404.853692 -297.121994) (xy 404.883257 -297.161338) (xy 404.906128 -297.204915)
			(xy 404.921712 -297.251596) (xy 404.929607 -297.300173) (xy 404.930102 -297.32478) (xy 405.269204 -297.32478)
			(xy 405.273164 -297.275726) (xy 405.284941 -297.227942) (xy 405.304232 -297.182666) (xy 405.330535 -297.14107)
			(xy 405.36317 -297.104233) (xy 405.401291 -297.073108) (xy 405.443912 -297.048501) (xy 405.489928 -297.031049)
			(xy 405.538147 -297.021205) (xy 405.587322 -297.019224) (xy 405.636177 -297.025156) (xy 405.683448 -297.038848)
			(xy 405.72791 -297.059946) (xy 405.768413 -297.087902) (xy 405.803906 -297.121994) (xy 405.833471 -297.161338)
			(xy 405.856342 -297.204915) (xy 405.871926 -297.251596) (xy 405.879821 -297.300173) (xy 405.880316 -297.32478)
			(xy 406.219164 -297.32478) (xy 406.223124 -297.275726) (xy 406.234901 -297.227942) (xy 406.254192 -297.182666)
			(xy 406.280495 -297.14107) (xy 406.31313 -297.104233) (xy 406.351251 -297.073108) (xy 406.393872 -297.048501)
			(xy 406.439888 -297.031049) (xy 406.488107 -297.021205) (xy 406.537282 -297.019224) (xy 406.586137 -297.025156)
			(xy 406.633408 -297.038848) (xy 406.67787 -297.059946) (xy 406.718373 -297.087902) (xy 406.753866 -297.121994)
			(xy 406.783431 -297.161338) (xy 406.806302 -297.204915) (xy 406.821886 -297.251596) (xy 406.829781 -297.300173)
			(xy 406.830276 -297.32478) (xy 408.119084 -297.32478) (xy 408.123044 -297.275726) (xy 408.134821 -297.227942)
			(xy 408.154112 -297.182666) (xy 408.180415 -297.14107) (xy 408.21305 -297.104233) (xy 408.251171 -297.073108)
			(xy 408.293792 -297.048501) (xy 408.339808 -297.031049) (xy 408.388027 -297.021205) (xy 408.437202 -297.019224)
			(xy 408.486057 -297.025156) (xy 408.533328 -297.038848) (xy 408.57779 -297.059946) (xy 408.618293 -297.087902)
			(xy 408.653786 -297.121994) (xy 408.683351 -297.161338) (xy 408.706222 -297.204915) (xy 408.721806 -297.251596)
			(xy 408.729701 -297.300173) (xy 408.730196 -297.32478) (xy 409.069044 -297.32478) (xy 409.073004 -297.275726)
			(xy 409.084781 -297.227942) (xy 409.104072 -297.182666) (xy 409.130375 -297.14107) (xy 409.16301 -297.104233)
			(xy 409.201131 -297.073108) (xy 409.243752 -297.048501) (xy 409.289768 -297.031049) (xy 409.337987 -297.021205)
			(xy 409.387162 -297.019224) (xy 409.436017 -297.025156) (xy 409.483288 -297.038848) (xy 409.52775 -297.059946)
			(xy 409.568253 -297.087902) (xy 409.603746 -297.121994) (xy 409.633311 -297.161338) (xy 409.656182 -297.204915)
			(xy 409.671766 -297.251596) (xy 409.679661 -297.300173) (xy 409.680156 -297.32478) (xy 410.019004 -297.32478)
			(xy 410.022964 -297.275726) (xy 410.034741 -297.227942) (xy 410.054032 -297.182666) (xy 410.080335 -297.14107)
			(xy 410.11297 -297.104233) (xy 410.151091 -297.073108) (xy 410.193712 -297.048501) (xy 410.239728 -297.031049)
			(xy 410.287947 -297.021205) (xy 410.337122 -297.019224) (xy 410.385977 -297.025156) (xy 410.433248 -297.038848)
			(xy 410.47771 -297.059946) (xy 410.518213 -297.087902) (xy 410.553706 -297.121994) (xy 410.583271 -297.161338)
			(xy 410.606142 -297.204915) (xy 410.621726 -297.251596) (xy 410.629621 -297.300173) (xy 410.630116 -297.32478)
			(xy 410.969218 -297.32478) (xy 410.973178 -297.275726) (xy 410.984955 -297.227942) (xy 411.004246 -297.182666)
			(xy 411.030549 -297.14107) (xy 411.063184 -297.104233) (xy 411.101305 -297.073108) (xy 411.143926 -297.048501)
			(xy 411.189942 -297.031049) (xy 411.238161 -297.021205) (xy 411.287336 -297.019224) (xy 411.336191 -297.025156)
			(xy 411.383462 -297.038848) (xy 411.427924 -297.059946) (xy 411.468427 -297.087902) (xy 411.50392 -297.121994)
			(xy 411.533485 -297.161338) (xy 411.556356 -297.204915) (xy 411.57194 -297.251596) (xy 411.579835 -297.300173)
			(xy 411.58033 -297.32478) (xy 411.919178 -297.32478) (xy 411.923138 -297.275726) (xy 411.934915 -297.227942)
			(xy 411.954206 -297.182666) (xy 411.980509 -297.14107) (xy 412.013144 -297.104233) (xy 412.051265 -297.073108)
			(xy 412.093886 -297.048501) (xy 412.139902 -297.031049) (xy 412.188121 -297.021205) (xy 412.237296 -297.019224)
			(xy 412.286151 -297.025156) (xy 412.333422 -297.038848) (xy 412.377884 -297.059946) (xy 412.418387 -297.087902)
			(xy 412.45388 -297.121994) (xy 412.483445 -297.161338) (xy 412.506316 -297.204915) (xy 412.5219 -297.251596)
			(xy 412.529795 -297.300173) (xy 412.53029 -297.32478) (xy 412.869138 -297.32478) (xy 412.873098 -297.275726)
			(xy 412.884875 -297.227942) (xy 412.904166 -297.182666) (xy 412.930469 -297.14107) (xy 412.963104 -297.104233)
			(xy 413.001225 -297.073108) (xy 413.043846 -297.048501) (xy 413.089862 -297.031049) (xy 413.138081 -297.021205)
			(xy 413.187256 -297.019224) (xy 413.236111 -297.025156) (xy 413.283382 -297.038848) (xy 413.327844 -297.059946)
			(xy 413.368347 -297.087902) (xy 413.40384 -297.121994) (xy 413.433405 -297.161338) (xy 413.456276 -297.204915)
			(xy 413.47186 -297.251596) (xy 413.479755 -297.300173) (xy 413.48025 -297.32478) (xy 413.819098 -297.32478)
			(xy 413.823058 -297.275726) (xy 413.834835 -297.227942) (xy 413.854126 -297.182666) (xy 413.880429 -297.14107)
			(xy 413.913064 -297.104233) (xy 413.951185 -297.073108) (xy 413.993806 -297.048501) (xy 414.039822 -297.031049)
			(xy 414.088041 -297.021205) (xy 414.137216 -297.019224) (xy 414.186071 -297.025156) (xy 414.233342 -297.038848)
			(xy 414.277804 -297.059946) (xy 414.318307 -297.087902) (xy 414.3538 -297.121994) (xy 414.383365 -297.161338)
			(xy 414.406236 -297.204915) (xy 414.42182 -297.251596) (xy 414.429715 -297.300173) (xy 414.43021 -297.32478)
			(xy 414.429715 -297.349387) (xy 414.42182 -297.397964) (xy 414.406236 -297.444645) (xy 414.383365 -297.488222)
			(xy 414.3538 -297.527566) (xy 414.318307 -297.561658) (xy 414.277804 -297.589614) (xy 414.233342 -297.610712)
			(xy 414.186071 -297.624404) (xy 414.137216 -297.630336) (xy 414.088041 -297.628355) (xy 414.039822 -297.618511)
			(xy 413.993806 -297.601059) (xy 413.951185 -297.576452) (xy 413.913064 -297.545327) (xy 413.880429 -297.50849)
			(xy 413.854126 -297.466894) (xy 413.834835 -297.421618) (xy 413.823058 -297.373834) (xy 413.819098 -297.32478)
			(xy 413.48025 -297.32478) (xy 413.479755 -297.349387) (xy 413.47186 -297.397964) (xy 413.456276 -297.444645)
			(xy 413.433405 -297.488222) (xy 413.40384 -297.527566) (xy 413.368347 -297.561658) (xy 413.327844 -297.589614)
			(xy 413.283382 -297.610712) (xy 413.236111 -297.624404) (xy 413.187256 -297.630336) (xy 413.138081 -297.628355)
			(xy 413.089862 -297.618511) (xy 413.043846 -297.601059) (xy 413.001225 -297.576452) (xy 412.963104 -297.545327)
			(xy 412.930469 -297.50849) (xy 412.904166 -297.466894) (xy 412.884875 -297.421618) (xy 412.873098 -297.373834)
			(xy 412.869138 -297.32478) (xy 412.53029 -297.32478) (xy 412.529795 -297.349387) (xy 412.5219 -297.397964)
			(xy 412.506316 -297.444645) (xy 412.483445 -297.488222) (xy 412.45388 -297.527566) (xy 412.418387 -297.561658)
			(xy 412.377884 -297.589614) (xy 412.333422 -297.610712) (xy 412.286151 -297.624404) (xy 412.237296 -297.630336)
			(xy 412.188121 -297.628355) (xy 412.139902 -297.618511) (xy 412.093886 -297.601059) (xy 412.051265 -297.576452)
			(xy 412.013144 -297.545327) (xy 411.980509 -297.50849) (xy 411.954206 -297.466894) (xy 411.934915 -297.421618)
			(xy 411.923138 -297.373834) (xy 411.919178 -297.32478) (xy 411.58033 -297.32478) (xy 411.579835 -297.349387)
			(xy 411.57194 -297.397964) (xy 411.556356 -297.444645) (xy 411.533485 -297.488222) (xy 411.50392 -297.527566)
			(xy 411.468427 -297.561658) (xy 411.427924 -297.589614) (xy 411.383462 -297.610712) (xy 411.336191 -297.624404)
			(xy 411.287336 -297.630336) (xy 411.238161 -297.628355) (xy 411.189942 -297.618511) (xy 411.143926 -297.601059)
			(xy 411.101305 -297.576452) (xy 411.063184 -297.545327) (xy 411.030549 -297.50849) (xy 411.004246 -297.466894)
			(xy 410.984955 -297.421618) (xy 410.973178 -297.373834) (xy 410.969218 -297.32478) (xy 410.630116 -297.32478)
			(xy 410.629621 -297.349387) (xy 410.621726 -297.397964) (xy 410.606142 -297.444645) (xy 410.583271 -297.488222)
			(xy 410.553706 -297.527566) (xy 410.518213 -297.561658) (xy 410.47771 -297.589614) (xy 410.433248 -297.610712)
			(xy 410.385977 -297.624404) (xy 410.337122 -297.630336) (xy 410.287947 -297.628355) (xy 410.239728 -297.618511)
			(xy 410.193712 -297.601059) (xy 410.151091 -297.576452) (xy 410.11297 -297.545327) (xy 410.080335 -297.50849)
			(xy 410.054032 -297.466894) (xy 410.034741 -297.421618) (xy 410.022964 -297.373834) (xy 410.019004 -297.32478)
			(xy 409.680156 -297.32478) (xy 409.679661 -297.349387) (xy 409.671766 -297.397964) (xy 409.656182 -297.444645)
			(xy 409.633311 -297.488222) (xy 409.603746 -297.527566) (xy 409.568253 -297.561658) (xy 409.52775 -297.589614)
			(xy 409.483288 -297.610712) (xy 409.436017 -297.624404) (xy 409.387162 -297.630336) (xy 409.337987 -297.628355)
			(xy 409.289768 -297.618511) (xy 409.243752 -297.601059) (xy 409.201131 -297.576452) (xy 409.16301 -297.545327)
			(xy 409.130375 -297.50849) (xy 409.104072 -297.466894) (xy 409.084781 -297.421618) (xy 409.073004 -297.373834)
			(xy 409.069044 -297.32478) (xy 408.730196 -297.32478) (xy 408.729701 -297.349387) (xy 408.721806 -297.397964)
			(xy 408.706222 -297.444645) (xy 408.683351 -297.488222) (xy 408.653786 -297.527566) (xy 408.618293 -297.561658)
			(xy 408.57779 -297.589614) (xy 408.533328 -297.610712) (xy 408.486057 -297.624404) (xy 408.437202 -297.630336)
			(xy 408.388027 -297.628355) (xy 408.339808 -297.618511) (xy 408.293792 -297.601059) (xy 408.251171 -297.576452)
			(xy 408.21305 -297.545327) (xy 408.180415 -297.50849) (xy 408.154112 -297.466894) (xy 408.134821 -297.421618)
			(xy 408.123044 -297.373834) (xy 408.119084 -297.32478) (xy 406.830276 -297.32478) (xy 406.829781 -297.349387)
			(xy 406.821886 -297.397964) (xy 406.806302 -297.444645) (xy 406.783431 -297.488222) (xy 406.753866 -297.527566)
			(xy 406.718373 -297.561658) (xy 406.67787 -297.589614) (xy 406.633408 -297.610712) (xy 406.586137 -297.624404)
			(xy 406.537282 -297.630336) (xy 406.488107 -297.628355) (xy 406.439888 -297.618511) (xy 406.393872 -297.601059)
			(xy 406.351251 -297.576452) (xy 406.31313 -297.545327) (xy 406.280495 -297.50849) (xy 406.254192 -297.466894)
			(xy 406.234901 -297.421618) (xy 406.223124 -297.373834) (xy 406.219164 -297.32478) (xy 405.880316 -297.32478)
			(xy 405.879821 -297.349387) (xy 405.871926 -297.397964) (xy 405.856342 -297.444645) (xy 405.833471 -297.488222)
			(xy 405.803906 -297.527566) (xy 405.768413 -297.561658) (xy 405.72791 -297.589614) (xy 405.683448 -297.610712)
			(xy 405.636177 -297.624404) (xy 405.587322 -297.630336) (xy 405.538147 -297.628355) (xy 405.489928 -297.618511)
			(xy 405.443912 -297.601059) (xy 405.401291 -297.576452) (xy 405.36317 -297.545327) (xy 405.330535 -297.50849)
			(xy 405.304232 -297.466894) (xy 405.284941 -297.421618) (xy 405.273164 -297.373834) (xy 405.269204 -297.32478)
			(xy 404.930102 -297.32478) (xy 404.929607 -297.349387) (xy 404.921712 -297.397964) (xy 404.906128 -297.444645)
			(xy 404.883257 -297.488222) (xy 404.853692 -297.527566) (xy 404.818199 -297.561658) (xy 404.777696 -297.589614)
			(xy 404.733234 -297.610712) (xy 404.685963 -297.624404) (xy 404.637108 -297.630336) (xy 404.587933 -297.628355)
			(xy 404.539714 -297.618511) (xy 404.493698 -297.601059) (xy 404.451077 -297.576452) (xy 404.412956 -297.545327)
			(xy 404.380321 -297.50849) (xy 404.354018 -297.466894) (xy 404.334727 -297.421618) (xy 404.32295 -297.373834)
			(xy 404.31899 -297.32478) (xy 403.980142 -297.32478) (xy 403.979647 -297.349387) (xy 403.971752 -297.397964)
			(xy 403.956168 -297.444645) (xy 403.933297 -297.488222) (xy 403.903732 -297.527566) (xy 403.868239 -297.561658)
			(xy 403.827736 -297.589614) (xy 403.783274 -297.610712) (xy 403.736003 -297.624404) (xy 403.687148 -297.630336)
			(xy 403.637973 -297.628355) (xy 403.589754 -297.618511) (xy 403.543738 -297.601059) (xy 403.501117 -297.576452)
			(xy 403.462996 -297.545327) (xy 403.430361 -297.50849) (xy 403.404058 -297.466894) (xy 403.384767 -297.421618)
			(xy 403.37299 -297.373834) (xy 403.36903 -297.32478) (xy 403.030182 -297.32478) (xy 403.029687 -297.349387)
			(xy 403.021792 -297.397964) (xy 403.006208 -297.444645) (xy 402.983337 -297.488222) (xy 402.953772 -297.527566)
			(xy 402.918279 -297.561658) (xy 402.877776 -297.589614) (xy 402.833314 -297.610712) (xy 402.786043 -297.624404)
			(xy 402.737188 -297.630336) (xy 402.688013 -297.628355) (xy 402.639794 -297.618511) (xy 402.593778 -297.601059)
			(xy 402.551157 -297.576452) (xy 402.513036 -297.545327) (xy 402.480401 -297.50849) (xy 402.454098 -297.466894)
			(xy 402.434807 -297.421618) (xy 402.42303 -297.373834) (xy 402.41907 -297.32478) (xy 402.080222 -297.32478)
			(xy 402.079727 -297.349387) (xy 402.071832 -297.397964) (xy 402.056248 -297.444645) (xy 402.033377 -297.488222)
			(xy 402.003812 -297.527566) (xy 401.968319 -297.561658) (xy 401.927816 -297.589614) (xy 401.883354 -297.610712)
			(xy 401.836083 -297.624404) (xy 401.787228 -297.630336) (xy 401.738053 -297.628355) (xy 401.689834 -297.618511)
			(xy 401.643818 -297.601059) (xy 401.601197 -297.576452) (xy 401.563076 -297.545327) (xy 401.530441 -297.50849)
			(xy 401.504138 -297.466894) (xy 401.484847 -297.421618) (xy 401.47307 -297.373834) (xy 401.46911 -297.32478)
			(xy 401.130262 -297.32478) (xy 401.129767 -297.349387) (xy 401.121872 -297.397964) (xy 401.106288 -297.444645)
			(xy 401.083417 -297.488222) (xy 401.053852 -297.527566) (xy 401.018359 -297.561658) (xy 400.977856 -297.589614)
			(xy 400.933394 -297.610712) (xy 400.886123 -297.624404) (xy 400.837268 -297.630336) (xy 400.788093 -297.628355)
			(xy 400.739874 -297.618511) (xy 400.693858 -297.601059) (xy 400.651237 -297.576452) (xy 400.613116 -297.545327)
			(xy 400.580481 -297.50849) (xy 400.554178 -297.466894) (xy 400.534887 -297.421618) (xy 400.52311 -297.373834)
			(xy 400.51915 -297.32478) (xy 400.180302 -297.32478) (xy 400.179807 -297.349387) (xy 400.171912 -297.397964)
			(xy 400.156328 -297.444645) (xy 400.133457 -297.488222) (xy 400.103892 -297.527566) (xy 400.068399 -297.561658)
			(xy 400.027896 -297.589614) (xy 399.983434 -297.610712) (xy 399.936163 -297.624404) (xy 399.887308 -297.630336)
			(xy 399.838133 -297.628355) (xy 399.789914 -297.618511) (xy 399.743898 -297.601059) (xy 399.701277 -297.576452)
			(xy 399.663156 -297.545327) (xy 399.630521 -297.50849) (xy 399.604218 -297.466894) (xy 399.584927 -297.421618)
			(xy 399.57315 -297.373834) (xy 399.56919 -297.32478) (xy 399.230342 -297.32478) (xy 399.229847 -297.349387)
			(xy 399.221952 -297.397964) (xy 399.206368 -297.444645) (xy 399.183497 -297.488222) (xy 399.153932 -297.527566)
			(xy 399.118439 -297.561658) (xy 399.077936 -297.589614) (xy 399.033474 -297.610712) (xy 398.986203 -297.624404)
			(xy 398.937348 -297.630336) (xy 398.888173 -297.628355) (xy 398.839954 -297.618511) (xy 398.793938 -297.601059)
			(xy 398.751317 -297.576452) (xy 398.713196 -297.545327) (xy 398.680561 -297.50849) (xy 398.654258 -297.466894)
			(xy 398.634967 -297.421618) (xy 398.62319 -297.373834) (xy 398.61923 -297.32478) (xy 398.280128 -297.32478)
			(xy 398.279633 -297.349387) (xy 398.271738 -297.397964) (xy 398.256154 -297.444645) (xy 398.233283 -297.488222)
			(xy 398.203718 -297.527566) (xy 398.168225 -297.561658) (xy 398.127722 -297.589614) (xy 398.08326 -297.610712)
			(xy 398.035989 -297.624404) (xy 397.987134 -297.630336) (xy 397.937959 -297.628355) (xy 397.88974 -297.618511)
			(xy 397.843724 -297.601059) (xy 397.801103 -297.576452) (xy 397.762982 -297.545327) (xy 397.730347 -297.50849)
			(xy 397.704044 -297.466894) (xy 397.684753 -297.421618) (xy 397.672976 -297.373834) (xy 397.669016 -297.32478)
			(xy 397.330168 -297.32478) (xy 397.329673 -297.349387) (xy 397.321778 -297.397964) (xy 397.306194 -297.444645)
			(xy 397.283323 -297.488222) (xy 397.253758 -297.527566) (xy 397.218265 -297.561658) (xy 397.177762 -297.589614)
			(xy 397.1333 -297.610712) (xy 397.086029 -297.624404) (xy 397.037174 -297.630336) (xy 396.987999 -297.628355)
			(xy 396.93978 -297.618511) (xy 396.893764 -297.601059) (xy 396.851143 -297.576452) (xy 396.813022 -297.545327)
			(xy 396.780387 -297.50849) (xy 396.754084 -297.466894) (xy 396.734793 -297.421618) (xy 396.723016 -297.373834)
			(xy 396.719056 -297.32478) (xy 396.380709 -297.32478) (xy 396.380711 -297.3248) (xy 396.37654 -297.375135)
			(xy 396.364141 -297.424097) (xy 396.343853 -297.47035) (xy 396.316228 -297.512633) (xy 396.28202 -297.549792)
			(xy 396.242163 -297.580815) (xy 396.197743 -297.604854) (xy 396.149972 -297.621253) (xy 396.100154 -297.629567)
			(xy 396.0749 -297.630088) (xy 396.052523 -297.629706) (xy 396.008247 -297.623189) (xy 395.965396 -297.610279)
			(xy 395.924888 -297.591254) (xy 395.88759 -297.566521) (xy 395.870684 -297.551856) (xy 395.87043 -297.551856)
			(xy 395.862901 -297.545669) (xy 395.844608 -297.539001) (xy 395.82515 -297.53967) (xy 395.816074 -297.54322)
			(xy 395.731238 -297.580812) (xy 395.722449 -297.58519) (xy 395.708814 -297.599297) (xy 395.70146 -297.617485)
			(xy 395.701012 -297.627294) (xy 395.701012 -297.902884) (xy 395.700463 -297.929653) (xy 395.691096 -297.982365)
			(xy 395.67268 -298.032637) (xy 395.645781 -298.078927) (xy 395.611222 -298.119817) (xy 395.570062 -298.154055)
			(xy 395.547088 -298.167806) (xy 395.41069 -298.24553) (xy 395.404742 -298.24864) (xy 395.391747 -298.251979)
			(xy 395.385036 -298.252134) (xy 395.316964 -298.251626) (xy 395.288262 -298.276518) (xy 395.285468 -298.295822)
			(xy 395.284588 -298.305008) (xy 395.288707 -298.322982) (xy 395.298952 -298.338313) (xy 395.313983 -298.348995)
			(xy 395.322806 -298.351702) (xy 395.372336 -298.36491) (xy 395.378756 -298.366808) (xy 395.390341 -298.373508)
			(xy 395.395196 -298.378118) (xy 395.40561 -298.388532) (xy 395.413044 -298.395248) (xy 395.431544 -298.402884)
			(xy 395.451558 -298.402884) (xy 395.470058 -298.395248) (xy 395.477492 -298.388532) (xy 395.503146 -298.362878)
			(xy 395.510568 -298.356066) (xy 395.529151 -298.34833) (xy 395.539214 -298.347892) (xy 395.669008 -298.347892)
			(xy 395.678625 -298.347514) (xy 395.696515 -298.340459) (xy 395.703806 -298.334176) (xy 395.754352 -298.286932)
			(xy 395.76104 -298.280192) (xy 395.769257 -298.26309) (xy 395.770354 -298.253658) (xy 395.770354 -298.25315)
			(xy 395.772537 -298.229124) (xy 395.783483 -298.182141) (xy 395.801681 -298.137465) (xy 395.826679 -298.096206)
			(xy 395.857854 -298.059392) (xy 395.894431 -298.027939) (xy 395.935499 -298.002629) (xy 395.980037 -297.984093)
			(xy 396.026935 -297.972792) (xy 396.075027 -297.969007) (xy 396.123116 -297.972832) (xy 396.170005 -297.984172)
			(xy 396.214527 -298.002745) (xy 396.255574 -298.028089) (xy 396.292125 -298.059572) (xy 396.323269 -298.096412)
			(xy 396.348233 -298.137692) (xy 396.366394 -298.182383) (xy 396.3773 -298.229375) (xy 396.379446 -298.253404)
			(xy 396.379446 -298.253658) (xy 396.380536 -298.263089) (xy 396.388768 -298.280184) (xy 396.395448 -298.286932)
			(xy 396.445994 -298.334176) (xy 396.453312 -298.340416) (xy 396.471185 -298.347473) (xy 396.480792 -298.347892)
			(xy 396.618968 -298.347892) (xy 396.628583 -298.347494) (xy 396.646474 -298.340453) (xy 396.653766 -298.334176)
			(xy 396.704312 -298.286932) (xy 396.711009 -298.2802) (xy 396.719219 -298.263091) (xy 396.720314 -298.253658)
			(xy 396.720314 -298.25315) (xy 396.722698 -298.227799) (xy 396.734666 -298.178314) (xy 396.754679 -298.1315)
			(xy 396.78218 -298.088655) (xy 396.816408 -298.050965) (xy 396.856415 -298.019477) (xy 396.901091 -297.995062)
			(xy 396.949199 -297.978398) (xy 396.999404 -297.969945) (xy 397.02486 -297.969432) (xy 397.048854 -297.969875)
			(xy 397.096252 -297.977377) (xy 397.141893 -297.992203) (xy 397.184651 -298.013987) (xy 397.223475 -298.042192)
			(xy 397.257408 -298.076125) (xy 397.285613 -298.114949) (xy 397.307397 -298.157707) (xy 397.322223 -298.203348)
			(xy 397.329725 -298.250746) (xy 397.330168 -298.27474) (xy 397.669016 -298.27474) (xy 397.672976 -298.225686)
			(xy 397.684753 -298.177902) (xy 397.704044 -298.132626) (xy 397.730347 -298.09103) (xy 397.762982 -298.054193)
			(xy 397.801103 -298.023068) (xy 397.843724 -297.998461) (xy 397.88974 -297.981009) (xy 397.937959 -297.971165)
			(xy 397.987134 -297.969184) (xy 398.035989 -297.975116) (xy 398.08326 -297.988808) (xy 398.127722 -298.009906)
			(xy 398.168225 -298.037862) (xy 398.203718 -298.071954) (xy 398.233283 -298.111298) (xy 398.256154 -298.154875)
			(xy 398.271738 -298.201556) (xy 398.279633 -298.250133) (xy 398.280128 -298.27474) (xy 398.61923 -298.27474)
			(xy 398.62319 -298.225686) (xy 398.634967 -298.177902) (xy 398.654258 -298.132626) (xy 398.680561 -298.09103)
			(xy 398.713196 -298.054193) (xy 398.751317 -298.023068) (xy 398.793938 -297.998461) (xy 398.839954 -297.981009)
			(xy 398.888173 -297.971165) (xy 398.937348 -297.969184) (xy 398.986203 -297.975116) (xy 399.033474 -297.988808)
			(xy 399.077936 -298.009906) (xy 399.118439 -298.037862) (xy 399.153932 -298.071954) (xy 399.183497 -298.111298)
			(xy 399.206368 -298.154875) (xy 399.221952 -298.201556) (xy 399.229847 -298.250133) (xy 399.230342 -298.27474)
			(xy 399.56919 -298.27474) (xy 399.57315 -298.225686) (xy 399.584927 -298.177902) (xy 399.604218 -298.132626)
			(xy 399.630521 -298.09103) (xy 399.663156 -298.054193) (xy 399.701277 -298.023068) (xy 399.743898 -297.998461)
			(xy 399.789914 -297.981009) (xy 399.838133 -297.971165) (xy 399.887308 -297.969184) (xy 399.936163 -297.975116)
			(xy 399.983434 -297.988808) (xy 400.027896 -298.009906) (xy 400.068399 -298.037862) (xy 400.103892 -298.071954)
			(xy 400.133457 -298.111298) (xy 400.156328 -298.154875) (xy 400.171912 -298.201556) (xy 400.179807 -298.250133)
			(xy 400.180302 -298.27474) (xy 400.51915 -298.27474) (xy 400.52311 -298.225686) (xy 400.534887 -298.177902)
			(xy 400.554178 -298.132626) (xy 400.580481 -298.09103) (xy 400.613116 -298.054193) (xy 400.651237 -298.023068)
			(xy 400.693858 -297.998461) (xy 400.739874 -297.981009) (xy 400.788093 -297.971165) (xy 400.837268 -297.969184)
			(xy 400.886123 -297.975116) (xy 400.933394 -297.988808) (xy 400.977856 -298.009906) (xy 401.018359 -298.037862)
			(xy 401.053852 -298.071954) (xy 401.083417 -298.111298) (xy 401.106288 -298.154875) (xy 401.121872 -298.201556)
			(xy 401.129767 -298.250133) (xy 401.130262 -298.27474) (xy 401.46911 -298.27474) (xy 401.47307 -298.225686)
			(xy 401.484847 -298.177902) (xy 401.504138 -298.132626) (xy 401.530441 -298.09103) (xy 401.563076 -298.054193)
			(xy 401.601197 -298.023068) (xy 401.643818 -297.998461) (xy 401.689834 -297.981009) (xy 401.738053 -297.971165)
			(xy 401.787228 -297.969184) (xy 401.836083 -297.975116) (xy 401.883354 -297.988808) (xy 401.927816 -298.009906)
			(xy 401.968319 -298.037862) (xy 402.003812 -298.071954) (xy 402.033377 -298.111298) (xy 402.056248 -298.154875)
			(xy 402.071832 -298.201556) (xy 402.079727 -298.250133) (xy 402.080222 -298.27474) (xy 402.41907 -298.27474)
			(xy 402.42303 -298.225686) (xy 402.434807 -298.177902) (xy 402.454098 -298.132626) (xy 402.480401 -298.09103)
			(xy 402.513036 -298.054193) (xy 402.551157 -298.023068) (xy 402.593778 -297.998461) (xy 402.639794 -297.981009)
			(xy 402.688013 -297.971165) (xy 402.737188 -297.969184) (xy 402.786043 -297.975116) (xy 402.833314 -297.988808)
			(xy 402.877776 -298.009906) (xy 402.918279 -298.037862) (xy 402.953772 -298.071954) (xy 402.983337 -298.111298)
			(xy 403.006208 -298.154875) (xy 403.021792 -298.201556) (xy 403.029687 -298.250133) (xy 403.030182 -298.27474)
			(xy 403.36903 -298.27474) (xy 403.37299 -298.225686) (xy 403.384767 -298.177902) (xy 403.404058 -298.132626)
			(xy 403.430361 -298.09103) (xy 403.462996 -298.054193) (xy 403.501117 -298.023068) (xy 403.543738 -297.998461)
			(xy 403.589754 -297.981009) (xy 403.637973 -297.971165) (xy 403.687148 -297.969184) (xy 403.736003 -297.975116)
			(xy 403.783274 -297.988808) (xy 403.827736 -298.009906) (xy 403.868239 -298.037862) (xy 403.903732 -298.071954)
			(xy 403.933297 -298.111298) (xy 403.956168 -298.154875) (xy 403.971752 -298.201556) (xy 403.979647 -298.250133)
			(xy 403.980142 -298.27474) (xy 404.31899 -298.27474) (xy 404.32295 -298.225686) (xy 404.334727 -298.177902)
			(xy 404.354018 -298.132626) (xy 404.380321 -298.09103) (xy 404.412956 -298.054193) (xy 404.451077 -298.023068)
			(xy 404.493698 -297.998461) (xy 404.539714 -297.981009) (xy 404.587933 -297.971165) (xy 404.637108 -297.969184)
			(xy 404.685963 -297.975116) (xy 404.733234 -297.988808) (xy 404.777696 -298.009906) (xy 404.818199 -298.037862)
			(xy 404.853692 -298.071954) (xy 404.883257 -298.111298) (xy 404.906128 -298.154875) (xy 404.921712 -298.201556)
			(xy 404.929607 -298.250133) (xy 404.930102 -298.27474) (xy 405.269204 -298.27474) (xy 405.273164 -298.225686)
			(xy 405.284941 -298.177902) (xy 405.304232 -298.132626) (xy 405.330535 -298.09103) (xy 405.36317 -298.054193)
			(xy 405.401291 -298.023068) (xy 405.443912 -297.998461) (xy 405.489928 -297.981009) (xy 405.538147 -297.971165)
			(xy 405.587322 -297.969184) (xy 405.636177 -297.975116) (xy 405.683448 -297.988808) (xy 405.72791 -298.009906)
			(xy 405.768413 -298.037862) (xy 405.803906 -298.071954) (xy 405.833471 -298.111298) (xy 405.856342 -298.154875)
			(xy 405.871926 -298.201556) (xy 405.879821 -298.250133) (xy 405.880316 -298.27474) (xy 406.219164 -298.27474)
			(xy 406.223124 -298.225686) (xy 406.234901 -298.177902) (xy 406.254192 -298.132626) (xy 406.280495 -298.09103)
			(xy 406.31313 -298.054193) (xy 406.351251 -298.023068) (xy 406.393872 -297.998461) (xy 406.439888 -297.981009)
			(xy 406.488107 -297.971165) (xy 406.537282 -297.969184) (xy 406.586137 -297.975116) (xy 406.633408 -297.988808)
			(xy 406.67787 -298.009906) (xy 406.718373 -298.037862) (xy 406.753866 -298.071954) (xy 406.783431 -298.111298)
			(xy 406.806302 -298.154875) (xy 406.821886 -298.201556) (xy 406.829781 -298.250133) (xy 406.830276 -298.27474)
			(xy 408.119084 -298.27474) (xy 408.123044 -298.225686) (xy 408.134821 -298.177902) (xy 408.154112 -298.132626)
			(xy 408.180415 -298.09103) (xy 408.21305 -298.054193) (xy 408.251171 -298.023068) (xy 408.293792 -297.998461)
			(xy 408.339808 -297.981009) (xy 408.388027 -297.971165) (xy 408.437202 -297.969184) (xy 408.486057 -297.975116)
			(xy 408.533328 -297.988808) (xy 408.57779 -298.009906) (xy 408.618293 -298.037862) (xy 408.653786 -298.071954)
			(xy 408.683351 -298.111298) (xy 408.706222 -298.154875) (xy 408.721806 -298.201556) (xy 408.729701 -298.250133)
			(xy 408.730196 -298.27474) (xy 409.069044 -298.27474) (xy 409.073004 -298.225686) (xy 409.084781 -298.177902)
			(xy 409.104072 -298.132626) (xy 409.130375 -298.09103) (xy 409.16301 -298.054193) (xy 409.201131 -298.023068)
			(xy 409.243752 -297.998461) (xy 409.289768 -297.981009) (xy 409.337987 -297.971165) (xy 409.387162 -297.969184)
			(xy 409.436017 -297.975116) (xy 409.483288 -297.988808) (xy 409.52775 -298.009906) (xy 409.568253 -298.037862)
			(xy 409.603746 -298.071954) (xy 409.633311 -298.111298) (xy 409.656182 -298.154875) (xy 409.671766 -298.201556)
			(xy 409.679661 -298.250133) (xy 409.680156 -298.27474) (xy 410.019004 -298.27474) (xy 410.022964 -298.225686)
			(xy 410.034741 -298.177902) (xy 410.054032 -298.132626) (xy 410.080335 -298.09103) (xy 410.11297 -298.054193)
			(xy 410.151091 -298.023068) (xy 410.193712 -297.998461) (xy 410.239728 -297.981009) (xy 410.287947 -297.971165)
			(xy 410.337122 -297.969184) (xy 410.385977 -297.975116) (xy 410.433248 -297.988808) (xy 410.47771 -298.009906)
			(xy 410.518213 -298.037862) (xy 410.553706 -298.071954) (xy 410.583271 -298.111298) (xy 410.606142 -298.154875)
			(xy 410.621726 -298.201556) (xy 410.629621 -298.250133) (xy 410.630116 -298.27474) (xy 410.969218 -298.27474)
			(xy 410.973178 -298.225686) (xy 410.984955 -298.177902) (xy 411.004246 -298.132626) (xy 411.030549 -298.09103)
			(xy 411.063184 -298.054193) (xy 411.101305 -298.023068) (xy 411.143926 -297.998461) (xy 411.189942 -297.981009)
			(xy 411.238161 -297.971165) (xy 411.287336 -297.969184) (xy 411.336191 -297.975116) (xy 411.383462 -297.988808)
			(xy 411.427924 -298.009906) (xy 411.468427 -298.037862) (xy 411.50392 -298.071954) (xy 411.533485 -298.111298)
			(xy 411.556356 -298.154875) (xy 411.57194 -298.201556) (xy 411.579835 -298.250133) (xy 411.58033 -298.27474)
			(xy 411.919178 -298.27474) (xy 411.923138 -298.225686) (xy 411.934915 -298.177902) (xy 411.954206 -298.132626)
			(xy 411.980509 -298.09103) (xy 412.013144 -298.054193) (xy 412.051265 -298.023068) (xy 412.093886 -297.998461)
			(xy 412.139902 -297.981009) (xy 412.188121 -297.971165) (xy 412.237296 -297.969184) (xy 412.286151 -297.975116)
			(xy 412.333422 -297.988808) (xy 412.377884 -298.009906) (xy 412.418387 -298.037862) (xy 412.45388 -298.071954)
			(xy 412.483445 -298.111298) (xy 412.506316 -298.154875) (xy 412.5219 -298.201556) (xy 412.529795 -298.250133)
			(xy 412.53029 -298.27474) (xy 412.869138 -298.27474) (xy 412.873098 -298.225686) (xy 412.884875 -298.177902)
			(xy 412.904166 -298.132626) (xy 412.930469 -298.09103) (xy 412.963104 -298.054193) (xy 413.001225 -298.023068)
			(xy 413.043846 -297.998461) (xy 413.089862 -297.981009) (xy 413.138081 -297.971165) (xy 413.187256 -297.969184)
			(xy 413.236111 -297.975116) (xy 413.283382 -297.988808) (xy 413.327844 -298.009906) (xy 413.368347 -298.037862)
			(xy 413.40384 -298.071954) (xy 413.433405 -298.111298) (xy 413.456276 -298.154875) (xy 413.47186 -298.201556)
			(xy 413.479755 -298.250133) (xy 413.48025 -298.27474) (xy 413.819098 -298.27474) (xy 413.823058 -298.225686)
			(xy 413.834835 -298.177902) (xy 413.854126 -298.132626) (xy 413.880429 -298.09103) (xy 413.913064 -298.054193)
			(xy 413.951185 -298.023068) (xy 413.993806 -297.998461) (xy 414.039822 -297.981009) (xy 414.088041 -297.971165)
			(xy 414.137216 -297.969184) (xy 414.186071 -297.975116) (xy 414.233342 -297.988808) (xy 414.277804 -298.009906)
			(xy 414.318307 -298.037862) (xy 414.3538 -298.071954) (xy 414.383365 -298.111298) (xy 414.406236 -298.154875)
			(xy 414.42182 -298.201556) (xy 414.429715 -298.250133) (xy 414.43021 -298.27474) (xy 414.769058 -298.27474)
			(xy 414.773018 -298.225686) (xy 414.784795 -298.177902) (xy 414.804086 -298.132626) (xy 414.830389 -298.09103)
			(xy 414.863024 -298.054193) (xy 414.901145 -298.023068) (xy 414.943766 -297.998461) (xy 414.989782 -297.981009)
			(xy 415.038001 -297.971165) (xy 415.087176 -297.969184) (xy 415.136031 -297.975116) (xy 415.183302 -297.988808)
			(xy 415.227764 -298.009906) (xy 415.268267 -298.037862) (xy 415.30376 -298.071954) (xy 415.333325 -298.111298)
			(xy 415.356196 -298.154875) (xy 415.37178 -298.201556) (xy 415.379675 -298.250133) (xy 415.38017 -298.27474)
			(xy 415.719018 -298.27474) (xy 415.722978 -298.225686) (xy 415.734755 -298.177902) (xy 415.754046 -298.132626)
			(xy 415.780349 -298.09103) (xy 415.812984 -298.054193) (xy 415.851105 -298.023068) (xy 415.893726 -297.998461)
			(xy 415.939742 -297.981009) (xy 415.987961 -297.971165) (xy 416.037136 -297.969184) (xy 416.085991 -297.975116)
			(xy 416.133262 -297.988808) (xy 416.177724 -298.009906) (xy 416.218227 -298.037862) (xy 416.25372 -298.071954)
			(xy 416.283285 -298.111298) (xy 416.306156 -298.154875) (xy 416.32174 -298.201556) (xy 416.329635 -298.250133)
			(xy 416.33013 -298.27474) (xy 416.668978 -298.27474) (xy 416.672938 -298.225686) (xy 416.684715 -298.177902)
			(xy 416.704006 -298.132626) (xy 416.730309 -298.09103) (xy 416.762944 -298.054193) (xy 416.801065 -298.023068)
			(xy 416.843686 -297.998461) (xy 416.889702 -297.981009) (xy 416.937921 -297.971165) (xy 416.987096 -297.969184)
			(xy 417.035951 -297.975116) (xy 417.083222 -297.988808) (xy 417.127684 -298.009906) (xy 417.168187 -298.037862)
			(xy 417.20368 -298.071954) (xy 417.233245 -298.111298) (xy 417.256116 -298.154875) (xy 417.2717 -298.201556)
			(xy 417.279595 -298.250133) (xy 417.28009 -298.27474) (xy 417.279595 -298.299347) (xy 417.2717 -298.347924)
			(xy 417.256116 -298.394605) (xy 417.233245 -298.438182) (xy 417.20368 -298.477526) (xy 417.168187 -298.511618)
			(xy 417.127684 -298.539574) (xy 417.083222 -298.560672) (xy 417.035951 -298.574364) (xy 416.987096 -298.580296)
			(xy 416.937921 -298.578315) (xy 416.889702 -298.568471) (xy 416.843686 -298.551019) (xy 416.801065 -298.526412)
			(xy 416.762944 -298.495287) (xy 416.730309 -298.45845) (xy 416.704006 -298.416854) (xy 416.684715 -298.371578)
			(xy 416.672938 -298.323794) (xy 416.668978 -298.27474) (xy 416.33013 -298.27474) (xy 416.329635 -298.299347)
			(xy 416.32174 -298.347924) (xy 416.306156 -298.394605) (xy 416.283285 -298.438182) (xy 416.25372 -298.477526)
			(xy 416.218227 -298.511618) (xy 416.177724 -298.539574) (xy 416.133262 -298.560672) (xy 416.085991 -298.574364)
			(xy 416.037136 -298.580296) (xy 415.987961 -298.578315) (xy 415.939742 -298.568471) (xy 415.893726 -298.551019)
			(xy 415.851105 -298.526412) (xy 415.812984 -298.495287) (xy 415.780349 -298.45845) (xy 415.754046 -298.416854)
			(xy 415.734755 -298.371578) (xy 415.722978 -298.323794) (xy 415.719018 -298.27474) (xy 415.38017 -298.27474)
			(xy 415.379675 -298.299347) (xy 415.37178 -298.347924) (xy 415.356196 -298.394605) (xy 415.333325 -298.438182)
			(xy 415.30376 -298.477526) (xy 415.268267 -298.511618) (xy 415.227764 -298.539574) (xy 415.183302 -298.560672)
			(xy 415.136031 -298.574364) (xy 415.087176 -298.580296) (xy 415.038001 -298.578315) (xy 414.989782 -298.568471)
			(xy 414.943766 -298.551019) (xy 414.901145 -298.526412) (xy 414.863024 -298.495287) (xy 414.830389 -298.45845)
			(xy 414.804086 -298.416854) (xy 414.784795 -298.371578) (xy 414.773018 -298.323794) (xy 414.769058 -298.27474)
			(xy 414.43021 -298.27474) (xy 414.429715 -298.299347) (xy 414.42182 -298.347924) (xy 414.406236 -298.394605)
			(xy 414.383365 -298.438182) (xy 414.3538 -298.477526) (xy 414.318307 -298.511618) (xy 414.277804 -298.539574)
			(xy 414.233342 -298.560672) (xy 414.186071 -298.574364) (xy 414.137216 -298.580296) (xy 414.088041 -298.578315)
			(xy 414.039822 -298.568471) (xy 413.993806 -298.551019) (xy 413.951185 -298.526412) (xy 413.913064 -298.495287)
			(xy 413.880429 -298.45845) (xy 413.854126 -298.416854) (xy 413.834835 -298.371578) (xy 413.823058 -298.323794)
			(xy 413.819098 -298.27474) (xy 413.48025 -298.27474) (xy 413.479755 -298.299347) (xy 413.47186 -298.347924)
			(xy 413.456276 -298.394605) (xy 413.433405 -298.438182) (xy 413.40384 -298.477526) (xy 413.368347 -298.511618)
			(xy 413.327844 -298.539574) (xy 413.283382 -298.560672) (xy 413.236111 -298.574364) (xy 413.187256 -298.580296)
			(xy 413.138081 -298.578315) (xy 413.089862 -298.568471) (xy 413.043846 -298.551019) (xy 413.001225 -298.526412)
			(xy 412.963104 -298.495287) (xy 412.930469 -298.45845) (xy 412.904166 -298.416854) (xy 412.884875 -298.371578)
			(xy 412.873098 -298.323794) (xy 412.869138 -298.27474) (xy 412.53029 -298.27474) (xy 412.529795 -298.299347)
			(xy 412.5219 -298.347924) (xy 412.506316 -298.394605) (xy 412.483445 -298.438182) (xy 412.45388 -298.477526)
			(xy 412.418387 -298.511618) (xy 412.377884 -298.539574) (xy 412.333422 -298.560672) (xy 412.286151 -298.574364)
			(xy 412.237296 -298.580296) (xy 412.188121 -298.578315) (xy 412.139902 -298.568471) (xy 412.093886 -298.551019)
			(xy 412.051265 -298.526412) (xy 412.013144 -298.495287) (xy 411.980509 -298.45845) (xy 411.954206 -298.416854)
			(xy 411.934915 -298.371578) (xy 411.923138 -298.323794) (xy 411.919178 -298.27474) (xy 411.58033 -298.27474)
			(xy 411.579835 -298.299347) (xy 411.57194 -298.347924) (xy 411.556356 -298.394605) (xy 411.533485 -298.438182)
			(xy 411.50392 -298.477526) (xy 411.468427 -298.511618) (xy 411.427924 -298.539574) (xy 411.383462 -298.560672)
			(xy 411.336191 -298.574364) (xy 411.287336 -298.580296) (xy 411.238161 -298.578315) (xy 411.189942 -298.568471)
			(xy 411.143926 -298.551019) (xy 411.101305 -298.526412) (xy 411.063184 -298.495287) (xy 411.030549 -298.45845)
			(xy 411.004246 -298.416854) (xy 410.984955 -298.371578) (xy 410.973178 -298.323794) (xy 410.969218 -298.27474)
			(xy 410.630116 -298.27474) (xy 410.629621 -298.299347) (xy 410.621726 -298.347924) (xy 410.606142 -298.394605)
			(xy 410.583271 -298.438182) (xy 410.553706 -298.477526) (xy 410.518213 -298.511618) (xy 410.47771 -298.539574)
			(xy 410.433248 -298.560672) (xy 410.385977 -298.574364) (xy 410.337122 -298.580296) (xy 410.287947 -298.578315)
			(xy 410.239728 -298.568471) (xy 410.193712 -298.551019) (xy 410.151091 -298.526412) (xy 410.11297 -298.495287)
			(xy 410.080335 -298.45845) (xy 410.054032 -298.416854) (xy 410.034741 -298.371578) (xy 410.022964 -298.323794)
			(xy 410.019004 -298.27474) (xy 409.680156 -298.27474) (xy 409.679661 -298.299347) (xy 409.671766 -298.347924)
			(xy 409.656182 -298.394605) (xy 409.633311 -298.438182) (xy 409.603746 -298.477526) (xy 409.568253 -298.511618)
			(xy 409.52775 -298.539574) (xy 409.483288 -298.560672) (xy 409.436017 -298.574364) (xy 409.387162 -298.580296)
			(xy 409.337987 -298.578315) (xy 409.289768 -298.568471) (xy 409.243752 -298.551019) (xy 409.201131 -298.526412)
			(xy 409.16301 -298.495287) (xy 409.130375 -298.45845) (xy 409.104072 -298.416854) (xy 409.084781 -298.371578)
			(xy 409.073004 -298.323794) (xy 409.069044 -298.27474) (xy 408.730196 -298.27474) (xy 408.729701 -298.299347)
			(xy 408.721806 -298.347924) (xy 408.706222 -298.394605) (xy 408.683351 -298.438182) (xy 408.653786 -298.477526)
			(xy 408.618293 -298.511618) (xy 408.57779 -298.539574) (xy 408.533328 -298.560672) (xy 408.486057 -298.574364)
			(xy 408.437202 -298.580296) (xy 408.388027 -298.578315) (xy 408.339808 -298.568471) (xy 408.293792 -298.551019)
			(xy 408.251171 -298.526412) (xy 408.21305 -298.495287) (xy 408.180415 -298.45845) (xy 408.154112 -298.416854)
			(xy 408.134821 -298.371578) (xy 408.123044 -298.323794) (xy 408.119084 -298.27474) (xy 406.830276 -298.27474)
			(xy 406.829781 -298.299347) (xy 406.821886 -298.347924) (xy 406.806302 -298.394605) (xy 406.783431 -298.438182)
			(xy 406.753866 -298.477526) (xy 406.718373 -298.511618) (xy 406.67787 -298.539574) (xy 406.633408 -298.560672)
			(xy 406.586137 -298.574364) (xy 406.537282 -298.580296) (xy 406.488107 -298.578315) (xy 406.439888 -298.568471)
			(xy 406.393872 -298.551019) (xy 406.351251 -298.526412) (xy 406.31313 -298.495287) (xy 406.280495 -298.45845)
			(xy 406.254192 -298.416854) (xy 406.234901 -298.371578) (xy 406.223124 -298.323794) (xy 406.219164 -298.27474)
			(xy 405.880316 -298.27474) (xy 405.879821 -298.299347) (xy 405.871926 -298.347924) (xy 405.856342 -298.394605)
			(xy 405.833471 -298.438182) (xy 405.803906 -298.477526) (xy 405.768413 -298.511618) (xy 405.72791 -298.539574)
			(xy 405.683448 -298.560672) (xy 405.636177 -298.574364) (xy 405.587322 -298.580296) (xy 405.538147 -298.578315)
			(xy 405.489928 -298.568471) (xy 405.443912 -298.551019) (xy 405.401291 -298.526412) (xy 405.36317 -298.495287)
			(xy 405.330535 -298.45845) (xy 405.304232 -298.416854) (xy 405.284941 -298.371578) (xy 405.273164 -298.323794)
			(xy 405.269204 -298.27474) (xy 404.930102 -298.27474) (xy 404.929607 -298.299347) (xy 404.921712 -298.347924)
			(xy 404.906128 -298.394605) (xy 404.883257 -298.438182) (xy 404.853692 -298.477526) (xy 404.818199 -298.511618)
			(xy 404.777696 -298.539574) (xy 404.733234 -298.560672) (xy 404.685963 -298.574364) (xy 404.637108 -298.580296)
			(xy 404.587933 -298.578315) (xy 404.539714 -298.568471) (xy 404.493698 -298.551019) (xy 404.451077 -298.526412)
			(xy 404.412956 -298.495287) (xy 404.380321 -298.45845) (xy 404.354018 -298.416854) (xy 404.334727 -298.371578)
			(xy 404.32295 -298.323794) (xy 404.31899 -298.27474) (xy 403.980142 -298.27474) (xy 403.979647 -298.299347)
			(xy 403.971752 -298.347924) (xy 403.956168 -298.394605) (xy 403.933297 -298.438182) (xy 403.903732 -298.477526)
			(xy 403.868239 -298.511618) (xy 403.827736 -298.539574) (xy 403.783274 -298.560672) (xy 403.736003 -298.574364)
			(xy 403.687148 -298.580296) (xy 403.637973 -298.578315) (xy 403.589754 -298.568471) (xy 403.543738 -298.551019)
			(xy 403.501117 -298.526412) (xy 403.462996 -298.495287) (xy 403.430361 -298.45845) (xy 403.404058 -298.416854)
			(xy 403.384767 -298.371578) (xy 403.37299 -298.323794) (xy 403.36903 -298.27474) (xy 403.030182 -298.27474)
			(xy 403.029687 -298.299347) (xy 403.021792 -298.347924) (xy 403.006208 -298.394605) (xy 402.983337 -298.438182)
			(xy 402.953772 -298.477526) (xy 402.918279 -298.511618) (xy 402.877776 -298.539574) (xy 402.833314 -298.560672)
			(xy 402.786043 -298.574364) (xy 402.737188 -298.580296) (xy 402.688013 -298.578315) (xy 402.639794 -298.568471)
			(xy 402.593778 -298.551019) (xy 402.551157 -298.526412) (xy 402.513036 -298.495287) (xy 402.480401 -298.45845)
			(xy 402.454098 -298.416854) (xy 402.434807 -298.371578) (xy 402.42303 -298.323794) (xy 402.41907 -298.27474)
			(xy 402.080222 -298.27474) (xy 402.079727 -298.299347) (xy 402.071832 -298.347924) (xy 402.056248 -298.394605)
			(xy 402.033377 -298.438182) (xy 402.003812 -298.477526) (xy 401.968319 -298.511618) (xy 401.927816 -298.539574)
			(xy 401.883354 -298.560672) (xy 401.836083 -298.574364) (xy 401.787228 -298.580296) (xy 401.738053 -298.578315)
			(xy 401.689834 -298.568471) (xy 401.643818 -298.551019) (xy 401.601197 -298.526412) (xy 401.563076 -298.495287)
			(xy 401.530441 -298.45845) (xy 401.504138 -298.416854) (xy 401.484847 -298.371578) (xy 401.47307 -298.323794)
			(xy 401.46911 -298.27474) (xy 401.130262 -298.27474) (xy 401.129767 -298.299347) (xy 401.121872 -298.347924)
			(xy 401.106288 -298.394605) (xy 401.083417 -298.438182) (xy 401.053852 -298.477526) (xy 401.018359 -298.511618)
			(xy 400.977856 -298.539574) (xy 400.933394 -298.560672) (xy 400.886123 -298.574364) (xy 400.837268 -298.580296)
			(xy 400.788093 -298.578315) (xy 400.739874 -298.568471) (xy 400.693858 -298.551019) (xy 400.651237 -298.526412)
			(xy 400.613116 -298.495287) (xy 400.580481 -298.45845) (xy 400.554178 -298.416854) (xy 400.534887 -298.371578)
			(xy 400.52311 -298.323794) (xy 400.51915 -298.27474) (xy 400.180302 -298.27474) (xy 400.179807 -298.299347)
			(xy 400.171912 -298.347924) (xy 400.156328 -298.394605) (xy 400.133457 -298.438182) (xy 400.103892 -298.477526)
			(xy 400.068399 -298.511618) (xy 400.027896 -298.539574) (xy 399.983434 -298.560672) (xy 399.936163 -298.574364)
			(xy 399.887308 -298.580296) (xy 399.838133 -298.578315) (xy 399.789914 -298.568471) (xy 399.743898 -298.551019)
			(xy 399.701277 -298.526412) (xy 399.663156 -298.495287) (xy 399.630521 -298.45845) (xy 399.604218 -298.416854)
			(xy 399.584927 -298.371578) (xy 399.57315 -298.323794) (xy 399.56919 -298.27474) (xy 399.230342 -298.27474)
			(xy 399.229847 -298.299347) (xy 399.221952 -298.347924) (xy 399.206368 -298.394605) (xy 399.183497 -298.438182)
			(xy 399.153932 -298.477526) (xy 399.118439 -298.511618) (xy 399.077936 -298.539574) (xy 399.033474 -298.560672)
			(xy 398.986203 -298.574364) (xy 398.937348 -298.580296) (xy 398.888173 -298.578315) (xy 398.839954 -298.568471)
			(xy 398.793938 -298.551019) (xy 398.751317 -298.526412) (xy 398.713196 -298.495287) (xy 398.680561 -298.45845)
			(xy 398.654258 -298.416854) (xy 398.634967 -298.371578) (xy 398.62319 -298.323794) (xy 398.61923 -298.27474)
			(xy 398.280128 -298.27474) (xy 398.279633 -298.299347) (xy 398.271738 -298.347924) (xy 398.256154 -298.394605)
			(xy 398.233283 -298.438182) (xy 398.203718 -298.477526) (xy 398.168225 -298.511618) (xy 398.127722 -298.539574)
			(xy 398.08326 -298.560672) (xy 398.035989 -298.574364) (xy 397.987134 -298.580296) (xy 397.937959 -298.578315)
			(xy 397.88974 -298.568471) (xy 397.843724 -298.551019) (xy 397.801103 -298.526412) (xy 397.762982 -298.495287)
			(xy 397.730347 -298.45845) (xy 397.704044 -298.416854) (xy 397.684753 -298.371578) (xy 397.672976 -298.323794)
			(xy 397.669016 -298.27474) (xy 397.330168 -298.27474) (xy 397.329681 -298.299108) (xy 397.321889 -298.347217)
			(xy 397.314674 -298.370498) (xy 397.312114 -298.37954) (xy 397.313056 -298.398294) (xy 397.320715 -298.415439)
			(xy 397.32712 -298.422314) (xy 397.56461 -298.659804) (xy 397.571446 -298.667208) (xy 397.579168 -298.685804)
			(xy 397.579596 -298.695872) (xy 397.579596 -298.943268) (xy 397.580046 -298.953337) (xy 397.587856 -298.971904)
			(xy 397.602178 -298.986067) (xy 397.611346 -298.990258) (xy 397.698976 -299.025564) (xy 397.70853 -299.028865)
			(xy 397.728722 -299.028576) (xy 397.747265 -299.020576) (xy 397.754602 -299.013626) (xy 397.754602 -299.013372)
			(xy 397.77201 -298.995976) (xy 397.81137 -298.966438) (xy 397.854955 -298.943589) (xy 397.901639 -298.928022)
			(xy 397.950214 -298.920138) (xy 397.97482 -298.919646) (xy 398.00007 -298.920261) (xy 398.049882 -298.928576)
			(xy 398.097646 -298.944976) (xy 398.142059 -298.969014) (xy 398.18191 -299.000034) (xy 398.216113 -299.03719)
			(xy 398.243733 -299.079468) (xy 398.264018 -299.125716) (xy 398.276415 -299.174672) (xy 398.280581 -299.224954)
			(xy 416.668978 -299.224954) (xy 416.672938 -299.1759) (xy 416.684715 -299.128116) (xy 416.704006 -299.08284)
			(xy 416.730309 -299.041244) (xy 416.762944 -299.004407) (xy 416.801065 -298.973282) (xy 416.843686 -298.948675)
			(xy 416.889702 -298.931223) (xy 416.937921 -298.921379) (xy 416.987096 -298.919398) (xy 417.035951 -298.92533)
			(xy 417.083222 -298.939022) (xy 417.127684 -298.96012) (xy 417.168187 -298.988076) (xy 417.20368 -299.022168)
			(xy 417.233245 -299.061512) (xy 417.256116 -299.105089) (xy 417.2717 -299.15177) (xy 417.279595 -299.200347)
			(xy 417.28009 -299.224954) (xy 417.279595 -299.249561) (xy 417.2717 -299.298138) (xy 417.256116 -299.344819)
			(xy 417.233245 -299.388396) (xy 417.20368 -299.42774) (xy 417.168187 -299.461832) (xy 417.127684 -299.489788)
			(xy 417.083222 -299.510886) (xy 417.035951 -299.524578) (xy 416.987096 -299.53051) (xy 416.937921 -299.528529)
			(xy 416.889702 -299.518685) (xy 416.843686 -299.501233) (xy 416.801065 -299.476626) (xy 416.762944 -299.445501)
			(xy 416.730309 -299.408664) (xy 416.704006 -299.367068) (xy 416.684715 -299.321792) (xy 416.672938 -299.274008)
			(xy 416.668978 -299.224954) (xy 398.280581 -299.224954) (xy 398.280585 -299.225) (xy 398.276415 -299.275328)
			(xy 398.264018 -299.324284) (xy 398.243733 -299.370532) (xy 398.216113 -299.41281) (xy 398.18191 -299.449966)
			(xy 398.142059 -299.480986) (xy 398.097646 -299.505024) (xy 398.049882 -299.521424) (xy 398.00007 -299.529739)
			(xy 397.97482 -299.530262) (xy 397.950215 -299.529759) (xy 397.901642 -299.521876) (xy 397.854959 -299.506309)
			(xy 397.811375 -299.483462) (xy 397.772016 -299.453925) (xy 397.754602 -299.436536) (xy 397.754602 -299.436282)
			(xy 397.747296 -299.429274) (xy 397.728744 -299.42121) (xy 397.708516 -299.420956) (xy 397.698976 -299.424344)
			(xy 397.611346 -299.45965) (xy 397.602172 -299.463845) (xy 397.587808 -299.477976) (xy 397.580028 -299.496564)
			(xy 397.579596 -299.50664) (xy 397.579596 -299.893228) (xy 397.580076 -299.903294) (xy 397.587871 -299.92186)
			(xy 397.602183 -299.936025) (xy 397.611346 -299.940218) (xy 397.698976 -299.975524) (xy 397.708527 -299.978836)
			(xy 397.728723 -299.978547) (xy 397.747267 -299.970541) (xy 397.754602 -299.963586) (xy 397.754602 -299.963332)
			(xy 397.772003 -299.945929) (xy 397.811366 -299.916393) (xy 397.854953 -299.893547) (xy 397.901638 -299.877981)
			(xy 397.950214 -299.870098) (xy 397.97482 -299.869606) (xy 398.000075 -299.870101) (xy 398.049897 -299.878418)
			(xy 398.09767 -299.894821) (xy 398.142092 -299.918864) (xy 398.181951 -299.94989) (xy 398.21616 -299.987053)
			(xy 398.243786 -300.029339) (xy 398.264075 -300.075596) (xy 398.276474 -300.124562) (xy 398.280645 -300.1749)
			(xy 398.280644 -300.174914) (xy 398.61923 -300.174914) (xy 398.62319 -300.12586) (xy 398.634967 -300.078076)
			(xy 398.654258 -300.0328) (xy 398.680561 -299.991204) (xy 398.713196 -299.954367) (xy 398.751317 -299.923242)
			(xy 398.793938 -299.898635) (xy 398.839954 -299.881183) (xy 398.888173 -299.871339) (xy 398.937348 -299.869358)
			(xy 398.986203 -299.87529) (xy 399.033474 -299.888982) (xy 399.077936 -299.91008) (xy 399.118439 -299.938036)
			(xy 399.153932 -299.972128) (xy 399.183497 -300.011472) (xy 399.206368 -300.055049) (xy 399.221952 -300.10173)
			(xy 399.229847 -300.150307) (xy 399.230342 -300.174914) (xy 399.56919 -300.174914) (xy 399.57315 -300.12586)
			(xy 399.584927 -300.078076) (xy 399.604218 -300.0328) (xy 399.630521 -299.991204) (xy 399.663156 -299.954367)
			(xy 399.701277 -299.923242) (xy 399.743898 -299.898635) (xy 399.789914 -299.881183) (xy 399.838133 -299.871339)
			(xy 399.887308 -299.869358) (xy 399.936163 -299.87529) (xy 399.983434 -299.888982) (xy 400.027896 -299.91008)
			(xy 400.068399 -299.938036) (xy 400.103892 -299.972128) (xy 400.133457 -300.011472) (xy 400.156328 -300.055049)
			(xy 400.171912 -300.10173) (xy 400.179807 -300.150307) (xy 400.180302 -300.174914) (xy 400.51915 -300.174914)
			(xy 400.52311 -300.12586) (xy 400.534887 -300.078076) (xy 400.554178 -300.0328) (xy 400.580481 -299.991204)
			(xy 400.613116 -299.954367) (xy 400.651237 -299.923242) (xy 400.693858 -299.898635) (xy 400.739874 -299.881183)
			(xy 400.788093 -299.871339) (xy 400.837268 -299.869358) (xy 400.886123 -299.87529) (xy 400.933394 -299.888982)
			(xy 400.977856 -299.91008) (xy 401.018359 -299.938036) (xy 401.053852 -299.972128) (xy 401.083417 -300.011472)
			(xy 401.106288 -300.055049) (xy 401.121872 -300.10173) (xy 401.129767 -300.150307) (xy 401.130262 -300.174914)
			(xy 401.46911 -300.174914) (xy 401.47307 -300.12586) (xy 401.484847 -300.078076) (xy 401.504138 -300.0328)
			(xy 401.530441 -299.991204) (xy 401.563076 -299.954367) (xy 401.601197 -299.923242) (xy 401.643818 -299.898635)
			(xy 401.689834 -299.881183) (xy 401.738053 -299.871339) (xy 401.787228 -299.869358) (xy 401.836083 -299.87529)
			(xy 401.883354 -299.888982) (xy 401.927816 -299.91008) (xy 401.968319 -299.938036) (xy 402.003812 -299.972128)
			(xy 402.033377 -300.011472) (xy 402.056248 -300.055049) (xy 402.071832 -300.10173) (xy 402.079727 -300.150307)
			(xy 402.080222 -300.174914) (xy 402.41907 -300.174914) (xy 402.42303 -300.12586) (xy 402.434807 -300.078076)
			(xy 402.454098 -300.0328) (xy 402.480401 -299.991204) (xy 402.513036 -299.954367) (xy 402.551157 -299.923242)
			(xy 402.593778 -299.898635) (xy 402.639794 -299.881183) (xy 402.688013 -299.871339) (xy 402.737188 -299.869358)
			(xy 402.786043 -299.87529) (xy 402.833314 -299.888982) (xy 402.877776 -299.91008) (xy 402.918279 -299.938036)
			(xy 402.953772 -299.972128) (xy 402.983337 -300.011472) (xy 403.006208 -300.055049) (xy 403.021792 -300.10173)
			(xy 403.029687 -300.150307) (xy 403.030182 -300.174914) (xy 403.36903 -300.174914) (xy 403.37299 -300.12586)
			(xy 403.384767 -300.078076) (xy 403.404058 -300.0328) (xy 403.430361 -299.991204) (xy 403.462996 -299.954367)
			(xy 403.501117 -299.923242) (xy 403.543738 -299.898635) (xy 403.589754 -299.881183) (xy 403.637973 -299.871339)
			(xy 403.687148 -299.869358) (xy 403.736003 -299.87529) (xy 403.783274 -299.888982) (xy 403.827736 -299.91008)
			(xy 403.868239 -299.938036) (xy 403.903732 -299.972128) (xy 403.933297 -300.011472) (xy 403.956168 -300.055049)
			(xy 403.971752 -300.10173) (xy 403.979647 -300.150307) (xy 403.980142 -300.174914) (xy 404.31899 -300.174914)
			(xy 404.32295 -300.12586) (xy 404.334727 -300.078076) (xy 404.354018 -300.0328) (xy 404.380321 -299.991204)
			(xy 404.412956 -299.954367) (xy 404.451077 -299.923242) (xy 404.493698 -299.898635) (xy 404.539714 -299.881183)
			(xy 404.587933 -299.871339) (xy 404.637108 -299.869358) (xy 404.685963 -299.87529) (xy 404.733234 -299.888982)
			(xy 404.777696 -299.91008) (xy 404.818199 -299.938036) (xy 404.853692 -299.972128) (xy 404.883257 -300.011472)
			(xy 404.906128 -300.055049) (xy 404.921712 -300.10173) (xy 404.929607 -300.150307) (xy 404.930102 -300.174914)
			(xy 405.269204 -300.174914) (xy 405.273164 -300.12586) (xy 405.284941 -300.078076) (xy 405.304232 -300.0328)
			(xy 405.330535 -299.991204) (xy 405.36317 -299.954367) (xy 405.401291 -299.923242) (xy 405.443912 -299.898635)
			(xy 405.489928 -299.881183) (xy 405.538147 -299.871339) (xy 405.587322 -299.869358) (xy 405.636177 -299.87529)
			(xy 405.683448 -299.888982) (xy 405.72791 -299.91008) (xy 405.768413 -299.938036) (xy 405.803906 -299.972128)
			(xy 405.833471 -300.011472) (xy 405.856342 -300.055049) (xy 405.871926 -300.10173) (xy 405.879821 -300.150307)
			(xy 405.880316 -300.174914) (xy 406.219164 -300.174914) (xy 406.223124 -300.12586) (xy 406.234901 -300.078076)
			(xy 406.254192 -300.0328) (xy 406.280495 -299.991204) (xy 406.31313 -299.954367) (xy 406.351251 -299.923242)
			(xy 406.393872 -299.898635) (xy 406.439888 -299.881183) (xy 406.488107 -299.871339) (xy 406.537282 -299.869358)
			(xy 406.586137 -299.87529) (xy 406.633408 -299.888982) (xy 406.67787 -299.91008) (xy 406.718373 -299.938036)
			(xy 406.753866 -299.972128) (xy 406.783431 -300.011472) (xy 406.806302 -300.055049) (xy 406.821886 -300.10173)
			(xy 406.829781 -300.150307) (xy 406.830276 -300.174914) (xy 408.119084 -300.174914) (xy 408.123044 -300.12586)
			(xy 408.134821 -300.078076) (xy 408.154112 -300.0328) (xy 408.180415 -299.991204) (xy 408.21305 -299.954367)
			(xy 408.251171 -299.923242) (xy 408.293792 -299.898635) (xy 408.339808 -299.881183) (xy 408.388027 -299.871339)
			(xy 408.437202 -299.869358) (xy 408.486057 -299.87529) (xy 408.533328 -299.888982) (xy 408.57779 -299.91008)
			(xy 408.618293 -299.938036) (xy 408.653786 -299.972128) (xy 408.683351 -300.011472) (xy 408.706222 -300.055049)
			(xy 408.721806 -300.10173) (xy 408.729701 -300.150307) (xy 408.730196 -300.174914) (xy 409.069044 -300.174914)
			(xy 409.073004 -300.12586) (xy 409.084781 -300.078076) (xy 409.104072 -300.0328) (xy 409.130375 -299.991204)
			(xy 409.16301 -299.954367) (xy 409.201131 -299.923242) (xy 409.243752 -299.898635) (xy 409.289768 -299.881183)
			(xy 409.337987 -299.871339) (xy 409.387162 -299.869358) (xy 409.436017 -299.87529) (xy 409.483288 -299.888982)
			(xy 409.52775 -299.91008) (xy 409.568253 -299.938036) (xy 409.603746 -299.972128) (xy 409.633311 -300.011472)
			(xy 409.656182 -300.055049) (xy 409.671766 -300.10173) (xy 409.679661 -300.150307) (xy 409.680156 -300.174914)
			(xy 410.019004 -300.174914) (xy 410.022964 -300.12586) (xy 410.034741 -300.078076) (xy 410.054032 -300.0328)
			(xy 410.080335 -299.991204) (xy 410.11297 -299.954367) (xy 410.151091 -299.923242) (xy 410.193712 -299.898635)
			(xy 410.239728 -299.881183) (xy 410.287947 -299.871339) (xy 410.337122 -299.869358) (xy 410.385977 -299.87529)
			(xy 410.433248 -299.888982) (xy 410.47771 -299.91008) (xy 410.518213 -299.938036) (xy 410.553706 -299.972128)
			(xy 410.583271 -300.011472) (xy 410.606142 -300.055049) (xy 410.621726 -300.10173) (xy 410.629621 -300.150307)
			(xy 410.630116 -300.174914) (xy 410.969218 -300.174914) (xy 410.973178 -300.12586) (xy 410.984955 -300.078076)
			(xy 411.004246 -300.0328) (xy 411.030549 -299.991204) (xy 411.063184 -299.954367) (xy 411.101305 -299.923242)
			(xy 411.143926 -299.898635) (xy 411.189942 -299.881183) (xy 411.238161 -299.871339) (xy 411.287336 -299.869358)
			(xy 411.336191 -299.87529) (xy 411.383462 -299.888982) (xy 411.427924 -299.91008) (xy 411.468427 -299.938036)
			(xy 411.50392 -299.972128) (xy 411.533485 -300.011472) (xy 411.556356 -300.055049) (xy 411.57194 -300.10173)
			(xy 411.579835 -300.150307) (xy 411.58033 -300.174914) (xy 411.919178 -300.174914) (xy 411.923138 -300.12586)
			(xy 411.934915 -300.078076) (xy 411.954206 -300.0328) (xy 411.980509 -299.991204) (xy 412.013144 -299.954367)
			(xy 412.051265 -299.923242) (xy 412.093886 -299.898635) (xy 412.139902 -299.881183) (xy 412.188121 -299.871339)
			(xy 412.237296 -299.869358) (xy 412.286151 -299.87529) (xy 412.333422 -299.888982) (xy 412.377884 -299.91008)
			(xy 412.418387 -299.938036) (xy 412.45388 -299.972128) (xy 412.483445 -300.011472) (xy 412.506316 -300.055049)
			(xy 412.5219 -300.10173) (xy 412.529795 -300.150307) (xy 412.53029 -300.174914) (xy 412.869138 -300.174914)
			(xy 412.873098 -300.12586) (xy 412.884875 -300.078076) (xy 412.904166 -300.0328) (xy 412.930469 -299.991204)
			(xy 412.963104 -299.954367) (xy 413.001225 -299.923242) (xy 413.043846 -299.898635) (xy 413.089862 -299.881183)
			(xy 413.138081 -299.871339) (xy 413.187256 -299.869358) (xy 413.236111 -299.87529) (xy 413.283382 -299.888982)
			(xy 413.327844 -299.91008) (xy 413.368347 -299.938036) (xy 413.40384 -299.972128) (xy 413.433405 -300.011472)
			(xy 413.456276 -300.055049) (xy 413.47186 -300.10173) (xy 413.479755 -300.150307) (xy 413.48025 -300.174914)
			(xy 413.819098 -300.174914) (xy 413.823058 -300.12586) (xy 413.834835 -300.078076) (xy 413.854126 -300.0328)
			(xy 413.880429 -299.991204) (xy 413.913064 -299.954367) (xy 413.951185 -299.923242) (xy 413.993806 -299.898635)
			(xy 414.039822 -299.881183) (xy 414.088041 -299.871339) (xy 414.137216 -299.869358) (xy 414.186071 -299.87529)
			(xy 414.233342 -299.888982) (xy 414.277804 -299.91008) (xy 414.318307 -299.938036) (xy 414.3538 -299.972128)
			(xy 414.383365 -300.011472) (xy 414.406236 -300.055049) (xy 414.42182 -300.10173) (xy 414.429715 -300.150307)
			(xy 414.43021 -300.174914) (xy 414.769058 -300.174914) (xy 414.773018 -300.12586) (xy 414.784795 -300.078076)
			(xy 414.804086 -300.0328) (xy 414.830389 -299.991204) (xy 414.863024 -299.954367) (xy 414.901145 -299.923242)
			(xy 414.943766 -299.898635) (xy 414.989782 -299.881183) (xy 415.038001 -299.871339) (xy 415.087176 -299.869358)
			(xy 415.136031 -299.87529) (xy 415.183302 -299.888982) (xy 415.227764 -299.91008) (xy 415.268267 -299.938036)
			(xy 415.30376 -299.972128) (xy 415.333325 -300.011472) (xy 415.356196 -300.055049) (xy 415.37178 -300.10173)
			(xy 415.379675 -300.150307) (xy 415.38017 -300.174914) (xy 415.719018 -300.174914) (xy 415.722978 -300.12586)
			(xy 415.734755 -300.078076) (xy 415.754046 -300.0328) (xy 415.780349 -299.991204) (xy 415.812984 -299.954367)
			(xy 415.851105 -299.923242) (xy 415.893726 -299.898635) (xy 415.939742 -299.881183) (xy 415.987961 -299.871339)
			(xy 416.037136 -299.869358) (xy 416.085991 -299.87529) (xy 416.133262 -299.888982) (xy 416.177724 -299.91008)
			(xy 416.218227 -299.938036) (xy 416.25372 -299.972128) (xy 416.283285 -300.011472) (xy 416.306156 -300.055049)
			(xy 416.32174 -300.10173) (xy 416.329635 -300.150307) (xy 416.33013 -300.174914) (xy 416.668978 -300.174914)
			(xy 416.672938 -300.12586) (xy 416.684715 -300.078076) (xy 416.704006 -300.0328) (xy 416.730309 -299.991204)
			(xy 416.762944 -299.954367) (xy 416.801065 -299.923242) (xy 416.843686 -299.898635) (xy 416.889702 -299.881183)
			(xy 416.937921 -299.871339) (xy 416.987096 -299.869358) (xy 417.035951 -299.87529) (xy 417.083222 -299.888982)
			(xy 417.127684 -299.91008) (xy 417.168187 -299.938036) (xy 417.20368 -299.972128) (xy 417.233245 -300.011472)
			(xy 417.256116 -300.055049) (xy 417.2717 -300.10173) (xy 417.279595 -300.150307) (xy 417.28009 -300.174914)
			(xy 417.279595 -300.199521) (xy 417.2717 -300.248098) (xy 417.256116 -300.294779) (xy 417.233245 -300.338356)
			(xy 417.20368 -300.3777) (xy 417.168187 -300.411792) (xy 417.127684 -300.439748) (xy 417.083222 -300.460846)
			(xy 417.035951 -300.474538) (xy 416.987096 -300.48047) (xy 416.937921 -300.478489) (xy 416.889702 -300.468645)
			(xy 416.843686 -300.451193) (xy 416.801065 -300.426586) (xy 416.762944 -300.395461) (xy 416.730309 -300.358624)
			(xy 416.704006 -300.317028) (xy 416.684715 -300.271752) (xy 416.672938 -300.223968) (xy 416.668978 -300.174914)
			(xy 416.33013 -300.174914) (xy 416.329635 -300.199521) (xy 416.32174 -300.248098) (xy 416.306156 -300.294779)
			(xy 416.283285 -300.338356) (xy 416.25372 -300.3777) (xy 416.218227 -300.411792) (xy 416.177724 -300.439748)
			(xy 416.133262 -300.460846) (xy 416.085991 -300.474538) (xy 416.037136 -300.48047) (xy 415.987961 -300.478489)
			(xy 415.939742 -300.468645) (xy 415.893726 -300.451193) (xy 415.851105 -300.426586) (xy 415.812984 -300.395461)
			(xy 415.780349 -300.358624) (xy 415.754046 -300.317028) (xy 415.734755 -300.271752) (xy 415.722978 -300.223968)
			(xy 415.719018 -300.174914) (xy 415.38017 -300.174914) (xy 415.379675 -300.199521) (xy 415.37178 -300.248098)
			(xy 415.356196 -300.294779) (xy 415.333325 -300.338356) (xy 415.30376 -300.3777) (xy 415.268267 -300.411792)
			(xy 415.227764 -300.439748) (xy 415.183302 -300.460846) (xy 415.136031 -300.474538) (xy 415.087176 -300.48047)
			(xy 415.038001 -300.478489) (xy 414.989782 -300.468645) (xy 414.943766 -300.451193) (xy 414.901145 -300.426586)
			(xy 414.863024 -300.395461) (xy 414.830389 -300.358624) (xy 414.804086 -300.317028) (xy 414.784795 -300.271752)
			(xy 414.773018 -300.223968) (xy 414.769058 -300.174914) (xy 414.43021 -300.174914) (xy 414.429715 -300.199521)
			(xy 414.42182 -300.248098) (xy 414.406236 -300.294779) (xy 414.383365 -300.338356) (xy 414.3538 -300.3777)
			(xy 414.318307 -300.411792) (xy 414.277804 -300.439748) (xy 414.233342 -300.460846) (xy 414.186071 -300.474538)
			(xy 414.137216 -300.48047) (xy 414.088041 -300.478489) (xy 414.039822 -300.468645) (xy 413.993806 -300.451193)
			(xy 413.951185 -300.426586) (xy 413.913064 -300.395461) (xy 413.880429 -300.358624) (xy 413.854126 -300.317028)
			(xy 413.834835 -300.271752) (xy 413.823058 -300.223968) (xy 413.819098 -300.174914) (xy 413.48025 -300.174914)
			(xy 413.479755 -300.199521) (xy 413.47186 -300.248098) (xy 413.456276 -300.294779) (xy 413.433405 -300.338356)
			(xy 413.40384 -300.3777) (xy 413.368347 -300.411792) (xy 413.327844 -300.439748) (xy 413.283382 -300.460846)
			(xy 413.236111 -300.474538) (xy 413.187256 -300.48047) (xy 413.138081 -300.478489) (xy 413.089862 -300.468645)
			(xy 413.043846 -300.451193) (xy 413.001225 -300.426586) (xy 412.963104 -300.395461) (xy 412.930469 -300.358624)
			(xy 412.904166 -300.317028) (xy 412.884875 -300.271752) (xy 412.873098 -300.223968) (xy 412.869138 -300.174914)
			(xy 412.53029 -300.174914) (xy 412.529795 -300.199521) (xy 412.5219 -300.248098) (xy 412.506316 -300.294779)
			(xy 412.483445 -300.338356) (xy 412.45388 -300.3777) (xy 412.418387 -300.411792) (xy 412.377884 -300.439748)
			(xy 412.333422 -300.460846) (xy 412.286151 -300.474538) (xy 412.237296 -300.48047) (xy 412.188121 -300.478489)
			(xy 412.139902 -300.468645) (xy 412.093886 -300.451193) (xy 412.051265 -300.426586) (xy 412.013144 -300.395461)
			(xy 411.980509 -300.358624) (xy 411.954206 -300.317028) (xy 411.934915 -300.271752) (xy 411.923138 -300.223968)
			(xy 411.919178 -300.174914) (xy 411.58033 -300.174914) (xy 411.579835 -300.199521) (xy 411.57194 -300.248098)
			(xy 411.556356 -300.294779) (xy 411.533485 -300.338356) (xy 411.50392 -300.3777) (xy 411.468427 -300.411792)
			(xy 411.427924 -300.439748) (xy 411.383462 -300.460846) (xy 411.336191 -300.474538) (xy 411.287336 -300.48047)
			(xy 411.238161 -300.478489) (xy 411.189942 -300.468645) (xy 411.143926 -300.451193) (xy 411.101305 -300.426586)
			(xy 411.063184 -300.395461) (xy 411.030549 -300.358624) (xy 411.004246 -300.317028) (xy 410.984955 -300.271752)
			(xy 410.973178 -300.223968) (xy 410.969218 -300.174914) (xy 410.630116 -300.174914) (xy 410.629621 -300.199521)
			(xy 410.621726 -300.248098) (xy 410.606142 -300.294779) (xy 410.583271 -300.338356) (xy 410.553706 -300.3777)
			(xy 410.518213 -300.411792) (xy 410.47771 -300.439748) (xy 410.433248 -300.460846) (xy 410.385977 -300.474538)
			(xy 410.337122 -300.48047) (xy 410.287947 -300.478489) (xy 410.239728 -300.468645) (xy 410.193712 -300.451193)
			(xy 410.151091 -300.426586) (xy 410.11297 -300.395461) (xy 410.080335 -300.358624) (xy 410.054032 -300.317028)
			(xy 410.034741 -300.271752) (xy 410.022964 -300.223968) (xy 410.019004 -300.174914) (xy 409.680156 -300.174914)
			(xy 409.679661 -300.199521) (xy 409.671766 -300.248098) (xy 409.656182 -300.294779) (xy 409.633311 -300.338356)
			(xy 409.603746 -300.3777) (xy 409.568253 -300.411792) (xy 409.52775 -300.439748) (xy 409.483288 -300.460846)
			(xy 409.436017 -300.474538) (xy 409.387162 -300.48047) (xy 409.337987 -300.478489) (xy 409.289768 -300.468645)
			(xy 409.243752 -300.451193) (xy 409.201131 -300.426586) (xy 409.16301 -300.395461) (xy 409.130375 -300.358624)
			(xy 409.104072 -300.317028) (xy 409.084781 -300.271752) (xy 409.073004 -300.223968) (xy 409.069044 -300.174914)
			(xy 408.730196 -300.174914) (xy 408.729701 -300.199521) (xy 408.721806 -300.248098) (xy 408.706222 -300.294779)
			(xy 408.683351 -300.338356) (xy 408.653786 -300.3777) (xy 408.618293 -300.411792) (xy 408.57779 -300.439748)
			(xy 408.533328 -300.460846) (xy 408.486057 -300.474538) (xy 408.437202 -300.48047) (xy 408.388027 -300.478489)
			(xy 408.339808 -300.468645) (xy 408.293792 -300.451193) (xy 408.251171 -300.426586) (xy 408.21305 -300.395461)
			(xy 408.180415 -300.358624) (xy 408.154112 -300.317028) (xy 408.134821 -300.271752) (xy 408.123044 -300.223968)
			(xy 408.119084 -300.174914) (xy 406.830276 -300.174914) (xy 406.829781 -300.199521) (xy 406.821886 -300.248098)
			(xy 406.806302 -300.294779) (xy 406.783431 -300.338356) (xy 406.753866 -300.3777) (xy 406.718373 -300.411792)
			(xy 406.67787 -300.439748) (xy 406.633408 -300.460846) (xy 406.586137 -300.474538) (xy 406.537282 -300.48047)
			(xy 406.488107 -300.478489) (xy 406.439888 -300.468645) (xy 406.393872 -300.451193) (xy 406.351251 -300.426586)
			(xy 406.31313 -300.395461) (xy 406.280495 -300.358624) (xy 406.254192 -300.317028) (xy 406.234901 -300.271752)
			(xy 406.223124 -300.223968) (xy 406.219164 -300.174914) (xy 405.880316 -300.174914) (xy 405.879821 -300.199521)
			(xy 405.871926 -300.248098) (xy 405.856342 -300.294779) (xy 405.833471 -300.338356) (xy 405.803906 -300.3777)
			(xy 405.768413 -300.411792) (xy 405.72791 -300.439748) (xy 405.683448 -300.460846) (xy 405.636177 -300.474538)
			(xy 405.587322 -300.48047) (xy 405.538147 -300.478489) (xy 405.489928 -300.468645) (xy 405.443912 -300.451193)
			(xy 405.401291 -300.426586) (xy 405.36317 -300.395461) (xy 405.330535 -300.358624) (xy 405.304232 -300.317028)
			(xy 405.284941 -300.271752) (xy 405.273164 -300.223968) (xy 405.269204 -300.174914) (xy 404.930102 -300.174914)
			(xy 404.929607 -300.199521) (xy 404.921712 -300.248098) (xy 404.906128 -300.294779) (xy 404.883257 -300.338356)
			(xy 404.853692 -300.3777) (xy 404.818199 -300.411792) (xy 404.777696 -300.439748) (xy 404.733234 -300.460846)
			(xy 404.685963 -300.474538) (xy 404.637108 -300.48047) (xy 404.587933 -300.478489) (xy 404.539714 -300.468645)
			(xy 404.493698 -300.451193) (xy 404.451077 -300.426586) (xy 404.412956 -300.395461) (xy 404.380321 -300.358624)
			(xy 404.354018 -300.317028) (xy 404.334727 -300.271752) (xy 404.32295 -300.223968) (xy 404.31899 -300.174914)
			(xy 403.980142 -300.174914) (xy 403.979647 -300.199521) (xy 403.971752 -300.248098) (xy 403.956168 -300.294779)
			(xy 403.933297 -300.338356) (xy 403.903732 -300.3777) (xy 403.868239 -300.411792) (xy 403.827736 -300.439748)
			(xy 403.783274 -300.460846) (xy 403.736003 -300.474538) (xy 403.687148 -300.48047) (xy 403.637973 -300.478489)
			(xy 403.589754 -300.468645) (xy 403.543738 -300.451193) (xy 403.501117 -300.426586) (xy 403.462996 -300.395461)
			(xy 403.430361 -300.358624) (xy 403.404058 -300.317028) (xy 403.384767 -300.271752) (xy 403.37299 -300.223968)
			(xy 403.36903 -300.174914) (xy 403.030182 -300.174914) (xy 403.029687 -300.199521) (xy 403.021792 -300.248098)
			(xy 403.006208 -300.294779) (xy 402.983337 -300.338356) (xy 402.953772 -300.3777) (xy 402.918279 -300.411792)
			(xy 402.877776 -300.439748) (xy 402.833314 -300.460846) (xy 402.786043 -300.474538) (xy 402.737188 -300.48047)
			(xy 402.688013 -300.478489) (xy 402.639794 -300.468645) (xy 402.593778 -300.451193) (xy 402.551157 -300.426586)
			(xy 402.513036 -300.395461) (xy 402.480401 -300.358624) (xy 402.454098 -300.317028) (xy 402.434807 -300.271752)
			(xy 402.42303 -300.223968) (xy 402.41907 -300.174914) (xy 402.080222 -300.174914) (xy 402.079727 -300.199521)
			(xy 402.071832 -300.248098) (xy 402.056248 -300.294779) (xy 402.033377 -300.338356) (xy 402.003812 -300.3777)
			(xy 401.968319 -300.411792) (xy 401.927816 -300.439748) (xy 401.883354 -300.460846) (xy 401.836083 -300.474538)
			(xy 401.787228 -300.48047) (xy 401.738053 -300.478489) (xy 401.689834 -300.468645) (xy 401.643818 -300.451193)
			(xy 401.601197 -300.426586) (xy 401.563076 -300.395461) (xy 401.530441 -300.358624) (xy 401.504138 -300.317028)
			(xy 401.484847 -300.271752) (xy 401.47307 -300.223968) (xy 401.46911 -300.174914) (xy 401.130262 -300.174914)
			(xy 401.129767 -300.199521) (xy 401.121872 -300.248098) (xy 401.106288 -300.294779) (xy 401.083417 -300.338356)
			(xy 401.053852 -300.3777) (xy 401.018359 -300.411792) (xy 400.977856 -300.439748) (xy 400.933394 -300.460846)
			(xy 400.886123 -300.474538) (xy 400.837268 -300.48047) (xy 400.788093 -300.478489) (xy 400.739874 -300.468645)
			(xy 400.693858 -300.451193) (xy 400.651237 -300.426586) (xy 400.613116 -300.395461) (xy 400.580481 -300.358624)
			(xy 400.554178 -300.317028) (xy 400.534887 -300.271752) (xy 400.52311 -300.223968) (xy 400.51915 -300.174914)
			(xy 400.180302 -300.174914) (xy 400.179807 -300.199521) (xy 400.171912 -300.248098) (xy 400.156328 -300.294779)
			(xy 400.133457 -300.338356) (xy 400.103892 -300.3777) (xy 400.068399 -300.411792) (xy 400.027896 -300.439748)
			(xy 399.983434 -300.460846) (xy 399.936163 -300.474538) (xy 399.887308 -300.48047) (xy 399.838133 -300.478489)
			(xy 399.789914 -300.468645) (xy 399.743898 -300.451193) (xy 399.701277 -300.426586) (xy 399.663156 -300.395461)
			(xy 399.630521 -300.358624) (xy 399.604218 -300.317028) (xy 399.584927 -300.271752) (xy 399.57315 -300.223968)
			(xy 399.56919 -300.174914) (xy 399.230342 -300.174914) (xy 399.229847 -300.199521) (xy 399.221952 -300.248098)
			(xy 399.206368 -300.294779) (xy 399.183497 -300.338356) (xy 399.153932 -300.3777) (xy 399.118439 -300.411792)
			(xy 399.077936 -300.439748) (xy 399.033474 -300.460846) (xy 398.986203 -300.474538) (xy 398.937348 -300.48047)
			(xy 398.888173 -300.478489) (xy 398.839954 -300.468645) (xy 398.793938 -300.451193) (xy 398.751317 -300.426586)
			(xy 398.713196 -300.395461) (xy 398.680561 -300.358624) (xy 398.654258 -300.317028) (xy 398.634967 -300.271752)
			(xy 398.62319 -300.223968) (xy 398.61923 -300.174914) (xy 398.280644 -300.174914) (xy 398.276474 -300.225238)
			(xy 398.264075 -300.274204) (xy 398.243786 -300.320461) (xy 398.21616 -300.362747) (xy 398.181951 -300.39991)
			(xy 398.142092 -300.430936) (xy 398.09767 -300.454979) (xy 398.049897 -300.471382) (xy 398.000075 -300.479699)
			(xy 397.97482 -300.480222) (xy 397.950215 -300.479731) (xy 397.90164 -300.471847) (xy 397.854957 -300.456278)
			(xy 397.811373 -300.433428) (xy 397.772015 -300.403887) (xy 397.754602 -300.386496) (xy 397.754602 -300.386242)
			(xy 397.747291 -300.379239) (xy 397.728742 -300.371167) (xy 397.708515 -300.370913) (xy 397.698976 -300.374304)
			(xy 397.611346 -300.40961) (xy 397.602148 -300.413761) (xy 397.587784 -300.427911) (xy 397.580017 -300.446518)
			(xy 397.579596 -300.4566) (xy 397.579596 -300.843188) (xy 397.580105 -300.853251) (xy 397.587887 -300.871816)
			(xy 397.602187 -300.885983) (xy 397.611346 -300.890178) (xy 397.698976 -300.925484) (xy 397.708525 -300.928806)
			(xy 397.728724 -300.928517) (xy 397.747269 -300.920505) (xy 397.754602 -300.913546) (xy 397.754602 -300.913292)
			(xy 397.771996 -300.895882) (xy 397.811362 -300.866349) (xy 397.854951 -300.843505) (xy 397.901637 -300.82794)
			(xy 397.950214 -300.820058) (xy 397.97482 -300.819566) (xy 398.000072 -300.820141) (xy 398.049887 -300.828457)
			(xy 398.097654 -300.844858) (xy 398.14207 -300.868897) (xy 398.181924 -300.899919) (xy 398.216128 -300.937077)
			(xy 398.24375 -300.979358) (xy 398.264037 -301.025609) (xy 398.276435 -301.074568) (xy 398.280603 -301.124874)
			(xy 416.668978 -301.124874) (xy 416.672938 -301.07582) (xy 416.684715 -301.028036) (xy 416.704006 -300.98276)
			(xy 416.730309 -300.941164) (xy 416.762944 -300.904327) (xy 416.801065 -300.873202) (xy 416.843686 -300.848595)
			(xy 416.889702 -300.831143) (xy 416.937921 -300.821299) (xy 416.987096 -300.819318) (xy 417.035951 -300.82525)
			(xy 417.083222 -300.838942) (xy 417.127684 -300.86004) (xy 417.168187 -300.887996) (xy 417.20368 -300.922088)
			(xy 417.233245 -300.961432) (xy 417.256116 -301.005009) (xy 417.2717 -301.05169) (xy 417.279595 -301.100267)
			(xy 417.28009 -301.124874) (xy 417.279595 -301.149481) (xy 417.2717 -301.198058) (xy 417.256116 -301.244739)
			(xy 417.233245 -301.288316) (xy 417.20368 -301.32766) (xy 417.168187 -301.361752) (xy 417.127684 -301.389708)
			(xy 417.083222 -301.410806) (xy 417.035951 -301.424498) (xy 416.987096 -301.43043) (xy 416.937921 -301.428449)
			(xy 416.889702 -301.418605) (xy 416.843686 -301.401153) (xy 416.801065 -301.376546) (xy 416.762944 -301.345421)
			(xy 416.730309 -301.308584) (xy 416.704006 -301.266988) (xy 416.684715 -301.221712) (xy 416.672938 -301.173928)
			(xy 416.668978 -301.124874) (xy 398.280603 -301.124874) (xy 398.280605 -301.1249) (xy 398.276435 -301.175232)
			(xy 398.264037 -301.224191) (xy 398.24375 -301.270442) (xy 398.216128 -301.312723) (xy 398.181924 -301.349881)
			(xy 398.14207 -301.380903) (xy 398.097654 -301.404942) (xy 398.049887 -301.421343) (xy 398.000072 -301.429659)
			(xy 397.97482 -301.430182) (xy 397.950216 -301.429673) (xy 397.901642 -301.42179) (xy 397.85496 -301.406225)
			(xy 397.811376 -301.383379) (xy 397.772017 -301.353844) (xy 397.754602 -301.336456) (xy 397.754602 -301.336202)
			(xy 397.747294 -301.329196) (xy 397.728743 -301.321129) (xy 397.708516 -301.320875) (xy 397.698976 -301.324264)
			(xy 397.611346 -301.35957) (xy 397.602164 -301.36375) (xy 397.5878 -301.377888) (xy 397.580024 -301.396482)
			(xy 397.579596 -301.40656) (xy 397.579596 -301.793148) (xy 397.580061 -301.803216) (xy 397.587863 -301.821782)
			(xy 397.602181 -301.835946) (xy 397.611346 -301.840138) (xy 397.698976 -301.875444) (xy 397.708529 -301.87875)
			(xy 397.728723 -301.878461) (xy 397.747266 -301.870458) (xy 397.754602 -301.863506) (xy 397.754602 -301.863252)
			(xy 397.772007 -301.845853) (xy 397.811368 -301.816315) (xy 397.854954 -301.793468) (xy 397.901639 -301.777902)
			(xy 397.950214 -301.770018) (xy 397.97482 -301.769526) (xy 398.000077 -301.769981) (xy 398.049902 -301.778299)
			(xy 398.097678 -301.794703) (xy 398.142103 -301.818747) (xy 398.181964 -301.849775) (xy 398.216176 -301.88694)
			(xy 398.243803 -301.92923) (xy 398.264094 -301.97549) (xy 398.276494 -302.024458) (xy 398.280665 -302.0748)
			(xy 398.280662 -302.074834) (xy 398.61923 -302.074834) (xy 398.62319 -302.02578) (xy 398.634967 -301.977996)
			(xy 398.654258 -301.93272) (xy 398.680561 -301.891124) (xy 398.713196 -301.854287) (xy 398.751317 -301.823162)
			(xy 398.793938 -301.798555) (xy 398.839954 -301.781103) (xy 398.888173 -301.771259) (xy 398.937348 -301.769278)
			(xy 398.986203 -301.77521) (xy 399.033474 -301.788902) (xy 399.077936 -301.81) (xy 399.118439 -301.837956)
			(xy 399.153932 -301.872048) (xy 399.183497 -301.911392) (xy 399.206368 -301.954969) (xy 399.221952 -302.00165)
			(xy 399.229847 -302.050227) (xy 399.230342 -302.074834) (xy 399.56919 -302.074834) (xy 399.57315 -302.02578)
			(xy 399.584927 -301.977996) (xy 399.604218 -301.93272) (xy 399.630521 -301.891124) (xy 399.663156 -301.854287)
			(xy 399.701277 -301.823162) (xy 399.743898 -301.798555) (xy 399.789914 -301.781103) (xy 399.838133 -301.771259)
			(xy 399.887308 -301.769278) (xy 399.936163 -301.77521) (xy 399.983434 -301.788902) (xy 400.027896 -301.81)
			(xy 400.068399 -301.837956) (xy 400.103892 -301.872048) (xy 400.133457 -301.911392) (xy 400.156328 -301.954969)
			(xy 400.171912 -302.00165) (xy 400.179807 -302.050227) (xy 400.180302 -302.074834) (xy 400.51915 -302.074834)
			(xy 400.52311 -302.02578) (xy 400.534887 -301.977996) (xy 400.554178 -301.93272) (xy 400.580481 -301.891124)
			(xy 400.613116 -301.854287) (xy 400.651237 -301.823162) (xy 400.693858 -301.798555) (xy 400.739874 -301.781103)
			(xy 400.788093 -301.771259) (xy 400.837268 -301.769278) (xy 400.886123 -301.77521) (xy 400.933394 -301.788902)
			(xy 400.977856 -301.81) (xy 401.018359 -301.837956) (xy 401.053852 -301.872048) (xy 401.083417 -301.911392)
			(xy 401.106288 -301.954969) (xy 401.121872 -302.00165) (xy 401.129767 -302.050227) (xy 401.130262 -302.074834)
			(xy 401.46911 -302.074834) (xy 401.47307 -302.02578) (xy 401.484847 -301.977996) (xy 401.504138 -301.93272)
			(xy 401.530441 -301.891124) (xy 401.563076 -301.854287) (xy 401.601197 -301.823162) (xy 401.643818 -301.798555)
			(xy 401.689834 -301.781103) (xy 401.738053 -301.771259) (xy 401.787228 -301.769278) (xy 401.836083 -301.77521)
			(xy 401.883354 -301.788902) (xy 401.927816 -301.81) (xy 401.968319 -301.837956) (xy 402.003812 -301.872048)
			(xy 402.033377 -301.911392) (xy 402.056248 -301.954969) (xy 402.071832 -302.00165) (xy 402.079727 -302.050227)
			(xy 402.080222 -302.074834) (xy 402.41907 -302.074834) (xy 402.42303 -302.02578) (xy 402.434807 -301.977996)
			(xy 402.454098 -301.93272) (xy 402.480401 -301.891124) (xy 402.513036 -301.854287) (xy 402.551157 -301.823162)
			(xy 402.593778 -301.798555) (xy 402.639794 -301.781103) (xy 402.688013 -301.771259) (xy 402.737188 -301.769278)
			(xy 402.786043 -301.77521) (xy 402.833314 -301.788902) (xy 402.877776 -301.81) (xy 402.918279 -301.837956)
			(xy 402.953772 -301.872048) (xy 402.983337 -301.911392) (xy 403.006208 -301.954969) (xy 403.021792 -302.00165)
			(xy 403.029687 -302.050227) (xy 403.030182 -302.074834) (xy 403.36903 -302.074834) (xy 403.37299 -302.02578)
			(xy 403.384767 -301.977996) (xy 403.404058 -301.93272) (xy 403.430361 -301.891124) (xy 403.462996 -301.854287)
			(xy 403.501117 -301.823162) (xy 403.543738 -301.798555) (xy 403.589754 -301.781103) (xy 403.637973 -301.771259)
			(xy 403.687148 -301.769278) (xy 403.736003 -301.77521) (xy 403.783274 -301.788902) (xy 403.827736 -301.81)
			(xy 403.868239 -301.837956) (xy 403.903732 -301.872048) (xy 403.933297 -301.911392) (xy 403.956168 -301.954969)
			(xy 403.971752 -302.00165) (xy 403.979647 -302.050227) (xy 403.980142 -302.074834) (xy 404.31899 -302.074834)
			(xy 404.32295 -302.02578) (xy 404.334727 -301.977996) (xy 404.354018 -301.93272) (xy 404.380321 -301.891124)
			(xy 404.412956 -301.854287) (xy 404.451077 -301.823162) (xy 404.493698 -301.798555) (xy 404.539714 -301.781103)
			(xy 404.587933 -301.771259) (xy 404.637108 -301.769278) (xy 404.685963 -301.77521) (xy 404.733234 -301.788902)
			(xy 404.777696 -301.81) (xy 404.818199 -301.837956) (xy 404.853692 -301.872048) (xy 404.883257 -301.911392)
			(xy 404.906128 -301.954969) (xy 404.921712 -302.00165) (xy 404.929607 -302.050227) (xy 404.930102 -302.074834)
			(xy 405.269204 -302.074834) (xy 405.273164 -302.02578) (xy 405.284941 -301.977996) (xy 405.304232 -301.93272)
			(xy 405.330535 -301.891124) (xy 405.36317 -301.854287) (xy 405.401291 -301.823162) (xy 405.443912 -301.798555)
			(xy 405.489928 -301.781103) (xy 405.538147 -301.771259) (xy 405.587322 -301.769278) (xy 405.636177 -301.77521)
			(xy 405.683448 -301.788902) (xy 405.72791 -301.81) (xy 405.768413 -301.837956) (xy 405.803906 -301.872048)
			(xy 405.833471 -301.911392) (xy 405.856342 -301.954969) (xy 405.871926 -302.00165) (xy 405.879821 -302.050227)
			(xy 405.880316 -302.074834) (xy 406.219164 -302.074834) (xy 406.223124 -302.02578) (xy 406.234901 -301.977996)
			(xy 406.254192 -301.93272) (xy 406.280495 -301.891124) (xy 406.31313 -301.854287) (xy 406.351251 -301.823162)
			(xy 406.393872 -301.798555) (xy 406.439888 -301.781103) (xy 406.488107 -301.771259) (xy 406.537282 -301.769278)
			(xy 406.586137 -301.77521) (xy 406.633408 -301.788902) (xy 406.67787 -301.81) (xy 406.718373 -301.837956)
			(xy 406.753866 -301.872048) (xy 406.783431 -301.911392) (xy 406.806302 -301.954969) (xy 406.821886 -302.00165)
			(xy 406.829781 -302.050227) (xy 406.830276 -302.074834) (xy 408.119084 -302.074834) (xy 408.123044 -302.02578)
			(xy 408.134821 -301.977996) (xy 408.154112 -301.93272) (xy 408.180415 -301.891124) (xy 408.21305 -301.854287)
			(xy 408.251171 -301.823162) (xy 408.293792 -301.798555) (xy 408.339808 -301.781103) (xy 408.388027 -301.771259)
			(xy 408.437202 -301.769278) (xy 408.486057 -301.77521) (xy 408.533328 -301.788902) (xy 408.57779 -301.81)
			(xy 408.618293 -301.837956) (xy 408.653786 -301.872048) (xy 408.683351 -301.911392) (xy 408.706222 -301.954969)
			(xy 408.721806 -302.00165) (xy 408.729701 -302.050227) (xy 408.730196 -302.074834) (xy 409.069044 -302.074834)
			(xy 409.073004 -302.02578) (xy 409.084781 -301.977996) (xy 409.104072 -301.93272) (xy 409.130375 -301.891124)
			(xy 409.16301 -301.854287) (xy 409.201131 -301.823162) (xy 409.243752 -301.798555) (xy 409.289768 -301.781103)
			(xy 409.337987 -301.771259) (xy 409.387162 -301.769278) (xy 409.436017 -301.77521) (xy 409.483288 -301.788902)
			(xy 409.52775 -301.81) (xy 409.568253 -301.837956) (xy 409.603746 -301.872048) (xy 409.633311 -301.911392)
			(xy 409.656182 -301.954969) (xy 409.671766 -302.00165) (xy 409.679661 -302.050227) (xy 409.680156 -302.074834)
			(xy 410.019004 -302.074834) (xy 410.022964 -302.02578) (xy 410.034741 -301.977996) (xy 410.054032 -301.93272)
			(xy 410.080335 -301.891124) (xy 410.11297 -301.854287) (xy 410.151091 -301.823162) (xy 410.193712 -301.798555)
			(xy 410.239728 -301.781103) (xy 410.287947 -301.771259) (xy 410.337122 -301.769278) (xy 410.385977 -301.77521)
			(xy 410.433248 -301.788902) (xy 410.47771 -301.81) (xy 410.518213 -301.837956) (xy 410.553706 -301.872048)
			(xy 410.583271 -301.911392) (xy 410.606142 -301.954969) (xy 410.621726 -302.00165) (xy 410.629621 -302.050227)
			(xy 410.630116 -302.074834) (xy 410.969218 -302.074834) (xy 410.973178 -302.02578) (xy 410.984955 -301.977996)
			(xy 411.004246 -301.93272) (xy 411.030549 -301.891124) (xy 411.063184 -301.854287) (xy 411.101305 -301.823162)
			(xy 411.143926 -301.798555) (xy 411.189942 -301.781103) (xy 411.238161 -301.771259) (xy 411.287336 -301.769278)
			(xy 411.336191 -301.77521) (xy 411.383462 -301.788902) (xy 411.427924 -301.81) (xy 411.468427 -301.837956)
			(xy 411.50392 -301.872048) (xy 411.533485 -301.911392) (xy 411.556356 -301.954969) (xy 411.57194 -302.00165)
			(xy 411.579835 -302.050227) (xy 411.58033 -302.074834) (xy 411.919178 -302.074834) (xy 411.923138 -302.02578)
			(xy 411.934915 -301.977996) (xy 411.954206 -301.93272) (xy 411.980509 -301.891124) (xy 412.013144 -301.854287)
			(xy 412.051265 -301.823162) (xy 412.093886 -301.798555) (xy 412.139902 -301.781103) (xy 412.188121 -301.771259)
			(xy 412.237296 -301.769278) (xy 412.286151 -301.77521) (xy 412.333422 -301.788902) (xy 412.377884 -301.81)
			(xy 412.418387 -301.837956) (xy 412.45388 -301.872048) (xy 412.483445 -301.911392) (xy 412.506316 -301.954969)
			(xy 412.5219 -302.00165) (xy 412.529795 -302.050227) (xy 412.53029 -302.074834) (xy 412.869138 -302.074834)
			(xy 412.873098 -302.02578) (xy 412.884875 -301.977996) (xy 412.904166 -301.93272) (xy 412.930469 -301.891124)
			(xy 412.963104 -301.854287) (xy 413.001225 -301.823162) (xy 413.043846 -301.798555) (xy 413.089862 -301.781103)
			(xy 413.138081 -301.771259) (xy 413.187256 -301.769278) (xy 413.236111 -301.77521) (xy 413.283382 -301.788902)
			(xy 413.327844 -301.81) (xy 413.368347 -301.837956) (xy 413.40384 -301.872048) (xy 413.433405 -301.911392)
			(xy 413.456276 -301.954969) (xy 413.47186 -302.00165) (xy 413.479755 -302.050227) (xy 413.48025 -302.074834)
			(xy 413.819098 -302.074834) (xy 413.823058 -302.02578) (xy 413.834835 -301.977996) (xy 413.854126 -301.93272)
			(xy 413.880429 -301.891124) (xy 413.913064 -301.854287) (xy 413.951185 -301.823162) (xy 413.993806 -301.798555)
			(xy 414.039822 -301.781103) (xy 414.088041 -301.771259) (xy 414.137216 -301.769278) (xy 414.186071 -301.77521)
			(xy 414.233342 -301.788902) (xy 414.277804 -301.81) (xy 414.318307 -301.837956) (xy 414.3538 -301.872048)
			(xy 414.383365 -301.911392) (xy 414.406236 -301.954969) (xy 414.42182 -302.00165) (xy 414.429715 -302.050227)
			(xy 414.43021 -302.074834) (xy 414.769058 -302.074834) (xy 414.773018 -302.02578) (xy 414.784795 -301.977996)
			(xy 414.804086 -301.93272) (xy 414.830389 -301.891124) (xy 414.863024 -301.854287) (xy 414.901145 -301.823162)
			(xy 414.943766 -301.798555) (xy 414.989782 -301.781103) (xy 415.038001 -301.771259) (xy 415.087176 -301.769278)
			(xy 415.136031 -301.77521) (xy 415.183302 -301.788902) (xy 415.227764 -301.81) (xy 415.268267 -301.837956)
			(xy 415.30376 -301.872048) (xy 415.333325 -301.911392) (xy 415.356196 -301.954969) (xy 415.37178 -302.00165)
			(xy 415.379675 -302.050227) (xy 415.38017 -302.074834) (xy 415.719018 -302.074834) (xy 415.722978 -302.02578)
			(xy 415.734755 -301.977996) (xy 415.754046 -301.93272) (xy 415.780349 -301.891124) (xy 415.812984 -301.854287)
			(xy 415.851105 -301.823162) (xy 415.893726 -301.798555) (xy 415.939742 -301.781103) (xy 415.987961 -301.771259)
			(xy 416.037136 -301.769278) (xy 416.085991 -301.77521) (xy 416.133262 -301.788902) (xy 416.177724 -301.81)
			(xy 416.218227 -301.837956) (xy 416.25372 -301.872048) (xy 416.283285 -301.911392) (xy 416.306156 -301.954969)
			(xy 416.32174 -302.00165) (xy 416.329635 -302.050227) (xy 416.33013 -302.074834) (xy 416.668978 -302.074834)
			(xy 416.672938 -302.02578) (xy 416.684715 -301.977996) (xy 416.704006 -301.93272) (xy 416.730309 -301.891124)
			(xy 416.762944 -301.854287) (xy 416.801065 -301.823162) (xy 416.843686 -301.798555) (xy 416.889702 -301.781103)
			(xy 416.937921 -301.771259) (xy 416.987096 -301.769278) (xy 417.035951 -301.77521) (xy 417.083222 -301.788902)
			(xy 417.127684 -301.81) (xy 417.168187 -301.837956) (xy 417.20368 -301.872048) (xy 417.233245 -301.911392)
			(xy 417.256116 -301.954969) (xy 417.2717 -302.00165) (xy 417.279595 -302.050227) (xy 417.28009 -302.074834)
			(xy 417.279595 -302.099441) (xy 417.2717 -302.148018) (xy 417.256116 -302.194699) (xy 417.233245 -302.238276)
			(xy 417.20368 -302.27762) (xy 417.168187 -302.311712) (xy 417.127684 -302.339668) (xy 417.083222 -302.360766)
			(xy 417.035951 -302.374458) (xy 416.987096 -302.38039) (xy 416.937921 -302.378409) (xy 416.889702 -302.368565)
			(xy 416.843686 -302.351113) (xy 416.801065 -302.326506) (xy 416.762944 -302.295381) (xy 416.730309 -302.258544)
			(xy 416.704006 -302.216948) (xy 416.684715 -302.171672) (xy 416.672938 -302.123888) (xy 416.668978 -302.074834)
			(xy 416.33013 -302.074834) (xy 416.329635 -302.099441) (xy 416.32174 -302.148018) (xy 416.306156 -302.194699)
			(xy 416.283285 -302.238276) (xy 416.25372 -302.27762) (xy 416.218227 -302.311712) (xy 416.177724 -302.339668)
			(xy 416.133262 -302.360766) (xy 416.085991 -302.374458) (xy 416.037136 -302.38039) (xy 415.987961 -302.378409)
			(xy 415.939742 -302.368565) (xy 415.893726 -302.351113) (xy 415.851105 -302.326506) (xy 415.812984 -302.295381)
			(xy 415.780349 -302.258544) (xy 415.754046 -302.216948) (xy 415.734755 -302.171672) (xy 415.722978 -302.123888)
			(xy 415.719018 -302.074834) (xy 415.38017 -302.074834) (xy 415.379675 -302.099441) (xy 415.37178 -302.148018)
			(xy 415.356196 -302.194699) (xy 415.333325 -302.238276) (xy 415.30376 -302.27762) (xy 415.268267 -302.311712)
			(xy 415.227764 -302.339668) (xy 415.183302 -302.360766) (xy 415.136031 -302.374458) (xy 415.087176 -302.38039)
			(xy 415.038001 -302.378409) (xy 414.989782 -302.368565) (xy 414.943766 -302.351113) (xy 414.901145 -302.326506)
			(xy 414.863024 -302.295381) (xy 414.830389 -302.258544) (xy 414.804086 -302.216948) (xy 414.784795 -302.171672)
			(xy 414.773018 -302.123888) (xy 414.769058 -302.074834) (xy 414.43021 -302.074834) (xy 414.429715 -302.099441)
			(xy 414.42182 -302.148018) (xy 414.406236 -302.194699) (xy 414.383365 -302.238276) (xy 414.3538 -302.27762)
			(xy 414.318307 -302.311712) (xy 414.277804 -302.339668) (xy 414.233342 -302.360766) (xy 414.186071 -302.374458)
			(xy 414.137216 -302.38039) (xy 414.088041 -302.378409) (xy 414.039822 -302.368565) (xy 413.993806 -302.351113)
			(xy 413.951185 -302.326506) (xy 413.913064 -302.295381) (xy 413.880429 -302.258544) (xy 413.854126 -302.216948)
			(xy 413.834835 -302.171672) (xy 413.823058 -302.123888) (xy 413.819098 -302.074834) (xy 413.48025 -302.074834)
			(xy 413.479755 -302.099441) (xy 413.47186 -302.148018) (xy 413.456276 -302.194699) (xy 413.433405 -302.238276)
			(xy 413.40384 -302.27762) (xy 413.368347 -302.311712) (xy 413.327844 -302.339668) (xy 413.283382 -302.360766)
			(xy 413.236111 -302.374458) (xy 413.187256 -302.38039) (xy 413.138081 -302.378409) (xy 413.089862 -302.368565)
			(xy 413.043846 -302.351113) (xy 413.001225 -302.326506) (xy 412.963104 -302.295381) (xy 412.930469 -302.258544)
			(xy 412.904166 -302.216948) (xy 412.884875 -302.171672) (xy 412.873098 -302.123888) (xy 412.869138 -302.074834)
			(xy 412.53029 -302.074834) (xy 412.529795 -302.099441) (xy 412.5219 -302.148018) (xy 412.506316 -302.194699)
			(xy 412.483445 -302.238276) (xy 412.45388 -302.27762) (xy 412.418387 -302.311712) (xy 412.377884 -302.339668)
			(xy 412.333422 -302.360766) (xy 412.286151 -302.374458) (xy 412.237296 -302.38039) (xy 412.188121 -302.378409)
			(xy 412.139902 -302.368565) (xy 412.093886 -302.351113) (xy 412.051265 -302.326506) (xy 412.013144 -302.295381)
			(xy 411.980509 -302.258544) (xy 411.954206 -302.216948) (xy 411.934915 -302.171672) (xy 411.923138 -302.123888)
			(xy 411.919178 -302.074834) (xy 411.58033 -302.074834) (xy 411.579835 -302.099441) (xy 411.57194 -302.148018)
			(xy 411.556356 -302.194699) (xy 411.533485 -302.238276) (xy 411.50392 -302.27762) (xy 411.468427 -302.311712)
			(xy 411.427924 -302.339668) (xy 411.383462 -302.360766) (xy 411.336191 -302.374458) (xy 411.287336 -302.38039)
			(xy 411.238161 -302.378409) (xy 411.189942 -302.368565) (xy 411.143926 -302.351113) (xy 411.101305 -302.326506)
			(xy 411.063184 -302.295381) (xy 411.030549 -302.258544) (xy 411.004246 -302.216948) (xy 410.984955 -302.171672)
			(xy 410.973178 -302.123888) (xy 410.969218 -302.074834) (xy 410.630116 -302.074834) (xy 410.629621 -302.099441)
			(xy 410.621726 -302.148018) (xy 410.606142 -302.194699) (xy 410.583271 -302.238276) (xy 410.553706 -302.27762)
			(xy 410.518213 -302.311712) (xy 410.47771 -302.339668) (xy 410.433248 -302.360766) (xy 410.385977 -302.374458)
			(xy 410.337122 -302.38039) (xy 410.287947 -302.378409) (xy 410.239728 -302.368565) (xy 410.193712 -302.351113)
			(xy 410.151091 -302.326506) (xy 410.11297 -302.295381) (xy 410.080335 -302.258544) (xy 410.054032 -302.216948)
			(xy 410.034741 -302.171672) (xy 410.022964 -302.123888) (xy 410.019004 -302.074834) (xy 409.680156 -302.074834)
			(xy 409.679661 -302.099441) (xy 409.671766 -302.148018) (xy 409.656182 -302.194699) (xy 409.633311 -302.238276)
			(xy 409.603746 -302.27762) (xy 409.568253 -302.311712) (xy 409.52775 -302.339668) (xy 409.483288 -302.360766)
			(xy 409.436017 -302.374458) (xy 409.387162 -302.38039) (xy 409.337987 -302.378409) (xy 409.289768 -302.368565)
			(xy 409.243752 -302.351113) (xy 409.201131 -302.326506) (xy 409.16301 -302.295381) (xy 409.130375 -302.258544)
			(xy 409.104072 -302.216948) (xy 409.084781 -302.171672) (xy 409.073004 -302.123888) (xy 409.069044 -302.074834)
			(xy 408.730196 -302.074834) (xy 408.729701 -302.099441) (xy 408.721806 -302.148018) (xy 408.706222 -302.194699)
			(xy 408.683351 -302.238276) (xy 408.653786 -302.27762) (xy 408.618293 -302.311712) (xy 408.57779 -302.339668)
			(xy 408.533328 -302.360766) (xy 408.486057 -302.374458) (xy 408.437202 -302.38039) (xy 408.388027 -302.378409)
			(xy 408.339808 -302.368565) (xy 408.293792 -302.351113) (xy 408.251171 -302.326506) (xy 408.21305 -302.295381)
			(xy 408.180415 -302.258544) (xy 408.154112 -302.216948) (xy 408.134821 -302.171672) (xy 408.123044 -302.123888)
			(xy 408.119084 -302.074834) (xy 406.830276 -302.074834) (xy 406.829781 -302.099441) (xy 406.821886 -302.148018)
			(xy 406.806302 -302.194699) (xy 406.783431 -302.238276) (xy 406.753866 -302.27762) (xy 406.718373 -302.311712)
			(xy 406.67787 -302.339668) (xy 406.633408 -302.360766) (xy 406.586137 -302.374458) (xy 406.537282 -302.38039)
			(xy 406.488107 -302.378409) (xy 406.439888 -302.368565) (xy 406.393872 -302.351113) (xy 406.351251 -302.326506)
			(xy 406.31313 -302.295381) (xy 406.280495 -302.258544) (xy 406.254192 -302.216948) (xy 406.234901 -302.171672)
			(xy 406.223124 -302.123888) (xy 406.219164 -302.074834) (xy 405.880316 -302.074834) (xy 405.879821 -302.099441)
			(xy 405.871926 -302.148018) (xy 405.856342 -302.194699) (xy 405.833471 -302.238276) (xy 405.803906 -302.27762)
			(xy 405.768413 -302.311712) (xy 405.72791 -302.339668) (xy 405.683448 -302.360766) (xy 405.636177 -302.374458)
			(xy 405.587322 -302.38039) (xy 405.538147 -302.378409) (xy 405.489928 -302.368565) (xy 405.443912 -302.351113)
			(xy 405.401291 -302.326506) (xy 405.36317 -302.295381) (xy 405.330535 -302.258544) (xy 405.304232 -302.216948)
			(xy 405.284941 -302.171672) (xy 405.273164 -302.123888) (xy 405.269204 -302.074834) (xy 404.930102 -302.074834)
			(xy 404.929607 -302.099441) (xy 404.921712 -302.148018) (xy 404.906128 -302.194699) (xy 404.883257 -302.238276)
			(xy 404.853692 -302.27762) (xy 404.818199 -302.311712) (xy 404.777696 -302.339668) (xy 404.733234 -302.360766)
			(xy 404.685963 -302.374458) (xy 404.637108 -302.38039) (xy 404.587933 -302.378409) (xy 404.539714 -302.368565)
			(xy 404.493698 -302.351113) (xy 404.451077 -302.326506) (xy 404.412956 -302.295381) (xy 404.380321 -302.258544)
			(xy 404.354018 -302.216948) (xy 404.334727 -302.171672) (xy 404.32295 -302.123888) (xy 404.31899 -302.074834)
			(xy 403.980142 -302.074834) (xy 403.979647 -302.099441) (xy 403.971752 -302.148018) (xy 403.956168 -302.194699)
			(xy 403.933297 -302.238276) (xy 403.903732 -302.27762) (xy 403.868239 -302.311712) (xy 403.827736 -302.339668)
			(xy 403.783274 -302.360766) (xy 403.736003 -302.374458) (xy 403.687148 -302.38039) (xy 403.637973 -302.378409)
			(xy 403.589754 -302.368565) (xy 403.543738 -302.351113) (xy 403.501117 -302.326506) (xy 403.462996 -302.295381)
			(xy 403.430361 -302.258544) (xy 403.404058 -302.216948) (xy 403.384767 -302.171672) (xy 403.37299 -302.123888)
			(xy 403.36903 -302.074834) (xy 403.030182 -302.074834) (xy 403.029687 -302.099441) (xy 403.021792 -302.148018)
			(xy 403.006208 -302.194699) (xy 402.983337 -302.238276) (xy 402.953772 -302.27762) (xy 402.918279 -302.311712)
			(xy 402.877776 -302.339668) (xy 402.833314 -302.360766) (xy 402.786043 -302.374458) (xy 402.737188 -302.38039)
			(xy 402.688013 -302.378409) (xy 402.639794 -302.368565) (xy 402.593778 -302.351113) (xy 402.551157 -302.326506)
			(xy 402.513036 -302.295381) (xy 402.480401 -302.258544) (xy 402.454098 -302.216948) (xy 402.434807 -302.171672)
			(xy 402.42303 -302.123888) (xy 402.41907 -302.074834) (xy 402.080222 -302.074834) (xy 402.079727 -302.099441)
			(xy 402.071832 -302.148018) (xy 402.056248 -302.194699) (xy 402.033377 -302.238276) (xy 402.003812 -302.27762)
			(xy 401.968319 -302.311712) (xy 401.927816 -302.339668) (xy 401.883354 -302.360766) (xy 401.836083 -302.374458)
			(xy 401.787228 -302.38039) (xy 401.738053 -302.378409) (xy 401.689834 -302.368565) (xy 401.643818 -302.351113)
			(xy 401.601197 -302.326506) (xy 401.563076 -302.295381) (xy 401.530441 -302.258544) (xy 401.504138 -302.216948)
			(xy 401.484847 -302.171672) (xy 401.47307 -302.123888) (xy 401.46911 -302.074834) (xy 401.130262 -302.074834)
			(xy 401.129767 -302.099441) (xy 401.121872 -302.148018) (xy 401.106288 -302.194699) (xy 401.083417 -302.238276)
			(xy 401.053852 -302.27762) (xy 401.018359 -302.311712) (xy 400.977856 -302.339668) (xy 400.933394 -302.360766)
			(xy 400.886123 -302.374458) (xy 400.837268 -302.38039) (xy 400.788093 -302.378409) (xy 400.739874 -302.368565)
			(xy 400.693858 -302.351113) (xy 400.651237 -302.326506) (xy 400.613116 -302.295381) (xy 400.580481 -302.258544)
			(xy 400.554178 -302.216948) (xy 400.534887 -302.171672) (xy 400.52311 -302.123888) (xy 400.51915 -302.074834)
			(xy 400.180302 -302.074834) (xy 400.179807 -302.099441) (xy 400.171912 -302.148018) (xy 400.156328 -302.194699)
			(xy 400.133457 -302.238276) (xy 400.103892 -302.27762) (xy 400.068399 -302.311712) (xy 400.027896 -302.339668)
			(xy 399.983434 -302.360766) (xy 399.936163 -302.374458) (xy 399.887308 -302.38039) (xy 399.838133 -302.378409)
			(xy 399.789914 -302.368565) (xy 399.743898 -302.351113) (xy 399.701277 -302.326506) (xy 399.663156 -302.295381)
			(xy 399.630521 -302.258544) (xy 399.604218 -302.216948) (xy 399.584927 -302.171672) (xy 399.57315 -302.123888)
			(xy 399.56919 -302.074834) (xy 399.230342 -302.074834) (xy 399.229847 -302.099441) (xy 399.221952 -302.148018)
			(xy 399.206368 -302.194699) (xy 399.183497 -302.238276) (xy 399.153932 -302.27762) (xy 399.118439 -302.311712)
			(xy 399.077936 -302.339668) (xy 399.033474 -302.360766) (xy 398.986203 -302.374458) (xy 398.937348 -302.38039)
			(xy 398.888173 -302.378409) (xy 398.839954 -302.368565) (xy 398.793938 -302.351113) (xy 398.751317 -302.326506)
			(xy 398.713196 -302.295381) (xy 398.680561 -302.258544) (xy 398.654258 -302.216948) (xy 398.634967 -302.171672)
			(xy 398.62319 -302.123888) (xy 398.61923 -302.074834) (xy 398.280662 -302.074834) (xy 398.276494 -302.125142)
			(xy 398.264094 -302.17411) (xy 398.243803 -302.22037) (xy 398.216176 -302.26266) (xy 398.181964 -302.299825)
			(xy 398.142103 -302.330853) (xy 398.097678 -302.354897) (xy 398.049902 -302.371301) (xy 398.000077 -302.379619)
			(xy 397.97482 -302.380142) (xy 397.950215 -302.379645) (xy 397.901641 -302.371761) (xy 397.854958 -302.356194)
			(xy 397.811374 -302.333345) (xy 397.772015 -302.303806) (xy 397.754602 -302.286416) (xy 397.754602 -302.286162)
			(xy 397.747298 -302.279152) (xy 397.728744 -302.271091) (xy 397.708517 -302.270837) (xy 397.698976 -302.274224)
			(xy 397.611346 -302.30953) (xy 397.60214 -302.313666) (xy 397.587777 -302.327822) (xy 397.580013 -302.346435)
			(xy 397.579596 -302.35652) (xy 397.579596 -302.743108) (xy 397.58009 -302.753173) (xy 397.587879 -302.771738)
			(xy 397.602185 -302.785904) (xy 397.611346 -302.790098) (xy 397.698976 -302.825404) (xy 397.708526 -302.828721)
			(xy 397.728724 -302.828432) (xy 397.747268 -302.820423) (xy 397.754602 -302.813466) (xy 397.754602 -302.813212)
			(xy 397.772 -302.795805) (xy 397.811364 -302.766271) (xy 397.854952 -302.743426) (xy 397.901637 -302.727861)
			(xy 397.950214 -302.719978) (xy 397.97482 -302.719486) (xy 398.000074 -302.720021) (xy 398.049892 -302.728337)
			(xy 398.097662 -302.74474) (xy 398.142081 -302.76878) (xy 398.181937 -302.799804) (xy 398.216144 -302.836965)
			(xy 398.243768 -302.879249) (xy 398.264056 -302.925503) (xy 398.276454 -302.974465) (xy 398.280625 -303.024794)
			(xy 398.61923 -303.024794) (xy 398.62319 -302.97574) (xy 398.634967 -302.927956) (xy 398.654258 -302.88268)
			(xy 398.680561 -302.841084) (xy 398.713196 -302.804247) (xy 398.751317 -302.773122) (xy 398.793938 -302.748515)
			(xy 398.839954 -302.731063) (xy 398.888173 -302.721219) (xy 398.937348 -302.719238) (xy 398.986203 -302.72517)
			(xy 399.033474 -302.738862) (xy 399.077936 -302.75996) (xy 399.118439 -302.787916) (xy 399.153932 -302.822008)
			(xy 399.183497 -302.861352) (xy 399.206368 -302.904929) (xy 399.221952 -302.95161) (xy 399.229847 -303.000187)
			(xy 399.230342 -303.024794) (xy 399.56919 -303.024794) (xy 399.57315 -302.97574) (xy 399.584927 -302.927956)
			(xy 399.604218 -302.88268) (xy 399.630521 -302.841084) (xy 399.663156 -302.804247) (xy 399.701277 -302.773122)
			(xy 399.743898 -302.748515) (xy 399.789914 -302.731063) (xy 399.838133 -302.721219) (xy 399.887308 -302.719238)
			(xy 399.936163 -302.72517) (xy 399.983434 -302.738862) (xy 400.027896 -302.75996) (xy 400.068399 -302.787916)
			(xy 400.103892 -302.822008) (xy 400.133457 -302.861352) (xy 400.156328 -302.904929) (xy 400.171912 -302.95161)
			(xy 400.179807 -303.000187) (xy 400.180302 -303.024794) (xy 400.51915 -303.024794) (xy 400.52311 -302.97574)
			(xy 400.534887 -302.927956) (xy 400.554178 -302.88268) (xy 400.580481 -302.841084) (xy 400.613116 -302.804247)
			(xy 400.651237 -302.773122) (xy 400.693858 -302.748515) (xy 400.739874 -302.731063) (xy 400.788093 -302.721219)
			(xy 400.837268 -302.719238) (xy 400.886123 -302.72517) (xy 400.933394 -302.738862) (xy 400.977856 -302.75996)
			(xy 401.018359 -302.787916) (xy 401.053852 -302.822008) (xy 401.083417 -302.861352) (xy 401.106288 -302.904929)
			(xy 401.121872 -302.95161) (xy 401.129767 -303.000187) (xy 401.130262 -303.024794) (xy 401.46911 -303.024794)
			(xy 401.47307 -302.97574) (xy 401.484847 -302.927956) (xy 401.504138 -302.88268) (xy 401.530441 -302.841084)
			(xy 401.563076 -302.804247) (xy 401.601197 -302.773122) (xy 401.643818 -302.748515) (xy 401.689834 -302.731063)
			(xy 401.738053 -302.721219) (xy 401.787228 -302.719238) (xy 401.836083 -302.72517) (xy 401.883354 -302.738862)
			(xy 401.927816 -302.75996) (xy 401.968319 -302.787916) (xy 402.003812 -302.822008) (xy 402.033377 -302.861352)
			(xy 402.056248 -302.904929) (xy 402.071832 -302.95161) (xy 402.079727 -303.000187) (xy 402.080222 -303.024794)
			(xy 402.41907 -303.024794) (xy 402.42303 -302.97574) (xy 402.434807 -302.927956) (xy 402.454098 -302.88268)
			(xy 402.480401 -302.841084) (xy 402.513036 -302.804247) (xy 402.551157 -302.773122) (xy 402.593778 -302.748515)
			(xy 402.639794 -302.731063) (xy 402.688013 -302.721219) (xy 402.737188 -302.719238) (xy 402.786043 -302.72517)
			(xy 402.833314 -302.738862) (xy 402.877776 -302.75996) (xy 402.918279 -302.787916) (xy 402.953772 -302.822008)
			(xy 402.983337 -302.861352) (xy 403.006208 -302.904929) (xy 403.021792 -302.95161) (xy 403.029687 -303.000187)
			(xy 403.030182 -303.024794) (xy 403.36903 -303.024794) (xy 403.37299 -302.97574) (xy 403.384767 -302.927956)
			(xy 403.404058 -302.88268) (xy 403.430361 -302.841084) (xy 403.462996 -302.804247) (xy 403.501117 -302.773122)
			(xy 403.543738 -302.748515) (xy 403.589754 -302.731063) (xy 403.637973 -302.721219) (xy 403.687148 -302.719238)
			(xy 403.736003 -302.72517) (xy 403.783274 -302.738862) (xy 403.827736 -302.75996) (xy 403.868239 -302.787916)
			(xy 403.903732 -302.822008) (xy 403.933297 -302.861352) (xy 403.956168 -302.904929) (xy 403.971752 -302.95161)
			(xy 403.979647 -303.000187) (xy 403.980142 -303.024794) (xy 404.31899 -303.024794) (xy 404.32295 -302.97574)
			(xy 404.334727 -302.927956) (xy 404.354018 -302.88268) (xy 404.380321 -302.841084) (xy 404.412956 -302.804247)
			(xy 404.451077 -302.773122) (xy 404.493698 -302.748515) (xy 404.539714 -302.731063) (xy 404.587933 -302.721219)
			(xy 404.637108 -302.719238) (xy 404.685963 -302.72517) (xy 404.733234 -302.738862) (xy 404.777696 -302.75996)
			(xy 404.818199 -302.787916) (xy 404.853692 -302.822008) (xy 404.883257 -302.861352) (xy 404.906128 -302.904929)
			(xy 404.921712 -302.95161) (xy 404.929607 -303.000187) (xy 404.930102 -303.024794) (xy 405.269204 -303.024794)
			(xy 405.273164 -302.97574) (xy 405.284941 -302.927956) (xy 405.304232 -302.88268) (xy 405.330535 -302.841084)
			(xy 405.36317 -302.804247) (xy 405.401291 -302.773122) (xy 405.443912 -302.748515) (xy 405.489928 -302.731063)
			(xy 405.538147 -302.721219) (xy 405.587322 -302.719238) (xy 405.636177 -302.72517) (xy 405.683448 -302.738862)
			(xy 405.72791 -302.75996) (xy 405.768413 -302.787916) (xy 405.803906 -302.822008) (xy 405.833471 -302.861352)
			(xy 405.856342 -302.904929) (xy 405.871926 -302.95161) (xy 405.879821 -303.000187) (xy 405.880316 -303.024794)
			(xy 406.219164 -303.024794) (xy 406.223124 -302.97574) (xy 406.234901 -302.927956) (xy 406.254192 -302.88268)
			(xy 406.280495 -302.841084) (xy 406.31313 -302.804247) (xy 406.351251 -302.773122) (xy 406.393872 -302.748515)
			(xy 406.439888 -302.731063) (xy 406.488107 -302.721219) (xy 406.537282 -302.719238) (xy 406.586137 -302.72517)
			(xy 406.633408 -302.738862) (xy 406.67787 -302.75996) (xy 406.718373 -302.787916) (xy 406.753866 -302.822008)
			(xy 406.783431 -302.861352) (xy 406.806302 -302.904929) (xy 406.821886 -302.95161) (xy 406.829781 -303.000187)
			(xy 406.830276 -303.024794) (xy 408.119084 -303.024794) (xy 408.123044 -302.97574) (xy 408.134821 -302.927956)
			(xy 408.154112 -302.88268) (xy 408.180415 -302.841084) (xy 408.21305 -302.804247) (xy 408.251171 -302.773122)
			(xy 408.293792 -302.748515) (xy 408.339808 -302.731063) (xy 408.388027 -302.721219) (xy 408.437202 -302.719238)
			(xy 408.486057 -302.72517) (xy 408.533328 -302.738862) (xy 408.57779 -302.75996) (xy 408.618293 -302.787916)
			(xy 408.653786 -302.822008) (xy 408.683351 -302.861352) (xy 408.706222 -302.904929) (xy 408.721806 -302.95161)
			(xy 408.729701 -303.000187) (xy 408.730196 -303.024794) (xy 409.069044 -303.024794) (xy 409.073004 -302.97574)
			(xy 409.084781 -302.927956) (xy 409.104072 -302.88268) (xy 409.130375 -302.841084) (xy 409.16301 -302.804247)
			(xy 409.201131 -302.773122) (xy 409.243752 -302.748515) (xy 409.289768 -302.731063) (xy 409.337987 -302.721219)
			(xy 409.387162 -302.719238) (xy 409.436017 -302.72517) (xy 409.483288 -302.738862) (xy 409.52775 -302.75996)
			(xy 409.568253 -302.787916) (xy 409.603746 -302.822008) (xy 409.633311 -302.861352) (xy 409.656182 -302.904929)
			(xy 409.671766 -302.95161) (xy 409.679661 -303.000187) (xy 409.680156 -303.024794) (xy 410.019004 -303.024794)
			(xy 410.022964 -302.97574) (xy 410.034741 -302.927956) (xy 410.054032 -302.88268) (xy 410.080335 -302.841084)
			(xy 410.11297 -302.804247) (xy 410.151091 -302.773122) (xy 410.193712 -302.748515) (xy 410.239728 -302.731063)
			(xy 410.287947 -302.721219) (xy 410.337122 -302.719238) (xy 410.385977 -302.72517) (xy 410.433248 -302.738862)
			(xy 410.47771 -302.75996) (xy 410.518213 -302.787916) (xy 410.553706 -302.822008) (xy 410.583271 -302.861352)
			(xy 410.606142 -302.904929) (xy 410.621726 -302.95161) (xy 410.629621 -303.000187) (xy 410.630116 -303.024794)
			(xy 410.969218 -303.024794) (xy 410.973178 -302.97574) (xy 410.984955 -302.927956) (xy 411.004246 -302.88268)
			(xy 411.030549 -302.841084) (xy 411.063184 -302.804247) (xy 411.101305 -302.773122) (xy 411.143926 -302.748515)
			(xy 411.189942 -302.731063) (xy 411.238161 -302.721219) (xy 411.287336 -302.719238) (xy 411.336191 -302.72517)
			(xy 411.383462 -302.738862) (xy 411.427924 -302.75996) (xy 411.468427 -302.787916) (xy 411.50392 -302.822008)
			(xy 411.533485 -302.861352) (xy 411.556356 -302.904929) (xy 411.57194 -302.95161) (xy 411.579835 -303.000187)
			(xy 411.58033 -303.024794) (xy 411.919178 -303.024794) (xy 411.923138 -302.97574) (xy 411.934915 -302.927956)
			(xy 411.954206 -302.88268) (xy 411.980509 -302.841084) (xy 412.013144 -302.804247) (xy 412.051265 -302.773122)
			(xy 412.093886 -302.748515) (xy 412.139902 -302.731063) (xy 412.188121 -302.721219) (xy 412.237296 -302.719238)
			(xy 412.286151 -302.72517) (xy 412.333422 -302.738862) (xy 412.377884 -302.75996) (xy 412.418387 -302.787916)
			(xy 412.45388 -302.822008) (xy 412.483445 -302.861352) (xy 412.506316 -302.904929) (xy 412.5219 -302.95161)
			(xy 412.529795 -303.000187) (xy 412.53029 -303.024794) (xy 412.869138 -303.024794) (xy 412.873098 -302.97574)
			(xy 412.884875 -302.927956) (xy 412.904166 -302.88268) (xy 412.930469 -302.841084) (xy 412.963104 -302.804247)
			(xy 413.001225 -302.773122) (xy 413.043846 -302.748515) (xy 413.089862 -302.731063) (xy 413.138081 -302.721219)
			(xy 413.187256 -302.719238) (xy 413.236111 -302.72517) (xy 413.283382 -302.738862) (xy 413.327844 -302.75996)
			(xy 413.368347 -302.787916) (xy 413.40384 -302.822008) (xy 413.433405 -302.861352) (xy 413.456276 -302.904929)
			(xy 413.47186 -302.95161) (xy 413.479755 -303.000187) (xy 413.48025 -303.024794) (xy 413.819098 -303.024794)
			(xy 413.823058 -302.97574) (xy 413.834835 -302.927956) (xy 413.854126 -302.88268) (xy 413.880429 -302.841084)
			(xy 413.913064 -302.804247) (xy 413.951185 -302.773122) (xy 413.993806 -302.748515) (xy 414.039822 -302.731063)
			(xy 414.088041 -302.721219) (xy 414.137216 -302.719238) (xy 414.186071 -302.72517) (xy 414.233342 -302.738862)
			(xy 414.277804 -302.75996) (xy 414.318307 -302.787916) (xy 414.3538 -302.822008) (xy 414.383365 -302.861352)
			(xy 414.406236 -302.904929) (xy 414.42182 -302.95161) (xy 414.429715 -303.000187) (xy 414.43021 -303.024794)
			(xy 414.769058 -303.024794) (xy 414.773018 -302.97574) (xy 414.784795 -302.927956) (xy 414.804086 -302.88268)
			(xy 414.830389 -302.841084) (xy 414.863024 -302.804247) (xy 414.901145 -302.773122) (xy 414.943766 -302.748515)
			(xy 414.989782 -302.731063) (xy 415.038001 -302.721219) (xy 415.087176 -302.719238) (xy 415.136031 -302.72517)
			(xy 415.183302 -302.738862) (xy 415.227764 -302.75996) (xy 415.268267 -302.787916) (xy 415.30376 -302.822008)
			(xy 415.333325 -302.861352) (xy 415.356196 -302.904929) (xy 415.37178 -302.95161) (xy 415.379675 -303.000187)
			(xy 415.38017 -303.024794) (xy 415.719018 -303.024794) (xy 415.722978 -302.97574) (xy 415.734755 -302.927956)
			(xy 415.754046 -302.88268) (xy 415.780349 -302.841084) (xy 415.812984 -302.804247) (xy 415.851105 -302.773122)
			(xy 415.893726 -302.748515) (xy 415.939742 -302.731063) (xy 415.987961 -302.721219) (xy 416.037136 -302.719238)
			(xy 416.085991 -302.72517) (xy 416.133262 -302.738862) (xy 416.177724 -302.75996) (xy 416.218227 -302.787916)
			(xy 416.25372 -302.822008) (xy 416.283285 -302.861352) (xy 416.306156 -302.904929) (xy 416.32174 -302.95161)
			(xy 416.329635 -303.000187) (xy 416.33013 -303.024794) (xy 416.329635 -303.049401) (xy 416.32174 -303.097978)
			(xy 416.306156 -303.144659) (xy 416.283285 -303.188236) (xy 416.25372 -303.22758) (xy 416.218227 -303.261672)
			(xy 416.177724 -303.289628) (xy 416.133262 -303.310726) (xy 416.085991 -303.324418) (xy 416.037136 -303.33035)
			(xy 415.987961 -303.328369) (xy 415.939742 -303.318525) (xy 415.893726 -303.301073) (xy 415.851105 -303.276466)
			(xy 415.812984 -303.245341) (xy 415.780349 -303.208504) (xy 415.754046 -303.166908) (xy 415.734755 -303.121632)
			(xy 415.722978 -303.073848) (xy 415.719018 -303.024794) (xy 415.38017 -303.024794) (xy 415.379675 -303.049401)
			(xy 415.37178 -303.097978) (xy 415.356196 -303.144659) (xy 415.333325 -303.188236) (xy 415.30376 -303.22758)
			(xy 415.268267 -303.261672) (xy 415.227764 -303.289628) (xy 415.183302 -303.310726) (xy 415.136031 -303.324418)
			(xy 415.087176 -303.33035) (xy 415.038001 -303.328369) (xy 414.989782 -303.318525) (xy 414.943766 -303.301073)
			(xy 414.901145 -303.276466) (xy 414.863024 -303.245341) (xy 414.830389 -303.208504) (xy 414.804086 -303.166908)
			(xy 414.784795 -303.121632) (xy 414.773018 -303.073848) (xy 414.769058 -303.024794) (xy 414.43021 -303.024794)
			(xy 414.429715 -303.049401) (xy 414.42182 -303.097978) (xy 414.406236 -303.144659) (xy 414.383365 -303.188236)
			(xy 414.3538 -303.22758) (xy 414.318307 -303.261672) (xy 414.277804 -303.289628) (xy 414.233342 -303.310726)
			(xy 414.186071 -303.324418) (xy 414.137216 -303.33035) (xy 414.088041 -303.328369) (xy 414.039822 -303.318525)
			(xy 413.993806 -303.301073) (xy 413.951185 -303.276466) (xy 413.913064 -303.245341) (xy 413.880429 -303.208504)
			(xy 413.854126 -303.166908) (xy 413.834835 -303.121632) (xy 413.823058 -303.073848) (xy 413.819098 -303.024794)
			(xy 413.48025 -303.024794) (xy 413.479755 -303.049401) (xy 413.47186 -303.097978) (xy 413.456276 -303.144659)
			(xy 413.433405 -303.188236) (xy 413.40384 -303.22758) (xy 413.368347 -303.261672) (xy 413.327844 -303.289628)
			(xy 413.283382 -303.310726) (xy 413.236111 -303.324418) (xy 413.187256 -303.33035) (xy 413.138081 -303.328369)
			(xy 413.089862 -303.318525) (xy 413.043846 -303.301073) (xy 413.001225 -303.276466) (xy 412.963104 -303.245341)
			(xy 412.930469 -303.208504) (xy 412.904166 -303.166908) (xy 412.884875 -303.121632) (xy 412.873098 -303.073848)
			(xy 412.869138 -303.024794) (xy 412.53029 -303.024794) (xy 412.529795 -303.049401) (xy 412.5219 -303.097978)
			(xy 412.506316 -303.144659) (xy 412.483445 -303.188236) (xy 412.45388 -303.22758) (xy 412.418387 -303.261672)
			(xy 412.377884 -303.289628) (xy 412.333422 -303.310726) (xy 412.286151 -303.324418) (xy 412.237296 -303.33035)
			(xy 412.188121 -303.328369) (xy 412.139902 -303.318525) (xy 412.093886 -303.301073) (xy 412.051265 -303.276466)
			(xy 412.013144 -303.245341) (xy 411.980509 -303.208504) (xy 411.954206 -303.166908) (xy 411.934915 -303.121632)
			(xy 411.923138 -303.073848) (xy 411.919178 -303.024794) (xy 411.58033 -303.024794) (xy 411.579835 -303.049401)
			(xy 411.57194 -303.097978) (xy 411.556356 -303.144659) (xy 411.533485 -303.188236) (xy 411.50392 -303.22758)
			(xy 411.468427 -303.261672) (xy 411.427924 -303.289628) (xy 411.383462 -303.310726) (xy 411.336191 -303.324418)
			(xy 411.287336 -303.33035) (xy 411.238161 -303.328369) (xy 411.189942 -303.318525) (xy 411.143926 -303.301073)
			(xy 411.101305 -303.276466) (xy 411.063184 -303.245341) (xy 411.030549 -303.208504) (xy 411.004246 -303.166908)
			(xy 410.984955 -303.121632) (xy 410.973178 -303.073848) (xy 410.969218 -303.024794) (xy 410.630116 -303.024794)
			(xy 410.629621 -303.049401) (xy 410.621726 -303.097978) (xy 410.606142 -303.144659) (xy 410.583271 -303.188236)
			(xy 410.553706 -303.22758) (xy 410.518213 -303.261672) (xy 410.47771 -303.289628) (xy 410.433248 -303.310726)
			(xy 410.385977 -303.324418) (xy 410.337122 -303.33035) (xy 410.287947 -303.328369) (xy 410.239728 -303.318525)
			(xy 410.193712 -303.301073) (xy 410.151091 -303.276466) (xy 410.11297 -303.245341) (xy 410.080335 -303.208504)
			(xy 410.054032 -303.166908) (xy 410.034741 -303.121632) (xy 410.022964 -303.073848) (xy 410.019004 -303.024794)
			(xy 409.680156 -303.024794) (xy 409.679661 -303.049401) (xy 409.671766 -303.097978) (xy 409.656182 -303.144659)
			(xy 409.633311 -303.188236) (xy 409.603746 -303.22758) (xy 409.568253 -303.261672) (xy 409.52775 -303.289628)
			(xy 409.483288 -303.310726) (xy 409.436017 -303.324418) (xy 409.387162 -303.33035) (xy 409.337987 -303.328369)
			(xy 409.289768 -303.318525) (xy 409.243752 -303.301073) (xy 409.201131 -303.276466) (xy 409.16301 -303.245341)
			(xy 409.130375 -303.208504) (xy 409.104072 -303.166908) (xy 409.084781 -303.121632) (xy 409.073004 -303.073848)
			(xy 409.069044 -303.024794) (xy 408.730196 -303.024794) (xy 408.729701 -303.049401) (xy 408.721806 -303.097978)
			(xy 408.706222 -303.144659) (xy 408.683351 -303.188236) (xy 408.653786 -303.22758) (xy 408.618293 -303.261672)
			(xy 408.57779 -303.289628) (xy 408.533328 -303.310726) (xy 408.486057 -303.324418) (xy 408.437202 -303.33035)
			(xy 408.388027 -303.328369) (xy 408.339808 -303.318525) (xy 408.293792 -303.301073) (xy 408.251171 -303.276466)
			(xy 408.21305 -303.245341) (xy 408.180415 -303.208504) (xy 408.154112 -303.166908) (xy 408.134821 -303.121632)
			(xy 408.123044 -303.073848) (xy 408.119084 -303.024794) (xy 406.830276 -303.024794) (xy 406.829781 -303.049401)
			(xy 406.821886 -303.097978) (xy 406.806302 -303.144659) (xy 406.783431 -303.188236) (xy 406.753866 -303.22758)
			(xy 406.718373 -303.261672) (xy 406.67787 -303.289628) (xy 406.633408 -303.310726) (xy 406.586137 -303.324418)
			(xy 406.537282 -303.33035) (xy 406.488107 -303.328369) (xy 406.439888 -303.318525) (xy 406.393872 -303.301073)
			(xy 406.351251 -303.276466) (xy 406.31313 -303.245341) (xy 406.280495 -303.208504) (xy 406.254192 -303.166908)
			(xy 406.234901 -303.121632) (xy 406.223124 -303.073848) (xy 406.219164 -303.024794) (xy 405.880316 -303.024794)
			(xy 405.879821 -303.049401) (xy 405.871926 -303.097978) (xy 405.856342 -303.144659) (xy 405.833471 -303.188236)
			(xy 405.803906 -303.22758) (xy 405.768413 -303.261672) (xy 405.72791 -303.289628) (xy 405.683448 -303.310726)
			(xy 405.636177 -303.324418) (xy 405.587322 -303.33035) (xy 405.538147 -303.328369) (xy 405.489928 -303.318525)
			(xy 405.443912 -303.301073) (xy 405.401291 -303.276466) (xy 405.36317 -303.245341) (xy 405.330535 -303.208504)
			(xy 405.304232 -303.166908) (xy 405.284941 -303.121632) (xy 405.273164 -303.073848) (xy 405.269204 -303.024794)
			(xy 404.930102 -303.024794) (xy 404.929607 -303.049401) (xy 404.921712 -303.097978) (xy 404.906128 -303.144659)
			(xy 404.883257 -303.188236) (xy 404.853692 -303.22758) (xy 404.818199 -303.261672) (xy 404.777696 -303.289628)
			(xy 404.733234 -303.310726) (xy 404.685963 -303.324418) (xy 404.637108 -303.33035) (xy 404.587933 -303.328369)
			(xy 404.539714 -303.318525) (xy 404.493698 -303.301073) (xy 404.451077 -303.276466) (xy 404.412956 -303.245341)
			(xy 404.380321 -303.208504) (xy 404.354018 -303.166908) (xy 404.334727 -303.121632) (xy 404.32295 -303.073848)
			(xy 404.31899 -303.024794) (xy 403.980142 -303.024794) (xy 403.979647 -303.049401) (xy 403.971752 -303.097978)
			(xy 403.956168 -303.144659) (xy 403.933297 -303.188236) (xy 403.903732 -303.22758) (xy 403.868239 -303.261672)
			(xy 403.827736 -303.289628) (xy 403.783274 -303.310726) (xy 403.736003 -303.324418) (xy 403.687148 -303.33035)
			(xy 403.637973 -303.328369) (xy 403.589754 -303.318525) (xy 403.543738 -303.301073) (xy 403.501117 -303.276466)
			(xy 403.462996 -303.245341) (xy 403.430361 -303.208504) (xy 403.404058 -303.166908) (xy 403.384767 -303.121632)
			(xy 403.37299 -303.073848) (xy 403.36903 -303.024794) (xy 403.030182 -303.024794) (xy 403.029687 -303.049401)
			(xy 403.021792 -303.097978) (xy 403.006208 -303.144659) (xy 402.983337 -303.188236) (xy 402.953772 -303.22758)
			(xy 402.918279 -303.261672) (xy 402.877776 -303.289628) (xy 402.833314 -303.310726) (xy 402.786043 -303.324418)
			(xy 402.737188 -303.33035) (xy 402.688013 -303.328369) (xy 402.639794 -303.318525) (xy 402.593778 -303.301073)
			(xy 402.551157 -303.276466) (xy 402.513036 -303.245341) (xy 402.480401 -303.208504) (xy 402.454098 -303.166908)
			(xy 402.434807 -303.121632) (xy 402.42303 -303.073848) (xy 402.41907 -303.024794) (xy 402.080222 -303.024794)
			(xy 402.079727 -303.049401) (xy 402.071832 -303.097978) (xy 402.056248 -303.144659) (xy 402.033377 -303.188236)
			(xy 402.003812 -303.22758) (xy 401.968319 -303.261672) (xy 401.927816 -303.289628) (xy 401.883354 -303.310726)
			(xy 401.836083 -303.324418) (xy 401.787228 -303.33035) (xy 401.738053 -303.328369) (xy 401.689834 -303.318525)
			(xy 401.643818 -303.301073) (xy 401.601197 -303.276466) (xy 401.563076 -303.245341) (xy 401.530441 -303.208504)
			(xy 401.504138 -303.166908) (xy 401.484847 -303.121632) (xy 401.47307 -303.073848) (xy 401.46911 -303.024794)
			(xy 401.130262 -303.024794) (xy 401.129767 -303.049401) (xy 401.121872 -303.097978) (xy 401.106288 -303.144659)
			(xy 401.083417 -303.188236) (xy 401.053852 -303.22758) (xy 401.018359 -303.261672) (xy 400.977856 -303.289628)
			(xy 400.933394 -303.310726) (xy 400.886123 -303.324418) (xy 400.837268 -303.33035) (xy 400.788093 -303.328369)
			(xy 400.739874 -303.318525) (xy 400.693858 -303.301073) (xy 400.651237 -303.276466) (xy 400.613116 -303.245341)
			(xy 400.580481 -303.208504) (xy 400.554178 -303.166908) (xy 400.534887 -303.121632) (xy 400.52311 -303.073848)
			(xy 400.51915 -303.024794) (xy 400.180302 -303.024794) (xy 400.179807 -303.049401) (xy 400.171912 -303.097978)
			(xy 400.156328 -303.144659) (xy 400.133457 -303.188236) (xy 400.103892 -303.22758) (xy 400.068399 -303.261672)
			(xy 400.027896 -303.289628) (xy 399.983434 -303.310726) (xy 399.936163 -303.324418) (xy 399.887308 -303.33035)
			(xy 399.838133 -303.328369) (xy 399.789914 -303.318525) (xy 399.743898 -303.301073) (xy 399.701277 -303.276466)
			(xy 399.663156 -303.245341) (xy 399.630521 -303.208504) (xy 399.604218 -303.166908) (xy 399.584927 -303.121632)
			(xy 399.57315 -303.073848) (xy 399.56919 -303.024794) (xy 399.230342 -303.024794) (xy 399.229847 -303.049401)
			(xy 399.221952 -303.097978) (xy 399.206368 -303.144659) (xy 399.183497 -303.188236) (xy 399.153932 -303.22758)
			(xy 399.118439 -303.261672) (xy 399.077936 -303.289628) (xy 399.033474 -303.310726) (xy 398.986203 -303.324418)
			(xy 398.937348 -303.33035) (xy 398.888173 -303.328369) (xy 398.839954 -303.318525) (xy 398.793938 -303.301073)
			(xy 398.751317 -303.276466) (xy 398.713196 -303.245341) (xy 398.680561 -303.208504) (xy 398.654258 -303.166908)
			(xy 398.634967 -303.121632) (xy 398.62319 -303.073848) (xy 398.61923 -303.024794) (xy 398.280625 -303.024794)
			(xy 398.280625 -303.0248) (xy 398.276454 -303.075135) (xy 398.264056 -303.124097) (xy 398.243768 -303.170351)
			(xy 398.216144 -303.212635) (xy 398.181937 -303.249796) (xy 398.142081 -303.28082) (xy 398.097662 -303.30486)
			(xy 398.049892 -303.321263) (xy 398.000074 -303.329579) (xy 397.97482 -303.330102) (xy 397.950214 -303.329618)
			(xy 397.901639 -303.321732) (xy 397.854955 -303.306163) (xy 397.811372 -303.283311) (xy 397.772014 -303.253768)
			(xy 397.754602 -303.236376) (xy 397.754602 -303.236122) (xy 397.747292 -303.229117) (xy 397.728743 -303.221048)
			(xy 397.708516 -303.220794) (xy 397.698976 -303.224184) (xy 397.611346 -303.25949) (xy 397.602156 -303.263655)
			(xy 397.587792 -303.277799) (xy 397.580021 -303.2964) (xy 397.579596 -303.30648) (xy 397.579596 -303.693068)
			(xy 397.580046 -303.703137) (xy 397.587856 -303.721704) (xy 397.602178 -303.735867) (xy 397.611346 -303.740058)
			(xy 397.698976 -303.775364) (xy 397.70853 -303.778665) (xy 397.728722 -303.778376) (xy 397.747265 -303.770376)
			(xy 397.754602 -303.763426) (xy 397.754602 -303.763172) (xy 397.77201 -303.745776) (xy 397.81137 -303.716238)
			(xy 397.854955 -303.693389) (xy 397.901639 -303.677822) (xy 397.950214 -303.669938) (xy 397.97482 -303.669446)
			(xy 398.00007 -303.670061) (xy 398.049882 -303.678376) (xy 398.097646 -303.694776) (xy 398.142059 -303.718814)
			(xy 398.18191 -303.749834) (xy 398.216113 -303.78699) (xy 398.243733 -303.829268) (xy 398.264018 -303.875516)
			(xy 398.276415 -303.924472) (xy 398.280581 -303.974754) (xy 398.61923 -303.974754) (xy 398.62319 -303.9257)
			(xy 398.634967 -303.877916) (xy 398.654258 -303.83264) (xy 398.680561 -303.791044) (xy 398.713196 -303.754207)
			(xy 398.751317 -303.723082) (xy 398.793938 -303.698475) (xy 398.839954 -303.681023) (xy 398.888173 -303.671179)
			(xy 398.937348 -303.669198) (xy 398.986203 -303.67513) (xy 399.033474 -303.688822) (xy 399.077936 -303.70992)
			(xy 399.118439 -303.737876) (xy 399.153932 -303.771968) (xy 399.183497 -303.811312) (xy 399.206368 -303.854889)
			(xy 399.221952 -303.90157) (xy 399.229847 -303.950147) (xy 399.230342 -303.974754) (xy 399.56919 -303.974754)
			(xy 399.57315 -303.9257) (xy 399.584927 -303.877916) (xy 399.604218 -303.83264) (xy 399.630521 -303.791044)
			(xy 399.663156 -303.754207) (xy 399.701277 -303.723082) (xy 399.743898 -303.698475) (xy 399.789914 -303.681023)
			(xy 399.838133 -303.671179) (xy 399.887308 -303.669198) (xy 399.936163 -303.67513) (xy 399.983434 -303.688822)
			(xy 400.027896 -303.70992) (xy 400.068399 -303.737876) (xy 400.103892 -303.771968) (xy 400.133457 -303.811312)
			(xy 400.156328 -303.854889) (xy 400.171912 -303.90157) (xy 400.179807 -303.950147) (xy 400.180302 -303.974754)
			(xy 400.51915 -303.974754) (xy 400.52311 -303.9257) (xy 400.534887 -303.877916) (xy 400.554178 -303.83264)
			(xy 400.580481 -303.791044) (xy 400.613116 -303.754207) (xy 400.651237 -303.723082) (xy 400.693858 -303.698475)
			(xy 400.739874 -303.681023) (xy 400.788093 -303.671179) (xy 400.837268 -303.669198) (xy 400.886123 -303.67513)
			(xy 400.933394 -303.688822) (xy 400.977856 -303.70992) (xy 401.018359 -303.737876) (xy 401.053852 -303.771968)
			(xy 401.083417 -303.811312) (xy 401.106288 -303.854889) (xy 401.121872 -303.90157) (xy 401.129767 -303.950147)
			(xy 401.130262 -303.974754) (xy 401.46911 -303.974754) (xy 401.47307 -303.9257) (xy 401.484847 -303.877916)
			(xy 401.504138 -303.83264) (xy 401.530441 -303.791044) (xy 401.563076 -303.754207) (xy 401.601197 -303.723082)
			(xy 401.643818 -303.698475) (xy 401.689834 -303.681023) (xy 401.738053 -303.671179) (xy 401.787228 -303.669198)
			(xy 401.836083 -303.67513) (xy 401.883354 -303.688822) (xy 401.927816 -303.70992) (xy 401.968319 -303.737876)
			(xy 402.003812 -303.771968) (xy 402.033377 -303.811312) (xy 402.056248 -303.854889) (xy 402.071832 -303.90157)
			(xy 402.079727 -303.950147) (xy 402.080222 -303.974754) (xy 402.41907 -303.974754) (xy 402.42303 -303.9257)
			(xy 402.434807 -303.877916) (xy 402.454098 -303.83264) (xy 402.480401 -303.791044) (xy 402.513036 -303.754207)
			(xy 402.551157 -303.723082) (xy 402.593778 -303.698475) (xy 402.639794 -303.681023) (xy 402.688013 -303.671179)
			(xy 402.737188 -303.669198) (xy 402.786043 -303.67513) (xy 402.833314 -303.688822) (xy 402.877776 -303.70992)
			(xy 402.918279 -303.737876) (xy 402.953772 -303.771968) (xy 402.983337 -303.811312) (xy 403.006208 -303.854889)
			(xy 403.021792 -303.90157) (xy 403.029687 -303.950147) (xy 403.030182 -303.974754) (xy 403.36903 -303.974754)
			(xy 403.37299 -303.9257) (xy 403.384767 -303.877916) (xy 403.404058 -303.83264) (xy 403.430361 -303.791044)
			(xy 403.462996 -303.754207) (xy 403.501117 -303.723082) (xy 403.543738 -303.698475) (xy 403.589754 -303.681023)
			(xy 403.637973 -303.671179) (xy 403.687148 -303.669198) (xy 403.736003 -303.67513) (xy 403.783274 -303.688822)
			(xy 403.827736 -303.70992) (xy 403.868239 -303.737876) (xy 403.903732 -303.771968) (xy 403.933297 -303.811312)
			(xy 403.956168 -303.854889) (xy 403.971752 -303.90157) (xy 403.979647 -303.950147) (xy 403.980142 -303.974754)
			(xy 404.31899 -303.974754) (xy 404.32295 -303.9257) (xy 404.334727 -303.877916) (xy 404.354018 -303.83264)
			(xy 404.380321 -303.791044) (xy 404.412956 -303.754207) (xy 404.451077 -303.723082) (xy 404.493698 -303.698475)
			(xy 404.539714 -303.681023) (xy 404.587933 -303.671179) (xy 404.637108 -303.669198) (xy 404.685963 -303.67513)
			(xy 404.733234 -303.688822) (xy 404.777696 -303.70992) (xy 404.818199 -303.737876) (xy 404.853692 -303.771968)
			(xy 404.883257 -303.811312) (xy 404.906128 -303.854889) (xy 404.921712 -303.90157) (xy 404.929607 -303.950147)
			(xy 404.930102 -303.974754) (xy 405.269204 -303.974754) (xy 405.273164 -303.9257) (xy 405.284941 -303.877916)
			(xy 405.304232 -303.83264) (xy 405.330535 -303.791044) (xy 405.36317 -303.754207) (xy 405.401291 -303.723082)
			(xy 405.443912 -303.698475) (xy 405.489928 -303.681023) (xy 405.538147 -303.671179) (xy 405.587322 -303.669198)
			(xy 405.636177 -303.67513) (xy 405.683448 -303.688822) (xy 405.72791 -303.70992) (xy 405.768413 -303.737876)
			(xy 405.803906 -303.771968) (xy 405.833471 -303.811312) (xy 405.856342 -303.854889) (xy 405.871926 -303.90157)
			(xy 405.879821 -303.950147) (xy 405.880316 -303.974754) (xy 406.219164 -303.974754) (xy 406.223124 -303.9257)
			(xy 406.234901 -303.877916) (xy 406.254192 -303.83264) (xy 406.280495 -303.791044) (xy 406.31313 -303.754207)
			(xy 406.351251 -303.723082) (xy 406.393872 -303.698475) (xy 406.439888 -303.681023) (xy 406.488107 -303.671179)
			(xy 406.537282 -303.669198) (xy 406.586137 -303.67513) (xy 406.633408 -303.688822) (xy 406.67787 -303.70992)
			(xy 406.718373 -303.737876) (xy 406.753866 -303.771968) (xy 406.783431 -303.811312) (xy 406.806302 -303.854889)
			(xy 406.821886 -303.90157) (xy 406.829781 -303.950147) (xy 406.830276 -303.974754) (xy 408.119084 -303.974754)
			(xy 408.123044 -303.9257) (xy 408.134821 -303.877916) (xy 408.154112 -303.83264) (xy 408.180415 -303.791044)
			(xy 408.21305 -303.754207) (xy 408.251171 -303.723082) (xy 408.293792 -303.698475) (xy 408.339808 -303.681023)
			(xy 408.388027 -303.671179) (xy 408.437202 -303.669198) (xy 408.486057 -303.67513) (xy 408.533328 -303.688822)
			(xy 408.57779 -303.70992) (xy 408.618293 -303.737876) (xy 408.653786 -303.771968) (xy 408.683351 -303.811312)
			(xy 408.706222 -303.854889) (xy 408.721806 -303.90157) (xy 408.729701 -303.950147) (xy 408.730196 -303.974754)
			(xy 409.069044 -303.974754) (xy 409.073004 -303.9257) (xy 409.084781 -303.877916) (xy 409.104072 -303.83264)
			(xy 409.130375 -303.791044) (xy 409.16301 -303.754207) (xy 409.201131 -303.723082) (xy 409.243752 -303.698475)
			(xy 409.289768 -303.681023) (xy 409.337987 -303.671179) (xy 409.387162 -303.669198) (xy 409.436017 -303.67513)
			(xy 409.483288 -303.688822) (xy 409.52775 -303.70992) (xy 409.568253 -303.737876) (xy 409.603746 -303.771968)
			(xy 409.633311 -303.811312) (xy 409.656182 -303.854889) (xy 409.671766 -303.90157) (xy 409.679661 -303.950147)
			(xy 409.680156 -303.974754) (xy 410.019004 -303.974754) (xy 410.022964 -303.9257) (xy 410.034741 -303.877916)
			(xy 410.054032 -303.83264) (xy 410.080335 -303.791044) (xy 410.11297 -303.754207) (xy 410.151091 -303.723082)
			(xy 410.193712 -303.698475) (xy 410.239728 -303.681023) (xy 410.287947 -303.671179) (xy 410.337122 -303.669198)
			(xy 410.385977 -303.67513) (xy 410.433248 -303.688822) (xy 410.47771 -303.70992) (xy 410.518213 -303.737876)
			(xy 410.553706 -303.771968) (xy 410.583271 -303.811312) (xy 410.606142 -303.854889) (xy 410.621726 -303.90157)
			(xy 410.629621 -303.950147) (xy 410.630116 -303.974754) (xy 410.969218 -303.974754) (xy 410.973178 -303.9257)
			(xy 410.984955 -303.877916) (xy 411.004246 -303.83264) (xy 411.030549 -303.791044) (xy 411.063184 -303.754207)
			(xy 411.101305 -303.723082) (xy 411.143926 -303.698475) (xy 411.189942 -303.681023) (xy 411.238161 -303.671179)
			(xy 411.287336 -303.669198) (xy 411.336191 -303.67513) (xy 411.383462 -303.688822) (xy 411.427924 -303.70992)
			(xy 411.468427 -303.737876) (xy 411.50392 -303.771968) (xy 411.533485 -303.811312) (xy 411.556356 -303.854889)
			(xy 411.57194 -303.90157) (xy 411.579835 -303.950147) (xy 411.58033 -303.974754) (xy 411.919178 -303.974754)
			(xy 411.923138 -303.9257) (xy 411.934915 -303.877916) (xy 411.954206 -303.83264) (xy 411.980509 -303.791044)
			(xy 412.013144 -303.754207) (xy 412.051265 -303.723082) (xy 412.093886 -303.698475) (xy 412.139902 -303.681023)
			(xy 412.188121 -303.671179) (xy 412.237296 -303.669198) (xy 412.286151 -303.67513) (xy 412.333422 -303.688822)
			(xy 412.377884 -303.70992) (xy 412.418387 -303.737876) (xy 412.45388 -303.771968) (xy 412.483445 -303.811312)
			(xy 412.506316 -303.854889) (xy 412.5219 -303.90157) (xy 412.529795 -303.950147) (xy 412.53029 -303.974754)
			(xy 412.869138 -303.974754) (xy 412.873098 -303.9257) (xy 412.884875 -303.877916) (xy 412.904166 -303.83264)
			(xy 412.930469 -303.791044) (xy 412.963104 -303.754207) (xy 413.001225 -303.723082) (xy 413.043846 -303.698475)
			(xy 413.089862 -303.681023) (xy 413.138081 -303.671179) (xy 413.187256 -303.669198) (xy 413.236111 -303.67513)
			(xy 413.283382 -303.688822) (xy 413.327844 -303.70992) (xy 413.368347 -303.737876) (xy 413.40384 -303.771968)
			(xy 413.433405 -303.811312) (xy 413.456276 -303.854889) (xy 413.47186 -303.90157) (xy 413.479755 -303.950147)
			(xy 413.48025 -303.974754) (xy 413.819098 -303.974754) (xy 413.823058 -303.9257) (xy 413.834835 -303.877916)
			(xy 413.854126 -303.83264) (xy 413.880429 -303.791044) (xy 413.913064 -303.754207) (xy 413.951185 -303.723082)
			(xy 413.993806 -303.698475) (xy 414.039822 -303.681023) (xy 414.088041 -303.671179) (xy 414.137216 -303.669198)
			(xy 414.186071 -303.67513) (xy 414.233342 -303.688822) (xy 414.277804 -303.70992) (xy 414.318307 -303.737876)
			(xy 414.3538 -303.771968) (xy 414.383365 -303.811312) (xy 414.406236 -303.854889) (xy 414.42182 -303.90157)
			(xy 414.429715 -303.950147) (xy 414.43021 -303.974754) (xy 414.769058 -303.974754) (xy 414.773018 -303.9257)
			(xy 414.784795 -303.877916) (xy 414.804086 -303.83264) (xy 414.830389 -303.791044) (xy 414.863024 -303.754207)
			(xy 414.901145 -303.723082) (xy 414.943766 -303.698475) (xy 414.989782 -303.681023) (xy 415.038001 -303.671179)
			(xy 415.087176 -303.669198) (xy 415.136031 -303.67513) (xy 415.183302 -303.688822) (xy 415.227764 -303.70992)
			(xy 415.268267 -303.737876) (xy 415.30376 -303.771968) (xy 415.333325 -303.811312) (xy 415.356196 -303.854889)
			(xy 415.37178 -303.90157) (xy 415.379675 -303.950147) (xy 415.38017 -303.974754) (xy 415.719018 -303.974754)
			(xy 415.722978 -303.9257) (xy 415.734755 -303.877916) (xy 415.754046 -303.83264) (xy 415.780349 -303.791044)
			(xy 415.812984 -303.754207) (xy 415.851105 -303.723082) (xy 415.893726 -303.698475) (xy 415.939742 -303.681023)
			(xy 415.987961 -303.671179) (xy 416.037136 -303.669198) (xy 416.085991 -303.67513) (xy 416.133262 -303.688822)
			(xy 416.177724 -303.70992) (xy 416.218227 -303.737876) (xy 416.25372 -303.771968) (xy 416.283285 -303.811312)
			(xy 416.306156 -303.854889) (xy 416.32174 -303.90157) (xy 416.329635 -303.950147) (xy 416.33013 -303.974754)
			(xy 416.329635 -303.999361) (xy 416.32174 -304.047938) (xy 416.306156 -304.094619) (xy 416.283285 -304.138196)
			(xy 416.25372 -304.17754) (xy 416.218227 -304.211632) (xy 416.177724 -304.239588) (xy 416.133262 -304.260686)
			(xy 416.085991 -304.274378) (xy 416.037136 -304.28031) (xy 415.987961 -304.278329) (xy 415.939742 -304.268485)
			(xy 415.893726 -304.251033) (xy 415.851105 -304.226426) (xy 415.812984 -304.195301) (xy 415.780349 -304.158464)
			(xy 415.754046 -304.116868) (xy 415.734755 -304.071592) (xy 415.722978 -304.023808) (xy 415.719018 -303.974754)
			(xy 415.38017 -303.974754) (xy 415.379675 -303.999361) (xy 415.37178 -304.047938) (xy 415.356196 -304.094619)
			(xy 415.333325 -304.138196) (xy 415.30376 -304.17754) (xy 415.268267 -304.211632) (xy 415.227764 -304.239588)
			(xy 415.183302 -304.260686) (xy 415.136031 -304.274378) (xy 415.087176 -304.28031) (xy 415.038001 -304.278329)
			(xy 414.989782 -304.268485) (xy 414.943766 -304.251033) (xy 414.901145 -304.226426) (xy 414.863024 -304.195301)
			(xy 414.830389 -304.158464) (xy 414.804086 -304.116868) (xy 414.784795 -304.071592) (xy 414.773018 -304.023808)
			(xy 414.769058 -303.974754) (xy 414.43021 -303.974754) (xy 414.429715 -303.999361) (xy 414.42182 -304.047938)
			(xy 414.406236 -304.094619) (xy 414.383365 -304.138196) (xy 414.3538 -304.17754) (xy 414.318307 -304.211632)
			(xy 414.277804 -304.239588) (xy 414.233342 -304.260686) (xy 414.186071 -304.274378) (xy 414.137216 -304.28031)
			(xy 414.088041 -304.278329) (xy 414.039822 -304.268485) (xy 413.993806 -304.251033) (xy 413.951185 -304.226426)
			(xy 413.913064 -304.195301) (xy 413.880429 -304.158464) (xy 413.854126 -304.116868) (xy 413.834835 -304.071592)
			(xy 413.823058 -304.023808) (xy 413.819098 -303.974754) (xy 413.48025 -303.974754) (xy 413.479755 -303.999361)
			(xy 413.47186 -304.047938) (xy 413.456276 -304.094619) (xy 413.433405 -304.138196) (xy 413.40384 -304.17754)
			(xy 413.368347 -304.211632) (xy 413.327844 -304.239588) (xy 413.283382 -304.260686) (xy 413.236111 -304.274378)
			(xy 413.187256 -304.28031) (xy 413.138081 -304.278329) (xy 413.089862 -304.268485) (xy 413.043846 -304.251033)
			(xy 413.001225 -304.226426) (xy 412.963104 -304.195301) (xy 412.930469 -304.158464) (xy 412.904166 -304.116868)
			(xy 412.884875 -304.071592) (xy 412.873098 -304.023808) (xy 412.869138 -303.974754) (xy 412.53029 -303.974754)
			(xy 412.529795 -303.999361) (xy 412.5219 -304.047938) (xy 412.506316 -304.094619) (xy 412.483445 -304.138196)
			(xy 412.45388 -304.17754) (xy 412.418387 -304.211632) (xy 412.377884 -304.239588) (xy 412.333422 -304.260686)
			(xy 412.286151 -304.274378) (xy 412.237296 -304.28031) (xy 412.188121 -304.278329) (xy 412.139902 -304.268485)
			(xy 412.093886 -304.251033) (xy 412.051265 -304.226426) (xy 412.013144 -304.195301) (xy 411.980509 -304.158464)
			(xy 411.954206 -304.116868) (xy 411.934915 -304.071592) (xy 411.923138 -304.023808) (xy 411.919178 -303.974754)
			(xy 411.58033 -303.974754) (xy 411.579835 -303.999361) (xy 411.57194 -304.047938) (xy 411.556356 -304.094619)
			(xy 411.533485 -304.138196) (xy 411.50392 -304.17754) (xy 411.468427 -304.211632) (xy 411.427924 -304.239588)
			(xy 411.383462 -304.260686) (xy 411.336191 -304.274378) (xy 411.287336 -304.28031) (xy 411.238161 -304.278329)
			(xy 411.189942 -304.268485) (xy 411.143926 -304.251033) (xy 411.101305 -304.226426) (xy 411.063184 -304.195301)
			(xy 411.030549 -304.158464) (xy 411.004246 -304.116868) (xy 410.984955 -304.071592) (xy 410.973178 -304.023808)
			(xy 410.969218 -303.974754) (xy 410.630116 -303.974754) (xy 410.629621 -303.999361) (xy 410.621726 -304.047938)
			(xy 410.606142 -304.094619) (xy 410.583271 -304.138196) (xy 410.553706 -304.17754) (xy 410.518213 -304.211632)
			(xy 410.47771 -304.239588) (xy 410.433248 -304.260686) (xy 410.385977 -304.274378) (xy 410.337122 -304.28031)
			(xy 410.287947 -304.278329) (xy 410.239728 -304.268485) (xy 410.193712 -304.251033) (xy 410.151091 -304.226426)
			(xy 410.11297 -304.195301) (xy 410.080335 -304.158464) (xy 410.054032 -304.116868) (xy 410.034741 -304.071592)
			(xy 410.022964 -304.023808) (xy 410.019004 -303.974754) (xy 409.680156 -303.974754) (xy 409.679661 -303.999361)
			(xy 409.671766 -304.047938) (xy 409.656182 -304.094619) (xy 409.633311 -304.138196) (xy 409.603746 -304.17754)
			(xy 409.568253 -304.211632) (xy 409.52775 -304.239588) (xy 409.483288 -304.260686) (xy 409.436017 -304.274378)
			(xy 409.387162 -304.28031) (xy 409.337987 -304.278329) (xy 409.289768 -304.268485) (xy 409.243752 -304.251033)
			(xy 409.201131 -304.226426) (xy 409.16301 -304.195301) (xy 409.130375 -304.158464) (xy 409.104072 -304.116868)
			(xy 409.084781 -304.071592) (xy 409.073004 -304.023808) (xy 409.069044 -303.974754) (xy 408.730196 -303.974754)
			(xy 408.729701 -303.999361) (xy 408.721806 -304.047938) (xy 408.706222 -304.094619) (xy 408.683351 -304.138196)
			(xy 408.653786 -304.17754) (xy 408.618293 -304.211632) (xy 408.57779 -304.239588) (xy 408.533328 -304.260686)
			(xy 408.486057 -304.274378) (xy 408.437202 -304.28031) (xy 408.388027 -304.278329) (xy 408.339808 -304.268485)
			(xy 408.293792 -304.251033) (xy 408.251171 -304.226426) (xy 408.21305 -304.195301) (xy 408.180415 -304.158464)
			(xy 408.154112 -304.116868) (xy 408.134821 -304.071592) (xy 408.123044 -304.023808) (xy 408.119084 -303.974754)
			(xy 406.830276 -303.974754) (xy 406.829781 -303.999361) (xy 406.821886 -304.047938) (xy 406.806302 -304.094619)
			(xy 406.783431 -304.138196) (xy 406.753866 -304.17754) (xy 406.718373 -304.211632) (xy 406.67787 -304.239588)
			(xy 406.633408 -304.260686) (xy 406.586137 -304.274378) (xy 406.537282 -304.28031) (xy 406.488107 -304.278329)
			(xy 406.439888 -304.268485) (xy 406.393872 -304.251033) (xy 406.351251 -304.226426) (xy 406.31313 -304.195301)
			(xy 406.280495 -304.158464) (xy 406.254192 -304.116868) (xy 406.234901 -304.071592) (xy 406.223124 -304.023808)
			(xy 406.219164 -303.974754) (xy 405.880316 -303.974754) (xy 405.879821 -303.999361) (xy 405.871926 -304.047938)
			(xy 405.856342 -304.094619) (xy 405.833471 -304.138196) (xy 405.803906 -304.17754) (xy 405.768413 -304.211632)
			(xy 405.72791 -304.239588) (xy 405.683448 -304.260686) (xy 405.636177 -304.274378) (xy 405.587322 -304.28031)
			(xy 405.538147 -304.278329) (xy 405.489928 -304.268485) (xy 405.443912 -304.251033) (xy 405.401291 -304.226426)
			(xy 405.36317 -304.195301) (xy 405.330535 -304.158464) (xy 405.304232 -304.116868) (xy 405.284941 -304.071592)
			(xy 405.273164 -304.023808) (xy 405.269204 -303.974754) (xy 404.930102 -303.974754) (xy 404.929607 -303.999361)
			(xy 404.921712 -304.047938) (xy 404.906128 -304.094619) (xy 404.883257 -304.138196) (xy 404.853692 -304.17754)
			(xy 404.818199 -304.211632) (xy 404.777696 -304.239588) (xy 404.733234 -304.260686) (xy 404.685963 -304.274378)
			(xy 404.637108 -304.28031) (xy 404.587933 -304.278329) (xy 404.539714 -304.268485) (xy 404.493698 -304.251033)
			(xy 404.451077 -304.226426) (xy 404.412956 -304.195301) (xy 404.380321 -304.158464) (xy 404.354018 -304.116868)
			(xy 404.334727 -304.071592) (xy 404.32295 -304.023808) (xy 404.31899 -303.974754) (xy 403.980142 -303.974754)
			(xy 403.979647 -303.999361) (xy 403.971752 -304.047938) (xy 403.956168 -304.094619) (xy 403.933297 -304.138196)
			(xy 403.903732 -304.17754) (xy 403.868239 -304.211632) (xy 403.827736 -304.239588) (xy 403.783274 -304.260686)
			(xy 403.736003 -304.274378) (xy 403.687148 -304.28031) (xy 403.637973 -304.278329) (xy 403.589754 -304.268485)
			(xy 403.543738 -304.251033) (xy 403.501117 -304.226426) (xy 403.462996 -304.195301) (xy 403.430361 -304.158464)
			(xy 403.404058 -304.116868) (xy 403.384767 -304.071592) (xy 403.37299 -304.023808) (xy 403.36903 -303.974754)
			(xy 403.030182 -303.974754) (xy 403.029687 -303.999361) (xy 403.021792 -304.047938) (xy 403.006208 -304.094619)
			(xy 402.983337 -304.138196) (xy 402.953772 -304.17754) (xy 402.918279 -304.211632) (xy 402.877776 -304.239588)
			(xy 402.833314 -304.260686) (xy 402.786043 -304.274378) (xy 402.737188 -304.28031) (xy 402.688013 -304.278329)
			(xy 402.639794 -304.268485) (xy 402.593778 -304.251033) (xy 402.551157 -304.226426) (xy 402.513036 -304.195301)
			(xy 402.480401 -304.158464) (xy 402.454098 -304.116868) (xy 402.434807 -304.071592) (xy 402.42303 -304.023808)
			(xy 402.41907 -303.974754) (xy 402.080222 -303.974754) (xy 402.079727 -303.999361) (xy 402.071832 -304.047938)
			(xy 402.056248 -304.094619) (xy 402.033377 -304.138196) (xy 402.003812 -304.17754) (xy 401.968319 -304.211632)
			(xy 401.927816 -304.239588) (xy 401.883354 -304.260686) (xy 401.836083 -304.274378) (xy 401.787228 -304.28031)
			(xy 401.738053 -304.278329) (xy 401.689834 -304.268485) (xy 401.643818 -304.251033) (xy 401.601197 -304.226426)
			(xy 401.563076 -304.195301) (xy 401.530441 -304.158464) (xy 401.504138 -304.116868) (xy 401.484847 -304.071592)
			(xy 401.47307 -304.023808) (xy 401.46911 -303.974754) (xy 401.130262 -303.974754) (xy 401.129767 -303.999361)
			(xy 401.121872 -304.047938) (xy 401.106288 -304.094619) (xy 401.083417 -304.138196) (xy 401.053852 -304.17754)
			(xy 401.018359 -304.211632) (xy 400.977856 -304.239588) (xy 400.933394 -304.260686) (xy 400.886123 -304.274378)
			(xy 400.837268 -304.28031) (xy 400.788093 -304.278329) (xy 400.739874 -304.268485) (xy 400.693858 -304.251033)
			(xy 400.651237 -304.226426) (xy 400.613116 -304.195301) (xy 400.580481 -304.158464) (xy 400.554178 -304.116868)
			(xy 400.534887 -304.071592) (xy 400.52311 -304.023808) (xy 400.51915 -303.974754) (xy 400.180302 -303.974754)
			(xy 400.179807 -303.999361) (xy 400.171912 -304.047938) (xy 400.156328 -304.094619) (xy 400.133457 -304.138196)
			(xy 400.103892 -304.17754) (xy 400.068399 -304.211632) (xy 400.027896 -304.239588) (xy 399.983434 -304.260686)
			(xy 399.936163 -304.274378) (xy 399.887308 -304.28031) (xy 399.838133 -304.278329) (xy 399.789914 -304.268485)
			(xy 399.743898 -304.251033) (xy 399.701277 -304.226426) (xy 399.663156 -304.195301) (xy 399.630521 -304.158464)
			(xy 399.604218 -304.116868) (xy 399.584927 -304.071592) (xy 399.57315 -304.023808) (xy 399.56919 -303.974754)
			(xy 399.230342 -303.974754) (xy 399.229847 -303.999361) (xy 399.221952 -304.047938) (xy 399.206368 -304.094619)
			(xy 399.183497 -304.138196) (xy 399.153932 -304.17754) (xy 399.118439 -304.211632) (xy 399.077936 -304.239588)
			(xy 399.033474 -304.260686) (xy 398.986203 -304.274378) (xy 398.937348 -304.28031) (xy 398.888173 -304.278329)
			(xy 398.839954 -304.268485) (xy 398.793938 -304.251033) (xy 398.751317 -304.226426) (xy 398.713196 -304.195301)
			(xy 398.680561 -304.158464) (xy 398.654258 -304.116868) (xy 398.634967 -304.071592) (xy 398.62319 -304.023808)
			(xy 398.61923 -303.974754) (xy 398.280581 -303.974754) (xy 398.280585 -303.9748) (xy 398.276415 -304.025128)
			(xy 398.264018 -304.074084) (xy 398.243733 -304.120332) (xy 398.216113 -304.16261) (xy 398.18191 -304.199766)
			(xy 398.142059 -304.230786) (xy 398.097646 -304.254824) (xy 398.049882 -304.271224) (xy 398.00007 -304.279539)
			(xy 397.97482 -304.280062) (xy 397.950215 -304.279559) (xy 397.901642 -304.271676) (xy 397.854959 -304.256109)
			(xy 397.811375 -304.233262) (xy 397.772016 -304.203725) (xy 397.754602 -304.186336) (xy 397.754602 -304.186082)
			(xy 397.747296 -304.179074) (xy 397.728744 -304.17101) (xy 397.708516 -304.170756) (xy 397.698976 -304.174144)
			(xy 397.611346 -304.20945) (xy 397.602172 -304.213645) (xy 397.587808 -304.227776) (xy 397.580028 -304.246364)
			(xy 397.579596 -304.25644) (xy 397.579596 -304.274728) (xy 397.579213 -304.284803) (xy 397.571466 -304.303402)
			(xy 397.56461 -304.310796) (xy 397.25473 -304.62093) (xy 397.247889 -304.628329) (xy 397.240169 -304.646929)
			(xy 397.239744 -304.656998) (xy 397.239744 -304.687478) (xy 397.240178 -304.696812) (xy 397.246804 -304.714265)
			(xy 397.252698 -304.721514) (xy 397.270755 -304.74268) (xy 397.299662 -304.79021) (xy 397.319481 -304.842189)
			(xy 397.329555 -304.896899) (xy 397.330168 -304.924714) (xy 397.669016 -304.924714) (xy 397.672976 -304.87566)
			(xy 397.684753 -304.827876) (xy 397.704044 -304.7826) (xy 397.730347 -304.741004) (xy 397.762982 -304.704167)
			(xy 397.801103 -304.673042) (xy 397.843724 -304.648435) (xy 397.88974 -304.630983) (xy 397.937959 -304.621139)
			(xy 397.987134 -304.619158) (xy 398.035989 -304.62509) (xy 398.08326 -304.638782) (xy 398.127722 -304.65988)
			(xy 398.168225 -304.687836) (xy 398.203718 -304.721928) (xy 398.233283 -304.761272) (xy 398.256154 -304.804849)
			(xy 398.271738 -304.85153) (xy 398.279633 -304.900107) (xy 398.280128 -304.924714) (xy 398.61923 -304.924714)
			(xy 398.62319 -304.87566) (xy 398.634967 -304.827876) (xy 398.654258 -304.7826) (xy 398.680561 -304.741004)
			(xy 398.713196 -304.704167) (xy 398.751317 -304.673042) (xy 398.793938 -304.648435) (xy 398.839954 -304.630983)
			(xy 398.888173 -304.621139) (xy 398.937348 -304.619158) (xy 398.986203 -304.62509) (xy 399.033474 -304.638782)
			(xy 399.077936 -304.65988) (xy 399.118439 -304.687836) (xy 399.153932 -304.721928) (xy 399.183497 -304.761272)
			(xy 399.206368 -304.804849) (xy 399.221952 -304.85153) (xy 399.229847 -304.900107) (xy 399.230342 -304.924714)
			(xy 399.56919 -304.924714) (xy 399.57315 -304.87566) (xy 399.584927 -304.827876) (xy 399.604218 -304.7826)
			(xy 399.630521 -304.741004) (xy 399.663156 -304.704167) (xy 399.701277 -304.673042) (xy 399.743898 -304.648435)
			(xy 399.789914 -304.630983) (xy 399.838133 -304.621139) (xy 399.887308 -304.619158) (xy 399.936163 -304.62509)
			(xy 399.983434 -304.638782) (xy 400.027896 -304.65988) (xy 400.068399 -304.687836) (xy 400.103892 -304.721928)
			(xy 400.133457 -304.761272) (xy 400.156328 -304.804849) (xy 400.171912 -304.85153) (xy 400.179807 -304.900107)
			(xy 400.180302 -304.924714) (xy 400.51915 -304.924714) (xy 400.52311 -304.87566) (xy 400.534887 -304.827876)
			(xy 400.554178 -304.7826) (xy 400.580481 -304.741004) (xy 400.613116 -304.704167) (xy 400.651237 -304.673042)
			(xy 400.693858 -304.648435) (xy 400.739874 -304.630983) (xy 400.788093 -304.621139) (xy 400.837268 -304.619158)
			(xy 400.886123 -304.62509) (xy 400.933394 -304.638782) (xy 400.977856 -304.65988) (xy 401.018359 -304.687836)
			(xy 401.053852 -304.721928) (xy 401.083417 -304.761272) (xy 401.106288 -304.804849) (xy 401.121872 -304.85153)
			(xy 401.129767 -304.900107) (xy 401.130262 -304.924714) (xy 401.46911 -304.924714) (xy 401.47307 -304.87566)
			(xy 401.484847 -304.827876) (xy 401.504138 -304.7826) (xy 401.530441 -304.741004) (xy 401.563076 -304.704167)
			(xy 401.601197 -304.673042) (xy 401.643818 -304.648435) (xy 401.689834 -304.630983) (xy 401.738053 -304.621139)
			(xy 401.787228 -304.619158) (xy 401.836083 -304.62509) (xy 401.883354 -304.638782) (xy 401.927816 -304.65988)
			(xy 401.968319 -304.687836) (xy 402.003812 -304.721928) (xy 402.033377 -304.761272) (xy 402.056248 -304.804849)
			(xy 402.071832 -304.85153) (xy 402.079727 -304.900107) (xy 402.080222 -304.924714) (xy 402.41907 -304.924714)
			(xy 402.42303 -304.87566) (xy 402.434807 -304.827876) (xy 402.454098 -304.7826) (xy 402.480401 -304.741004)
			(xy 402.513036 -304.704167) (xy 402.551157 -304.673042) (xy 402.593778 -304.648435) (xy 402.639794 -304.630983)
			(xy 402.688013 -304.621139) (xy 402.737188 -304.619158) (xy 402.786043 -304.62509) (xy 402.833314 -304.638782)
			(xy 402.877776 -304.65988) (xy 402.918279 -304.687836) (xy 402.953772 -304.721928) (xy 402.983337 -304.761272)
			(xy 403.006208 -304.804849) (xy 403.021792 -304.85153) (xy 403.029687 -304.900107) (xy 403.030182 -304.924714)
			(xy 403.36903 -304.924714) (xy 403.37299 -304.87566) (xy 403.384767 -304.827876) (xy 403.404058 -304.7826)
			(xy 403.430361 -304.741004) (xy 403.462996 -304.704167) (xy 403.501117 -304.673042) (xy 403.543738 -304.648435)
			(xy 403.589754 -304.630983) (xy 403.637973 -304.621139) (xy 403.687148 -304.619158) (xy 403.736003 -304.62509)
			(xy 403.783274 -304.638782) (xy 403.827736 -304.65988) (xy 403.868239 -304.687836) (xy 403.903732 -304.721928)
			(xy 403.933297 -304.761272) (xy 403.956168 -304.804849) (xy 403.971752 -304.85153) (xy 403.979647 -304.900107)
			(xy 403.980142 -304.924714) (xy 404.31899 -304.924714) (xy 404.32295 -304.87566) (xy 404.334727 -304.827876)
			(xy 404.354018 -304.7826) (xy 404.380321 -304.741004) (xy 404.412956 -304.704167) (xy 404.451077 -304.673042)
			(xy 404.493698 -304.648435) (xy 404.539714 -304.630983) (xy 404.587933 -304.621139) (xy 404.637108 -304.619158)
			(xy 404.685963 -304.62509) (xy 404.733234 -304.638782) (xy 404.777696 -304.65988) (xy 404.818199 -304.687836)
			(xy 404.853692 -304.721928) (xy 404.883257 -304.761272) (xy 404.906128 -304.804849) (xy 404.921712 -304.85153)
			(xy 404.929607 -304.900107) (xy 404.930102 -304.924714) (xy 405.269204 -304.924714) (xy 405.273164 -304.87566)
			(xy 405.284941 -304.827876) (xy 405.304232 -304.7826) (xy 405.330535 -304.741004) (xy 405.36317 -304.704167)
			(xy 405.401291 -304.673042) (xy 405.443912 -304.648435) (xy 405.489928 -304.630983) (xy 405.538147 -304.621139)
			(xy 405.587322 -304.619158) (xy 405.636177 -304.62509) (xy 405.683448 -304.638782) (xy 405.72791 -304.65988)
			(xy 405.768413 -304.687836) (xy 405.803906 -304.721928) (xy 405.833471 -304.761272) (xy 405.856342 -304.804849)
			(xy 405.871926 -304.85153) (xy 405.879821 -304.900107) (xy 405.880316 -304.924714) (xy 406.219164 -304.924714)
			(xy 406.223124 -304.87566) (xy 406.234901 -304.827876) (xy 406.254192 -304.7826) (xy 406.280495 -304.741004)
			(xy 406.31313 -304.704167) (xy 406.351251 -304.673042) (xy 406.393872 -304.648435) (xy 406.439888 -304.630983)
			(xy 406.488107 -304.621139) (xy 406.537282 -304.619158) (xy 406.586137 -304.62509) (xy 406.633408 -304.638782)
			(xy 406.67787 -304.65988) (xy 406.718373 -304.687836) (xy 406.753866 -304.721928) (xy 406.783431 -304.761272)
			(xy 406.806302 -304.804849) (xy 406.821886 -304.85153) (xy 406.829781 -304.900107) (xy 406.830276 -304.924714)
			(xy 408.119084 -304.924714) (xy 408.123044 -304.87566) (xy 408.134821 -304.827876) (xy 408.154112 -304.7826)
			(xy 408.180415 -304.741004) (xy 408.21305 -304.704167) (xy 408.251171 -304.673042) (xy 408.293792 -304.648435)
			(xy 408.339808 -304.630983) (xy 408.388027 -304.621139) (xy 408.437202 -304.619158) (xy 408.486057 -304.62509)
			(xy 408.533328 -304.638782) (xy 408.57779 -304.65988) (xy 408.618293 -304.687836) (xy 408.653786 -304.721928)
			(xy 408.683351 -304.761272) (xy 408.706222 -304.804849) (xy 408.721806 -304.85153) (xy 408.729701 -304.900107)
			(xy 408.730196 -304.924714) (xy 409.069044 -304.924714) (xy 409.073004 -304.87566) (xy 409.084781 -304.827876)
			(xy 409.104072 -304.7826) (xy 409.130375 -304.741004) (xy 409.16301 -304.704167) (xy 409.201131 -304.673042)
			(xy 409.243752 -304.648435) (xy 409.289768 -304.630983) (xy 409.337987 -304.621139) (xy 409.387162 -304.619158)
			(xy 409.436017 -304.62509) (xy 409.483288 -304.638782) (xy 409.52775 -304.65988) (xy 409.568253 -304.687836)
			(xy 409.603746 -304.721928) (xy 409.633311 -304.761272) (xy 409.656182 -304.804849) (xy 409.671766 -304.85153)
			(xy 409.679661 -304.900107) (xy 409.680156 -304.924714) (xy 410.019004 -304.924714) (xy 410.022964 -304.87566)
			(xy 410.034741 -304.827876) (xy 410.054032 -304.7826) (xy 410.080335 -304.741004) (xy 410.11297 -304.704167)
			(xy 410.151091 -304.673042) (xy 410.193712 -304.648435) (xy 410.239728 -304.630983) (xy 410.287947 -304.621139)
			(xy 410.337122 -304.619158) (xy 410.385977 -304.62509) (xy 410.433248 -304.638782) (xy 410.47771 -304.65988)
			(xy 410.518213 -304.687836) (xy 410.553706 -304.721928) (xy 410.583271 -304.761272) (xy 410.606142 -304.804849)
			(xy 410.621726 -304.85153) (xy 410.629621 -304.900107) (xy 410.630116 -304.924714) (xy 410.969218 -304.924714)
			(xy 410.973178 -304.87566) (xy 410.984955 -304.827876) (xy 411.004246 -304.7826) (xy 411.030549 -304.741004)
			(xy 411.063184 -304.704167) (xy 411.101305 -304.673042) (xy 411.143926 -304.648435) (xy 411.189942 -304.630983)
			(xy 411.238161 -304.621139) (xy 411.287336 -304.619158) (xy 411.336191 -304.62509) (xy 411.383462 -304.638782)
			(xy 411.427924 -304.65988) (xy 411.468427 -304.687836) (xy 411.50392 -304.721928) (xy 411.533485 -304.761272)
			(xy 411.556356 -304.804849) (xy 411.57194 -304.85153) (xy 411.579835 -304.900107) (xy 411.58033 -304.924714)
			(xy 411.919178 -304.924714) (xy 411.923138 -304.87566) (xy 411.934915 -304.827876) (xy 411.954206 -304.7826)
			(xy 411.980509 -304.741004) (xy 412.013144 -304.704167) (xy 412.051265 -304.673042) (xy 412.093886 -304.648435)
			(xy 412.139902 -304.630983) (xy 412.188121 -304.621139) (xy 412.237296 -304.619158) (xy 412.286151 -304.62509)
			(xy 412.333422 -304.638782) (xy 412.377884 -304.65988) (xy 412.418387 -304.687836) (xy 412.45388 -304.721928)
			(xy 412.483445 -304.761272) (xy 412.506316 -304.804849) (xy 412.5219 -304.85153) (xy 412.529795 -304.900107)
			(xy 412.53029 -304.924714) (xy 412.869138 -304.924714) (xy 412.873098 -304.87566) (xy 412.884875 -304.827876)
			(xy 412.904166 -304.7826) (xy 412.930469 -304.741004) (xy 412.963104 -304.704167) (xy 413.001225 -304.673042)
			(xy 413.043846 -304.648435) (xy 413.089862 -304.630983) (xy 413.138081 -304.621139) (xy 413.187256 -304.619158)
			(xy 413.236111 -304.62509) (xy 413.283382 -304.638782) (xy 413.327844 -304.65988) (xy 413.368347 -304.687836)
			(xy 413.40384 -304.721928) (xy 413.433405 -304.761272) (xy 413.456276 -304.804849) (xy 413.47186 -304.85153)
			(xy 413.479755 -304.900107) (xy 413.48025 -304.924714) (xy 413.819098 -304.924714) (xy 413.823058 -304.87566)
			(xy 413.834835 -304.827876) (xy 413.854126 -304.7826) (xy 413.880429 -304.741004) (xy 413.913064 -304.704167)
			(xy 413.951185 -304.673042) (xy 413.993806 -304.648435) (xy 414.039822 -304.630983) (xy 414.088041 -304.621139)
			(xy 414.137216 -304.619158) (xy 414.186071 -304.62509) (xy 414.233342 -304.638782) (xy 414.277804 -304.65988)
			(xy 414.318307 -304.687836) (xy 414.3538 -304.721928) (xy 414.383365 -304.761272) (xy 414.406236 -304.804849)
			(xy 414.42182 -304.85153) (xy 414.429715 -304.900107) (xy 414.43021 -304.924714) (xy 414.769058 -304.924714)
			(xy 414.773018 -304.87566) (xy 414.784795 -304.827876) (xy 414.804086 -304.7826) (xy 414.830389 -304.741004)
			(xy 414.863024 -304.704167) (xy 414.901145 -304.673042) (xy 414.943766 -304.648435) (xy 414.989782 -304.630983)
			(xy 415.038001 -304.621139) (xy 415.087176 -304.619158) (xy 415.136031 -304.62509) (xy 415.183302 -304.638782)
			(xy 415.227764 -304.65988) (xy 415.268267 -304.687836) (xy 415.30376 -304.721928) (xy 415.333325 -304.761272)
			(xy 415.356196 -304.804849) (xy 415.37178 -304.85153) (xy 415.379675 -304.900107) (xy 415.38017 -304.924714)
			(xy 415.719018 -304.924714) (xy 415.722978 -304.87566) (xy 415.734755 -304.827876) (xy 415.754046 -304.7826)
			(xy 415.780349 -304.741004) (xy 415.812984 -304.704167) (xy 415.851105 -304.673042) (xy 415.893726 -304.648435)
			(xy 415.939742 -304.630983) (xy 415.987961 -304.621139) (xy 416.037136 -304.619158) (xy 416.085991 -304.62509)
			(xy 416.133262 -304.638782) (xy 416.177724 -304.65988) (xy 416.218227 -304.687836) (xy 416.25372 -304.721928)
			(xy 416.283285 -304.761272) (xy 416.306156 -304.804849) (xy 416.32174 -304.85153) (xy 416.329635 -304.900107)
			(xy 416.33013 -304.924714) (xy 416.329635 -304.949321) (xy 416.32174 -304.997898) (xy 416.306156 -305.044579)
			(xy 416.283285 -305.088156) (xy 416.25372 -305.1275) (xy 416.218227 -305.161592) (xy 416.177724 -305.189548)
			(xy 416.133262 -305.210646) (xy 416.085991 -305.224338) (xy 416.037136 -305.23027) (xy 415.987961 -305.228289)
			(xy 415.939742 -305.218445) (xy 415.893726 -305.200993) (xy 415.851105 -305.176386) (xy 415.812984 -305.145261)
			(xy 415.780349 -305.108424) (xy 415.754046 -305.066828) (xy 415.734755 -305.021552) (xy 415.722978 -304.973768)
			(xy 415.719018 -304.924714) (xy 415.38017 -304.924714) (xy 415.379675 -304.949321) (xy 415.37178 -304.997898)
			(xy 415.356196 -305.044579) (xy 415.333325 -305.088156) (xy 415.30376 -305.1275) (xy 415.268267 -305.161592)
			(xy 415.227764 -305.189548) (xy 415.183302 -305.210646) (xy 415.136031 -305.224338) (xy 415.087176 -305.23027)
			(xy 415.038001 -305.228289) (xy 414.989782 -305.218445) (xy 414.943766 -305.200993) (xy 414.901145 -305.176386)
			(xy 414.863024 -305.145261) (xy 414.830389 -305.108424) (xy 414.804086 -305.066828) (xy 414.784795 -305.021552)
			(xy 414.773018 -304.973768) (xy 414.769058 -304.924714) (xy 414.43021 -304.924714) (xy 414.429715 -304.949321)
			(xy 414.42182 -304.997898) (xy 414.406236 -305.044579) (xy 414.383365 -305.088156) (xy 414.3538 -305.1275)
			(xy 414.318307 -305.161592) (xy 414.277804 -305.189548) (xy 414.233342 -305.210646) (xy 414.186071 -305.224338)
			(xy 414.137216 -305.23027) (xy 414.088041 -305.228289) (xy 414.039822 -305.218445) (xy 413.993806 -305.200993)
			(xy 413.951185 -305.176386) (xy 413.913064 -305.145261) (xy 413.880429 -305.108424) (xy 413.854126 -305.066828)
			(xy 413.834835 -305.021552) (xy 413.823058 -304.973768) (xy 413.819098 -304.924714) (xy 413.48025 -304.924714)
			(xy 413.479755 -304.949321) (xy 413.47186 -304.997898) (xy 413.456276 -305.044579) (xy 413.433405 -305.088156)
			(xy 413.40384 -305.1275) (xy 413.368347 -305.161592) (xy 413.327844 -305.189548) (xy 413.283382 -305.210646)
			(xy 413.236111 -305.224338) (xy 413.187256 -305.23027) (xy 413.138081 -305.228289) (xy 413.089862 -305.218445)
			(xy 413.043846 -305.200993) (xy 413.001225 -305.176386) (xy 412.963104 -305.145261) (xy 412.930469 -305.108424)
			(xy 412.904166 -305.066828) (xy 412.884875 -305.021552) (xy 412.873098 -304.973768) (xy 412.869138 -304.924714)
			(xy 412.53029 -304.924714) (xy 412.529795 -304.949321) (xy 412.5219 -304.997898) (xy 412.506316 -305.044579)
			(xy 412.483445 -305.088156) (xy 412.45388 -305.1275) (xy 412.418387 -305.161592) (xy 412.377884 -305.189548)
			(xy 412.333422 -305.210646) (xy 412.286151 -305.224338) (xy 412.237296 -305.23027) (xy 412.188121 -305.228289)
			(xy 412.139902 -305.218445) (xy 412.093886 -305.200993) (xy 412.051265 -305.176386) (xy 412.013144 -305.145261)
			(xy 411.980509 -305.108424) (xy 411.954206 -305.066828) (xy 411.934915 -305.021552) (xy 411.923138 -304.973768)
			(xy 411.919178 -304.924714) (xy 411.58033 -304.924714) (xy 411.579835 -304.949321) (xy 411.57194 -304.997898)
			(xy 411.556356 -305.044579) (xy 411.533485 -305.088156) (xy 411.50392 -305.1275) (xy 411.468427 -305.161592)
			(xy 411.427924 -305.189548) (xy 411.383462 -305.210646) (xy 411.336191 -305.224338) (xy 411.287336 -305.23027)
			(xy 411.238161 -305.228289) (xy 411.189942 -305.218445) (xy 411.143926 -305.200993) (xy 411.101305 -305.176386)
			(xy 411.063184 -305.145261) (xy 411.030549 -305.108424) (xy 411.004246 -305.066828) (xy 410.984955 -305.021552)
			(xy 410.973178 -304.973768) (xy 410.969218 -304.924714) (xy 410.630116 -304.924714) (xy 410.629621 -304.949321)
			(xy 410.621726 -304.997898) (xy 410.606142 -305.044579) (xy 410.583271 -305.088156) (xy 410.553706 -305.1275)
			(xy 410.518213 -305.161592) (xy 410.47771 -305.189548) (xy 410.433248 -305.210646) (xy 410.385977 -305.224338)
			(xy 410.337122 -305.23027) (xy 410.287947 -305.228289) (xy 410.239728 -305.218445) (xy 410.193712 -305.200993)
			(xy 410.151091 -305.176386) (xy 410.11297 -305.145261) (xy 410.080335 -305.108424) (xy 410.054032 -305.066828)
			(xy 410.034741 -305.021552) (xy 410.022964 -304.973768) (xy 410.019004 -304.924714) (xy 409.680156 -304.924714)
			(xy 409.679661 -304.949321) (xy 409.671766 -304.997898) (xy 409.656182 -305.044579) (xy 409.633311 -305.088156)
			(xy 409.603746 -305.1275) (xy 409.568253 -305.161592) (xy 409.52775 -305.189548) (xy 409.483288 -305.210646)
			(xy 409.436017 -305.224338) (xy 409.387162 -305.23027) (xy 409.337987 -305.228289) (xy 409.289768 -305.218445)
			(xy 409.243752 -305.200993) (xy 409.201131 -305.176386) (xy 409.16301 -305.145261) (xy 409.130375 -305.108424)
			(xy 409.104072 -305.066828) (xy 409.084781 -305.021552) (xy 409.073004 -304.973768) (xy 409.069044 -304.924714)
			(xy 408.730196 -304.924714) (xy 408.729701 -304.949321) (xy 408.721806 -304.997898) (xy 408.706222 -305.044579)
			(xy 408.683351 -305.088156) (xy 408.653786 -305.1275) (xy 408.618293 -305.161592) (xy 408.57779 -305.189548)
			(xy 408.533328 -305.210646) (xy 408.486057 -305.224338) (xy 408.437202 -305.23027) (xy 408.388027 -305.228289)
			(xy 408.339808 -305.218445) (xy 408.293792 -305.200993) (xy 408.251171 -305.176386) (xy 408.21305 -305.145261)
			(xy 408.180415 -305.108424) (xy 408.154112 -305.066828) (xy 408.134821 -305.021552) (xy 408.123044 -304.973768)
			(xy 408.119084 -304.924714) (xy 406.830276 -304.924714) (xy 406.829781 -304.949321) (xy 406.821886 -304.997898)
			(xy 406.806302 -305.044579) (xy 406.783431 -305.088156) (xy 406.753866 -305.1275) (xy 406.718373 -305.161592)
			(xy 406.67787 -305.189548) (xy 406.633408 -305.210646) (xy 406.586137 -305.224338) (xy 406.537282 -305.23027)
			(xy 406.488107 -305.228289) (xy 406.439888 -305.218445) (xy 406.393872 -305.200993) (xy 406.351251 -305.176386)
			(xy 406.31313 -305.145261) (xy 406.280495 -305.108424) (xy 406.254192 -305.066828) (xy 406.234901 -305.021552)
			(xy 406.223124 -304.973768) (xy 406.219164 -304.924714) (xy 405.880316 -304.924714) (xy 405.879821 -304.949321)
			(xy 405.871926 -304.997898) (xy 405.856342 -305.044579) (xy 405.833471 -305.088156) (xy 405.803906 -305.1275)
			(xy 405.768413 -305.161592) (xy 405.72791 -305.189548) (xy 405.683448 -305.210646) (xy 405.636177 -305.224338)
			(xy 405.587322 -305.23027) (xy 405.538147 -305.228289) (xy 405.489928 -305.218445) (xy 405.443912 -305.200993)
			(xy 405.401291 -305.176386) (xy 405.36317 -305.145261) (xy 405.330535 -305.108424) (xy 405.304232 -305.066828)
			(xy 405.284941 -305.021552) (xy 405.273164 -304.973768) (xy 405.269204 -304.924714) (xy 404.930102 -304.924714)
			(xy 404.929607 -304.949321) (xy 404.921712 -304.997898) (xy 404.906128 -305.044579) (xy 404.883257 -305.088156)
			(xy 404.853692 -305.1275) (xy 404.818199 -305.161592) (xy 404.777696 -305.189548) (xy 404.733234 -305.210646)
			(xy 404.685963 -305.224338) (xy 404.637108 -305.23027) (xy 404.587933 -305.228289) (xy 404.539714 -305.218445)
			(xy 404.493698 -305.200993) (xy 404.451077 -305.176386) (xy 404.412956 -305.145261) (xy 404.380321 -305.108424)
			(xy 404.354018 -305.066828) (xy 404.334727 -305.021552) (xy 404.32295 -304.973768) (xy 404.31899 -304.924714)
			(xy 403.980142 -304.924714) (xy 403.979647 -304.949321) (xy 403.971752 -304.997898) (xy 403.956168 -305.044579)
			(xy 403.933297 -305.088156) (xy 403.903732 -305.1275) (xy 403.868239 -305.161592) (xy 403.827736 -305.189548)
			(xy 403.783274 -305.210646) (xy 403.736003 -305.224338) (xy 403.687148 -305.23027) (xy 403.637973 -305.228289)
			(xy 403.589754 -305.218445) (xy 403.543738 -305.200993) (xy 403.501117 -305.176386) (xy 403.462996 -305.145261)
			(xy 403.430361 -305.108424) (xy 403.404058 -305.066828) (xy 403.384767 -305.021552) (xy 403.37299 -304.973768)
			(xy 403.36903 -304.924714) (xy 403.030182 -304.924714) (xy 403.029687 -304.949321) (xy 403.021792 -304.997898)
			(xy 403.006208 -305.044579) (xy 402.983337 -305.088156) (xy 402.953772 -305.1275) (xy 402.918279 -305.161592)
			(xy 402.877776 -305.189548) (xy 402.833314 -305.210646) (xy 402.786043 -305.224338) (xy 402.737188 -305.23027)
			(xy 402.688013 -305.228289) (xy 402.639794 -305.218445) (xy 402.593778 -305.200993) (xy 402.551157 -305.176386)
			(xy 402.513036 -305.145261) (xy 402.480401 -305.108424) (xy 402.454098 -305.066828) (xy 402.434807 -305.021552)
			(xy 402.42303 -304.973768) (xy 402.41907 -304.924714) (xy 402.080222 -304.924714) (xy 402.079727 -304.949321)
			(xy 402.071832 -304.997898) (xy 402.056248 -305.044579) (xy 402.033377 -305.088156) (xy 402.003812 -305.1275)
			(xy 401.968319 -305.161592) (xy 401.927816 -305.189548) (xy 401.883354 -305.210646) (xy 401.836083 -305.224338)
			(xy 401.787228 -305.23027) (xy 401.738053 -305.228289) (xy 401.689834 -305.218445) (xy 401.643818 -305.200993)
			(xy 401.601197 -305.176386) (xy 401.563076 -305.145261) (xy 401.530441 -305.108424) (xy 401.504138 -305.066828)
			(xy 401.484847 -305.021552) (xy 401.47307 -304.973768) (xy 401.46911 -304.924714) (xy 401.130262 -304.924714)
			(xy 401.129767 -304.949321) (xy 401.121872 -304.997898) (xy 401.106288 -305.044579) (xy 401.083417 -305.088156)
			(xy 401.053852 -305.1275) (xy 401.018359 -305.161592) (xy 400.977856 -305.189548) (xy 400.933394 -305.210646)
			(xy 400.886123 -305.224338) (xy 400.837268 -305.23027) (xy 400.788093 -305.228289) (xy 400.739874 -305.218445)
			(xy 400.693858 -305.200993) (xy 400.651237 -305.176386) (xy 400.613116 -305.145261) (xy 400.580481 -305.108424)
			(xy 400.554178 -305.066828) (xy 400.534887 -305.021552) (xy 400.52311 -304.973768) (xy 400.51915 -304.924714)
			(xy 400.180302 -304.924714) (xy 400.179807 -304.949321) (xy 400.171912 -304.997898) (xy 400.156328 -305.044579)
			(xy 400.133457 -305.088156) (xy 400.103892 -305.1275) (xy 400.068399 -305.161592) (xy 400.027896 -305.189548)
			(xy 399.983434 -305.210646) (xy 399.936163 -305.224338) (xy 399.887308 -305.23027) (xy 399.838133 -305.228289)
			(xy 399.789914 -305.218445) (xy 399.743898 -305.200993) (xy 399.701277 -305.176386) (xy 399.663156 -305.145261)
			(xy 399.630521 -305.108424) (xy 399.604218 -305.066828) (xy 399.584927 -305.021552) (xy 399.57315 -304.973768)
			(xy 399.56919 -304.924714) (xy 399.230342 -304.924714) (xy 399.229847 -304.949321) (xy 399.221952 -304.997898)
			(xy 399.206368 -305.044579) (xy 399.183497 -305.088156) (xy 399.153932 -305.1275) (xy 399.118439 -305.161592)
			(xy 399.077936 -305.189548) (xy 399.033474 -305.210646) (xy 398.986203 -305.224338) (xy 398.937348 -305.23027)
			(xy 398.888173 -305.228289) (xy 398.839954 -305.218445) (xy 398.793938 -305.200993) (xy 398.751317 -305.176386)
			(xy 398.713196 -305.145261) (xy 398.680561 -305.108424) (xy 398.654258 -305.066828) (xy 398.634967 -305.021552)
			(xy 398.62319 -304.973768) (xy 398.61923 -304.924714) (xy 398.280128 -304.924714) (xy 398.279633 -304.949321)
			(xy 398.271738 -304.997898) (xy 398.256154 -305.044579) (xy 398.233283 -305.088156) (xy 398.203718 -305.1275)
			(xy 398.168225 -305.161592) (xy 398.127722 -305.189548) (xy 398.08326 -305.210646) (xy 398.035989 -305.224338)
			(xy 397.987134 -305.23027) (xy 397.937959 -305.228289) (xy 397.88974 -305.218445) (xy 397.843724 -305.200993)
			(xy 397.801103 -305.176386) (xy 397.762982 -305.145261) (xy 397.730347 -305.108424) (xy 397.704044 -305.066828)
			(xy 397.684753 -305.021552) (xy 397.672976 -304.973768) (xy 397.669016 -304.924714) (xy 397.330168 -304.924714)
			(xy 397.329646 -304.949969) (xy 397.321333 -304.999791) (xy 397.304932 -305.047565) (xy 397.280891 -305.091988)
			(xy 397.249867 -305.131848) (xy 397.212705 -305.166058) (xy 397.170419 -305.193684) (xy 397.124163 -305.213974)
			(xy 397.075198 -305.226374) (xy 397.02486 -305.230545) (xy 396.974522 -305.226374) (xy 396.925557 -305.213974)
			(xy 396.879301 -305.193684) (xy 396.837015 -305.166058) (xy 396.799853 -305.131848) (xy 396.768829 -305.091988)
			(xy 396.744788 -305.047565) (xy 396.728387 -304.999791) (xy 396.720074 -304.949969) (xy 396.719552 -304.924714)
			(xy 396.719724 -304.910855) (xy 396.722271 -304.883254) (xy 396.724632 -304.869596) (xy 396.726664 -304.85842)
			(xy 396.721076 -304.836576) (xy 396.663672 -304.767996) (xy 396.656044 -304.759776) (xy 396.635754 -304.75029)
			(xy 396.624556 -304.749708) (xy 396.475204 -304.749708) (xy 396.463994 -304.750239) (xy 396.443691 -304.75974)
			(xy 396.436088 -304.767996) (xy 396.378684 -304.836576) (xy 396.373096 -304.85842) (xy 396.375128 -304.869596)
			(xy 396.377499 -304.883252) (xy 396.380045 -304.910854) (xy 396.380208 -304.924714) (xy 396.379686 -304.949969)
			(xy 396.371373 -304.999791) (xy 396.354972 -305.047565) (xy 396.330931 -305.091988) (xy 396.299907 -305.131848)
			(xy 396.262745 -305.166058) (xy 396.220459 -305.193684) (xy 396.174203 -305.213974) (xy 396.125238 -305.226374)
			(xy 396.0749 -305.230545) (xy 396.024562 -305.226374) (xy 395.975597 -305.213974) (xy 395.929341 -305.193684)
			(xy 395.887055 -305.166058) (xy 395.849893 -305.131848) (xy 395.818869 -305.091988) (xy 395.794828 -305.047565)
			(xy 395.778427 -304.999791) (xy 395.770114 -304.949969) (xy 395.769592 -304.924714) (xy 395.769763 -304.910855)
			(xy 395.772311 -304.883254) (xy 395.774672 -304.869596) (xy 395.776704 -304.85842) (xy 395.771116 -304.836576)
			(xy 395.713712 -304.767996) (xy 395.706068 -304.759795) (xy 395.68579 -304.750298) (xy 395.674596 -304.749708)
			(xy 395.525244 -304.749708) (xy 395.514037 -304.750261) (xy 395.493734 -304.759747) (xy 395.486128 -304.767996)
			(xy 395.428724 -304.836576) (xy 395.423136 -304.85842) (xy 395.425168 -304.869596) (xy 395.427539 -304.883252)
			(xy 395.430085 -304.910854) (xy 395.430248 -304.924714) (xy 395.429726 -304.949969) (xy 395.421413 -304.999791)
			(xy 395.405012 -305.047565) (xy 395.380971 -305.091988) (xy 395.349947 -305.131848) (xy 395.312785 -305.166058)
			(xy 395.270499 -305.193684) (xy 395.224243 -305.213974) (xy 395.175278 -305.226374) (xy 395.12494 -305.230545)
			(xy 395.074602 -305.226374) (xy 395.025637 -305.213974) (xy 394.979381 -305.193684) (xy 394.937095 -305.166058)
			(xy 394.899933 -305.131848) (xy 394.868909 -305.091988) (xy 394.844868 -305.047565) (xy 394.828467 -304.999791)
			(xy 394.820154 -304.949969) (xy 394.819632 -304.924714) (xy 394.819804 -304.910855) (xy 394.822351 -304.883254)
			(xy 394.824712 -304.869596) (xy 394.826744 -304.85842) (xy 394.821156 -304.836576) (xy 394.763752 -304.767996)
			(xy 394.756132 -304.759767) (xy 394.735836 -304.750286) (xy 394.724636 -304.749708) (xy 393.757658 -304.749708)
			(xy 393.75334 -304.75047) (xy 393.740112 -304.752639) (xy 393.713404 -304.754931) (xy 393.7 -304.755042)
			(xy 393.686597 -304.754921) (xy 393.659888 -304.752634) (xy 393.64666 -304.75047) (xy 393.642342 -304.749708)
			(xy 392.807444 -304.749708) (xy 392.803126 -304.75047) (xy 392.789899 -304.752641) (xy 392.76319 -304.754931)
			(xy 392.749786 -304.755042) (xy 392.736383 -304.754923) (xy 392.709674 -304.752635) (xy 392.696446 -304.75047)
			(xy 392.692128 -304.749708) (xy 391.857484 -304.749708) (xy 391.853166 -304.75047) (xy 391.839938 -304.752636)
			(xy 391.81323 -304.75493) (xy 391.799826 -304.755042) (xy 391.786423 -304.754918) (xy 391.759714 -304.752633)
			(xy 391.746486 -304.75047) (xy 391.742168 -304.749708) (xy 390.907524 -304.749708) (xy 390.903206 -304.75047)
			(xy 390.889979 -304.752644) (xy 390.86327 -304.754932) (xy 390.849866 -304.755042) (xy 390.836462 -304.754926)
			(xy 390.809754 -304.752636) (xy 390.796526 -304.75047) (xy 390.792208 -304.749708) (xy 389.957564 -304.749708)
			(xy 389.953246 -304.75047) (xy 389.940018 -304.752639) (xy 389.91331 -304.75493) (xy 389.899906 -304.755042)
			(xy 389.886503 -304.754921) (xy 389.859794 -304.752634) (xy 389.846566 -304.75047) (xy 389.842248 -304.749708)
			(xy 389.007604 -304.749708) (xy 389.003286 -304.75047) (xy 388.99006 -304.752646) (xy 388.96335 -304.754933)
			(xy 388.949946 -304.755042) (xy 388.936542 -304.754928) (xy 388.909834 -304.752637) (xy 388.896606 -304.75047)
			(xy 388.892288 -304.749708) (xy 388.057644 -304.749708) (xy 388.053326 -304.75047) (xy 388.040099 -304.752641)
			(xy 388.01339 -304.754931) (xy 387.999986 -304.755042) (xy 387.986583 -304.754923) (xy 387.959874 -304.752635)
			(xy 387.946646 -304.75047) (xy 387.942328 -304.749708) (xy 387.107684 -304.749708) (xy 387.103366 -304.75047)
			(xy 387.090138 -304.752636) (xy 387.06343 -304.75493) (xy 387.050026 -304.755042) (xy 387.036623 -304.754918)
			(xy 387.009914 -304.752633) (xy 386.996686 -304.75047) (xy 386.992368 -304.749708) (xy 386.15747 -304.749708)
			(xy 386.153152 -304.75047) (xy 386.139924 -304.752638) (xy 386.113216 -304.75493) (xy 386.099812 -304.755042)
			(xy 386.086409 -304.75492) (xy 386.0597 -304.752634) (xy 386.046472 -304.75047) (xy 386.042154 -304.749708)
			(xy 385.20751 -304.749708) (xy 385.203192 -304.75047) (xy 385.189965 -304.752646) (xy 385.163256 -304.754933)
			(xy 385.149852 -304.755042) (xy 385.136448 -304.754928) (xy 385.10974 -304.752636) (xy 385.096512 -304.75047)
			(xy 385.092194 -304.749708) (xy 384.258566 -304.749708) (xy 384.253994 -304.75047) (xy 384.240521 -304.752743)
			(xy 384.213301 -304.755157) (xy 384.199638 -304.755296) (xy 384.185975 -304.755162) (xy 384.158756 -304.752743)
			(xy 384.145282 -304.75047) (xy 384.14071 -304.749708) (xy 378.673614 -304.749708) (xy 378.663542 -304.7493)
			(xy 378.644943 -304.74157) (xy 378.637546 -304.734722) (xy 376.519186 -302.616108) (xy 376.512355 -302.608701)
			(xy 376.504631 -302.590107) (xy 376.5042 -302.58004) (xy 376.5042 -299.607478) (xy 376.505432 -299.582568)
			(xy 376.51501 -299.533625) (xy 376.532393 -299.486882) (xy 376.544332 -299.464984) (xy 376.563128 -299.435774)
			(xy 376.569302 -299.426444) (xy 376.57362 -299.404515) (xy 376.56821 -299.38283) (xy 376.561604 -299.373798)
			(xy 376.543834 -299.351006) (xy 376.514626 -299.301141) (xy 376.493272 -299.247441) (xy 376.48026 -299.191135)
			(xy 376.475889 -299.133511) (xy 376.35053 -299.133511) (xy 376.35053 -299.133514) (xy 376.350021 -299.1614)
			(xy 376.341901 -299.216576) (xy 376.325833 -299.269983) (xy 376.302161 -299.32048) (xy 376.271388 -299.366993)
			(xy 376.234171 -299.40853) (xy 376.191303 -299.444205) (xy 376.143697 -299.473259) (xy 376.092368 -299.495071)
			(xy 376.038411 -299.509177) (xy 375.982974 -299.515277) (xy 375.92724 -299.51324) (xy 375.872397 -299.50311)
			(xy 375.819613 -299.485103) (xy 375.770013 -299.459602) (xy 375.724655 -299.427151) (xy 375.684506 -299.388442)
			(xy 375.65042 -299.344299) (xy 375.623124 -299.295664) (xy 375.603201 -299.243573) (xy 375.591075 -299.189136)
			(xy 375.587004 -299.133514) (xy 374.875044 -299.133514) (xy 374.874535 -299.1614) (xy 374.866415 -299.216576)
			(xy 374.850347 -299.269983) (xy 374.826675 -299.32048) (xy 374.795902 -299.366993) (xy 374.758685 -299.40853)
			(xy 374.715817 -299.444205) (xy 374.668211 -299.473259) (xy 374.616882 -299.495071) (xy 374.562925 -299.509177)
			(xy 374.507488 -299.515277) (xy 374.451754 -299.51324) (xy 374.396911 -299.50311) (xy 374.344127 -299.485103)
			(xy 374.294527 -299.459602) (xy 374.249169 -299.427151) (xy 374.20902 -299.388442) (xy 374.174934 -299.344299)
			(xy 374.147638 -299.295664) (xy 374.127715 -299.243573) (xy 374.115589 -299.189136) (xy 374.111518 -299.133514)
			(xy 367.354104 -299.133514) (xy 367.354104 -301.031656) (xy 374.111518 -301.031656) (xy 374.115589 -300.976034)
			(xy 374.127715 -300.921597) (xy 374.147638 -300.869506) (xy 374.174934 -300.820871) (xy 374.20902 -300.776728)
			(xy 374.249169 -300.738019) (xy 374.294527 -300.705568) (xy 374.344127 -300.680067) (xy 374.396911 -300.66206)
			(xy 374.451754 -300.65193) (xy 374.507488 -300.649893) (xy 374.562925 -300.655993) (xy 374.616882 -300.670099)
			(xy 374.668211 -300.691911) (xy 374.715817 -300.720965) (xy 374.758685 -300.75664) (xy 374.795902 -300.798177)
			(xy 374.826675 -300.84469) (xy 374.850347 -300.895187) (xy 374.866415 -300.948594) (xy 374.874535 -301.00377)
			(xy 374.875044 -301.031656) (xy 375.596656 -301.031656) (xy 375.600727 -300.976034) (xy 375.612853 -300.921597)
			(xy 375.632776 -300.869506) (xy 375.660072 -300.820871) (xy 375.694158 -300.776728) (xy 375.734307 -300.738019)
			(xy 375.779665 -300.705568) (xy 375.829265 -300.680067) (xy 375.882049 -300.66206) (xy 375.936892 -300.65193)
			(xy 375.992626 -300.649893) (xy 376.048063 -300.655993) (xy 376.10202 -300.670099) (xy 376.153349 -300.691911)
			(xy 376.200955 -300.720965) (xy 376.243823 -300.75664) (xy 376.28104 -300.798177) (xy 376.311813 -300.84469)
			(xy 376.335485 -300.895187) (xy 376.351553 -300.948594) (xy 376.359673 -301.00377) (xy 376.360182 -301.031656)
			(xy 376.359673 -301.059542) (xy 376.351553 -301.114718) (xy 376.335485 -301.168125) (xy 376.311813 -301.218622)
			(xy 376.28104 -301.265135) (xy 376.243823 -301.306672) (xy 376.200955 -301.342347) (xy 376.153349 -301.371401)
			(xy 376.10202 -301.393213) (xy 376.048063 -301.407319) (xy 375.992626 -301.413419) (xy 375.936892 -301.411382)
			(xy 375.882049 -301.401252) (xy 375.829265 -301.383245) (xy 375.779665 -301.357744) (xy 375.734307 -301.325293)
			(xy 375.694158 -301.286584) (xy 375.660072 -301.242441) (xy 375.632776 -301.193806) (xy 375.612853 -301.141715)
			(xy 375.600727 -301.087278) (xy 375.596656 -301.031656) (xy 374.875044 -301.031656) (xy 374.874535 -301.059542)
			(xy 374.866415 -301.114718) (xy 374.850347 -301.168125) (xy 374.826675 -301.218622) (xy 374.795902 -301.265135)
			(xy 374.758685 -301.306672) (xy 374.715817 -301.342347) (xy 374.668211 -301.371401) (xy 374.616882 -301.393213)
			(xy 374.562925 -301.407319) (xy 374.507488 -301.413419) (xy 374.451754 -301.411382) (xy 374.396911 -301.401252)
			(xy 374.344127 -301.383245) (xy 374.294527 -301.357744) (xy 374.249169 -301.325293) (xy 374.20902 -301.286584)
			(xy 374.174934 -301.242441) (xy 374.147638 -301.193806) (xy 374.127715 -301.141715) (xy 374.115589 -301.087278)
			(xy 374.111518 -301.031656) (xy 367.354104 -301.031656) (xy 367.354104 -305.361436) (xy 375.710316 -305.361436)
			(xy 375.710319 -305.306922) (xy 375.71808 -305.252964) (xy 375.733442 -305.200659) (xy 375.756091 -305.151073)
			(xy 375.785568 -305.105216) (xy 375.82127 -305.06402) (xy 375.862473 -305.028325) (xy 375.908336 -304.998858)
			(xy 375.957926 -304.976217) (xy 376.010233 -304.960865) (xy 376.064193 -304.953113) (xy 376.09145 -304.952654)
			(xy 376.091704 -304.952654) (xy 376.11939 -304.95367) (xy 376.130566 -304.954432) (xy 376.151648 -304.946558)
			(xy 376.221752 -304.873914) (xy 376.229118 -304.852578) (xy 376.227848 -304.841402) (xy 376.226788 -304.831148)
			(xy 376.225643 -304.810562) (xy 376.225562 -304.800254) (xy 376.226127 -304.773006) (xy 376.233889 -304.719067)
			(xy 376.249249 -304.66678) (xy 376.271893 -304.617212) (xy 376.30136 -304.571371) (xy 376.337052 -304.530191)
			(xy 376.378241 -304.494508) (xy 376.424089 -304.465051) (xy 376.473662 -304.442418) (xy 376.525951 -304.427071)
			(xy 376.579893 -304.419321) (xy 376.634388 -304.419327) (xy 376.688328 -304.427088) (xy 376.740615 -304.442447)
			(xy 376.790183 -304.46509) (xy 376.836024 -304.494557) (xy 376.877206 -304.530248) (xy 376.912888 -304.571437)
			(xy 376.942346 -304.617284) (xy 376.96498 -304.666857) (xy 376.980328 -304.719146) (xy 376.988078 -304.773088)
			(xy 376.988073 -304.827583) (xy 376.980313 -304.881523) (xy 376.964955 -304.93381) (xy 376.942312 -304.983378)
			(xy 376.912846 -305.02922) (xy 376.877156 -305.070402) (xy 376.835968 -305.106085) (xy 376.790121 -305.135544)
			(xy 376.740548 -305.158178) (xy 376.688259 -305.173527) (xy 376.634318 -305.181278) (xy 376.60707 -305.181762)
			(xy 376.606816 -305.181762) (xy 376.57913 -305.180746) (xy 376.567954 -305.179984) (xy 376.546872 -305.187858)
			(xy 376.476768 -305.260502) (xy 376.469402 -305.281838) (xy 376.470672 -305.293014) (xy 376.471734 -305.303268)
			(xy 376.472877 -305.323853) (xy 376.472958 -305.334162) (xy 376.472486 -305.361419) (xy 376.46695 -305.399948)
			(xy 384.844048 -305.399948) (xy 384.848008 -305.350894) (xy 384.859785 -305.30311) (xy 384.879076 -305.257834)
			(xy 384.905379 -305.216238) (xy 384.938014 -305.179401) (xy 384.976135 -305.148276) (xy 385.018756 -305.123669)
			(xy 385.064772 -305.106217) (xy 385.112991 -305.096373) (xy 385.162166 -305.094392) (xy 385.211021 -305.100324)
			(xy 385.258292 -305.114016) (xy 385.302754 -305.135114) (xy 385.343257 -305.16307) (xy 385.37875 -305.197162)
			(xy 385.408315 -305.236506) (xy 385.431186 -305.280083) (xy 385.44677 -305.326764) (xy 385.454665 -305.375341)
			(xy 385.45516 -305.399948) (xy 385.794008 -305.399948) (xy 385.797968 -305.350894) (xy 385.809745 -305.30311)
			(xy 385.829036 -305.257834) (xy 385.855339 -305.216238) (xy 385.887974 -305.179401) (xy 385.926095 -305.148276)
			(xy 385.968716 -305.123669) (xy 386.014732 -305.106217) (xy 386.062951 -305.096373) (xy 386.112126 -305.094392)
			(xy 386.160981 -305.100324) (xy 386.208252 -305.114016) (xy 386.252714 -305.135114) (xy 386.293217 -305.16307)
			(xy 386.32871 -305.197162) (xy 386.358275 -305.236506) (xy 386.381146 -305.280083) (xy 386.39673 -305.326764)
			(xy 386.404625 -305.375341) (xy 386.40512 -305.399948) (xy 386.744222 -305.399948) (xy 386.748182 -305.350894)
			(xy 386.759959 -305.30311) (xy 386.77925 -305.257834) (xy 386.805553 -305.216238) (xy 386.838188 -305.179401)
			(xy 386.876309 -305.148276) (xy 386.91893 -305.123669) (xy 386.964946 -305.106217) (xy 387.013165 -305.096373)
			(xy 387.06234 -305.094392) (xy 387.111195 -305.100324) (xy 387.158466 -305.114016) (xy 387.202928 -305.135114)
			(xy 387.243431 -305.16307) (xy 387.278924 -305.197162) (xy 387.308489 -305.236506) (xy 387.33136 -305.280083)
			(xy 387.346944 -305.326764) (xy 387.354839 -305.375341) (xy 387.355334 -305.399948) (xy 387.694182 -305.399948)
			(xy 387.698142 -305.350894) (xy 387.709919 -305.30311) (xy 387.72921 -305.257834) (xy 387.755513 -305.216238)
			(xy 387.788148 -305.179401) (xy 387.826269 -305.148276) (xy 387.86889 -305.123669) (xy 387.914906 -305.106217)
			(xy 387.963125 -305.096373) (xy 388.0123 -305.094392) (xy 388.061155 -305.100324) (xy 388.108426 -305.114016)
			(xy 388.152888 -305.135114) (xy 388.193391 -305.16307) (xy 388.228884 -305.197162) (xy 388.258449 -305.236506)
			(xy 388.28132 -305.280083) (xy 388.296904 -305.326764) (xy 388.304799 -305.375341) (xy 388.305294 -305.399948)
			(xy 388.644142 -305.399948) (xy 388.648102 -305.350894) (xy 388.659879 -305.30311) (xy 388.67917 -305.257834)
			(xy 388.705473 -305.216238) (xy 388.738108 -305.179401) (xy 388.776229 -305.148276) (xy 388.81885 -305.123669)
			(xy 388.864866 -305.106217) (xy 388.913085 -305.096373) (xy 388.96226 -305.094392) (xy 389.011115 -305.100324)
			(xy 389.058386 -305.114016) (xy 389.102848 -305.135114) (xy 389.143351 -305.16307) (xy 389.178844 -305.197162)
			(xy 389.208409 -305.236506) (xy 389.23128 -305.280083) (xy 389.246864 -305.326764) (xy 389.254759 -305.375341)
			(xy 389.255254 -305.399948) (xy 389.594102 -305.399948) (xy 389.598062 -305.350894) (xy 389.609839 -305.30311)
			(xy 389.62913 -305.257834) (xy 389.655433 -305.216238) (xy 389.688068 -305.179401) (xy 389.726189 -305.148276)
			(xy 389.76881 -305.123669) (xy 389.814826 -305.106217) (xy 389.863045 -305.096373) (xy 389.91222 -305.094392)
			(xy 389.961075 -305.100324) (xy 390.008346 -305.114016) (xy 390.052808 -305.135114) (xy 390.093311 -305.16307)
			(xy 390.128804 -305.197162) (xy 390.158369 -305.236506) (xy 390.18124 -305.280083) (xy 390.196824 -305.326764)
			(xy 390.204719 -305.375341) (xy 390.205214 -305.399948) (xy 390.544062 -305.399948) (xy 390.548022 -305.350894)
			(xy 390.559799 -305.30311) (xy 390.57909 -305.257834) (xy 390.605393 -305.216238) (xy 390.638028 -305.179401)
			(xy 390.676149 -305.148276) (xy 390.71877 -305.123669) (xy 390.764786 -305.106217) (xy 390.813005 -305.096373)
			(xy 390.86218 -305.094392) (xy 390.911035 -305.100324) (xy 390.958306 -305.114016) (xy 391.002768 -305.135114)
			(xy 391.043271 -305.16307) (xy 391.078764 -305.197162) (xy 391.108329 -305.236506) (xy 391.1312 -305.280083)
			(xy 391.146784 -305.326764) (xy 391.154679 -305.375341) (xy 391.155174 -305.399948) (xy 391.494022 -305.399948)
			(xy 391.497982 -305.350894) (xy 391.509759 -305.30311) (xy 391.52905 -305.257834) (xy 391.555353 -305.216238)
			(xy 391.587988 -305.179401) (xy 391.626109 -305.148276) (xy 391.66873 -305.123669) (xy 391.714746 -305.106217)
			(xy 391.762965 -305.096373) (xy 391.81214 -305.094392) (xy 391.860995 -305.100324) (xy 391.908266 -305.114016)
			(xy 391.952728 -305.135114) (xy 391.993231 -305.16307) (xy 392.028724 -305.197162) (xy 392.058289 -305.236506)
			(xy 392.08116 -305.280083) (xy 392.096744 -305.326764) (xy 392.104639 -305.375341) (xy 392.105134 -305.399948)
			(xy 392.443982 -305.399948) (xy 392.447942 -305.350894) (xy 392.459719 -305.30311) (xy 392.47901 -305.257834)
			(xy 392.505313 -305.216238) (xy 392.537948 -305.179401) (xy 392.576069 -305.148276) (xy 392.61869 -305.123669)
			(xy 392.664706 -305.106217) (xy 392.712925 -305.096373) (xy 392.7621 -305.094392) (xy 392.810955 -305.100324)
			(xy 392.858226 -305.114016) (xy 392.902688 -305.135114) (xy 392.943191 -305.16307) (xy 392.978684 -305.197162)
			(xy 393.008249 -305.236506) (xy 393.03112 -305.280083) (xy 393.046704 -305.326764) (xy 393.054599 -305.375341)
			(xy 393.055094 -305.399948) (xy 393.394196 -305.399948) (xy 393.398156 -305.350894) (xy 393.409933 -305.30311)
			(xy 393.429224 -305.257834) (xy 393.455527 -305.216238) (xy 393.488162 -305.179401) (xy 393.526283 -305.148276)
			(xy 393.568904 -305.123669) (xy 393.61492 -305.106217) (xy 393.663139 -305.096373) (xy 393.712314 -305.094392)
			(xy 393.761169 -305.100324) (xy 393.80844 -305.114016) (xy 393.852902 -305.135114) (xy 393.893405 -305.16307)
			(xy 393.928898 -305.197162) (xy 393.958463 -305.236506) (xy 393.981334 -305.280083) (xy 393.996918 -305.326764)
			(xy 394.004813 -305.375341) (xy 394.005308 -305.399948) (xy 394.004813 -305.424555) (xy 393.996918 -305.473132)
			(xy 393.981334 -305.519813) (xy 393.958463 -305.56339) (xy 393.928898 -305.602734) (xy 393.893405 -305.636826)
			(xy 393.852902 -305.664782) (xy 393.80844 -305.68588) (xy 393.761169 -305.699572) (xy 393.712314 -305.705504)
			(xy 393.663139 -305.703523) (xy 393.61492 -305.693679) (xy 393.568904 -305.676227) (xy 393.526283 -305.65162)
			(xy 393.488162 -305.620495) (xy 393.455527 -305.583658) (xy 393.429224 -305.542062) (xy 393.409933 -305.496786)
			(xy 393.398156 -305.449002) (xy 393.394196 -305.399948) (xy 393.055094 -305.399948) (xy 393.054599 -305.424555)
			(xy 393.046704 -305.473132) (xy 393.03112 -305.519813) (xy 393.008249 -305.56339) (xy 392.978684 -305.602734)
			(xy 392.943191 -305.636826) (xy 392.902688 -305.664782) (xy 392.858226 -305.68588) (xy 392.810955 -305.699572)
			(xy 392.7621 -305.705504) (xy 392.712925 -305.703523) (xy 392.664706 -305.693679) (xy 392.61869 -305.676227)
			(xy 392.576069 -305.65162) (xy 392.537948 -305.620495) (xy 392.505313 -305.583658) (xy 392.47901 -305.542062)
			(xy 392.459719 -305.496786) (xy 392.447942 -305.449002) (xy 392.443982 -305.399948) (xy 392.105134 -305.399948)
			(xy 392.104639 -305.424555) (xy 392.096744 -305.473132) (xy 392.08116 -305.519813) (xy 392.058289 -305.56339)
			(xy 392.028724 -305.602734) (xy 391.993231 -305.636826) (xy 391.952728 -305.664782) (xy 391.908266 -305.68588)
			(xy 391.860995 -305.699572) (xy 391.81214 -305.705504) (xy 391.762965 -305.703523) (xy 391.714746 -305.693679)
			(xy 391.66873 -305.676227) (xy 391.626109 -305.65162) (xy 391.587988 -305.620495) (xy 391.555353 -305.583658)
			(xy 391.52905 -305.542062) (xy 391.509759 -305.496786) (xy 391.497982 -305.449002) (xy 391.494022 -305.399948)
			(xy 391.155174 -305.399948) (xy 391.154679 -305.424555) (xy 391.146784 -305.473132) (xy 391.1312 -305.519813)
			(xy 391.108329 -305.56339) (xy 391.078764 -305.602734) (xy 391.043271 -305.636826) (xy 391.002768 -305.664782)
			(xy 390.958306 -305.68588) (xy 390.911035 -305.699572) (xy 390.86218 -305.705504) (xy 390.813005 -305.703523)
			(xy 390.764786 -305.693679) (xy 390.71877 -305.676227) (xy 390.676149 -305.65162) (xy 390.638028 -305.620495)
			(xy 390.605393 -305.583658) (xy 390.57909 -305.542062) (xy 390.559799 -305.496786) (xy 390.548022 -305.449002)
			(xy 390.544062 -305.399948) (xy 390.205214 -305.399948) (xy 390.204719 -305.424555) (xy 390.196824 -305.473132)
			(xy 390.18124 -305.519813) (xy 390.158369 -305.56339) (xy 390.128804 -305.602734) (xy 390.093311 -305.636826)
			(xy 390.052808 -305.664782) (xy 390.008346 -305.68588) (xy 389.961075 -305.699572) (xy 389.91222 -305.705504)
			(xy 389.863045 -305.703523) (xy 389.814826 -305.693679) (xy 389.76881 -305.676227) (xy 389.726189 -305.65162)
			(xy 389.688068 -305.620495) (xy 389.655433 -305.583658) (xy 389.62913 -305.542062) (xy 389.609839 -305.496786)
			(xy 389.598062 -305.449002) (xy 389.594102 -305.399948) (xy 389.255254 -305.399948) (xy 389.254759 -305.424555)
			(xy 389.246864 -305.473132) (xy 389.23128 -305.519813) (xy 389.208409 -305.56339) (xy 389.178844 -305.602734)
			(xy 389.143351 -305.636826) (xy 389.102848 -305.664782) (xy 389.058386 -305.68588) (xy 389.011115 -305.699572)
			(xy 388.96226 -305.705504) (xy 388.913085 -305.703523) (xy 388.864866 -305.693679) (xy 388.81885 -305.676227)
			(xy 388.776229 -305.65162) (xy 388.738108 -305.620495) (xy 388.705473 -305.583658) (xy 388.67917 -305.542062)
			(xy 388.659879 -305.496786) (xy 388.648102 -305.449002) (xy 388.644142 -305.399948) (xy 388.305294 -305.399948)
			(xy 388.304799 -305.424555) (xy 388.296904 -305.473132) (xy 388.28132 -305.519813) (xy 388.258449 -305.56339)
			(xy 388.228884 -305.602734) (xy 388.193391 -305.636826) (xy 388.152888 -305.664782) (xy 388.108426 -305.68588)
			(xy 388.061155 -305.699572) (xy 388.0123 -305.705504) (xy 387.963125 -305.703523) (xy 387.914906 -305.693679)
			(xy 387.86889 -305.676227) (xy 387.826269 -305.65162) (xy 387.788148 -305.620495) (xy 387.755513 -305.583658)
			(xy 387.72921 -305.542062) (xy 387.709919 -305.496786) (xy 387.698142 -305.449002) (xy 387.694182 -305.399948)
			(xy 387.355334 -305.399948) (xy 387.354839 -305.424555) (xy 387.346944 -305.473132) (xy 387.33136 -305.519813)
			(xy 387.308489 -305.56339) (xy 387.278924 -305.602734) (xy 387.243431 -305.636826) (xy 387.202928 -305.664782)
			(xy 387.158466 -305.68588) (xy 387.111195 -305.699572) (xy 387.06234 -305.705504) (xy 387.013165 -305.703523)
			(xy 386.964946 -305.693679) (xy 386.91893 -305.676227) (xy 386.876309 -305.65162) (xy 386.838188 -305.620495)
			(xy 386.805553 -305.583658) (xy 386.77925 -305.542062) (xy 386.759959 -305.496786) (xy 386.748182 -305.449002)
			(xy 386.744222 -305.399948) (xy 386.40512 -305.399948) (xy 386.404625 -305.424555) (xy 386.39673 -305.473132)
			(xy 386.381146 -305.519813) (xy 386.358275 -305.56339) (xy 386.32871 -305.602734) (xy 386.293217 -305.636826)
			(xy 386.252714 -305.664782) (xy 386.208252 -305.68588) (xy 386.160981 -305.699572) (xy 386.112126 -305.705504)
			(xy 386.062951 -305.703523) (xy 386.014732 -305.693679) (xy 385.968716 -305.676227) (xy 385.926095 -305.65162)
			(xy 385.887974 -305.620495) (xy 385.855339 -305.583658) (xy 385.829036 -305.542062) (xy 385.809745 -305.496786)
			(xy 385.797968 -305.449002) (xy 385.794008 -305.399948) (xy 385.45516 -305.399948) (xy 385.454665 -305.424555)
			(xy 385.44677 -305.473132) (xy 385.431186 -305.519813) (xy 385.408315 -305.56339) (xy 385.37875 -305.602734)
			(xy 385.343257 -305.636826) (xy 385.302754 -305.664782) (xy 385.258292 -305.68588) (xy 385.211021 -305.699572)
			(xy 385.162166 -305.705504) (xy 385.112991 -305.703523) (xy 385.064772 -305.693679) (xy 385.018756 -305.676227)
			(xy 384.976135 -305.65162) (xy 384.938014 -305.620495) (xy 384.905379 -305.583658) (xy 384.879076 -305.542062)
			(xy 384.859785 -305.496786) (xy 384.848008 -305.449002) (xy 384.844048 -305.399948) (xy 376.46695 -305.399948)
			(xy 376.464733 -305.415379) (xy 376.449379 -305.467686) (xy 376.426737 -305.517275) (xy 376.397268 -305.563137)
			(xy 376.361571 -305.604338) (xy 376.320374 -305.64004) (xy 376.274516 -305.669514) (xy 376.224929 -305.692162)
			(xy 376.172624 -305.707523) (xy 376.118666 -305.715282) (xy 376.064152 -305.715284) (xy 376.010193 -305.707526)
			(xy 375.957887 -305.692168) (xy 375.908299 -305.669523) (xy 375.862439 -305.64005) (xy 375.821241 -305.60435)
			(xy 375.785543 -305.563151) (xy 375.756072 -305.51729) (xy 375.733427 -305.467702) (xy 375.718071 -305.415396)
			(xy 375.710316 -305.361436) (xy 367.354104 -305.361436) (xy 367.354104 -305.908964) (xy 367.353669 -305.919029)
			(xy 367.345939 -305.937617) (xy 367.339118 -305.945032) (xy 367.231422 -306.052728) (xy 374.990866 -306.052728)
			(xy 374.994937 -305.997106) (xy 375.007063 -305.942669) (xy 375.026986 -305.890578) (xy 375.054282 -305.841943)
			(xy 375.088368 -305.7978) (xy 375.128517 -305.759091) (xy 375.173875 -305.72664) (xy 375.223475 -305.701139)
			(xy 375.276259 -305.683132) (xy 375.331102 -305.673002) (xy 375.386836 -305.670965) (xy 375.442273 -305.677065)
			(xy 375.49623 -305.691171) (xy 375.547559 -305.712983) (xy 375.595165 -305.742037) (xy 375.638033 -305.777712)
			(xy 375.67525 -305.819249) (xy 375.706023 -305.865762) (xy 375.71032 -305.874928) (xy 394.819136 -305.874928)
			(xy 394.823096 -305.825874) (xy 394.834873 -305.77809) (xy 394.854164 -305.732814) (xy 394.880467 -305.691218)
			(xy 394.913102 -305.654381) (xy 394.951223 -305.623256) (xy 394.993844 -305.598649) (xy 395.03986 -305.581197)
			(xy 395.088079 -305.571353) (xy 395.137254 -305.569372) (xy 395.186109 -305.575304) (xy 395.23338 -305.588996)
			(xy 395.277842 -305.610094) (xy 395.318345 -305.63805) (xy 395.353838 -305.672142) (xy 395.383403 -305.711486)
			(xy 395.406274 -305.755063) (xy 395.421858 -305.801744) (xy 395.429753 -305.850321) (xy 395.430248 -305.874928)
			(xy 395.769096 -305.874928) (xy 395.773056 -305.825874) (xy 395.784833 -305.77809) (xy 395.804124 -305.732814)
			(xy 395.830427 -305.691218) (xy 395.863062 -305.654381) (xy 395.901183 -305.623256) (xy 395.943804 -305.598649)
			(xy 395.98982 -305.581197) (xy 396.038039 -305.571353) (xy 396.087214 -305.569372) (xy 396.136069 -305.575304)
			(xy 396.18334 -305.588996) (xy 396.227802 -305.610094) (xy 396.268305 -305.63805) (xy 396.303798 -305.672142)
			(xy 396.333363 -305.711486) (xy 396.356234 -305.755063) (xy 396.371818 -305.801744) (xy 396.379713 -305.850321)
			(xy 396.380208 -305.874928) (xy 396.719056 -305.874928) (xy 396.723016 -305.825874) (xy 396.734793 -305.77809)
			(xy 396.754084 -305.732814) (xy 396.780387 -305.691218) (xy 396.813022 -305.654381) (xy 396.851143 -305.623256)
			(xy 396.893764 -305.598649) (xy 396.93978 -305.581197) (xy 396.987999 -305.571353) (xy 397.037174 -305.569372)
			(xy 397.086029 -305.575304) (xy 397.1333 -305.588996) (xy 397.177762 -305.610094) (xy 397.218265 -305.63805)
			(xy 397.253758 -305.672142) (xy 397.283323 -305.711486) (xy 397.306194 -305.755063) (xy 397.321778 -305.801744)
			(xy 397.329673 -305.850321) (xy 397.330168 -305.874928) (xy 397.669016 -305.874928) (xy 397.672976 -305.825874)
			(xy 397.684753 -305.77809) (xy 397.704044 -305.732814) (xy 397.730347 -305.691218) (xy 397.762982 -305.654381)
			(xy 397.801103 -305.623256) (xy 397.843724 -305.598649) (xy 397.88974 -305.581197) (xy 397.937959 -305.571353)
			(xy 397.987134 -305.569372) (xy 398.035989 -305.575304) (xy 398.08326 -305.588996) (xy 398.127722 -305.610094)
			(xy 398.168225 -305.63805) (xy 398.203718 -305.672142) (xy 398.233283 -305.711486) (xy 398.256154 -305.755063)
			(xy 398.271738 -305.801744) (xy 398.279633 -305.850321) (xy 398.280128 -305.874928) (xy 398.61923 -305.874928)
			(xy 398.62319 -305.825874) (xy 398.634967 -305.77809) (xy 398.654258 -305.732814) (xy 398.680561 -305.691218)
			(xy 398.713196 -305.654381) (xy 398.751317 -305.623256) (xy 398.793938 -305.598649) (xy 398.839954 -305.581197)
			(xy 398.888173 -305.571353) (xy 398.937348 -305.569372) (xy 398.986203 -305.575304) (xy 399.033474 -305.588996)
			(xy 399.077936 -305.610094) (xy 399.118439 -305.63805) (xy 399.153932 -305.672142) (xy 399.183497 -305.711486)
			(xy 399.206368 -305.755063) (xy 399.221952 -305.801744) (xy 399.229847 -305.850321) (xy 399.230342 -305.874928)
			(xy 399.56919 -305.874928) (xy 399.57315 -305.825874) (xy 399.584927 -305.77809) (xy 399.604218 -305.732814)
			(xy 399.630521 -305.691218) (xy 399.663156 -305.654381) (xy 399.701277 -305.623256) (xy 399.743898 -305.598649)
			(xy 399.789914 -305.581197) (xy 399.838133 -305.571353) (xy 399.887308 -305.569372) (xy 399.936163 -305.575304)
			(xy 399.983434 -305.588996) (xy 400.027896 -305.610094) (xy 400.068399 -305.63805) (xy 400.103892 -305.672142)
			(xy 400.133457 -305.711486) (xy 400.156328 -305.755063) (xy 400.171912 -305.801744) (xy 400.179807 -305.850321)
			(xy 400.180302 -305.874928) (xy 400.51915 -305.874928) (xy 400.52311 -305.825874) (xy 400.534887 -305.77809)
			(xy 400.554178 -305.732814) (xy 400.580481 -305.691218) (xy 400.613116 -305.654381) (xy 400.651237 -305.623256)
			(xy 400.693858 -305.598649) (xy 400.739874 -305.581197) (xy 400.788093 -305.571353) (xy 400.837268 -305.569372)
			(xy 400.886123 -305.575304) (xy 400.933394 -305.588996) (xy 400.977856 -305.610094) (xy 401.018359 -305.63805)
			(xy 401.053852 -305.672142) (xy 401.083417 -305.711486) (xy 401.106288 -305.755063) (xy 401.121872 -305.801744)
			(xy 401.129767 -305.850321) (xy 401.130262 -305.874928) (xy 401.46911 -305.874928) (xy 401.47307 -305.825874)
			(xy 401.484847 -305.77809) (xy 401.504138 -305.732814) (xy 401.530441 -305.691218) (xy 401.563076 -305.654381)
			(xy 401.601197 -305.623256) (xy 401.643818 -305.598649) (xy 401.689834 -305.581197) (xy 401.738053 -305.571353)
			(xy 401.787228 -305.569372) (xy 401.836083 -305.575304) (xy 401.883354 -305.588996) (xy 401.927816 -305.610094)
			(xy 401.968319 -305.63805) (xy 402.003812 -305.672142) (xy 402.033377 -305.711486) (xy 402.056248 -305.755063)
			(xy 402.071832 -305.801744) (xy 402.079727 -305.850321) (xy 402.080222 -305.874928) (xy 402.41907 -305.874928)
			(xy 402.42303 -305.825874) (xy 402.434807 -305.77809) (xy 402.454098 -305.732814) (xy 402.480401 -305.691218)
			(xy 402.513036 -305.654381) (xy 402.551157 -305.623256) (xy 402.593778 -305.598649) (xy 402.639794 -305.581197)
			(xy 402.688013 -305.571353) (xy 402.737188 -305.569372) (xy 402.786043 -305.575304) (xy 402.833314 -305.588996)
			(xy 402.877776 -305.610094) (xy 402.918279 -305.63805) (xy 402.953772 -305.672142) (xy 402.983337 -305.711486)
			(xy 403.006208 -305.755063) (xy 403.021792 -305.801744) (xy 403.029687 -305.850321) (xy 403.030182 -305.874928)
			(xy 403.36903 -305.874928) (xy 403.37299 -305.825874) (xy 403.384767 -305.77809) (xy 403.404058 -305.732814)
			(xy 403.430361 -305.691218) (xy 403.462996 -305.654381) (xy 403.501117 -305.623256) (xy 403.543738 -305.598649)
			(xy 403.589754 -305.581197) (xy 403.637973 -305.571353) (xy 403.687148 -305.569372) (xy 403.736003 -305.575304)
			(xy 403.783274 -305.588996) (xy 403.827736 -305.610094) (xy 403.868239 -305.63805) (xy 403.903732 -305.672142)
			(xy 403.933297 -305.711486) (xy 403.956168 -305.755063) (xy 403.971752 -305.801744) (xy 403.979647 -305.850321)
			(xy 403.980142 -305.874928) (xy 404.31899 -305.874928) (xy 404.32295 -305.825874) (xy 404.334727 -305.77809)
			(xy 404.354018 -305.732814) (xy 404.380321 -305.691218) (xy 404.412956 -305.654381) (xy 404.451077 -305.623256)
			(xy 404.493698 -305.598649) (xy 404.539714 -305.581197) (xy 404.587933 -305.571353) (xy 404.637108 -305.569372)
			(xy 404.685963 -305.575304) (xy 404.733234 -305.588996) (xy 404.777696 -305.610094) (xy 404.818199 -305.63805)
			(xy 404.853692 -305.672142) (xy 404.883257 -305.711486) (xy 404.906128 -305.755063) (xy 404.921712 -305.801744)
			(xy 404.929607 -305.850321) (xy 404.930102 -305.874928) (xy 405.269204 -305.874928) (xy 405.273164 -305.825874)
			(xy 405.284941 -305.77809) (xy 405.304232 -305.732814) (xy 405.330535 -305.691218) (xy 405.36317 -305.654381)
			(xy 405.401291 -305.623256) (xy 405.443912 -305.598649) (xy 405.489928 -305.581197) (xy 405.538147 -305.571353)
			(xy 405.587322 -305.569372) (xy 405.636177 -305.575304) (xy 405.683448 -305.588996) (xy 405.72791 -305.610094)
			(xy 405.768413 -305.63805) (xy 405.803906 -305.672142) (xy 405.833471 -305.711486) (xy 405.856342 -305.755063)
			(xy 405.871926 -305.801744) (xy 405.879821 -305.850321) (xy 405.880316 -305.874928) (xy 406.219164 -305.874928)
			(xy 406.223124 -305.825874) (xy 406.234901 -305.77809) (xy 406.254192 -305.732814) (xy 406.280495 -305.691218)
			(xy 406.31313 -305.654381) (xy 406.351251 -305.623256) (xy 406.393872 -305.598649) (xy 406.439888 -305.581197)
			(xy 406.488107 -305.571353) (xy 406.537282 -305.569372) (xy 406.586137 -305.575304) (xy 406.633408 -305.588996)
			(xy 406.67787 -305.610094) (xy 406.718373 -305.63805) (xy 406.753866 -305.672142) (xy 406.783431 -305.711486)
			(xy 406.806302 -305.755063) (xy 406.821886 -305.801744) (xy 406.829781 -305.850321) (xy 406.830276 -305.874928)
			(xy 408.119084 -305.874928) (xy 408.123044 -305.825874) (xy 408.134821 -305.77809) (xy 408.154112 -305.732814)
			(xy 408.180415 -305.691218) (xy 408.21305 -305.654381) (xy 408.251171 -305.623256) (xy 408.293792 -305.598649)
			(xy 408.339808 -305.581197) (xy 408.388027 -305.571353) (xy 408.437202 -305.569372) (xy 408.486057 -305.575304)
			(xy 408.533328 -305.588996) (xy 408.57779 -305.610094) (xy 408.618293 -305.63805) (xy 408.653786 -305.672142)
			(xy 408.683351 -305.711486) (xy 408.706222 -305.755063) (xy 408.721806 -305.801744) (xy 408.729701 -305.850321)
			(xy 408.730196 -305.874928) (xy 408.729701 -305.899535) (xy 408.721806 -305.948112) (xy 408.706222 -305.994793)
			(xy 408.683351 -306.03837) (xy 408.653786 -306.077714) (xy 408.618293 -306.111806) (xy 408.57779 -306.139762)
			(xy 408.533328 -306.16086) (xy 408.486057 -306.174552) (xy 408.437202 -306.180484) (xy 408.388027 -306.178503)
			(xy 408.339808 -306.168659) (xy 408.293792 -306.151207) (xy 408.251171 -306.1266) (xy 408.21305 -306.095475)
			(xy 408.180415 -306.058638) (xy 408.154112 -306.017042) (xy 408.134821 -305.971766) (xy 408.123044 -305.923982)
			(xy 408.119084 -305.874928) (xy 406.830276 -305.874928) (xy 406.829781 -305.899535) (xy 406.821886 -305.948112)
			(xy 406.806302 -305.994793) (xy 406.783431 -306.03837) (xy 406.753866 -306.077714) (xy 406.718373 -306.111806)
			(xy 406.67787 -306.139762) (xy 406.633408 -306.16086) (xy 406.586137 -306.174552) (xy 406.537282 -306.180484)
			(xy 406.488107 -306.178503) (xy 406.439888 -306.168659) (xy 406.393872 -306.151207) (xy 406.351251 -306.1266)
			(xy 406.31313 -306.095475) (xy 406.280495 -306.058638) (xy 406.254192 -306.017042) (xy 406.234901 -305.971766)
			(xy 406.223124 -305.923982) (xy 406.219164 -305.874928) (xy 405.880316 -305.874928) (xy 405.879821 -305.899535)
			(xy 405.871926 -305.948112) (xy 405.856342 -305.994793) (xy 405.833471 -306.03837) (xy 405.803906 -306.077714)
			(xy 405.768413 -306.111806) (xy 405.72791 -306.139762) (xy 405.683448 -306.16086) (xy 405.636177 -306.174552)
			(xy 405.587322 -306.180484) (xy 405.538147 -306.178503) (xy 405.489928 -306.168659) (xy 405.443912 -306.151207)
			(xy 405.401291 -306.1266) (xy 405.36317 -306.095475) (xy 405.330535 -306.058638) (xy 405.304232 -306.017042)
			(xy 405.284941 -305.971766) (xy 405.273164 -305.923982) (xy 405.269204 -305.874928) (xy 404.930102 -305.874928)
			(xy 404.929607 -305.899535) (xy 404.921712 -305.948112) (xy 404.906128 -305.994793) (xy 404.883257 -306.03837)
			(xy 404.853692 -306.077714) (xy 404.818199 -306.111806) (xy 404.777696 -306.139762) (xy 404.733234 -306.16086)
			(xy 404.685963 -306.174552) (xy 404.637108 -306.180484) (xy 404.587933 -306.178503) (xy 404.539714 -306.168659)
			(xy 404.493698 -306.151207) (xy 404.451077 -306.1266) (xy 404.412956 -306.095475) (xy 404.380321 -306.058638)
			(xy 404.354018 -306.017042) (xy 404.334727 -305.971766) (xy 404.32295 -305.923982) (xy 404.31899 -305.874928)
			(xy 403.980142 -305.874928) (xy 403.979647 -305.899535) (xy 403.971752 -305.948112) (xy 403.956168 -305.994793)
			(xy 403.933297 -306.03837) (xy 403.903732 -306.077714) (xy 403.868239 -306.111806) (xy 403.827736 -306.139762)
			(xy 403.783274 -306.16086) (xy 403.736003 -306.174552) (xy 403.687148 -306.180484) (xy 403.637973 -306.178503)
			(xy 403.589754 -306.168659) (xy 403.543738 -306.151207) (xy 403.501117 -306.1266) (xy 403.462996 -306.095475)
			(xy 403.430361 -306.058638) (xy 403.404058 -306.017042) (xy 403.384767 -305.971766) (xy 403.37299 -305.923982)
			(xy 403.36903 -305.874928) (xy 403.030182 -305.874928) (xy 403.029687 -305.899535) (xy 403.021792 -305.948112)
			(xy 403.006208 -305.994793) (xy 402.983337 -306.03837) (xy 402.953772 -306.077714) (xy 402.918279 -306.111806)
			(xy 402.877776 -306.139762) (xy 402.833314 -306.16086) (xy 402.786043 -306.174552) (xy 402.737188 -306.180484)
			(xy 402.688013 -306.178503) (xy 402.639794 -306.168659) (xy 402.593778 -306.151207) (xy 402.551157 -306.1266)
			(xy 402.513036 -306.095475) (xy 402.480401 -306.058638) (xy 402.454098 -306.017042) (xy 402.434807 -305.971766)
			(xy 402.42303 -305.923982) (xy 402.41907 -305.874928) (xy 402.080222 -305.874928) (xy 402.079727 -305.899535)
			(xy 402.071832 -305.948112) (xy 402.056248 -305.994793) (xy 402.033377 -306.03837) (xy 402.003812 -306.077714)
			(xy 401.968319 -306.111806) (xy 401.927816 -306.139762) (xy 401.883354 -306.16086) (xy 401.836083 -306.174552)
			(xy 401.787228 -306.180484) (xy 401.738053 -306.178503) (xy 401.689834 -306.168659) (xy 401.643818 -306.151207)
			(xy 401.601197 -306.1266) (xy 401.563076 -306.095475) (xy 401.530441 -306.058638) (xy 401.504138 -306.017042)
			(xy 401.484847 -305.971766) (xy 401.47307 -305.923982) (xy 401.46911 -305.874928) (xy 401.130262 -305.874928)
			(xy 401.129767 -305.899535) (xy 401.121872 -305.948112) (xy 401.106288 -305.994793) (xy 401.083417 -306.03837)
			(xy 401.053852 -306.077714) (xy 401.018359 -306.111806) (xy 400.977856 -306.139762) (xy 400.933394 -306.16086)
			(xy 400.886123 -306.174552) (xy 400.837268 -306.180484) (xy 400.788093 -306.178503) (xy 400.739874 -306.168659)
			(xy 400.693858 -306.151207) (xy 400.651237 -306.1266) (xy 400.613116 -306.095475) (xy 400.580481 -306.058638)
			(xy 400.554178 -306.017042) (xy 400.534887 -305.971766) (xy 400.52311 -305.923982) (xy 400.51915 -305.874928)
			(xy 400.180302 -305.874928) (xy 400.179807 -305.899535) (xy 400.171912 -305.948112) (xy 400.156328 -305.994793)
			(xy 400.133457 -306.03837) (xy 400.103892 -306.077714) (xy 400.068399 -306.111806) (xy 400.027896 -306.139762)
			(xy 399.983434 -306.16086) (xy 399.936163 -306.174552) (xy 399.887308 -306.180484) (xy 399.838133 -306.178503)
			(xy 399.789914 -306.168659) (xy 399.743898 -306.151207) (xy 399.701277 -306.1266) (xy 399.663156 -306.095475)
			(xy 399.630521 -306.058638) (xy 399.604218 -306.017042) (xy 399.584927 -305.971766) (xy 399.57315 -305.923982)
			(xy 399.56919 -305.874928) (xy 399.230342 -305.874928) (xy 399.229847 -305.899535) (xy 399.221952 -305.948112)
			(xy 399.206368 -305.994793) (xy 399.183497 -306.03837) (xy 399.153932 -306.077714) (xy 399.118439 -306.111806)
			(xy 399.077936 -306.139762) (xy 399.033474 -306.16086) (xy 398.986203 -306.174552) (xy 398.937348 -306.180484)
			(xy 398.888173 -306.178503) (xy 398.839954 -306.168659) (xy 398.793938 -306.151207) (xy 398.751317 -306.1266)
			(xy 398.713196 -306.095475) (xy 398.680561 -306.058638) (xy 398.654258 -306.017042) (xy 398.634967 -305.971766)
			(xy 398.62319 -305.923982) (xy 398.61923 -305.874928) (xy 398.280128 -305.874928) (xy 398.279633 -305.899535)
			(xy 398.271738 -305.948112) (xy 398.256154 -305.994793) (xy 398.233283 -306.03837) (xy 398.203718 -306.077714)
			(xy 398.168225 -306.111806) (xy 398.127722 -306.139762) (xy 398.08326 -306.16086) (xy 398.035989 -306.174552)
			(xy 397.987134 -306.180484) (xy 397.937959 -306.178503) (xy 397.88974 -306.168659) (xy 397.843724 -306.151207)
			(xy 397.801103 -306.1266) (xy 397.762982 -306.095475) (xy 397.730347 -306.058638) (xy 397.704044 -306.017042)
			(xy 397.684753 -305.971766) (xy 397.672976 -305.923982) (xy 397.669016 -305.874928) (xy 397.330168 -305.874928)
			(xy 397.329673 -305.899535) (xy 397.321778 -305.948112) (xy 397.306194 -305.994793) (xy 397.283323 -306.03837)
			(xy 397.253758 -306.077714) (xy 397.218265 -306.111806) (xy 397.177762 -306.139762) (xy 397.1333 -306.16086)
			(xy 397.086029 -306.174552) (xy 397.037174 -306.180484) (xy 396.987999 -306.178503) (xy 396.93978 -306.168659)
			(xy 396.893764 -306.151207) (xy 396.851143 -306.1266) (xy 396.813022 -306.095475) (xy 396.780387 -306.058638)
			(xy 396.754084 -306.017042) (xy 396.734793 -305.971766) (xy 396.723016 -305.923982) (xy 396.719056 -305.874928)
			(xy 396.380208 -305.874928) (xy 396.379713 -305.899535) (xy 396.371818 -305.948112) (xy 396.356234 -305.994793)
			(xy 396.333363 -306.03837) (xy 396.303798 -306.077714) (xy 396.268305 -306.111806) (xy 396.227802 -306.139762)
			(xy 396.18334 -306.16086) (xy 396.136069 -306.174552) (xy 396.087214 -306.180484) (xy 396.038039 -306.178503)
			(xy 395.98982 -306.168659) (xy 395.943804 -306.151207) (xy 395.901183 -306.1266) (xy 395.863062 -306.095475)
			(xy 395.830427 -306.058638) (xy 395.804124 -306.017042) (xy 395.784833 -305.971766) (xy 395.773056 -305.923982)
			(xy 395.769096 -305.874928) (xy 395.430248 -305.874928) (xy 395.429753 -305.899535) (xy 395.421858 -305.948112)
			(xy 395.406274 -305.994793) (xy 395.383403 -306.03837) (xy 395.353838 -306.077714) (xy 395.318345 -306.111806)
			(xy 395.277842 -306.139762) (xy 395.23338 -306.16086) (xy 395.186109 -306.174552) (xy 395.137254 -306.180484)
			(xy 395.088079 -306.178503) (xy 395.03986 -306.168659) (xy 394.993844 -306.151207) (xy 394.951223 -306.1266)
			(xy 394.913102 -306.095475) (xy 394.880467 -306.058638) (xy 394.854164 -306.017042) (xy 394.834873 -305.971766)
			(xy 394.823096 -305.923982) (xy 394.819136 -305.874928) (xy 375.71032 -305.874928) (xy 375.729695 -305.916259)
			(xy 375.745763 -305.969666) (xy 375.753883 -306.024842) (xy 375.754392 -306.052728) (xy 375.753883 -306.080614)
			(xy 375.745763 -306.13579) (xy 375.729695 -306.189197) (xy 375.706023 -306.239694) (xy 375.67525 -306.286207)
			(xy 375.638033 -306.327744) (xy 375.611095 -306.350162) (xy 383.893834 -306.350162) (xy 383.897794 -306.301108)
			(xy 383.909571 -306.253324) (xy 383.928862 -306.208048) (xy 383.955165 -306.166452) (xy 383.9878 -306.129615)
			(xy 384.025921 -306.09849) (xy 384.068542 -306.073883) (xy 384.114558 -306.056431) (xy 384.162777 -306.046587)
			(xy 384.211952 -306.044606) (xy 384.260807 -306.050538) (xy 384.308078 -306.06423) (xy 384.35254 -306.085328)
			(xy 384.393043 -306.113284) (xy 384.428536 -306.147376) (xy 384.458101 -306.18672) (xy 384.480972 -306.230297)
			(xy 384.496556 -306.276978) (xy 384.504451 -306.325555) (xy 384.504941 -306.349908) (xy 384.844048 -306.349908)
			(xy 384.848008 -306.300854) (xy 384.859785 -306.25307) (xy 384.879076 -306.207794) (xy 384.905379 -306.166198)
			(xy 384.938014 -306.129361) (xy 384.976135 -306.098236) (xy 385.018756 -306.073629) (xy 385.064772 -306.056177)
			(xy 385.112991 -306.046333) (xy 385.162166 -306.044352) (xy 385.211021 -306.050284) (xy 385.258292 -306.063976)
			(xy 385.302754 -306.085074) (xy 385.343257 -306.11303) (xy 385.37875 -306.147122) (xy 385.408315 -306.186466)
			(xy 385.431186 -306.230043) (xy 385.44677 -306.276724) (xy 385.454665 -306.325301) (xy 385.45516 -306.349908)
			(xy 385.794008 -306.349908) (xy 385.797968 -306.300854) (xy 385.809745 -306.25307) (xy 385.829036 -306.207794)
			(xy 385.855339 -306.166198) (xy 385.887974 -306.129361) (xy 385.926095 -306.098236) (xy 385.968716 -306.073629)
			(xy 386.014732 -306.056177) (xy 386.062951 -306.046333) (xy 386.112126 -306.044352) (xy 386.160981 -306.050284)
			(xy 386.208252 -306.063976) (xy 386.252714 -306.085074) (xy 386.293217 -306.11303) (xy 386.32871 -306.147122)
			(xy 386.358275 -306.186466) (xy 386.381146 -306.230043) (xy 386.39673 -306.276724) (xy 386.404625 -306.325301)
			(xy 386.40512 -306.349908) (xy 386.744222 -306.349908) (xy 386.748182 -306.300854) (xy 386.759959 -306.25307)
			(xy 386.77925 -306.207794) (xy 386.805553 -306.166198) (xy 386.838188 -306.129361) (xy 386.876309 -306.098236)
			(xy 386.91893 -306.073629) (xy 386.964946 -306.056177) (xy 387.013165 -306.046333) (xy 387.06234 -306.044352)
			(xy 387.111195 -306.050284) (xy 387.158466 -306.063976) (xy 387.202928 -306.085074) (xy 387.243431 -306.11303)
			(xy 387.278924 -306.147122) (xy 387.308489 -306.186466) (xy 387.33136 -306.230043) (xy 387.346944 -306.276724)
			(xy 387.354839 -306.325301) (xy 387.355334 -306.349908) (xy 387.694182 -306.349908) (xy 387.698142 -306.300854)
			(xy 387.709919 -306.25307) (xy 387.72921 -306.207794) (xy 387.755513 -306.166198) (xy 387.788148 -306.129361)
			(xy 387.826269 -306.098236) (xy 387.86889 -306.073629) (xy 387.914906 -306.056177) (xy 387.963125 -306.046333)
			(xy 388.0123 -306.044352) (xy 388.061155 -306.050284) (xy 388.108426 -306.063976) (xy 388.152888 -306.085074)
			(xy 388.193391 -306.11303) (xy 388.228884 -306.147122) (xy 388.258449 -306.186466) (xy 388.28132 -306.230043)
			(xy 388.296904 -306.276724) (xy 388.304799 -306.325301) (xy 388.305294 -306.349908) (xy 388.644142 -306.349908)
			(xy 388.648102 -306.300854) (xy 388.659879 -306.25307) (xy 388.67917 -306.207794) (xy 388.705473 -306.166198)
			(xy 388.738108 -306.129361) (xy 388.776229 -306.098236) (xy 388.81885 -306.073629) (xy 388.864866 -306.056177)
			(xy 388.913085 -306.046333) (xy 388.96226 -306.044352) (xy 389.011115 -306.050284) (xy 389.058386 -306.063976)
			(xy 389.102848 -306.085074) (xy 389.143351 -306.11303) (xy 389.178844 -306.147122) (xy 389.208409 -306.186466)
			(xy 389.23128 -306.230043) (xy 389.246864 -306.276724) (xy 389.254759 -306.325301) (xy 389.255254 -306.349908)
			(xy 389.594102 -306.349908) (xy 389.598062 -306.300854) (xy 389.609839 -306.25307) (xy 389.62913 -306.207794)
			(xy 389.655433 -306.166198) (xy 389.688068 -306.129361) (xy 389.726189 -306.098236) (xy 389.76881 -306.073629)
			(xy 389.814826 -306.056177) (xy 389.863045 -306.046333) (xy 389.91222 -306.044352) (xy 389.961075 -306.050284)
			(xy 390.008346 -306.063976) (xy 390.052808 -306.085074) (xy 390.093311 -306.11303) (xy 390.128804 -306.147122)
			(xy 390.158369 -306.186466) (xy 390.18124 -306.230043) (xy 390.196824 -306.276724) (xy 390.204719 -306.325301)
			(xy 390.205214 -306.349908) (xy 390.544062 -306.349908) (xy 390.548022 -306.300854) (xy 390.559799 -306.25307)
			(xy 390.57909 -306.207794) (xy 390.605393 -306.166198) (xy 390.638028 -306.129361) (xy 390.676149 -306.098236)
			(xy 390.71877 -306.073629) (xy 390.764786 -306.056177) (xy 390.813005 -306.046333) (xy 390.86218 -306.044352)
			(xy 390.911035 -306.050284) (xy 390.958306 -306.063976) (xy 391.002768 -306.085074) (xy 391.043271 -306.11303)
			(xy 391.078764 -306.147122) (xy 391.108329 -306.186466) (xy 391.1312 -306.230043) (xy 391.146784 -306.276724)
			(xy 391.154679 -306.325301) (xy 391.155174 -306.349908) (xy 391.494022 -306.349908) (xy 391.497982 -306.300854)
			(xy 391.509759 -306.25307) (xy 391.52905 -306.207794) (xy 391.555353 -306.166198) (xy 391.587988 -306.129361)
			(xy 391.626109 -306.098236) (xy 391.66873 -306.073629) (xy 391.714746 -306.056177) (xy 391.762965 -306.046333)
			(xy 391.81214 -306.044352) (xy 391.860995 -306.050284) (xy 391.908266 -306.063976) (xy 391.952728 -306.085074)
			(xy 391.993231 -306.11303) (xy 392.028724 -306.147122) (xy 392.058289 -306.186466) (xy 392.08116 -306.230043)
			(xy 392.096744 -306.276724) (xy 392.104639 -306.325301) (xy 392.105134 -306.349908) (xy 392.443982 -306.349908)
			(xy 392.447942 -306.300854) (xy 392.459719 -306.25307) (xy 392.47901 -306.207794) (xy 392.505313 -306.166198)
			(xy 392.537948 -306.129361) (xy 392.576069 -306.098236) (xy 392.61869 -306.073629) (xy 392.664706 -306.056177)
			(xy 392.712925 -306.046333) (xy 392.7621 -306.044352) (xy 392.810955 -306.050284) (xy 392.858226 -306.063976)
			(xy 392.902688 -306.085074) (xy 392.943191 -306.11303) (xy 392.978684 -306.147122) (xy 393.008249 -306.186466)
			(xy 393.03112 -306.230043) (xy 393.046704 -306.276724) (xy 393.054599 -306.325301) (xy 393.055094 -306.349908)
			(xy 393.394196 -306.349908) (xy 393.398156 -306.300854) (xy 393.409933 -306.25307) (xy 393.429224 -306.207794)
			(xy 393.455527 -306.166198) (xy 393.488162 -306.129361) (xy 393.526283 -306.098236) (xy 393.568904 -306.073629)
			(xy 393.61492 -306.056177) (xy 393.663139 -306.046333) (xy 393.712314 -306.044352) (xy 393.761169 -306.050284)
			(xy 393.80844 -306.063976) (xy 393.852902 -306.085074) (xy 393.893405 -306.11303) (xy 393.928898 -306.147122)
			(xy 393.958463 -306.186466) (xy 393.981334 -306.230043) (xy 393.996918 -306.276724) (xy 394.004813 -306.325301)
			(xy 394.005308 -306.349908) (xy 394.004813 -306.374515) (xy 393.996918 -306.423092) (xy 393.981334 -306.469773)
			(xy 393.958463 -306.51335) (xy 393.928898 -306.552694) (xy 393.893405 -306.586786) (xy 393.852902 -306.614742)
			(xy 393.80844 -306.63584) (xy 393.761169 -306.649532) (xy 393.712314 -306.655464) (xy 393.663139 -306.653483)
			(xy 393.61492 -306.643639) (xy 393.568904 -306.626187) (xy 393.526283 -306.60158) (xy 393.488162 -306.570455)
			(xy 393.455527 -306.533618) (xy 393.429224 -306.492022) (xy 393.409933 -306.446746) (xy 393.398156 -306.398962)
			(xy 393.394196 -306.349908) (xy 393.055094 -306.349908) (xy 393.054599 -306.374515) (xy 393.046704 -306.423092)
			(xy 393.03112 -306.469773) (xy 393.008249 -306.51335) (xy 392.978684 -306.552694) (xy 392.943191 -306.586786)
			(xy 392.902688 -306.614742) (xy 392.858226 -306.63584) (xy 392.810955 -306.649532) (xy 392.7621 -306.655464)
			(xy 392.712925 -306.653483) (xy 392.664706 -306.643639) (xy 392.61869 -306.626187) (xy 392.576069 -306.60158)
			(xy 392.537948 -306.570455) (xy 392.505313 -306.533618) (xy 392.47901 -306.492022) (xy 392.459719 -306.446746)
			(xy 392.447942 -306.398962) (xy 392.443982 -306.349908) (xy 392.105134 -306.349908) (xy 392.104639 -306.374515)
			(xy 392.096744 -306.423092) (xy 392.08116 -306.469773) (xy 392.058289 -306.51335) (xy 392.028724 -306.552694)
			(xy 391.993231 -306.586786) (xy 391.952728 -306.614742) (xy 391.908266 -306.63584) (xy 391.860995 -306.649532)
			(xy 391.81214 -306.655464) (xy 391.762965 -306.653483) (xy 391.714746 -306.643639) (xy 391.66873 -306.626187)
			(xy 391.626109 -306.60158) (xy 391.587988 -306.570455) (xy 391.555353 -306.533618) (xy 391.52905 -306.492022)
			(xy 391.509759 -306.446746) (xy 391.497982 -306.398962) (xy 391.494022 -306.349908) (xy 391.155174 -306.349908)
			(xy 391.154679 -306.374515) (xy 391.146784 -306.423092) (xy 391.1312 -306.469773) (xy 391.108329 -306.51335)
			(xy 391.078764 -306.552694) (xy 391.043271 -306.586786) (xy 391.002768 -306.614742) (xy 390.958306 -306.63584)
			(xy 390.911035 -306.649532) (xy 390.86218 -306.655464) (xy 390.813005 -306.653483) (xy 390.764786 -306.643639)
			(xy 390.71877 -306.626187) (xy 390.676149 -306.60158) (xy 390.638028 -306.570455) (xy 390.605393 -306.533618)
			(xy 390.57909 -306.492022) (xy 390.559799 -306.446746) (xy 390.548022 -306.398962) (xy 390.544062 -306.349908)
			(xy 390.205214 -306.349908) (xy 390.204719 -306.374515) (xy 390.196824 -306.423092) (xy 390.18124 -306.469773)
			(xy 390.158369 -306.51335) (xy 390.128804 -306.552694) (xy 390.093311 -306.586786) (xy 390.052808 -306.614742)
			(xy 390.008346 -306.63584) (xy 389.961075 -306.649532) (xy 389.91222 -306.655464) (xy 389.863045 -306.653483)
			(xy 389.814826 -306.643639) (xy 389.76881 -306.626187) (xy 389.726189 -306.60158) (xy 389.688068 -306.570455)
			(xy 389.655433 -306.533618) (xy 389.62913 -306.492022) (xy 389.609839 -306.446746) (xy 389.598062 -306.398962)
			(xy 389.594102 -306.349908) (xy 389.255254 -306.349908) (xy 389.254759 -306.374515) (xy 389.246864 -306.423092)
			(xy 389.23128 -306.469773) (xy 389.208409 -306.51335) (xy 389.178844 -306.552694) (xy 389.143351 -306.586786)
			(xy 389.102848 -306.614742) (xy 389.058386 -306.63584) (xy 389.011115 -306.649532) (xy 388.96226 -306.655464)
			(xy 388.913085 -306.653483) (xy 388.864866 -306.643639) (xy 388.81885 -306.626187) (xy 388.776229 -306.60158)
			(xy 388.738108 -306.570455) (xy 388.705473 -306.533618) (xy 388.67917 -306.492022) (xy 388.659879 -306.446746)
			(xy 388.648102 -306.398962) (xy 388.644142 -306.349908) (xy 388.305294 -306.349908) (xy 388.304799 -306.374515)
			(xy 388.296904 -306.423092) (xy 388.28132 -306.469773) (xy 388.258449 -306.51335) (xy 388.228884 -306.552694)
			(xy 388.193391 -306.586786) (xy 388.152888 -306.614742) (xy 388.108426 -306.63584) (xy 388.061155 -306.649532)
			(xy 388.0123 -306.655464) (xy 387.963125 -306.653483) (xy 387.914906 -306.643639) (xy 387.86889 -306.626187)
			(xy 387.826269 -306.60158) (xy 387.788148 -306.570455) (xy 387.755513 -306.533618) (xy 387.72921 -306.492022)
			(xy 387.709919 -306.446746) (xy 387.698142 -306.398962) (xy 387.694182 -306.349908) (xy 387.355334 -306.349908)
			(xy 387.354839 -306.374515) (xy 387.346944 -306.423092) (xy 387.33136 -306.469773) (xy 387.308489 -306.51335)
			(xy 387.278924 -306.552694) (xy 387.243431 -306.586786) (xy 387.202928 -306.614742) (xy 387.158466 -306.63584)
			(xy 387.111195 -306.649532) (xy 387.06234 -306.655464) (xy 387.013165 -306.653483) (xy 386.964946 -306.643639)
			(xy 386.91893 -306.626187) (xy 386.876309 -306.60158) (xy 386.838188 -306.570455) (xy 386.805553 -306.533618)
			(xy 386.77925 -306.492022) (xy 386.759959 -306.446746) (xy 386.748182 -306.398962) (xy 386.744222 -306.349908)
			(xy 386.40512 -306.349908) (xy 386.404625 -306.374515) (xy 386.39673 -306.423092) (xy 386.381146 -306.469773)
			(xy 386.358275 -306.51335) (xy 386.32871 -306.552694) (xy 386.293217 -306.586786) (xy 386.252714 -306.614742)
			(xy 386.208252 -306.63584) (xy 386.160981 -306.649532) (xy 386.112126 -306.655464) (xy 386.062951 -306.653483)
			(xy 386.014732 -306.643639) (xy 385.968716 -306.626187) (xy 385.926095 -306.60158) (xy 385.887974 -306.570455)
			(xy 385.855339 -306.533618) (xy 385.829036 -306.492022) (xy 385.809745 -306.446746) (xy 385.797968 -306.398962)
			(xy 385.794008 -306.349908) (xy 385.45516 -306.349908) (xy 385.454665 -306.374515) (xy 385.44677 -306.423092)
			(xy 385.431186 -306.469773) (xy 385.408315 -306.51335) (xy 385.37875 -306.552694) (xy 385.343257 -306.586786)
			(xy 385.302754 -306.614742) (xy 385.258292 -306.63584) (xy 385.211021 -306.649532) (xy 385.162166 -306.655464)
			(xy 385.112991 -306.653483) (xy 385.064772 -306.643639) (xy 385.018756 -306.626187) (xy 384.976135 -306.60158)
			(xy 384.938014 -306.570455) (xy 384.905379 -306.533618) (xy 384.879076 -306.492022) (xy 384.859785 -306.446746)
			(xy 384.848008 -306.398962) (xy 384.844048 -306.349908) (xy 384.504941 -306.349908) (xy 384.504946 -306.350162)
			(xy 384.504451 -306.374769) (xy 384.496556 -306.423346) (xy 384.480972 -306.470027) (xy 384.458101 -306.513604)
			(xy 384.428536 -306.552948) (xy 384.393043 -306.58704) (xy 384.35254 -306.614996) (xy 384.308078 -306.636094)
			(xy 384.260807 -306.649786) (xy 384.211952 -306.655718) (xy 384.162777 -306.653737) (xy 384.114558 -306.643893)
			(xy 384.068542 -306.626441) (xy 384.025921 -306.601834) (xy 383.9878 -306.570709) (xy 383.955165 -306.533872)
			(xy 383.928862 -306.492276) (xy 383.909571 -306.447) (xy 383.897794 -306.399216) (xy 383.893834 -306.350162)
			(xy 375.611095 -306.350162) (xy 375.595165 -306.363419) (xy 375.547559 -306.392473) (xy 375.49623 -306.414285)
			(xy 375.442273 -306.428391) (xy 375.386836 -306.434491) (xy 375.331102 -306.432454) (xy 375.276259 -306.422324)
			(xy 375.223475 -306.404317) (xy 375.173875 -306.378816) (xy 375.128517 -306.346365) (xy 375.088368 -306.307656)
			(xy 375.054282 -306.263513) (xy 375.026986 -306.214878) (xy 375.007063 -306.162787) (xy 374.994937 -306.10835)
			(xy 374.990866 -306.052728) (xy 367.231422 -306.052728) (xy 366.518952 -306.765198) (xy 378.025404 -306.765198)
			(xy 378.029475 -306.709576) (xy 378.041601 -306.655139) (xy 378.061524 -306.603048) (xy 378.08882 -306.554413)
			(xy 378.122906 -306.51027) (xy 378.163055 -306.471561) (xy 378.208413 -306.43911) (xy 378.258013 -306.413609)
			(xy 378.310797 -306.395602) (xy 378.36564 -306.385472) (xy 378.421374 -306.383435) (xy 378.476811 -306.389535)
			(xy 378.530768 -306.403641) (xy 378.582097 -306.425453) (xy 378.629703 -306.454507) (xy 378.672571 -306.490182)
			(xy 378.709788 -306.531719) (xy 378.740561 -306.578232) (xy 378.764233 -306.628729) (xy 378.780301 -306.682136)
			(xy 378.788421 -306.737312) (xy 378.78893 -306.765198) (xy 378.788421 -306.793084) (xy 378.783741 -306.824888)
			(xy 394.819136 -306.824888) (xy 394.823096 -306.775834) (xy 394.834873 -306.72805) (xy 394.854164 -306.682774)
			(xy 394.880467 -306.641178) (xy 394.913102 -306.604341) (xy 394.951223 -306.573216) (xy 394.993844 -306.548609)
			(xy 395.03986 -306.531157) (xy 395.088079 -306.521313) (xy 395.137254 -306.519332) (xy 395.186109 -306.525264)
			(xy 395.23338 -306.538956) (xy 395.277842 -306.560054) (xy 395.318345 -306.58801) (xy 395.353838 -306.622102)
			(xy 395.383403 -306.661446) (xy 395.406274 -306.705023) (xy 395.421858 -306.751704) (xy 395.429753 -306.800281)
			(xy 395.430248 -306.824888) (xy 395.769096 -306.824888) (xy 395.773056 -306.775834) (xy 395.784833 -306.72805)
			(xy 395.804124 -306.682774) (xy 395.830427 -306.641178) (xy 395.863062 -306.604341) (xy 395.901183 -306.573216)
			(xy 395.943804 -306.548609) (xy 395.98982 -306.531157) (xy 396.038039 -306.521313) (xy 396.087214 -306.519332)
			(xy 396.136069 -306.525264) (xy 396.18334 -306.538956) (xy 396.227802 -306.560054) (xy 396.268305 -306.58801)
			(xy 396.303798 -306.622102) (xy 396.333363 -306.661446) (xy 396.356234 -306.705023) (xy 396.371818 -306.751704)
			(xy 396.379713 -306.800281) (xy 396.380208 -306.824888) (xy 396.719056 -306.824888) (xy 396.723016 -306.775834)
			(xy 396.734793 -306.72805) (xy 396.754084 -306.682774) (xy 396.780387 -306.641178) (xy 396.813022 -306.604341)
			(xy 396.851143 -306.573216) (xy 396.893764 -306.548609) (xy 396.93978 -306.531157) (xy 396.987999 -306.521313)
			(xy 397.037174 -306.519332) (xy 397.086029 -306.525264) (xy 397.1333 -306.538956) (xy 397.177762 -306.560054)
			(xy 397.218265 -306.58801) (xy 397.253758 -306.622102) (xy 397.283323 -306.661446) (xy 397.306194 -306.705023)
			(xy 397.321778 -306.751704) (xy 397.329673 -306.800281) (xy 397.330168 -306.824888) (xy 397.669016 -306.824888)
			(xy 397.672976 -306.775834) (xy 397.684753 -306.72805) (xy 397.704044 -306.682774) (xy 397.730347 -306.641178)
			(xy 397.762982 -306.604341) (xy 397.801103 -306.573216) (xy 397.843724 -306.548609) (xy 397.88974 -306.531157)
			(xy 397.937959 -306.521313) (xy 397.987134 -306.519332) (xy 398.035989 -306.525264) (xy 398.08326 -306.538956)
			(xy 398.127722 -306.560054) (xy 398.168225 -306.58801) (xy 398.203718 -306.622102) (xy 398.233283 -306.661446)
			(xy 398.256154 -306.705023) (xy 398.271738 -306.751704) (xy 398.279633 -306.800281) (xy 398.280128 -306.824888)
			(xy 398.61923 -306.824888) (xy 398.62319 -306.775834) (xy 398.634967 -306.72805) (xy 398.654258 -306.682774)
			(xy 398.680561 -306.641178) (xy 398.713196 -306.604341) (xy 398.751317 -306.573216) (xy 398.793938 -306.548609)
			(xy 398.839954 -306.531157) (xy 398.888173 -306.521313) (xy 398.937348 -306.519332) (xy 398.986203 -306.525264)
			(xy 399.033474 -306.538956) (xy 399.077936 -306.560054) (xy 399.118439 -306.58801) (xy 399.153932 -306.622102)
			(xy 399.183497 -306.661446) (xy 399.206368 -306.705023) (xy 399.221952 -306.751704) (xy 399.229847 -306.800281)
			(xy 399.230342 -306.824888) (xy 399.56919 -306.824888) (xy 399.57315 -306.775834) (xy 399.584927 -306.72805)
			(xy 399.604218 -306.682774) (xy 399.630521 -306.641178) (xy 399.663156 -306.604341) (xy 399.701277 -306.573216)
			(xy 399.743898 -306.548609) (xy 399.789914 -306.531157) (xy 399.838133 -306.521313) (xy 399.887308 -306.519332)
			(xy 399.936163 -306.525264) (xy 399.983434 -306.538956) (xy 400.027896 -306.560054) (xy 400.068399 -306.58801)
			(xy 400.103892 -306.622102) (xy 400.133457 -306.661446) (xy 400.156328 -306.705023) (xy 400.171912 -306.751704)
			(xy 400.179807 -306.800281) (xy 400.180302 -306.824888) (xy 400.51915 -306.824888) (xy 400.52311 -306.775834)
			(xy 400.534887 -306.72805) (xy 400.554178 -306.682774) (xy 400.580481 -306.641178) (xy 400.613116 -306.604341)
			(xy 400.651237 -306.573216) (xy 400.693858 -306.548609) (xy 400.739874 -306.531157) (xy 400.788093 -306.521313)
			(xy 400.837268 -306.519332) (xy 400.886123 -306.525264) (xy 400.933394 -306.538956) (xy 400.977856 -306.560054)
			(xy 401.018359 -306.58801) (xy 401.053852 -306.622102) (xy 401.083417 -306.661446) (xy 401.106288 -306.705023)
			(xy 401.121872 -306.751704) (xy 401.129767 -306.800281) (xy 401.130262 -306.824888) (xy 401.46911 -306.824888)
			(xy 401.47307 -306.775834) (xy 401.484847 -306.72805) (xy 401.504138 -306.682774) (xy 401.530441 -306.641178)
			(xy 401.563076 -306.604341) (xy 401.601197 -306.573216) (xy 401.643818 -306.548609) (xy 401.689834 -306.531157)
			(xy 401.738053 -306.521313) (xy 401.787228 -306.519332) (xy 401.836083 -306.525264) (xy 401.883354 -306.538956)
			(xy 401.927816 -306.560054) (xy 401.968319 -306.58801) (xy 402.003812 -306.622102) (xy 402.033377 -306.661446)
			(xy 402.056248 -306.705023) (xy 402.071832 -306.751704) (xy 402.079727 -306.800281) (xy 402.080222 -306.824888)
			(xy 402.41907 -306.824888) (xy 402.42303 -306.775834) (xy 402.434807 -306.72805) (xy 402.454098 -306.682774)
			(xy 402.480401 -306.641178) (xy 402.513036 -306.604341) (xy 402.551157 -306.573216) (xy 402.593778 -306.548609)
			(xy 402.639794 -306.531157) (xy 402.688013 -306.521313) (xy 402.737188 -306.519332) (xy 402.786043 -306.525264)
			(xy 402.833314 -306.538956) (xy 402.877776 -306.560054) (xy 402.918279 -306.58801) (xy 402.953772 -306.622102)
			(xy 402.983337 -306.661446) (xy 403.006208 -306.705023) (xy 403.021792 -306.751704) (xy 403.029687 -306.800281)
			(xy 403.030182 -306.824888) (xy 403.36903 -306.824888) (xy 403.37299 -306.775834) (xy 403.384767 -306.72805)
			(xy 403.404058 -306.682774) (xy 403.430361 -306.641178) (xy 403.462996 -306.604341) (xy 403.501117 -306.573216)
			(xy 403.543738 -306.548609) (xy 403.589754 -306.531157) (xy 403.637973 -306.521313) (xy 403.687148 -306.519332)
			(xy 403.736003 -306.525264) (xy 403.783274 -306.538956) (xy 403.827736 -306.560054) (xy 403.868239 -306.58801)
			(xy 403.903732 -306.622102) (xy 403.933297 -306.661446) (xy 403.956168 -306.705023) (xy 403.971752 -306.751704)
			(xy 403.979647 -306.800281) (xy 403.980142 -306.824888) (xy 404.31899 -306.824888) (xy 404.32295 -306.775834)
			(xy 404.334727 -306.72805) (xy 404.354018 -306.682774) (xy 404.380321 -306.641178) (xy 404.412956 -306.604341)
			(xy 404.451077 -306.573216) (xy 404.493698 -306.548609) (xy 404.539714 -306.531157) (xy 404.587933 -306.521313)
			(xy 404.637108 -306.519332) (xy 404.685963 -306.525264) (xy 404.733234 -306.538956) (xy 404.777696 -306.560054)
			(xy 404.818199 -306.58801) (xy 404.853692 -306.622102) (xy 404.883257 -306.661446) (xy 404.906128 -306.705023)
			(xy 404.921712 -306.751704) (xy 404.929607 -306.800281) (xy 404.930102 -306.824888) (xy 405.269204 -306.824888)
			(xy 405.273164 -306.775834) (xy 405.284941 -306.72805) (xy 405.304232 -306.682774) (xy 405.330535 -306.641178)
			(xy 405.36317 -306.604341) (xy 405.401291 -306.573216) (xy 405.443912 -306.548609) (xy 405.489928 -306.531157)
			(xy 405.538147 -306.521313) (xy 405.587322 -306.519332) (xy 405.636177 -306.525264) (xy 405.683448 -306.538956)
			(xy 405.72791 -306.560054) (xy 405.768413 -306.58801) (xy 405.803906 -306.622102) (xy 405.833471 -306.661446)
			(xy 405.856342 -306.705023) (xy 405.871926 -306.751704) (xy 405.879821 -306.800281) (xy 405.880316 -306.824888)
			(xy 406.219164 -306.824888) (xy 406.223124 -306.775834) (xy 406.234901 -306.72805) (xy 406.254192 -306.682774)
			(xy 406.280495 -306.641178) (xy 406.31313 -306.604341) (xy 406.351251 -306.573216) (xy 406.393872 -306.548609)
			(xy 406.439888 -306.531157) (xy 406.488107 -306.521313) (xy 406.537282 -306.519332) (xy 406.586137 -306.525264)
			(xy 406.633408 -306.538956) (xy 406.67787 -306.560054) (xy 406.718373 -306.58801) (xy 406.753866 -306.622102)
			(xy 406.783431 -306.661446) (xy 406.806302 -306.705023) (xy 406.821886 -306.751704) (xy 406.829781 -306.800281)
			(xy 406.830276 -306.824888) (xy 408.119084 -306.824888) (xy 408.123044 -306.775834) (xy 408.134821 -306.72805)
			(xy 408.154112 -306.682774) (xy 408.180415 -306.641178) (xy 408.21305 -306.604341) (xy 408.251171 -306.573216)
			(xy 408.293792 -306.548609) (xy 408.339808 -306.531157) (xy 408.388027 -306.521313) (xy 408.437202 -306.519332)
			(xy 408.486057 -306.525264) (xy 408.533328 -306.538956) (xy 408.57779 -306.560054) (xy 408.618293 -306.58801)
			(xy 408.653786 -306.622102) (xy 408.683351 -306.661446) (xy 408.706222 -306.705023) (xy 408.721806 -306.751704)
			(xy 408.729701 -306.800281) (xy 408.730196 -306.824888) (xy 408.729701 -306.849495) (xy 408.721806 -306.898072)
			(xy 408.706222 -306.944753) (xy 408.683351 -306.98833) (xy 408.653786 -307.027674) (xy 408.618293 -307.061766)
			(xy 408.57779 -307.089722) (xy 408.533328 -307.11082) (xy 408.486057 -307.124512) (xy 408.437202 -307.130444)
			(xy 408.388027 -307.128463) (xy 408.339808 -307.118619) (xy 408.293792 -307.101167) (xy 408.251171 -307.07656)
			(xy 408.21305 -307.045435) (xy 408.180415 -307.008598) (xy 408.154112 -306.967002) (xy 408.134821 -306.921726)
			(xy 408.123044 -306.873942) (xy 408.119084 -306.824888) (xy 406.830276 -306.824888) (xy 406.829781 -306.849495)
			(xy 406.821886 -306.898072) (xy 406.806302 -306.944753) (xy 406.783431 -306.98833) (xy 406.753866 -307.027674)
			(xy 406.718373 -307.061766) (xy 406.67787 -307.089722) (xy 406.633408 -307.11082) (xy 406.586137 -307.124512)
			(xy 406.537282 -307.130444) (xy 406.488107 -307.128463) (xy 406.439888 -307.118619) (xy 406.393872 -307.101167)
			(xy 406.351251 -307.07656) (xy 406.31313 -307.045435) (xy 406.280495 -307.008598) (xy 406.254192 -306.967002)
			(xy 406.234901 -306.921726) (xy 406.223124 -306.873942) (xy 406.219164 -306.824888) (xy 405.880316 -306.824888)
			(xy 405.879821 -306.849495) (xy 405.871926 -306.898072) (xy 405.856342 -306.944753) (xy 405.833471 -306.98833)
			(xy 405.803906 -307.027674) (xy 405.768413 -307.061766) (xy 405.72791 -307.089722) (xy 405.683448 -307.11082)
			(xy 405.636177 -307.124512) (xy 405.587322 -307.130444) (xy 405.538147 -307.128463) (xy 405.489928 -307.118619)
			(xy 405.443912 -307.101167) (xy 405.401291 -307.07656) (xy 405.36317 -307.045435) (xy 405.330535 -307.008598)
			(xy 405.304232 -306.967002) (xy 405.284941 -306.921726) (xy 405.273164 -306.873942) (xy 405.269204 -306.824888)
			(xy 404.930102 -306.824888) (xy 404.929607 -306.849495) (xy 404.921712 -306.898072) (xy 404.906128 -306.944753)
			(xy 404.883257 -306.98833) (xy 404.853692 -307.027674) (xy 404.818199 -307.061766) (xy 404.777696 -307.089722)
			(xy 404.733234 -307.11082) (xy 404.685963 -307.124512) (xy 404.637108 -307.130444) (xy 404.587933 -307.128463)
			(xy 404.539714 -307.118619) (xy 404.493698 -307.101167) (xy 404.451077 -307.07656) (xy 404.412956 -307.045435)
			(xy 404.380321 -307.008598) (xy 404.354018 -306.967002) (xy 404.334727 -306.921726) (xy 404.32295 -306.873942)
			(xy 404.31899 -306.824888) (xy 403.980142 -306.824888) (xy 403.979647 -306.849495) (xy 403.971752 -306.898072)
			(xy 403.956168 -306.944753) (xy 403.933297 -306.98833) (xy 403.903732 -307.027674) (xy 403.868239 -307.061766)
			(xy 403.827736 -307.089722) (xy 403.783274 -307.11082) (xy 403.736003 -307.124512) (xy 403.687148 -307.130444)
			(xy 403.637973 -307.128463) (xy 403.589754 -307.118619) (xy 403.543738 -307.101167) (xy 403.501117 -307.07656)
			(xy 403.462996 -307.045435) (xy 403.430361 -307.008598) (xy 403.404058 -306.967002) (xy 403.384767 -306.921726)
			(xy 403.37299 -306.873942) (xy 403.36903 -306.824888) (xy 403.030182 -306.824888) (xy 403.029687 -306.849495)
			(xy 403.021792 -306.898072) (xy 403.006208 -306.944753) (xy 402.983337 -306.98833) (xy 402.953772 -307.027674)
			(xy 402.918279 -307.061766) (xy 402.877776 -307.089722) (xy 402.833314 -307.11082) (xy 402.786043 -307.124512)
			(xy 402.737188 -307.130444) (xy 402.688013 -307.128463) (xy 402.639794 -307.118619) (xy 402.593778 -307.101167)
			(xy 402.551157 -307.07656) (xy 402.513036 -307.045435) (xy 402.480401 -307.008598) (xy 402.454098 -306.967002)
			(xy 402.434807 -306.921726) (xy 402.42303 -306.873942) (xy 402.41907 -306.824888) (xy 402.080222 -306.824888)
			(xy 402.079727 -306.849495) (xy 402.071832 -306.898072) (xy 402.056248 -306.944753) (xy 402.033377 -306.98833)
			(xy 402.003812 -307.027674) (xy 401.968319 -307.061766) (xy 401.927816 -307.089722) (xy 401.883354 -307.11082)
			(xy 401.836083 -307.124512) (xy 401.787228 -307.130444) (xy 401.738053 -307.128463) (xy 401.689834 -307.118619)
			(xy 401.643818 -307.101167) (xy 401.601197 -307.07656) (xy 401.563076 -307.045435) (xy 401.530441 -307.008598)
			(xy 401.504138 -306.967002) (xy 401.484847 -306.921726) (xy 401.47307 -306.873942) (xy 401.46911 -306.824888)
			(xy 401.130262 -306.824888) (xy 401.129767 -306.849495) (xy 401.121872 -306.898072) (xy 401.106288 -306.944753)
			(xy 401.083417 -306.98833) (xy 401.053852 -307.027674) (xy 401.018359 -307.061766) (xy 400.977856 -307.089722)
			(xy 400.933394 -307.11082) (xy 400.886123 -307.124512) (xy 400.837268 -307.130444) (xy 400.788093 -307.128463)
			(xy 400.739874 -307.118619) (xy 400.693858 -307.101167) (xy 400.651237 -307.07656) (xy 400.613116 -307.045435)
			(xy 400.580481 -307.008598) (xy 400.554178 -306.967002) (xy 400.534887 -306.921726) (xy 400.52311 -306.873942)
			(xy 400.51915 -306.824888) (xy 400.180302 -306.824888) (xy 400.179807 -306.849495) (xy 400.171912 -306.898072)
			(xy 400.156328 -306.944753) (xy 400.133457 -306.98833) (xy 400.103892 -307.027674) (xy 400.068399 -307.061766)
			(xy 400.027896 -307.089722) (xy 399.983434 -307.11082) (xy 399.936163 -307.124512) (xy 399.887308 -307.130444)
			(xy 399.838133 -307.128463) (xy 399.789914 -307.118619) (xy 399.743898 -307.101167) (xy 399.701277 -307.07656)
			(xy 399.663156 -307.045435) (xy 399.630521 -307.008598) (xy 399.604218 -306.967002) (xy 399.584927 -306.921726)
			(xy 399.57315 -306.873942) (xy 399.56919 -306.824888) (xy 399.230342 -306.824888) (xy 399.229847 -306.849495)
			(xy 399.221952 -306.898072) (xy 399.206368 -306.944753) (xy 399.183497 -306.98833) (xy 399.153932 -307.027674)
			(xy 399.118439 -307.061766) (xy 399.077936 -307.089722) (xy 399.033474 -307.11082) (xy 398.986203 -307.124512)
			(xy 398.937348 -307.130444) (xy 398.888173 -307.128463) (xy 398.839954 -307.118619) (xy 398.793938 -307.101167)
			(xy 398.751317 -307.07656) (xy 398.713196 -307.045435) (xy 398.680561 -307.008598) (xy 398.654258 -306.967002)
			(xy 398.634967 -306.921726) (xy 398.62319 -306.873942) (xy 398.61923 -306.824888) (xy 398.280128 -306.824888)
			(xy 398.279633 -306.849495) (xy 398.271738 -306.898072) (xy 398.256154 -306.944753) (xy 398.233283 -306.98833)
			(xy 398.203718 -307.027674) (xy 398.168225 -307.061766) (xy 398.127722 -307.089722) (xy 398.08326 -307.11082)
			(xy 398.035989 -307.124512) (xy 397.987134 -307.130444) (xy 397.937959 -307.128463) (xy 397.88974 -307.118619)
			(xy 397.843724 -307.101167) (xy 397.801103 -307.07656) (xy 397.762982 -307.045435) (xy 397.730347 -307.008598)
			(xy 397.704044 -306.967002) (xy 397.684753 -306.921726) (xy 397.672976 -306.873942) (xy 397.669016 -306.824888)
			(xy 397.330168 -306.824888) (xy 397.329673 -306.849495) (xy 397.321778 -306.898072) (xy 397.306194 -306.944753)
			(xy 397.283323 -306.98833) (xy 397.253758 -307.027674) (xy 397.218265 -307.061766) (xy 397.177762 -307.089722)
			(xy 397.1333 -307.11082) (xy 397.086029 -307.124512) (xy 397.037174 -307.130444) (xy 396.987999 -307.128463)
			(xy 396.93978 -307.118619) (xy 396.893764 -307.101167) (xy 396.851143 -307.07656) (xy 396.813022 -307.045435)
			(xy 396.780387 -307.008598) (xy 396.754084 -306.967002) (xy 396.734793 -306.921726) (xy 396.723016 -306.873942)
			(xy 396.719056 -306.824888) (xy 396.380208 -306.824888) (xy 396.379713 -306.849495) (xy 396.371818 -306.898072)
			(xy 396.356234 -306.944753) (xy 396.333363 -306.98833) (xy 396.303798 -307.027674) (xy 396.268305 -307.061766)
			(xy 396.227802 -307.089722) (xy 396.18334 -307.11082) (xy 396.136069 -307.124512) (xy 396.087214 -307.130444)
			(xy 396.038039 -307.128463) (xy 395.98982 -307.118619) (xy 395.943804 -307.101167) (xy 395.901183 -307.07656)
			(xy 395.863062 -307.045435) (xy 395.830427 -307.008598) (xy 395.804124 -306.967002) (xy 395.784833 -306.921726)
			(xy 395.773056 -306.873942) (xy 395.769096 -306.824888) (xy 395.430248 -306.824888) (xy 395.429753 -306.849495)
			(xy 395.421858 -306.898072) (xy 395.406274 -306.944753) (xy 395.383403 -306.98833) (xy 395.353838 -307.027674)
			(xy 395.318345 -307.061766) (xy 395.277842 -307.089722) (xy 395.23338 -307.11082) (xy 395.186109 -307.124512)
			(xy 395.137254 -307.130444) (xy 395.088079 -307.128463) (xy 395.03986 -307.118619) (xy 394.993844 -307.101167)
			(xy 394.951223 -307.07656) (xy 394.913102 -307.045435) (xy 394.880467 -307.008598) (xy 394.854164 -306.967002)
			(xy 394.834873 -306.921726) (xy 394.823096 -306.873942) (xy 394.819136 -306.824888) (xy 378.783741 -306.824888)
			(xy 378.780301 -306.84826) (xy 378.764233 -306.901667) (xy 378.740561 -306.952164) (xy 378.709788 -306.998677)
			(xy 378.672571 -307.040214) (xy 378.629703 -307.075889) (xy 378.582097 -307.104943) (xy 378.530768 -307.126755)
			(xy 378.476811 -307.140861) (xy 378.421374 -307.146961) (xy 378.36564 -307.144924) (xy 378.310797 -307.134794)
			(xy 378.258013 -307.116787) (xy 378.208413 -307.091286) (xy 378.163055 -307.058835) (xy 378.122906 -307.020126)
			(xy 378.08882 -306.975983) (xy 378.061524 -306.927348) (xy 378.041601 -306.875257) (xy 378.029475 -306.82082)
			(xy 378.025404 -306.765198) (xy 366.518952 -306.765198) (xy 366.043972 -307.240178) (xy 380.16002 -307.240178)
			(xy 380.164091 -307.184556) (xy 380.176217 -307.130119) (xy 380.19614 -307.078028) (xy 380.223436 -307.029393)
			(xy 380.257522 -306.98525) (xy 380.297671 -306.946541) (xy 380.343029 -306.91409) (xy 380.392629 -306.888589)
			(xy 380.445413 -306.870582) (xy 380.500256 -306.860452) (xy 380.55599 -306.858415) (xy 380.611427 -306.864515)
			(xy 380.665384 -306.878621) (xy 380.716713 -306.900433) (xy 380.764319 -306.929487) (xy 380.807187 -306.965162)
			(xy 380.844404 -307.006699) (xy 380.875177 -307.053212) (xy 380.898849 -307.103709) (xy 380.914917 -307.157116)
			(xy 380.923037 -307.212292) (xy 380.923546 -307.240178) (xy 380.923037 -307.268064) (xy 380.918357 -307.299868)
			(xy 384.844048 -307.299868) (xy 384.848008 -307.250814) (xy 384.859785 -307.20303) (xy 384.879076 -307.157754)
			(xy 384.905379 -307.116158) (xy 384.938014 -307.079321) (xy 384.976135 -307.048196) (xy 385.018756 -307.023589)
			(xy 385.064772 -307.006137) (xy 385.112991 -306.996293) (xy 385.162166 -306.994312) (xy 385.211021 -307.000244)
			(xy 385.258292 -307.013936) (xy 385.302754 -307.035034) (xy 385.343257 -307.06299) (xy 385.37875 -307.097082)
			(xy 385.408315 -307.136426) (xy 385.431186 -307.180003) (xy 385.44677 -307.226684) (xy 385.454665 -307.275261)
			(xy 385.45516 -307.299868) (xy 385.794008 -307.299868) (xy 385.797968 -307.250814) (xy 385.809745 -307.20303)
			(xy 385.829036 -307.157754) (xy 385.855339 -307.116158) (xy 385.887974 -307.079321) (xy 385.926095 -307.048196)
			(xy 385.968716 -307.023589) (xy 386.014732 -307.006137) (xy 386.062951 -306.996293) (xy 386.112126 -306.994312)
			(xy 386.160981 -307.000244) (xy 386.208252 -307.013936) (xy 386.252714 -307.035034) (xy 386.293217 -307.06299)
			(xy 386.32871 -307.097082) (xy 386.358275 -307.136426) (xy 386.381146 -307.180003) (xy 386.39673 -307.226684)
			(xy 386.404625 -307.275261) (xy 386.40512 -307.299868) (xy 386.744222 -307.299868) (xy 386.748182 -307.250814)
			(xy 386.759959 -307.20303) (xy 386.77925 -307.157754) (xy 386.805553 -307.116158) (xy 386.838188 -307.079321)
			(xy 386.876309 -307.048196) (xy 386.91893 -307.023589) (xy 386.964946 -307.006137) (xy 387.013165 -306.996293)
			(xy 387.06234 -306.994312) (xy 387.111195 -307.000244) (xy 387.158466 -307.013936) (xy 387.202928 -307.035034)
			(xy 387.243431 -307.06299) (xy 387.278924 -307.097082) (xy 387.308489 -307.136426) (xy 387.33136 -307.180003)
			(xy 387.346944 -307.226684) (xy 387.354839 -307.275261) (xy 387.355334 -307.299868) (xy 387.694182 -307.299868)
			(xy 387.698142 -307.250814) (xy 387.709919 -307.20303) (xy 387.72921 -307.157754) (xy 387.755513 -307.116158)
			(xy 387.788148 -307.079321) (xy 387.826269 -307.048196) (xy 387.86889 -307.023589) (xy 387.914906 -307.006137)
			(xy 387.963125 -306.996293) (xy 388.0123 -306.994312) (xy 388.061155 -307.000244) (xy 388.108426 -307.013936)
			(xy 388.152888 -307.035034) (xy 388.193391 -307.06299) (xy 388.228884 -307.097082) (xy 388.258449 -307.136426)
			(xy 388.28132 -307.180003) (xy 388.296904 -307.226684) (xy 388.304799 -307.275261) (xy 388.305294 -307.299868)
			(xy 388.644142 -307.299868) (xy 388.648102 -307.250814) (xy 388.659879 -307.20303) (xy 388.67917 -307.157754)
			(xy 388.705473 -307.116158) (xy 388.738108 -307.079321) (xy 388.776229 -307.048196) (xy 388.81885 -307.023589)
			(xy 388.864866 -307.006137) (xy 388.913085 -306.996293) (xy 388.96226 -306.994312) (xy 389.011115 -307.000244)
			(xy 389.058386 -307.013936) (xy 389.102848 -307.035034) (xy 389.143351 -307.06299) (xy 389.178844 -307.097082)
			(xy 389.208409 -307.136426) (xy 389.23128 -307.180003) (xy 389.246864 -307.226684) (xy 389.254759 -307.275261)
			(xy 389.255254 -307.299868) (xy 389.594102 -307.299868) (xy 389.598062 -307.250814) (xy 389.609839 -307.20303)
			(xy 389.62913 -307.157754) (xy 389.655433 -307.116158) (xy 389.688068 -307.079321) (xy 389.726189 -307.048196)
			(xy 389.76881 -307.023589) (xy 389.814826 -307.006137) (xy 389.863045 -306.996293) (xy 389.91222 -306.994312)
			(xy 389.961075 -307.000244) (xy 390.008346 -307.013936) (xy 390.052808 -307.035034) (xy 390.093311 -307.06299)
			(xy 390.128804 -307.097082) (xy 390.158369 -307.136426) (xy 390.18124 -307.180003) (xy 390.196824 -307.226684)
			(xy 390.204719 -307.275261) (xy 390.205214 -307.299868) (xy 390.544062 -307.299868) (xy 390.548022 -307.250814)
			(xy 390.559799 -307.20303) (xy 390.57909 -307.157754) (xy 390.605393 -307.116158) (xy 390.638028 -307.079321)
			(xy 390.676149 -307.048196) (xy 390.71877 -307.023589) (xy 390.764786 -307.006137) (xy 390.813005 -306.996293)
			(xy 390.86218 -306.994312) (xy 390.911035 -307.000244) (xy 390.958306 -307.013936) (xy 391.002768 -307.035034)
			(xy 391.043271 -307.06299) (xy 391.078764 -307.097082) (xy 391.108329 -307.136426) (xy 391.1312 -307.180003)
			(xy 391.146784 -307.226684) (xy 391.154679 -307.275261) (xy 391.155174 -307.299868) (xy 391.494022 -307.299868)
			(xy 391.497982 -307.250814) (xy 391.509759 -307.20303) (xy 391.52905 -307.157754) (xy 391.555353 -307.116158)
			(xy 391.587988 -307.079321) (xy 391.626109 -307.048196) (xy 391.66873 -307.023589) (xy 391.714746 -307.006137)
			(xy 391.762965 -306.996293) (xy 391.81214 -306.994312) (xy 391.860995 -307.000244) (xy 391.908266 -307.013936)
			(xy 391.952728 -307.035034) (xy 391.993231 -307.06299) (xy 392.028724 -307.097082) (xy 392.058289 -307.136426)
			(xy 392.08116 -307.180003) (xy 392.096744 -307.226684) (xy 392.104639 -307.275261) (xy 392.105134 -307.299868)
			(xy 392.443982 -307.299868) (xy 392.447942 -307.250814) (xy 392.459719 -307.20303) (xy 392.47901 -307.157754)
			(xy 392.505313 -307.116158) (xy 392.537948 -307.079321) (xy 392.576069 -307.048196) (xy 392.61869 -307.023589)
			(xy 392.664706 -307.006137) (xy 392.712925 -306.996293) (xy 392.7621 -306.994312) (xy 392.810955 -307.000244)
			(xy 392.858226 -307.013936) (xy 392.902688 -307.035034) (xy 392.943191 -307.06299) (xy 392.978684 -307.097082)
			(xy 393.008249 -307.136426) (xy 393.03112 -307.180003) (xy 393.046704 -307.226684) (xy 393.054599 -307.275261)
			(xy 393.055094 -307.299868) (xy 393.394196 -307.299868) (xy 393.398156 -307.250814) (xy 393.409933 -307.20303)
			(xy 393.429224 -307.157754) (xy 393.455527 -307.116158) (xy 393.488162 -307.079321) (xy 393.526283 -307.048196)
			(xy 393.568904 -307.023589) (xy 393.61492 -307.006137) (xy 393.663139 -306.996293) (xy 393.712314 -306.994312)
			(xy 393.761169 -307.000244) (xy 393.80844 -307.013936) (xy 393.852902 -307.035034) (xy 393.893405 -307.06299)
			(xy 393.928898 -307.097082) (xy 393.958463 -307.136426) (xy 393.981334 -307.180003) (xy 393.996918 -307.226684)
			(xy 394.004813 -307.275261) (xy 394.005308 -307.299868) (xy 394.004813 -307.324475) (xy 393.996918 -307.373052)
			(xy 393.981334 -307.419733) (xy 393.958463 -307.46331) (xy 393.928898 -307.502654) (xy 393.893405 -307.536746)
			(xy 393.852902 -307.564702) (xy 393.80844 -307.5858) (xy 393.761169 -307.599492) (xy 393.712314 -307.605424)
			(xy 393.663139 -307.603443) (xy 393.61492 -307.593599) (xy 393.568904 -307.576147) (xy 393.526283 -307.55154)
			(xy 393.488162 -307.520415) (xy 393.455527 -307.483578) (xy 393.429224 -307.441982) (xy 393.409933 -307.396706)
			(xy 393.398156 -307.348922) (xy 393.394196 -307.299868) (xy 393.055094 -307.299868) (xy 393.054599 -307.324475)
			(xy 393.046704 -307.373052) (xy 393.03112 -307.419733) (xy 393.008249 -307.46331) (xy 392.978684 -307.502654)
			(xy 392.943191 -307.536746) (xy 392.902688 -307.564702) (xy 392.858226 -307.5858) (xy 392.810955 -307.599492)
			(xy 392.7621 -307.605424) (xy 392.712925 -307.603443) (xy 392.664706 -307.593599) (xy 392.61869 -307.576147)
			(xy 392.576069 -307.55154) (xy 392.537948 -307.520415) (xy 392.505313 -307.483578) (xy 392.47901 -307.441982)
			(xy 392.459719 -307.396706) (xy 392.447942 -307.348922) (xy 392.443982 -307.299868) (xy 392.105134 -307.299868)
			(xy 392.104639 -307.324475) (xy 392.096744 -307.373052) (xy 392.08116 -307.419733) (xy 392.058289 -307.46331)
			(xy 392.028724 -307.502654) (xy 391.993231 -307.536746) (xy 391.952728 -307.564702) (xy 391.908266 -307.5858)
			(xy 391.860995 -307.599492) (xy 391.81214 -307.605424) (xy 391.762965 -307.603443) (xy 391.714746 -307.593599)
			(xy 391.66873 -307.576147) (xy 391.626109 -307.55154) (xy 391.587988 -307.520415) (xy 391.555353 -307.483578)
			(xy 391.52905 -307.441982) (xy 391.509759 -307.396706) (xy 391.497982 -307.348922) (xy 391.494022 -307.299868)
			(xy 391.155174 -307.299868) (xy 391.154679 -307.324475) (xy 391.146784 -307.373052) (xy 391.1312 -307.419733)
			(xy 391.108329 -307.46331) (xy 391.078764 -307.502654) (xy 391.043271 -307.536746) (xy 391.002768 -307.564702)
			(xy 390.958306 -307.5858) (xy 390.911035 -307.599492) (xy 390.86218 -307.605424) (xy 390.813005 -307.603443)
			(xy 390.764786 -307.593599) (xy 390.71877 -307.576147) (xy 390.676149 -307.55154) (xy 390.638028 -307.520415)
			(xy 390.605393 -307.483578) (xy 390.57909 -307.441982) (xy 390.559799 -307.396706) (xy 390.548022 -307.348922)
			(xy 390.544062 -307.299868) (xy 390.205214 -307.299868) (xy 390.204719 -307.324475) (xy 390.196824 -307.373052)
			(xy 390.18124 -307.419733) (xy 390.158369 -307.46331) (xy 390.128804 -307.502654) (xy 390.093311 -307.536746)
			(xy 390.052808 -307.564702) (xy 390.008346 -307.5858) (xy 389.961075 -307.599492) (xy 389.91222 -307.605424)
			(xy 389.863045 -307.603443) (xy 389.814826 -307.593599) (xy 389.76881 -307.576147) (xy 389.726189 -307.55154)
			(xy 389.688068 -307.520415) (xy 389.655433 -307.483578) (xy 389.62913 -307.441982) (xy 389.609839 -307.396706)
			(xy 389.598062 -307.348922) (xy 389.594102 -307.299868) (xy 389.255254 -307.299868) (xy 389.254759 -307.324475)
			(xy 389.246864 -307.373052) (xy 389.23128 -307.419733) (xy 389.208409 -307.46331) (xy 389.178844 -307.502654)
			(xy 389.143351 -307.536746) (xy 389.102848 -307.564702) (xy 389.058386 -307.5858) (xy 389.011115 -307.599492)
			(xy 388.96226 -307.605424) (xy 388.913085 -307.603443) (xy 388.864866 -307.593599) (xy 388.81885 -307.576147)
			(xy 388.776229 -307.55154) (xy 388.738108 -307.520415) (xy 388.705473 -307.483578) (xy 388.67917 -307.441982)
			(xy 388.659879 -307.396706) (xy 388.648102 -307.348922) (xy 388.644142 -307.299868) (xy 388.305294 -307.299868)
			(xy 388.304799 -307.324475) (xy 388.296904 -307.373052) (xy 388.28132 -307.419733) (xy 388.258449 -307.46331)
			(xy 388.228884 -307.502654) (xy 388.193391 -307.536746) (xy 388.152888 -307.564702) (xy 388.108426 -307.5858)
			(xy 388.061155 -307.599492) (xy 388.0123 -307.605424) (xy 387.963125 -307.603443) (xy 387.914906 -307.593599)
			(xy 387.86889 -307.576147) (xy 387.826269 -307.55154) (xy 387.788148 -307.520415) (xy 387.755513 -307.483578)
			(xy 387.72921 -307.441982) (xy 387.709919 -307.396706) (xy 387.698142 -307.348922) (xy 387.694182 -307.299868)
			(xy 387.355334 -307.299868) (xy 387.354839 -307.324475) (xy 387.346944 -307.373052) (xy 387.33136 -307.419733)
			(xy 387.308489 -307.46331) (xy 387.278924 -307.502654) (xy 387.243431 -307.536746) (xy 387.202928 -307.564702)
			(xy 387.158466 -307.5858) (xy 387.111195 -307.599492) (xy 387.06234 -307.605424) (xy 387.013165 -307.603443)
			(xy 386.964946 -307.593599) (xy 386.91893 -307.576147) (xy 386.876309 -307.55154) (xy 386.838188 -307.520415)
			(xy 386.805553 -307.483578) (xy 386.77925 -307.441982) (xy 386.759959 -307.396706) (xy 386.748182 -307.348922)
			(xy 386.744222 -307.299868) (xy 386.40512 -307.299868) (xy 386.404625 -307.324475) (xy 386.39673 -307.373052)
			(xy 386.381146 -307.419733) (xy 386.358275 -307.46331) (xy 386.32871 -307.502654) (xy 386.293217 -307.536746)
			(xy 386.252714 -307.564702) (xy 386.208252 -307.5858) (xy 386.160981 -307.599492) (xy 386.112126 -307.605424)
			(xy 386.062951 -307.603443) (xy 386.014732 -307.593599) (xy 385.968716 -307.576147) (xy 385.926095 -307.55154)
			(xy 385.887974 -307.520415) (xy 385.855339 -307.483578) (xy 385.829036 -307.441982) (xy 385.809745 -307.396706)
			(xy 385.797968 -307.348922) (xy 385.794008 -307.299868) (xy 385.45516 -307.299868) (xy 385.454665 -307.324475)
			(xy 385.44677 -307.373052) (xy 385.431186 -307.419733) (xy 385.408315 -307.46331) (xy 385.37875 -307.502654)
			(xy 385.343257 -307.536746) (xy 385.302754 -307.564702) (xy 385.258292 -307.5858) (xy 385.211021 -307.599492)
			(xy 385.162166 -307.605424) (xy 385.112991 -307.603443) (xy 385.064772 -307.593599) (xy 385.018756 -307.576147)
			(xy 384.976135 -307.55154) (xy 384.938014 -307.520415) (xy 384.905379 -307.483578) (xy 384.879076 -307.441982)
			(xy 384.859785 -307.396706) (xy 384.848008 -307.348922) (xy 384.844048 -307.299868) (xy 380.918357 -307.299868)
			(xy 380.914917 -307.32324) (xy 380.898849 -307.376647) (xy 380.875177 -307.427144) (xy 380.844404 -307.473657)
			(xy 380.807187 -307.515194) (xy 380.764319 -307.550869) (xy 380.716713 -307.579923) (xy 380.665384 -307.601735)
			(xy 380.611427 -307.615841) (xy 380.55599 -307.621941) (xy 380.500256 -307.619904) (xy 380.445413 -307.609774)
			(xy 380.392629 -307.591767) (xy 380.343029 -307.566266) (xy 380.297671 -307.533815) (xy 380.257522 -307.495106)
			(xy 380.223436 -307.450963) (xy 380.19614 -307.402328) (xy 380.176217 -307.350237) (xy 380.164091 -307.2958)
			(xy 380.16002 -307.240178) (xy 366.043972 -307.240178) (xy 365.509302 -307.774848) (xy 394.819136 -307.774848)
			(xy 394.823096 -307.725794) (xy 394.834873 -307.67801) (xy 394.854164 -307.632734) (xy 394.880467 -307.591138)
			(xy 394.913102 -307.554301) (xy 394.951223 -307.523176) (xy 394.993844 -307.498569) (xy 395.03986 -307.481117)
			(xy 395.088079 -307.471273) (xy 395.137254 -307.469292) (xy 395.186109 -307.475224) (xy 395.23338 -307.488916)
			(xy 395.277842 -307.510014) (xy 395.318345 -307.53797) (xy 395.353838 -307.572062) (xy 395.383403 -307.611406)
			(xy 395.406274 -307.654983) (xy 395.421858 -307.701664) (xy 395.429753 -307.750241) (xy 395.430248 -307.774848)
			(xy 395.769096 -307.774848) (xy 395.773056 -307.725794) (xy 395.784833 -307.67801) (xy 395.804124 -307.632734)
			(xy 395.830427 -307.591138) (xy 395.863062 -307.554301) (xy 395.901183 -307.523176) (xy 395.943804 -307.498569)
			(xy 395.98982 -307.481117) (xy 396.038039 -307.471273) (xy 396.087214 -307.469292) (xy 396.136069 -307.475224)
			(xy 396.18334 -307.488916) (xy 396.227802 -307.510014) (xy 396.268305 -307.53797) (xy 396.303798 -307.572062)
			(xy 396.333363 -307.611406) (xy 396.356234 -307.654983) (xy 396.371818 -307.701664) (xy 396.379713 -307.750241)
			(xy 396.380208 -307.774848) (xy 396.719056 -307.774848) (xy 396.723016 -307.725794) (xy 396.734793 -307.67801)
			(xy 396.754084 -307.632734) (xy 396.780387 -307.591138) (xy 396.813022 -307.554301) (xy 396.851143 -307.523176)
			(xy 396.893764 -307.498569) (xy 396.93978 -307.481117) (xy 396.987999 -307.471273) (xy 397.037174 -307.469292)
			(xy 397.086029 -307.475224) (xy 397.1333 -307.488916) (xy 397.177762 -307.510014) (xy 397.218265 -307.53797)
			(xy 397.253758 -307.572062) (xy 397.283323 -307.611406) (xy 397.306194 -307.654983) (xy 397.321778 -307.701664)
			(xy 397.329673 -307.750241) (xy 397.330168 -307.774848) (xy 397.669016 -307.774848) (xy 397.672976 -307.725794)
			(xy 397.684753 -307.67801) (xy 397.704044 -307.632734) (xy 397.730347 -307.591138) (xy 397.762982 -307.554301)
			(xy 397.801103 -307.523176) (xy 397.843724 -307.498569) (xy 397.88974 -307.481117) (xy 397.937959 -307.471273)
			(xy 397.987134 -307.469292) (xy 398.035989 -307.475224) (xy 398.08326 -307.488916) (xy 398.127722 -307.510014)
			(xy 398.168225 -307.53797) (xy 398.203718 -307.572062) (xy 398.233283 -307.611406) (xy 398.256154 -307.654983)
			(xy 398.271738 -307.701664) (xy 398.279633 -307.750241) (xy 398.280128 -307.774848) (xy 398.61923 -307.774848)
			(xy 398.62319 -307.725794) (xy 398.634967 -307.67801) (xy 398.654258 -307.632734) (xy 398.680561 -307.591138)
			(xy 398.713196 -307.554301) (xy 398.751317 -307.523176) (xy 398.793938 -307.498569) (xy 398.839954 -307.481117)
			(xy 398.888173 -307.471273) (xy 398.937348 -307.469292) (xy 398.986203 -307.475224) (xy 399.033474 -307.488916)
			(xy 399.077936 -307.510014) (xy 399.118439 -307.53797) (xy 399.153932 -307.572062) (xy 399.183497 -307.611406)
			(xy 399.206368 -307.654983) (xy 399.221952 -307.701664) (xy 399.229847 -307.750241) (xy 399.230342 -307.774848)
			(xy 399.56919 -307.774848) (xy 399.57315 -307.725794) (xy 399.584927 -307.67801) (xy 399.604218 -307.632734)
			(xy 399.630521 -307.591138) (xy 399.663156 -307.554301) (xy 399.701277 -307.523176) (xy 399.743898 -307.498569)
			(xy 399.789914 -307.481117) (xy 399.838133 -307.471273) (xy 399.887308 -307.469292) (xy 399.936163 -307.475224)
			(xy 399.983434 -307.488916) (xy 400.027896 -307.510014) (xy 400.068399 -307.53797) (xy 400.103892 -307.572062)
			(xy 400.133457 -307.611406) (xy 400.156328 -307.654983) (xy 400.171912 -307.701664) (xy 400.179807 -307.750241)
			(xy 400.180302 -307.774848) (xy 400.51915 -307.774848) (xy 400.52311 -307.725794) (xy 400.534887 -307.67801)
			(xy 400.554178 -307.632734) (xy 400.580481 -307.591138) (xy 400.613116 -307.554301) (xy 400.651237 -307.523176)
			(xy 400.693858 -307.498569) (xy 400.739874 -307.481117) (xy 400.788093 -307.471273) (xy 400.837268 -307.469292)
			(xy 400.886123 -307.475224) (xy 400.933394 -307.488916) (xy 400.977856 -307.510014) (xy 401.018359 -307.53797)
			(xy 401.053852 -307.572062) (xy 401.083417 -307.611406) (xy 401.106288 -307.654983) (xy 401.121872 -307.701664)
			(xy 401.129767 -307.750241) (xy 401.130262 -307.774848) (xy 401.46911 -307.774848) (xy 401.47307 -307.725794)
			(xy 401.484847 -307.67801) (xy 401.504138 -307.632734) (xy 401.530441 -307.591138) (xy 401.563076 -307.554301)
			(xy 401.601197 -307.523176) (xy 401.643818 -307.498569) (xy 401.689834 -307.481117) (xy 401.738053 -307.471273)
			(xy 401.787228 -307.469292) (xy 401.836083 -307.475224) (xy 401.883354 -307.488916) (xy 401.927816 -307.510014)
			(xy 401.968319 -307.53797) (xy 402.003812 -307.572062) (xy 402.033377 -307.611406) (xy 402.056248 -307.654983)
			(xy 402.071832 -307.701664) (xy 402.079727 -307.750241) (xy 402.080222 -307.774848) (xy 402.41907 -307.774848)
			(xy 402.42303 -307.725794) (xy 402.434807 -307.67801) (xy 402.454098 -307.632734) (xy 402.480401 -307.591138)
			(xy 402.513036 -307.554301) (xy 402.551157 -307.523176) (xy 402.593778 -307.498569) (xy 402.639794 -307.481117)
			(xy 402.688013 -307.471273) (xy 402.737188 -307.469292) (xy 402.786043 -307.475224) (xy 402.833314 -307.488916)
			(xy 402.877776 -307.510014) (xy 402.918279 -307.53797) (xy 402.953772 -307.572062) (xy 402.983337 -307.611406)
			(xy 403.006208 -307.654983) (xy 403.021792 -307.701664) (xy 403.029687 -307.750241) (xy 403.030182 -307.774848)
			(xy 403.36903 -307.774848) (xy 403.37299 -307.725794) (xy 403.384767 -307.67801) (xy 403.404058 -307.632734)
			(xy 403.430361 -307.591138) (xy 403.462996 -307.554301) (xy 403.501117 -307.523176) (xy 403.543738 -307.498569)
			(xy 403.589754 -307.481117) (xy 403.637973 -307.471273) (xy 403.687148 -307.469292) (xy 403.736003 -307.475224)
			(xy 403.783274 -307.488916) (xy 403.827736 -307.510014) (xy 403.868239 -307.53797) (xy 403.903732 -307.572062)
			(xy 403.933297 -307.611406) (xy 403.956168 -307.654983) (xy 403.971752 -307.701664) (xy 403.979647 -307.750241)
			(xy 403.980142 -307.774848) (xy 404.319244 -307.774848) (xy 404.323204 -307.725794) (xy 404.334981 -307.67801)
			(xy 404.354272 -307.632734) (xy 404.380575 -307.591138) (xy 404.41321 -307.554301) (xy 404.451331 -307.523176)
			(xy 404.493952 -307.498569) (xy 404.539968 -307.481117) (xy 404.588187 -307.471273) (xy 404.637362 -307.469292)
			(xy 404.686217 -307.475224) (xy 404.733488 -307.488916) (xy 404.77795 -307.510014) (xy 404.818453 -307.53797)
			(xy 404.853946 -307.572062) (xy 404.883511 -307.611406) (xy 404.906382 -307.654983) (xy 404.921966 -307.701664)
			(xy 404.929861 -307.750241) (xy 404.930356 -307.774848) (xy 405.269204 -307.774848) (xy 405.273164 -307.725794)
			(xy 405.284941 -307.67801) (xy 405.304232 -307.632734) (xy 405.330535 -307.591138) (xy 405.36317 -307.554301)
			(xy 405.401291 -307.523176) (xy 405.443912 -307.498569) (xy 405.489928 -307.481117) (xy 405.538147 -307.471273)
			(xy 405.587322 -307.469292) (xy 405.636177 -307.475224) (xy 405.683448 -307.488916) (xy 405.72791 -307.510014)
			(xy 405.768413 -307.53797) (xy 405.803906 -307.572062) (xy 405.833471 -307.611406) (xy 405.856342 -307.654983)
			(xy 405.871926 -307.701664) (xy 405.879821 -307.750241) (xy 405.880316 -307.774848) (xy 406.219164 -307.774848)
			(xy 406.223124 -307.725794) (xy 406.234901 -307.67801) (xy 406.254192 -307.632734) (xy 406.280495 -307.591138)
			(xy 406.31313 -307.554301) (xy 406.351251 -307.523176) (xy 406.393872 -307.498569) (xy 406.439888 -307.481117)
			(xy 406.488107 -307.471273) (xy 406.537282 -307.469292) (xy 406.586137 -307.475224) (xy 406.633408 -307.488916)
			(xy 406.67787 -307.510014) (xy 406.718373 -307.53797) (xy 406.753866 -307.572062) (xy 406.783431 -307.611406)
			(xy 406.806302 -307.654983) (xy 406.821886 -307.701664) (xy 406.829781 -307.750241) (xy 406.830276 -307.774848)
			(xy 408.119084 -307.774848) (xy 408.123044 -307.725794) (xy 408.134821 -307.67801) (xy 408.154112 -307.632734)
			(xy 408.180415 -307.591138) (xy 408.21305 -307.554301) (xy 408.251171 -307.523176) (xy 408.293792 -307.498569)
			(xy 408.339808 -307.481117) (xy 408.388027 -307.471273) (xy 408.437202 -307.469292) (xy 408.486057 -307.475224)
			(xy 408.533328 -307.488916) (xy 408.57779 -307.510014) (xy 408.618293 -307.53797) (xy 408.653786 -307.572062)
			(xy 408.683351 -307.611406) (xy 408.706222 -307.654983) (xy 408.721806 -307.701664) (xy 408.729701 -307.750241)
			(xy 408.730196 -307.774848) (xy 408.729701 -307.799455) (xy 408.721806 -307.848032) (xy 408.706222 -307.894713)
			(xy 408.683351 -307.93829) (xy 408.653786 -307.977634) (xy 408.618293 -308.011726) (xy 408.57779 -308.039682)
			(xy 408.533328 -308.06078) (xy 408.486057 -308.074472) (xy 408.437202 -308.080404) (xy 408.388027 -308.078423)
			(xy 408.339808 -308.068579) (xy 408.293792 -308.051127) (xy 408.251171 -308.02652) (xy 408.21305 -307.995395)
			(xy 408.180415 -307.958558) (xy 408.154112 -307.916962) (xy 408.134821 -307.871686) (xy 408.123044 -307.823902)
			(xy 408.119084 -307.774848) (xy 406.830276 -307.774848) (xy 406.829781 -307.799455) (xy 406.821886 -307.848032)
			(xy 406.806302 -307.894713) (xy 406.783431 -307.93829) (xy 406.753866 -307.977634) (xy 406.718373 -308.011726)
			(xy 406.67787 -308.039682) (xy 406.633408 -308.06078) (xy 406.586137 -308.074472) (xy 406.537282 -308.080404)
			(xy 406.488107 -308.078423) (xy 406.439888 -308.068579) (xy 406.393872 -308.051127) (xy 406.351251 -308.02652)
			(xy 406.31313 -307.995395) (xy 406.280495 -307.958558) (xy 406.254192 -307.916962) (xy 406.234901 -307.871686)
			(xy 406.223124 -307.823902) (xy 406.219164 -307.774848) (xy 405.880316 -307.774848) (xy 405.879821 -307.799455)
			(xy 405.871926 -307.848032) (xy 405.856342 -307.894713) (xy 405.833471 -307.93829) (xy 405.803906 -307.977634)
			(xy 405.768413 -308.011726) (xy 405.72791 -308.039682) (xy 405.683448 -308.06078) (xy 405.636177 -308.074472)
			(xy 405.587322 -308.080404) (xy 405.538147 -308.078423) (xy 405.489928 -308.068579) (xy 405.443912 -308.051127)
			(xy 405.401291 -308.02652) (xy 405.36317 -307.995395) (xy 405.330535 -307.958558) (xy 405.304232 -307.916962)
			(xy 405.284941 -307.871686) (xy 405.273164 -307.823902) (xy 405.269204 -307.774848) (xy 404.930356 -307.774848)
			(xy 404.929861 -307.799455) (xy 404.921966 -307.848032) (xy 404.906382 -307.894713) (xy 404.883511 -307.93829)
			(xy 404.853946 -307.977634) (xy 404.818453 -308.011726) (xy 404.77795 -308.039682) (xy 404.733488 -308.06078)
			(xy 404.686217 -308.074472) (xy 404.637362 -308.080404) (xy 404.588187 -308.078423) (xy 404.539968 -308.068579)
			(xy 404.493952 -308.051127) (xy 404.451331 -308.02652) (xy 404.41321 -307.995395) (xy 404.380575 -307.958558)
			(xy 404.354272 -307.916962) (xy 404.334981 -307.871686) (xy 404.323204 -307.823902) (xy 404.319244 -307.774848)
			(xy 403.980142 -307.774848) (xy 403.979647 -307.799455) (xy 403.971752 -307.848032) (xy 403.956168 -307.894713)
			(xy 403.933297 -307.93829) (xy 403.903732 -307.977634) (xy 403.868239 -308.011726) (xy 403.827736 -308.039682)
			(xy 403.783274 -308.06078) (xy 403.736003 -308.074472) (xy 403.687148 -308.080404) (xy 403.637973 -308.078423)
			(xy 403.589754 -308.068579) (xy 403.543738 -308.051127) (xy 403.501117 -308.02652) (xy 403.462996 -307.995395)
			(xy 403.430361 -307.958558) (xy 403.404058 -307.916962) (xy 403.384767 -307.871686) (xy 403.37299 -307.823902)
			(xy 403.36903 -307.774848) (xy 403.030182 -307.774848) (xy 403.029687 -307.799455) (xy 403.021792 -307.848032)
			(xy 403.006208 -307.894713) (xy 402.983337 -307.93829) (xy 402.953772 -307.977634) (xy 402.918279 -308.011726)
			(xy 402.877776 -308.039682) (xy 402.833314 -308.06078) (xy 402.786043 -308.074472) (xy 402.737188 -308.080404)
			(xy 402.688013 -308.078423) (xy 402.639794 -308.068579) (xy 402.593778 -308.051127) (xy 402.551157 -308.02652)
			(xy 402.513036 -307.995395) (xy 402.480401 -307.958558) (xy 402.454098 -307.916962) (xy 402.434807 -307.871686)
			(xy 402.42303 -307.823902) (xy 402.41907 -307.774848) (xy 402.080222 -307.774848) (xy 402.079727 -307.799455)
			(xy 402.071832 -307.848032) (xy 402.056248 -307.894713) (xy 402.033377 -307.93829) (xy 402.003812 -307.977634)
			(xy 401.968319 -308.011726) (xy 401.927816 -308.039682) (xy 401.883354 -308.06078) (xy 401.836083 -308.074472)
			(xy 401.787228 -308.080404) (xy 401.738053 -308.078423) (xy 401.689834 -308.068579) (xy 401.643818 -308.051127)
			(xy 401.601197 -308.02652) (xy 401.563076 -307.995395) (xy 401.530441 -307.958558) (xy 401.504138 -307.916962)
			(xy 401.484847 -307.871686) (xy 401.47307 -307.823902) (xy 401.46911 -307.774848) (xy 401.130262 -307.774848)
			(xy 401.129767 -307.799455) (xy 401.121872 -307.848032) (xy 401.106288 -307.894713) (xy 401.083417 -307.93829)
			(xy 401.053852 -307.977634) (xy 401.018359 -308.011726) (xy 400.977856 -308.039682) (xy 400.933394 -308.06078)
			(xy 400.886123 -308.074472) (xy 400.837268 -308.080404) (xy 400.788093 -308.078423) (xy 400.739874 -308.068579)
			(xy 400.693858 -308.051127) (xy 400.651237 -308.02652) (xy 400.613116 -307.995395) (xy 400.580481 -307.958558)
			(xy 400.554178 -307.916962) (xy 400.534887 -307.871686) (xy 400.52311 -307.823902) (xy 400.51915 -307.774848)
			(xy 400.180302 -307.774848) (xy 400.179807 -307.799455) (xy 400.171912 -307.848032) (xy 400.156328 -307.894713)
			(xy 400.133457 -307.93829) (xy 400.103892 -307.977634) (xy 400.068399 -308.011726) (xy 400.027896 -308.039682)
			(xy 399.983434 -308.06078) (xy 399.936163 -308.074472) (xy 399.887308 -308.080404) (xy 399.838133 -308.078423)
			(xy 399.789914 -308.068579) (xy 399.743898 -308.051127) (xy 399.701277 -308.02652) (xy 399.663156 -307.995395)
			(xy 399.630521 -307.958558) (xy 399.604218 -307.916962) (xy 399.584927 -307.871686) (xy 399.57315 -307.823902)
			(xy 399.56919 -307.774848) (xy 399.230342 -307.774848) (xy 399.229847 -307.799455) (xy 399.221952 -307.848032)
			(xy 399.206368 -307.894713) (xy 399.183497 -307.93829) (xy 399.153932 -307.977634) (xy 399.118439 -308.011726)
			(xy 399.077936 -308.039682) (xy 399.033474 -308.06078) (xy 398.986203 -308.074472) (xy 398.937348 -308.080404)
			(xy 398.888173 -308.078423) (xy 398.839954 -308.068579) (xy 398.793938 -308.051127) (xy 398.751317 -308.02652)
			(xy 398.713196 -307.995395) (xy 398.680561 -307.958558) (xy 398.654258 -307.916962) (xy 398.634967 -307.871686)
			(xy 398.62319 -307.823902) (xy 398.61923 -307.774848) (xy 398.280128 -307.774848) (xy 398.279633 -307.799455)
			(xy 398.271738 -307.848032) (xy 398.256154 -307.894713) (xy 398.233283 -307.93829) (xy 398.203718 -307.977634)
			(xy 398.168225 -308.011726) (xy 398.127722 -308.039682) (xy 398.08326 -308.06078) (xy 398.035989 -308.074472)
			(xy 397.987134 -308.080404) (xy 397.937959 -308.078423) (xy 397.88974 -308.068579) (xy 397.843724 -308.051127)
			(xy 397.801103 -308.02652) (xy 397.762982 -307.995395) (xy 397.730347 -307.958558) (xy 397.704044 -307.916962)
			(xy 397.684753 -307.871686) (xy 397.672976 -307.823902) (xy 397.669016 -307.774848) (xy 397.330168 -307.774848)
			(xy 397.329673 -307.799455) (xy 397.321778 -307.848032) (xy 397.306194 -307.894713) (xy 397.283323 -307.93829)
			(xy 397.253758 -307.977634) (xy 397.218265 -308.011726) (xy 397.177762 -308.039682) (xy 397.1333 -308.06078)
			(xy 397.086029 -308.074472) (xy 397.037174 -308.080404) (xy 396.987999 -308.078423) (xy 396.93978 -308.068579)
			(xy 396.893764 -308.051127) (xy 396.851143 -308.02652) (xy 396.813022 -307.995395) (xy 396.780387 -307.958558)
			(xy 396.754084 -307.916962) (xy 396.734793 -307.871686) (xy 396.723016 -307.823902) (xy 396.719056 -307.774848)
			(xy 396.380208 -307.774848) (xy 396.379713 -307.799455) (xy 396.371818 -307.848032) (xy 396.356234 -307.894713)
			(xy 396.333363 -307.93829) (xy 396.303798 -307.977634) (xy 396.268305 -308.011726) (xy 396.227802 -308.039682)
			(xy 396.18334 -308.06078) (xy 396.136069 -308.074472) (xy 396.087214 -308.080404) (xy 396.038039 -308.078423)
			(xy 395.98982 -308.068579) (xy 395.943804 -308.051127) (xy 395.901183 -308.02652) (xy 395.863062 -307.995395)
			(xy 395.830427 -307.958558) (xy 395.804124 -307.916962) (xy 395.784833 -307.871686) (xy 395.773056 -307.823902)
			(xy 395.769096 -307.774848) (xy 395.430248 -307.774848) (xy 395.429753 -307.799455) (xy 395.421858 -307.848032)
			(xy 395.406274 -307.894713) (xy 395.383403 -307.93829) (xy 395.353838 -307.977634) (xy 395.318345 -308.011726)
			(xy 395.277842 -308.039682) (xy 395.23338 -308.06078) (xy 395.186109 -308.074472) (xy 395.137254 -308.080404)
			(xy 395.088079 -308.078423) (xy 395.03986 -308.068579) (xy 394.993844 -308.051127) (xy 394.951223 -308.02652)
			(xy 394.913102 -307.995395) (xy 394.880467 -307.958558) (xy 394.854164 -307.916962) (xy 394.834873 -307.871686)
			(xy 394.823096 -307.823902) (xy 394.819136 -307.774848) (xy 365.509302 -307.774848) (xy 364.833662 -308.450488)
			(xy 376.378214 -308.450488) (xy 376.382285 -308.394866) (xy 376.394411 -308.340429) (xy 376.414334 -308.288338)
			(xy 376.44163 -308.239703) (xy 376.475716 -308.19556) (xy 376.515865 -308.156851) (xy 376.561223 -308.1244)
			(xy 376.610823 -308.098899) (xy 376.663607 -308.080892) (xy 376.71845 -308.070762) (xy 376.774184 -308.068725)
			(xy 376.829621 -308.074825) (xy 376.883578 -308.088931) (xy 376.934907 -308.110743) (xy 376.982513 -308.139797)
			(xy 377.025381 -308.175472) (xy 377.062598 -308.217009) (xy 377.084479 -308.250082) (xy 383.893834 -308.250082)
			(xy 383.897794 -308.201028) (xy 383.909571 -308.153244) (xy 383.928862 -308.107968) (xy 383.955165 -308.066372)
			(xy 383.9878 -308.029535) (xy 384.025921 -307.99841) (xy 384.068542 -307.973803) (xy 384.114558 -307.956351)
			(xy 384.162777 -307.946507) (xy 384.211952 -307.944526) (xy 384.260807 -307.950458) (xy 384.308078 -307.96415)
			(xy 384.35254 -307.985248) (xy 384.393043 -308.013204) (xy 384.428536 -308.047296) (xy 384.458101 -308.08664)
			(xy 384.480972 -308.130217) (xy 384.496556 -308.176898) (xy 384.504451 -308.225475) (xy 384.504941 -308.249828)
			(xy 384.844048 -308.249828) (xy 384.848008 -308.200774) (xy 384.859785 -308.15299) (xy 384.879076 -308.107714)
			(xy 384.905379 -308.066118) (xy 384.938014 -308.029281) (xy 384.976135 -307.998156) (xy 385.018756 -307.973549)
			(xy 385.064772 -307.956097) (xy 385.112991 -307.946253) (xy 385.162166 -307.944272) (xy 385.211021 -307.950204)
			(xy 385.258292 -307.963896) (xy 385.302754 -307.984994) (xy 385.343257 -308.01295) (xy 385.37875 -308.047042)
			(xy 385.408315 -308.086386) (xy 385.431186 -308.129963) (xy 385.44677 -308.176644) (xy 385.454665 -308.225221)
			(xy 385.45516 -308.249828) (xy 385.794008 -308.249828) (xy 385.797968 -308.200774) (xy 385.809745 -308.15299)
			(xy 385.829036 -308.107714) (xy 385.855339 -308.066118) (xy 385.887974 -308.029281) (xy 385.926095 -307.998156)
			(xy 385.968716 -307.973549) (xy 386.014732 -307.956097) (xy 386.062951 -307.946253) (xy 386.112126 -307.944272)
			(xy 386.160981 -307.950204) (xy 386.208252 -307.963896) (xy 386.252714 -307.984994) (xy 386.293217 -308.01295)
			(xy 386.32871 -308.047042) (xy 386.358275 -308.086386) (xy 386.381146 -308.129963) (xy 386.39673 -308.176644)
			(xy 386.404625 -308.225221) (xy 386.40512 -308.249828) (xy 386.744222 -308.249828) (xy 386.748182 -308.200774)
			(xy 386.759959 -308.15299) (xy 386.77925 -308.107714) (xy 386.805553 -308.066118) (xy 386.838188 -308.029281)
			(xy 386.876309 -307.998156) (xy 386.91893 -307.973549) (xy 386.964946 -307.956097) (xy 387.013165 -307.946253)
			(xy 387.06234 -307.944272) (xy 387.111195 -307.950204) (xy 387.158466 -307.963896) (xy 387.202928 -307.984994)
			(xy 387.243431 -308.01295) (xy 387.278924 -308.047042) (xy 387.308489 -308.086386) (xy 387.33136 -308.129963)
			(xy 387.346944 -308.176644) (xy 387.354839 -308.225221) (xy 387.355334 -308.249828) (xy 387.694182 -308.249828)
			(xy 387.698142 -308.200774) (xy 387.709919 -308.15299) (xy 387.72921 -308.107714) (xy 387.755513 -308.066118)
			(xy 387.788148 -308.029281) (xy 387.826269 -307.998156) (xy 387.86889 -307.973549) (xy 387.914906 -307.956097)
			(xy 387.963125 -307.946253) (xy 388.0123 -307.944272) (xy 388.061155 -307.950204) (xy 388.108426 -307.963896)
			(xy 388.152888 -307.984994) (xy 388.193391 -308.01295) (xy 388.228884 -308.047042) (xy 388.258449 -308.086386)
			(xy 388.28132 -308.129963) (xy 388.296904 -308.176644) (xy 388.304799 -308.225221) (xy 388.305294 -308.249828)
			(xy 388.644142 -308.249828) (xy 388.648102 -308.200774) (xy 388.659879 -308.15299) (xy 388.67917 -308.107714)
			(xy 388.705473 -308.066118) (xy 388.738108 -308.029281) (xy 388.776229 -307.998156) (xy 388.81885 -307.973549)
			(xy 388.864866 -307.956097) (xy 388.913085 -307.946253) (xy 388.96226 -307.944272) (xy 389.011115 -307.950204)
			(xy 389.058386 -307.963896) (xy 389.102848 -307.984994) (xy 389.143351 -308.01295) (xy 389.178844 -308.047042)
			(xy 389.208409 -308.086386) (xy 389.23128 -308.129963) (xy 389.246864 -308.176644) (xy 389.254759 -308.225221)
			(xy 389.255254 -308.249828) (xy 389.594102 -308.249828) (xy 389.598062 -308.200774) (xy 389.609839 -308.15299)
			(xy 389.62913 -308.107714) (xy 389.655433 -308.066118) (xy 389.688068 -308.029281) (xy 389.726189 -307.998156)
			(xy 389.76881 -307.973549) (xy 389.814826 -307.956097) (xy 389.863045 -307.946253) (xy 389.91222 -307.944272)
			(xy 389.961075 -307.950204) (xy 390.008346 -307.963896) (xy 390.052808 -307.984994) (xy 390.093311 -308.01295)
			(xy 390.128804 -308.047042) (xy 390.158369 -308.086386) (xy 390.18124 -308.129963) (xy 390.196824 -308.176644)
			(xy 390.204719 -308.225221) (xy 390.205214 -308.249828) (xy 390.544062 -308.249828) (xy 390.548022 -308.200774)
			(xy 390.559799 -308.15299) (xy 390.57909 -308.107714) (xy 390.605393 -308.066118) (xy 390.638028 -308.029281)
			(xy 390.676149 -307.998156) (xy 390.71877 -307.973549) (xy 390.764786 -307.956097) (xy 390.813005 -307.946253)
			(xy 390.86218 -307.944272) (xy 390.911035 -307.950204) (xy 390.958306 -307.963896) (xy 391.002768 -307.984994)
			(xy 391.043271 -308.01295) (xy 391.078764 -308.047042) (xy 391.108329 -308.086386) (xy 391.1312 -308.129963)
			(xy 391.146784 -308.176644) (xy 391.154679 -308.225221) (xy 391.155174 -308.249828) (xy 391.494022 -308.249828)
			(xy 391.497982 -308.200774) (xy 391.509759 -308.15299) (xy 391.52905 -308.107714) (xy 391.555353 -308.066118)
			(xy 391.587988 -308.029281) (xy 391.626109 -307.998156) (xy 391.66873 -307.973549) (xy 391.714746 -307.956097)
			(xy 391.762965 -307.946253) (xy 391.81214 -307.944272) (xy 391.860995 -307.950204) (xy 391.908266 -307.963896)
			(xy 391.952728 -307.984994) (xy 391.993231 -308.01295) (xy 392.028724 -308.047042) (xy 392.058289 -308.086386)
			(xy 392.08116 -308.129963) (xy 392.096744 -308.176644) (xy 392.104639 -308.225221) (xy 392.105134 -308.249828)
			(xy 392.443982 -308.249828) (xy 392.447942 -308.200774) (xy 392.459719 -308.15299) (xy 392.47901 -308.107714)
			(xy 392.505313 -308.066118) (xy 392.537948 -308.029281) (xy 392.576069 -307.998156) (xy 392.61869 -307.973549)
			(xy 392.664706 -307.956097) (xy 392.712925 -307.946253) (xy 392.7621 -307.944272) (xy 392.810955 -307.950204)
			(xy 392.858226 -307.963896) (xy 392.902688 -307.984994) (xy 392.943191 -308.01295) (xy 392.978684 -308.047042)
			(xy 393.008249 -308.086386) (xy 393.03112 -308.129963) (xy 393.046704 -308.176644) (xy 393.054599 -308.225221)
			(xy 393.055094 -308.249828) (xy 393.394196 -308.249828) (xy 393.398156 -308.200774) (xy 393.409933 -308.15299)
			(xy 393.429224 -308.107714) (xy 393.455527 -308.066118) (xy 393.488162 -308.029281) (xy 393.526283 -307.998156)
			(xy 393.568904 -307.973549) (xy 393.61492 -307.956097) (xy 393.663139 -307.946253) (xy 393.712314 -307.944272)
			(xy 393.761169 -307.950204) (xy 393.80844 -307.963896) (xy 393.852902 -307.984994) (xy 393.893405 -308.01295)
			(xy 393.928898 -308.047042) (xy 393.958463 -308.086386) (xy 393.981334 -308.129963) (xy 393.996918 -308.176644)
			(xy 394.004813 -308.225221) (xy 394.005308 -308.249828) (xy 394.004813 -308.274435) (xy 393.996918 -308.323012)
			(xy 393.981334 -308.369693) (xy 393.958463 -308.41327) (xy 393.928898 -308.452614) (xy 393.893405 -308.486706)
			(xy 393.852902 -308.514662) (xy 393.80844 -308.53576) (xy 393.761169 -308.549452) (xy 393.712314 -308.555384)
			(xy 393.663139 -308.553403) (xy 393.61492 -308.543559) (xy 393.568904 -308.526107) (xy 393.526283 -308.5015)
			(xy 393.488162 -308.470375) (xy 393.455527 -308.433538) (xy 393.429224 -308.391942) (xy 393.409933 -308.346666)
			(xy 393.398156 -308.298882) (xy 393.394196 -308.249828) (xy 393.055094 -308.249828) (xy 393.054599 -308.274435)
			(xy 393.046704 -308.323012) (xy 393.03112 -308.369693) (xy 393.008249 -308.41327) (xy 392.978684 -308.452614)
			(xy 392.943191 -308.486706) (xy 392.902688 -308.514662) (xy 392.858226 -308.53576) (xy 392.810955 -308.549452)
			(xy 392.7621 -308.555384) (xy 392.712925 -308.553403) (xy 392.664706 -308.543559) (xy 392.61869 -308.526107)
			(xy 392.576069 -308.5015) (xy 392.537948 -308.470375) (xy 392.505313 -308.433538) (xy 392.47901 -308.391942)
			(xy 392.459719 -308.346666) (xy 392.447942 -308.298882) (xy 392.443982 -308.249828) (xy 392.105134 -308.249828)
			(xy 392.104639 -308.274435) (xy 392.096744 -308.323012) (xy 392.08116 -308.369693) (xy 392.058289 -308.41327)
			(xy 392.028724 -308.452614) (xy 391.993231 -308.486706) (xy 391.952728 -308.514662) (xy 391.908266 -308.53576)
			(xy 391.860995 -308.549452) (xy 391.81214 -308.555384) (xy 391.762965 -308.553403) (xy 391.714746 -308.543559)
			(xy 391.66873 -308.526107) (xy 391.626109 -308.5015) (xy 391.587988 -308.470375) (xy 391.555353 -308.433538)
			(xy 391.52905 -308.391942) (xy 391.509759 -308.346666) (xy 391.497982 -308.298882) (xy 391.494022 -308.249828)
			(xy 391.155174 -308.249828) (xy 391.154679 -308.274435) (xy 391.146784 -308.323012) (xy 391.1312 -308.369693)
			(xy 391.108329 -308.41327) (xy 391.078764 -308.452614) (xy 391.043271 -308.486706) (xy 391.002768 -308.514662)
			(xy 390.958306 -308.53576) (xy 390.911035 -308.549452) (xy 390.86218 -308.555384) (xy 390.813005 -308.553403)
			(xy 390.764786 -308.543559) (xy 390.71877 -308.526107) (xy 390.676149 -308.5015) (xy 390.638028 -308.470375)
			(xy 390.605393 -308.433538) (xy 390.57909 -308.391942) (xy 390.559799 -308.346666) (xy 390.548022 -308.298882)
			(xy 390.544062 -308.249828) (xy 390.205214 -308.249828) (xy 390.204719 -308.274435) (xy 390.196824 -308.323012)
			(xy 390.18124 -308.369693) (xy 390.158369 -308.41327) (xy 390.128804 -308.452614) (xy 390.093311 -308.486706)
			(xy 390.052808 -308.514662) (xy 390.008346 -308.53576) (xy 389.961075 -308.549452) (xy 389.91222 -308.555384)
			(xy 389.863045 -308.553403) (xy 389.814826 -308.543559) (xy 389.76881 -308.526107) (xy 389.726189 -308.5015)
			(xy 389.688068 -308.470375) (xy 389.655433 -308.433538) (xy 389.62913 -308.391942) (xy 389.609839 -308.346666)
			(xy 389.598062 -308.298882) (xy 389.594102 -308.249828) (xy 389.255254 -308.249828) (xy 389.254759 -308.274435)
			(xy 389.246864 -308.323012) (xy 389.23128 -308.369693) (xy 389.208409 -308.41327) (xy 389.178844 -308.452614)
			(xy 389.143351 -308.486706) (xy 389.102848 -308.514662) (xy 389.058386 -308.53576) (xy 389.011115 -308.549452)
			(xy 388.96226 -308.555384) (xy 388.913085 -308.553403) (xy 388.864866 -308.543559) (xy 388.81885 -308.526107)
			(xy 388.776229 -308.5015) (xy 388.738108 -308.470375) (xy 388.705473 -308.433538) (xy 388.67917 -308.391942)
			(xy 388.659879 -308.346666) (xy 388.648102 -308.298882) (xy 388.644142 -308.249828) (xy 388.305294 -308.249828)
			(xy 388.304799 -308.274435) (xy 388.296904 -308.323012) (xy 388.28132 -308.369693) (xy 388.258449 -308.41327)
			(xy 388.228884 -308.452614) (xy 388.193391 -308.486706) (xy 388.152888 -308.514662) (xy 388.108426 -308.53576)
			(xy 388.061155 -308.549452) (xy 388.0123 -308.555384) (xy 387.963125 -308.553403) (xy 387.914906 -308.543559)
			(xy 387.86889 -308.526107) (xy 387.826269 -308.5015) (xy 387.788148 -308.470375) (xy 387.755513 -308.433538)
			(xy 387.72921 -308.391942) (xy 387.709919 -308.346666) (xy 387.698142 -308.298882) (xy 387.694182 -308.249828)
			(xy 387.355334 -308.249828) (xy 387.354839 -308.274435) (xy 387.346944 -308.323012) (xy 387.33136 -308.369693)
			(xy 387.308489 -308.41327) (xy 387.278924 -308.452614) (xy 387.243431 -308.486706) (xy 387.202928 -308.514662)
			(xy 387.158466 -308.53576) (xy 387.111195 -308.549452) (xy 387.06234 -308.555384) (xy 387.013165 -308.553403)
			(xy 386.964946 -308.543559) (xy 386.91893 -308.526107) (xy 386.876309 -308.5015) (xy 386.838188 -308.470375)
			(xy 386.805553 -308.433538) (xy 386.77925 -308.391942) (xy 386.759959 -308.346666) (xy 386.748182 -308.298882)
			(xy 386.744222 -308.249828) (xy 386.40512 -308.249828) (xy 386.404625 -308.274435) (xy 386.39673 -308.323012)
			(xy 386.381146 -308.369693) (xy 386.358275 -308.41327) (xy 386.32871 -308.452614) (xy 386.293217 -308.486706)
			(xy 386.252714 -308.514662) (xy 386.208252 -308.53576) (xy 386.160981 -308.549452) (xy 386.112126 -308.555384)
			(xy 386.062951 -308.553403) (xy 386.014732 -308.543559) (xy 385.968716 -308.526107) (xy 385.926095 -308.5015)
			(xy 385.887974 -308.470375) (xy 385.855339 -308.433538) (xy 385.829036 -308.391942) (xy 385.809745 -308.346666)
			(xy 385.797968 -308.298882) (xy 385.794008 -308.249828) (xy 385.45516 -308.249828) (xy 385.454665 -308.274435)
			(xy 385.44677 -308.323012) (xy 385.431186 -308.369693) (xy 385.408315 -308.41327) (xy 385.37875 -308.452614)
			(xy 385.343257 -308.486706) (xy 385.302754 -308.514662) (xy 385.258292 -308.53576) (xy 385.211021 -308.549452)
			(xy 385.162166 -308.555384) (xy 385.112991 -308.553403) (xy 385.064772 -308.543559) (xy 385.018756 -308.526107)
			(xy 384.976135 -308.5015) (xy 384.938014 -308.470375) (xy 384.905379 -308.433538) (xy 384.879076 -308.391942)
			(xy 384.859785 -308.346666) (xy 384.848008 -308.298882) (xy 384.844048 -308.249828) (xy 384.504941 -308.249828)
			(xy 384.504946 -308.250082) (xy 384.504451 -308.274689) (xy 384.496556 -308.323266) (xy 384.480972 -308.369947)
			(xy 384.458101 -308.413524) (xy 384.428536 -308.452868) (xy 384.393043 -308.48696) (xy 384.35254 -308.514916)
			(xy 384.308078 -308.536014) (xy 384.260807 -308.549706) (xy 384.211952 -308.555638) (xy 384.162777 -308.553657)
			(xy 384.114558 -308.543813) (xy 384.068542 -308.526361) (xy 384.025921 -308.501754) (xy 383.9878 -308.470629)
			(xy 383.955165 -308.433792) (xy 383.928862 -308.392196) (xy 383.909571 -308.34692) (xy 383.897794 -308.299136)
			(xy 383.893834 -308.250082) (xy 377.084479 -308.250082) (xy 377.093371 -308.263522) (xy 377.117043 -308.314019)
			(xy 377.133111 -308.367426) (xy 377.141231 -308.422602) (xy 377.14174 -308.450488) (xy 377.141231 -308.478374)
			(xy 377.133111 -308.53355) (xy 377.117043 -308.586957) (xy 377.093371 -308.637454) (xy 377.078766 -308.65953)
			(xy 378.705616 -308.65953) (xy 378.709687 -308.603908) (xy 378.721813 -308.549471) (xy 378.741736 -308.49738)
			(xy 378.769032 -308.448745) (xy 378.803118 -308.404602) (xy 378.843267 -308.365893) (xy 378.888625 -308.333442)
			(xy 378.938225 -308.307941) (xy 378.991009 -308.289934) (xy 379.045852 -308.279804) (xy 379.101586 -308.277767)
			(xy 379.157023 -308.283867) (xy 379.21098 -308.297973) (xy 379.262309 -308.319785) (xy 379.309915 -308.348839)
			(xy 379.352783 -308.384514) (xy 379.39 -308.426051) (xy 379.420773 -308.472564) (xy 379.444445 -308.523061)
			(xy 379.460513 -308.576468) (xy 379.468633 -308.631644) (xy 379.469142 -308.65953) (xy 379.468633 -308.687416)
			(xy 379.460513 -308.742592) (xy 379.444445 -308.795999) (xy 379.420773 -308.846496) (xy 379.39 -308.893009)
			(xy 379.352783 -308.934546) (xy 379.309915 -308.970221) (xy 379.262309 -308.999275) (xy 379.21098 -309.021087)
			(xy 379.157023 -309.035193) (xy 379.101586 -309.041293) (xy 379.045852 -309.039256) (xy 378.991009 -309.029126)
			(xy 378.938225 -309.011119) (xy 378.888625 -308.985618) (xy 378.843267 -308.953167) (xy 378.803118 -308.914458)
			(xy 378.769032 -308.870315) (xy 378.741736 -308.82168) (xy 378.721813 -308.769589) (xy 378.709687 -308.715152)
			(xy 378.705616 -308.65953) (xy 377.078766 -308.65953) (xy 377.062598 -308.683967) (xy 377.025381 -308.725504)
			(xy 376.982513 -308.761179) (xy 376.934907 -308.790233) (xy 376.883578 -308.812045) (xy 376.829621 -308.826151)
			(xy 376.774184 -308.832251) (xy 376.71845 -308.830214) (xy 376.663607 -308.820084) (xy 376.610823 -308.802077)
			(xy 376.561223 -308.776576) (xy 376.515865 -308.744125) (xy 376.475716 -308.705416) (xy 376.44163 -308.661273)
			(xy 376.414334 -308.612638) (xy 376.394411 -308.560547) (xy 376.382285 -308.50611) (xy 376.378214 -308.450488)
			(xy 364.833662 -308.450488) (xy 364.691422 -308.592728) (xy 364.684023 -308.59957) (xy 364.665424 -308.607287)
			(xy 364.655354 -308.607714) (xy 352.836988 -308.607714) (xy 352.830977 -308.607877) (xy 352.819291 -308.610694)
			(xy 352.813874 -308.613302) (xy 352.8104 -308.615142) (xy 352.804022 -308.619736) (xy 352.801174 -308.622446)
			(xy 352.008694 -309.414926) (xy 375.299984 -309.414926) (xy 375.304055 -309.359304) (xy 375.316181 -309.304867)
			(xy 375.336104 -309.252776) (xy 375.3634 -309.204141) (xy 375.397486 -309.159998) (xy 375.437635 -309.121289)
			(xy 375.482993 -309.088838) (xy 375.532593 -309.063337) (xy 375.585377 -309.04533) (xy 375.64022 -309.0352)
			(xy 375.695954 -309.033163) (xy 375.751391 -309.039263) (xy 375.805348 -309.053369) (xy 375.856677 -309.075181)
			(xy 375.904283 -309.104235) (xy 375.947151 -309.13991) (xy 375.984368 -309.181447) (xy 375.996502 -309.199788)
			(xy 384.844048 -309.199788) (xy 384.848008 -309.150734) (xy 384.859785 -309.10295) (xy 384.879076 -309.057674)
			(xy 384.905379 -309.016078) (xy 384.938014 -308.979241) (xy 384.976135 -308.948116) (xy 385.018756 -308.923509)
			(xy 385.064772 -308.906057) (xy 385.112991 -308.896213) (xy 385.162166 -308.894232) (xy 385.211021 -308.900164)
			(xy 385.258292 -308.913856) (xy 385.302754 -308.934954) (xy 385.343257 -308.96291) (xy 385.37875 -308.997002)
			(xy 385.408315 -309.036346) (xy 385.431186 -309.079923) (xy 385.44677 -309.126604) (xy 385.454665 -309.175181)
			(xy 385.45516 -309.199788) (xy 385.794008 -309.199788) (xy 385.797968 -309.150734) (xy 385.809745 -309.10295)
			(xy 385.829036 -309.057674) (xy 385.855339 -309.016078) (xy 385.887974 -308.979241) (xy 385.926095 -308.948116)
			(xy 385.968716 -308.923509) (xy 386.014732 -308.906057) (xy 386.062951 -308.896213) (xy 386.112126 -308.894232)
			(xy 386.160981 -308.900164) (xy 386.208252 -308.913856) (xy 386.252714 -308.934954) (xy 386.293217 -308.96291)
			(xy 386.32871 -308.997002) (xy 386.358275 -309.036346) (xy 386.381146 -309.079923) (xy 386.39673 -309.126604)
			(xy 386.404625 -309.175181) (xy 386.40512 -309.199788) (xy 386.744222 -309.199788) (xy 386.748182 -309.150734)
			(xy 386.759959 -309.10295) (xy 386.77925 -309.057674) (xy 386.805553 -309.016078) (xy 386.838188 -308.979241)
			(xy 386.876309 -308.948116) (xy 386.91893 -308.923509) (xy 386.964946 -308.906057) (xy 387.013165 -308.896213)
			(xy 387.06234 -308.894232) (xy 387.111195 -308.900164) (xy 387.158466 -308.913856) (xy 387.202928 -308.934954)
			(xy 387.243431 -308.96291) (xy 387.278924 -308.997002) (xy 387.308489 -309.036346) (xy 387.33136 -309.079923)
			(xy 387.346944 -309.126604) (xy 387.354839 -309.175181) (xy 387.355334 -309.199788) (xy 387.694182 -309.199788)
			(xy 387.698142 -309.150734) (xy 387.709919 -309.10295) (xy 387.72921 -309.057674) (xy 387.755513 -309.016078)
			(xy 387.788148 -308.979241) (xy 387.826269 -308.948116) (xy 387.86889 -308.923509) (xy 387.914906 -308.906057)
			(xy 387.963125 -308.896213) (xy 388.0123 -308.894232) (xy 388.061155 -308.900164) (xy 388.108426 -308.913856)
			(xy 388.152888 -308.934954) (xy 388.193391 -308.96291) (xy 388.228884 -308.997002) (xy 388.258449 -309.036346)
			(xy 388.28132 -309.079923) (xy 388.296904 -309.126604) (xy 388.304799 -309.175181) (xy 388.305294 -309.199788)
			(xy 388.644142 -309.199788) (xy 388.648102 -309.150734) (xy 388.659879 -309.10295) (xy 388.67917 -309.057674)
			(xy 388.705473 -309.016078) (xy 388.738108 -308.979241) (xy 388.776229 -308.948116) (xy 388.81885 -308.923509)
			(xy 388.864866 -308.906057) (xy 388.913085 -308.896213) (xy 388.96226 -308.894232) (xy 389.011115 -308.900164)
			(xy 389.058386 -308.913856) (xy 389.102848 -308.934954) (xy 389.143351 -308.96291) (xy 389.178844 -308.997002)
			(xy 389.208409 -309.036346) (xy 389.23128 -309.079923) (xy 389.246864 -309.126604) (xy 389.254759 -309.175181)
			(xy 389.255254 -309.199788) (xy 389.594102 -309.199788) (xy 389.598062 -309.150734) (xy 389.609839 -309.10295)
			(xy 389.62913 -309.057674) (xy 389.655433 -309.016078) (xy 389.688068 -308.979241) (xy 389.726189 -308.948116)
			(xy 389.76881 -308.923509) (xy 389.814826 -308.906057) (xy 389.863045 -308.896213) (xy 389.91222 -308.894232)
			(xy 389.961075 -308.900164) (xy 390.008346 -308.913856) (xy 390.052808 -308.934954) (xy 390.093311 -308.96291)
			(xy 390.128804 -308.997002) (xy 390.158369 -309.036346) (xy 390.18124 -309.079923) (xy 390.196824 -309.126604)
			(xy 390.204719 -309.175181) (xy 390.205214 -309.199788) (xy 390.544062 -309.199788) (xy 390.548022 -309.150734)
			(xy 390.559799 -309.10295) (xy 390.57909 -309.057674) (xy 390.605393 -309.016078) (xy 390.638028 -308.979241)
			(xy 390.676149 -308.948116) (xy 390.71877 -308.923509) (xy 390.764786 -308.906057) (xy 390.813005 -308.896213)
			(xy 390.86218 -308.894232) (xy 390.911035 -308.900164) (xy 390.958306 -308.913856) (xy 391.002768 -308.934954)
			(xy 391.043271 -308.96291) (xy 391.078764 -308.997002) (xy 391.108329 -309.036346) (xy 391.1312 -309.079923)
			(xy 391.146784 -309.126604) (xy 391.154679 -309.175181) (xy 391.155174 -309.199788) (xy 391.494022 -309.199788)
			(xy 391.497982 -309.150734) (xy 391.509759 -309.10295) (xy 391.52905 -309.057674) (xy 391.555353 -309.016078)
			(xy 391.587988 -308.979241) (xy 391.626109 -308.948116) (xy 391.66873 -308.923509) (xy 391.714746 -308.906057)
			(xy 391.762965 -308.896213) (xy 391.81214 -308.894232) (xy 391.860995 -308.900164) (xy 391.908266 -308.913856)
			(xy 391.952728 -308.934954) (xy 391.993231 -308.96291) (xy 392.028724 -308.997002) (xy 392.058289 -309.036346)
			(xy 392.08116 -309.079923) (xy 392.096744 -309.126604) (xy 392.104639 -309.175181) (xy 392.105134 -309.199788)
			(xy 392.443982 -309.199788) (xy 392.447942 -309.150734) (xy 392.459719 -309.10295) (xy 392.47901 -309.057674)
			(xy 392.505313 -309.016078) (xy 392.537948 -308.979241) (xy 392.576069 -308.948116) (xy 392.61869 -308.923509)
			(xy 392.664706 -308.906057) (xy 392.712925 -308.896213) (xy 392.7621 -308.894232) (xy 392.810955 -308.900164)
			(xy 392.858226 -308.913856) (xy 392.902688 -308.934954) (xy 392.943191 -308.96291) (xy 392.978684 -308.997002)
			(xy 393.008249 -309.036346) (xy 393.03112 -309.079923) (xy 393.046704 -309.126604) (xy 393.054599 -309.175181)
			(xy 393.055094 -309.199788) (xy 393.394196 -309.199788) (xy 393.398156 -309.150734) (xy 393.409933 -309.10295)
			(xy 393.429224 -309.057674) (xy 393.455527 -309.016078) (xy 393.488162 -308.979241) (xy 393.526283 -308.948116)
			(xy 393.568904 -308.923509) (xy 393.61492 -308.906057) (xy 393.663139 -308.896213) (xy 393.712314 -308.894232)
			(xy 393.761169 -308.900164) (xy 393.80844 -308.913856) (xy 393.852902 -308.934954) (xy 393.893405 -308.96291)
			(xy 393.928898 -308.997002) (xy 393.958463 -309.036346) (xy 393.981334 -309.079923) (xy 393.996918 -309.126604)
			(xy 394.004813 -309.175181) (xy 394.005142 -309.191549) (xy 394.344268 -309.191549) (xy 394.349631 -309.142197)
			(xy 394.362906 -309.094362) (xy 394.383746 -309.049305) (xy 394.4116 -309.008213) (xy 394.445735 -308.972169)
			(xy 394.485252 -308.942122) (xy 394.529109 -308.918864) (xy 394.576151 -308.903007) (xy 394.625139 -308.894969)
			(xy 394.64996 -308.89448) (xy 394.664143 -308.894662) (xy 394.692383 -308.897331) (xy 394.706348 -308.899814)
			(xy 394.720306 -308.902031) (xy 394.748443 -308.89944) (xy 394.774793 -308.88924) (xy 394.797341 -308.872212)
			(xy 394.814361 -308.849657) (xy 394.82455 -308.823302) (xy 394.827129 -308.795165) (xy 394.824966 -308.781196)
			(xy 394.822494 -308.767229) (xy 394.819819 -308.73899) (xy 394.819632 -308.724808) (xy 394.820069 -308.699987)
			(xy 394.828099 -308.650999) (xy 394.843948 -308.603955) (xy 394.867199 -308.560095) (xy 394.89724 -308.520574)
			(xy 394.933278 -308.486434) (xy 394.974365 -308.458573) (xy 395.019417 -308.437727) (xy 395.067249 -308.424444)
			(xy 395.1166 -308.419074) (xy 395.166169 -308.421758) (xy 395.214651 -308.432426) (xy 395.260768 -308.450798)
			(xy 395.303306 -308.476388) (xy 395.341144 -308.508522) (xy 395.373284 -308.546355) (xy 395.398881 -308.588889)
			(xy 395.417259 -308.635003) (xy 395.427935 -308.683484) (xy 395.43018 -308.724808) (xy 395.769096 -308.724808)
			(xy 395.773056 -308.675754) (xy 395.784833 -308.62797) (xy 395.804124 -308.582694) (xy 395.830427 -308.541098)
			(xy 395.863062 -308.504261) (xy 395.901183 -308.473136) (xy 395.943804 -308.448529) (xy 395.98982 -308.431077)
			(xy 396.038039 -308.421233) (xy 396.087214 -308.419252) (xy 396.136069 -308.425184) (xy 396.18334 -308.438876)
			(xy 396.227802 -308.459974) (xy 396.268305 -308.48793) (xy 396.303798 -308.522022) (xy 396.333363 -308.561366)
			(xy 396.356234 -308.604943) (xy 396.371818 -308.651624) (xy 396.379713 -308.700201) (xy 396.380208 -308.724808)
			(xy 396.719056 -308.724808) (xy 396.723016 -308.675754) (xy 396.734793 -308.62797) (xy 396.754084 -308.582694)
			(xy 396.780387 -308.541098) (xy 396.813022 -308.504261) (xy 396.851143 -308.473136) (xy 396.893764 -308.448529)
			(xy 396.93978 -308.431077) (xy 396.987999 -308.421233) (xy 397.037174 -308.419252) (xy 397.086029 -308.425184)
			(xy 397.1333 -308.438876) (xy 397.177762 -308.459974) (xy 397.218265 -308.48793) (xy 397.253758 -308.522022)
			(xy 397.283323 -308.561366) (xy 397.306194 -308.604943) (xy 397.321778 -308.651624) (xy 397.329673 -308.700201)
			(xy 397.330168 -308.724808) (xy 397.669016 -308.724808) (xy 397.672976 -308.675754) (xy 397.684753 -308.62797)
			(xy 397.704044 -308.582694) (xy 397.730347 -308.541098) (xy 397.762982 -308.504261) (xy 397.801103 -308.473136)
			(xy 397.843724 -308.448529) (xy 397.88974 -308.431077) (xy 397.937959 -308.421233) (xy 397.987134 -308.419252)
			(xy 398.035989 -308.425184) (xy 398.08326 -308.438876) (xy 398.127722 -308.459974) (xy 398.168225 -308.48793)
			(xy 398.203718 -308.522022) (xy 398.233283 -308.561366) (xy 398.256154 -308.604943) (xy 398.271738 -308.651624)
			(xy 398.279633 -308.700201) (xy 398.280128 -308.724808) (xy 398.61923 -308.724808) (xy 398.62319 -308.675754)
			(xy 398.634967 -308.62797) (xy 398.654258 -308.582694) (xy 398.680561 -308.541098) (xy 398.713196 -308.504261)
			(xy 398.751317 -308.473136) (xy 398.793938 -308.448529) (xy 398.839954 -308.431077) (xy 398.888173 -308.421233)
			(xy 398.937348 -308.419252) (xy 398.986203 -308.425184) (xy 399.033474 -308.438876) (xy 399.077936 -308.459974)
			(xy 399.118439 -308.48793) (xy 399.153932 -308.522022) (xy 399.183497 -308.561366) (xy 399.206368 -308.604943)
			(xy 399.221952 -308.651624) (xy 399.229847 -308.700201) (xy 399.230342 -308.724808) (xy 399.56919 -308.724808)
			(xy 399.57315 -308.675754) (xy 399.584927 -308.62797) (xy 399.604218 -308.582694) (xy 399.630521 -308.541098)
			(xy 399.663156 -308.504261) (xy 399.701277 -308.473136) (xy 399.743898 -308.448529) (xy 399.789914 -308.431077)
			(xy 399.838133 -308.421233) (xy 399.887308 -308.419252) (xy 399.936163 -308.425184) (xy 399.983434 -308.438876)
			(xy 400.027896 -308.459974) (xy 400.068399 -308.48793) (xy 400.103892 -308.522022) (xy 400.133457 -308.561366)
			(xy 400.156328 -308.604943) (xy 400.171912 -308.651624) (xy 400.179807 -308.700201) (xy 400.180302 -308.724808)
			(xy 400.51915 -308.724808) (xy 400.52311 -308.675754) (xy 400.534887 -308.62797) (xy 400.554178 -308.582694)
			(xy 400.580481 -308.541098) (xy 400.613116 -308.504261) (xy 400.651237 -308.473136) (xy 400.693858 -308.448529)
			(xy 400.739874 -308.431077) (xy 400.788093 -308.421233) (xy 400.837268 -308.419252) (xy 400.886123 -308.425184)
			(xy 400.933394 -308.438876) (xy 400.977856 -308.459974) (xy 401.018359 -308.48793) (xy 401.053852 -308.522022)
			(xy 401.083417 -308.561366) (xy 401.106288 -308.604943) (xy 401.121872 -308.651624) (xy 401.129767 -308.700201)
			(xy 401.130262 -308.724808) (xy 401.46911 -308.724808) (xy 401.47307 -308.675754) (xy 401.484847 -308.62797)
			(xy 401.504138 -308.582694) (xy 401.530441 -308.541098) (xy 401.563076 -308.504261) (xy 401.601197 -308.473136)
			(xy 401.643818 -308.448529) (xy 401.689834 -308.431077) (xy 401.738053 -308.421233) (xy 401.787228 -308.419252)
			(xy 401.836083 -308.425184) (xy 401.883354 -308.438876) (xy 401.927816 -308.459974) (xy 401.968319 -308.48793)
			(xy 402.003812 -308.522022) (xy 402.033377 -308.561366) (xy 402.056248 -308.604943) (xy 402.071832 -308.651624)
			(xy 402.079727 -308.700201) (xy 402.080222 -308.724808) (xy 402.41907 -308.724808) (xy 402.42303 -308.675754)
			(xy 402.434807 -308.62797) (xy 402.454098 -308.582694) (xy 402.480401 -308.541098) (xy 402.513036 -308.504261)
			(xy 402.551157 -308.473136) (xy 402.593778 -308.448529) (xy 402.639794 -308.431077) (xy 402.688013 -308.421233)
			(xy 402.737188 -308.419252) (xy 402.786043 -308.425184) (xy 402.833314 -308.438876) (xy 402.877776 -308.459974)
			(xy 402.918279 -308.48793) (xy 402.953772 -308.522022) (xy 402.983337 -308.561366) (xy 403.006208 -308.604943)
			(xy 403.021792 -308.651624) (xy 403.029687 -308.700201) (xy 403.030182 -308.724808) (xy 403.030015 -308.733103)
			(xy 403.369048 -308.733103) (xy 403.371732 -308.683527) (xy 403.382403 -308.635038) (xy 403.400777 -308.588915)
			(xy 403.426371 -308.546372) (xy 403.458512 -308.50853) (xy 403.496351 -308.476387) (xy 403.538892 -308.450789)
			(xy 403.585013 -308.43241) (xy 403.633501 -308.421736) (xy 403.683077 -308.419047) (xy 403.732435 -308.424414)
			(xy 403.780274 -308.437696) (xy 403.825334 -308.458543) (xy 403.866428 -308.486405) (xy 403.902472 -308.520548)
			(xy 403.932518 -308.560073) (xy 403.955773 -308.603939) (xy 403.971625 -308.650989) (xy 403.979657 -308.699984)
			(xy 403.980142 -308.724808) (xy 403.979966 -308.738991) (xy 403.977293 -308.767231) (xy 403.974808 -308.781196)
			(xy 403.972522 -308.793642) (xy 403.979888 -308.817264) (xy 404.057358 -308.894734) (xy 404.08098 -308.9021)
			(xy 404.093426 -308.899814) (xy 404.107392 -308.897338) (xy 404.135631 -308.894666) (xy 404.149814 -308.89448)
			(xy 404.164061 -308.894646) (xy 404.192429 -308.897316) (xy 404.206456 -308.899814) (xy 404.218902 -308.9021)
			(xy 404.242524 -308.894734) (xy 404.311104 -308.826408) (xy 404.319271 -308.817179) (xy 404.326573 -308.793683)
			(xy 404.325074 -308.78145) (xy 404.325074 -308.780942) (xy 404.322607 -308.767039) (xy 404.319938 -308.738927)
			(xy 404.31974 -308.724808) (xy 404.320169 -308.699987) (xy 404.328199 -308.650999) (xy 404.344048 -308.603956)
			(xy 404.367299 -308.560096) (xy 404.397339 -308.520575) (xy 404.433377 -308.486435) (xy 404.474463 -308.458574)
			(xy 404.519515 -308.437728) (xy 404.567347 -308.424444) (xy 404.616697 -308.419074) (xy 404.666266 -308.421758)
			(xy 404.714748 -308.432426) (xy 404.760865 -308.450796) (xy 404.803403 -308.476385) (xy 404.841241 -308.508519)
			(xy 404.873382 -308.546351) (xy 404.898979 -308.588885) (xy 404.917358 -308.634999) (xy 404.928035 -308.683478)
			(xy 404.93028 -308.724808) (xy 406.219164 -308.724808) (xy 406.223124 -308.675754) (xy 406.234901 -308.62797)
			(xy 406.254192 -308.582694) (xy 406.280495 -308.541098) (xy 406.31313 -308.504261) (xy 406.351251 -308.473136)
			(xy 406.393872 -308.448529) (xy 406.439888 -308.431077) (xy 406.488107 -308.421233) (xy 406.537282 -308.419252)
			(xy 406.586137 -308.425184) (xy 406.633408 -308.438876) (xy 406.67787 -308.459974) (xy 406.718373 -308.48793)
			(xy 406.753866 -308.522022) (xy 406.783431 -308.561366) (xy 406.806302 -308.604943) (xy 406.821886 -308.651624)
			(xy 406.829781 -308.700201) (xy 406.830276 -308.724808) (xy 406.829781 -308.749415) (xy 406.821886 -308.797992)
			(xy 406.806302 -308.844673) (xy 406.783431 -308.88825) (xy 406.753866 -308.927594) (xy 406.718373 -308.961686)
			(xy 406.67787 -308.989642) (xy 406.633408 -309.01074) (xy 406.586137 -309.024432) (xy 406.537282 -309.030364)
			(xy 406.488107 -309.028383) (xy 406.439888 -309.018539) (xy 406.393872 -309.001087) (xy 406.351251 -308.97648)
			(xy 406.31313 -308.945355) (xy 406.280495 -308.908518) (xy 406.254192 -308.866922) (xy 406.234901 -308.821646)
			(xy 406.223124 -308.773862) (xy 406.219164 -308.724808) (xy 404.93028 -308.724808) (xy 404.930728 -308.733047)
			(xy 404.925366 -308.782398) (xy 404.912092 -308.830232) (xy 404.891253 -308.875288) (xy 404.8634 -308.91638)
			(xy 404.829267 -308.952424) (xy 404.789752 -308.982471) (xy 404.745896 -309.00573) (xy 404.698855 -309.021588)
			(xy 404.649869 -309.029626) (xy 404.625048 -309.030116) (xy 404.610801 -309.029949) (xy 404.582434 -309.027276)
			(xy 404.568406 -309.024782) (xy 404.55596 -309.022496) (xy 404.532338 -309.029862) (xy 404.463758 -309.098188)
			(xy 404.455589 -309.107416) (xy 404.44829 -309.130913) (xy 404.449788 -309.143146) (xy 404.449788 -309.143654)
			(xy 404.452256 -309.157557) (xy 404.454924 -309.185669) (xy 404.455122 -309.199788) (xy 404.454943 -309.213971)
			(xy 404.452273 -309.242211) (xy 404.449788 -309.256176) (xy 404.447502 -309.268622) (xy 404.454868 -309.292244)
			(xy 404.532338 -309.369714) (xy 404.55596 -309.37708) (xy 404.568406 -309.374794) (xy 404.582372 -309.372321)
			(xy 404.610612 -309.369647) (xy 404.624794 -309.36946) (xy 404.648783 -309.369968) (xy 404.696172 -309.377472)
			(xy 404.741803 -309.392297) (xy 404.784554 -309.414077) (xy 404.823371 -309.442276) (xy 404.857299 -309.4762)
			(xy 404.885503 -309.515014) (xy 404.907289 -309.557762) (xy 404.922119 -309.603391) (xy 404.929629 -309.650779)
			(xy 404.930102 -309.674768) (xy 404.929921 -309.688951) (xy 404.927252 -309.717191) (xy 404.924768 -309.731156)
			(xy 404.924768 -309.73141) (xy 404.923328 -309.743641) (xy 404.930604 -309.767124) (xy 404.938738 -309.776368)
			(xy 405.007318 -309.844694) (xy 405.03094 -309.85206) (xy 405.043386 -309.849774) (xy 405.057416 -309.847294)
			(xy 405.085782 -309.844619) (xy 405.100028 -309.84444) (xy 405.114211 -309.844612) (xy 405.142451 -309.847287)
			(xy 405.156416 -309.849774) (xy 405.168862 -309.85206) (xy 405.192484 -309.844694) (xy 405.269954 -309.767224)
			(xy 405.27732 -309.743602) (xy 405.275034 -309.731156) (xy 405.272556 -309.71719) (xy 405.269885 -309.688951)
			(xy 405.2697 -309.674768) (xy 405.270222 -309.649513) (xy 405.278535 -309.599691) (xy 405.294936 -309.551917)
			(xy 405.318977 -309.507494) (xy 405.350001 -309.467634) (xy 405.387163 -309.433424) (xy 405.429449 -309.405798)
			(xy 405.475705 -309.385508) (xy 405.52467 -309.373108) (xy 405.575008 -309.368937) (xy 405.625346 -309.373108)
			(xy 405.674311 -309.385508) (xy 405.720567 -309.405798) (xy 405.762853 -309.433424) (xy 405.800015 -309.467634)
			(xy 405.831039 -309.507494) (xy 405.85508 -309.551917) (xy 405.871481 -309.599691) (xy 405.879794 -309.649513)
			(xy 405.880316 -309.674768) (xy 405.880135 -309.688951) (xy 405.877466 -309.717191) (xy 405.874982 -309.731156)
			(xy 405.872696 -309.743602) (xy 405.880062 -309.767224) (xy 405.957532 -309.844694) (xy 405.981154 -309.85206)
			(xy 405.9936 -309.849774) (xy 406.007566 -309.847301) (xy 406.035806 -309.844627) (xy 406.049988 -309.84444)
			(xy 406.074809 -309.844865) (xy 406.123798 -309.852894) (xy 406.170843 -309.868743) (xy 406.214703 -309.891993)
			(xy 406.254225 -309.922033) (xy 406.288366 -309.958072) (xy 406.316228 -309.999158) (xy 406.337075 -310.044211)
			(xy 406.350359 -310.092043) (xy 406.35573 -310.141394) (xy 406.355278 -310.149748) (xy 406.694144 -310.149748)
			(xy 406.698104 -310.100694) (xy 406.709881 -310.05291) (xy 406.729172 -310.007634) (xy 406.755475 -309.966038)
			(xy 406.78811 -309.929201) (xy 406.826231 -309.898076) (xy 406.868852 -309.873469) (xy 406.914868 -309.856017)
			(xy 406.963087 -309.846173) (xy 407.012262 -309.844192) (xy 407.061117 -309.850124) (xy 407.108388 -309.863816)
			(xy 407.15285 -309.884914) (xy 407.193353 -309.91287) (xy 407.228846 -309.946962) (xy 407.258411 -309.986306)
			(xy 407.281282 -310.029883) (xy 407.296866 -310.076564) (xy 407.304761 -310.125141) (xy 407.305256 -310.149748)
			(xy 407.644104 -310.149748) (xy 407.648064 -310.100694) (xy 407.659841 -310.05291) (xy 407.679132 -310.007634)
			(xy 407.705435 -309.966038) (xy 407.73807 -309.929201) (xy 407.776191 -309.898076) (xy 407.818812 -309.873469)
			(xy 407.864828 -309.856017) (xy 407.913047 -309.846173) (xy 407.962222 -309.844192) (xy 408.011077 -309.850124)
			(xy 408.058348 -309.863816) (xy 408.10281 -309.884914) (xy 408.143313 -309.91287) (xy 408.178806 -309.946962)
			(xy 408.208371 -309.986306) (xy 408.231242 -310.029883) (xy 408.246826 -310.076564) (xy 408.254721 -310.125141)
			(xy 408.255216 -310.149748) (xy 408.254721 -310.174355) (xy 408.246826 -310.222932) (xy 408.231242 -310.269613)
			(xy 408.208371 -310.31319) (xy 408.178806 -310.352534) (xy 408.143313 -310.386626) (xy 408.10281 -310.414582)
			(xy 408.058348 -310.43568) (xy 408.011077 -310.449372) (xy 407.962222 -310.455304) (xy 407.913047 -310.453323)
			(xy 407.864828 -310.443479) (xy 407.818812 -310.426027) (xy 407.776191 -310.40142) (xy 407.73807 -310.370295)
			(xy 407.705435 -310.333458) (xy 407.679132 -310.291862) (xy 407.659841 -310.246586) (xy 407.648064 -310.198802)
			(xy 407.644104 -310.149748) (xy 407.305256 -310.149748) (xy 407.304761 -310.174355) (xy 407.296866 -310.222932)
			(xy 407.281282 -310.269613) (xy 407.258411 -310.31319) (xy 407.228846 -310.352534) (xy 407.193353 -310.386626)
			(xy 407.15285 -310.414582) (xy 407.108388 -310.43568) (xy 407.061117 -310.449372) (xy 407.012262 -310.455304)
			(xy 406.963087 -310.453323) (xy 406.914868 -310.443479) (xy 406.868852 -310.426027) (xy 406.826231 -310.40142)
			(xy 406.78811 -310.370295) (xy 406.755475 -310.333458) (xy 406.729172 -310.291862) (xy 406.709881 -310.246586)
			(xy 406.698104 -310.198802) (xy 406.694144 -310.149748) (xy 406.355278 -310.149748) (xy 406.353047 -310.190964)
			(xy 406.342379 -310.239447) (xy 406.324009 -310.285565) (xy 406.298419 -310.328104) (xy 406.266285 -310.365942)
			(xy 406.228453 -310.398084) (xy 406.185919 -310.423682) (xy 406.139804 -310.442061) (xy 406.091324 -310.452738)
			(xy 406.041754 -310.455432) (xy 405.992402 -310.45007) (xy 405.944568 -310.436796) (xy 405.899511 -310.415957)
			(xy 405.858418 -310.388104) (xy 405.822374 -310.35397) (xy 405.792326 -310.314454) (xy 405.769066 -310.270598)
			(xy 405.753209 -310.223556) (xy 405.74517 -310.174569) (xy 405.74468 -310.149748) (xy 405.744864 -310.135565)
			(xy 405.747531 -310.107325) (xy 405.750014 -310.09336) (xy 405.7523 -310.080914) (xy 405.744934 -310.057292)
			(xy 405.667464 -309.979822) (xy 405.643842 -309.972456) (xy 405.631396 -309.974742) (xy 405.617429 -309.977215)
			(xy 405.58919 -309.979889) (xy 405.575008 -309.980076) (xy 405.560825 -309.979899) (xy 405.532585 -309.977227)
			(xy 405.51862 -309.974742) (xy 405.506174 -309.972456) (xy 405.482552 -309.979822) (xy 405.405082 -310.057292)
			(xy 405.397716 -310.080914) (xy 405.400002 -310.09336) (xy 405.402483 -310.107325) (xy 405.405152 -310.135565)
			(xy 405.405336 -310.149748) (xy 405.404814 -310.175003) (xy 405.396501 -310.224825) (xy 405.3801 -310.272599)
			(xy 405.356059 -310.317022) (xy 405.325035 -310.356882) (xy 405.287873 -310.391092) (xy 405.245587 -310.418718)
			(xy 405.199331 -310.439008) (xy 405.150366 -310.451408) (xy 405.100028 -310.455579) (xy 405.04969 -310.451408)
			(xy 405.000725 -310.439008) (xy 404.954469 -310.418718) (xy 404.912183 -310.391092) (xy 404.875021 -310.356882)
			(xy 404.843997 -310.317022) (xy 404.819956 -310.272599) (xy 404.803555 -310.224825) (xy 404.795242 -310.175003)
			(xy 404.79472 -310.149748) (xy 404.794903 -310.135565) (xy 404.797571 -310.107325) (xy 404.800054 -310.09336)
			(xy 404.800054 -310.093106) (xy 404.801571 -310.080877) (xy 404.794246 -310.057384) (xy 404.786084 -310.048148)
			(xy 404.717504 -309.979822) (xy 404.693882 -309.972456) (xy 404.681436 -309.974742) (xy 404.667408 -309.977233)
			(xy 404.63904 -309.979901) (xy 404.624794 -309.980076) (xy 404.610611 -309.979901) (xy 404.582371 -309.977228)
			(xy 404.568406 -309.974742) (xy 404.55596 -309.972456) (xy 404.532338 -309.979822) (xy 404.454868 -310.057292)
			(xy 404.447502 -310.080914) (xy 404.449788 -310.09336) (xy 404.452269 -310.107325) (xy 404.454938 -310.135565)
			(xy 404.455122 -310.149748) (xy 404.45457 -310.174564) (xy 404.446533 -310.223542) (xy 404.430678 -310.270574)
			(xy 404.407424 -310.314422) (xy 404.377382 -310.35393) (xy 404.341344 -310.388057) (xy 404.300259 -310.415905)
			(xy 404.255211 -310.43674) (xy 404.207386 -310.450012) (xy 404.158044 -310.455372) (xy 404.108484 -310.452679)
			(xy 404.060013 -310.442004) (xy 404.013907 -310.423628) (xy 403.971382 -310.398035) (xy 403.933557 -310.365899)
			(xy 403.901429 -310.328068) (xy 403.875845 -310.285537) (xy 403.857478 -310.239428) (xy 403.846813 -310.190955)
			(xy 403.84413 -310.141394) (xy 403.8495 -310.092053) (xy 403.862782 -310.04423) (xy 403.883625 -309.999186)
			(xy 403.911481 -309.958108) (xy 403.945616 -309.922077) (xy 403.98513 -309.892043) (xy 404.028983 -309.868797)
			(xy 404.076018 -309.852952) (xy 404.124998 -309.844925) (xy 404.149814 -309.84444) (xy 404.163997 -309.844614)
			(xy 404.192237 -309.847288) (xy 404.206202 -309.849774) (xy 404.218648 -309.85206) (xy 404.24227 -309.844694)
			(xy 404.31974 -309.767224) (xy 404.327106 -309.743602) (xy 404.32482 -309.731156) (xy 404.322342 -309.71719)
			(xy 404.319671 -309.688951) (xy 404.319486 -309.674768) (xy 404.319658 -309.660585) (xy 404.322333 -309.632345)
			(xy 404.32482 -309.61838) (xy 404.327106 -309.605934) (xy 404.31974 -309.582312) (xy 404.24227 -309.504842)
			(xy 404.218648 -309.497476) (xy 404.206202 -309.499762) (xy 404.192235 -309.502234) (xy 404.163996 -309.504909)
			(xy 404.149814 -309.505096) (xy 404.125821 -309.504649) (xy 404.078424 -309.497144) (xy 404.032786 -309.482316)
			(xy 403.990029 -309.460532) (xy 403.951207 -309.432326) (xy 403.917275 -309.398395) (xy 403.889069 -309.359573)
			(xy 403.867284 -309.316816) (xy 403.852457 -309.271177) (xy 403.844951 -309.223781) (xy 403.844506 -309.199788)
			(xy 403.844681 -309.185605) (xy 403.847354 -309.157365) (xy 403.84984 -309.1434) (xy 403.852126 -309.130954)
			(xy 403.84476 -309.107332) (xy 403.76729 -309.029862) (xy 403.743668 -309.022496) (xy 403.731222 -309.024782)
			(xy 403.717257 -309.027265) (xy 403.689017 -309.029933) (xy 403.674834 -309.030116) (xy 403.65001 -309.029659)
			(xy 403.601014 -309.021632) (xy 403.553963 -309.005784) (xy 403.510095 -308.982532) (xy 403.470568 -308.95249)
			(xy 403.436421 -308.916448) (xy 403.408555 -308.875356) (xy 403.387705 -308.830298) (xy 403.374419 -308.78246)
			(xy 403.369048 -308.733103) (xy 403.030015 -308.733103) (xy 403.029687 -308.749415) (xy 403.021792 -308.797992)
			(xy 403.006208 -308.844673) (xy 402.983337 -308.88825) (xy 402.953772 -308.927594) (xy 402.918279 -308.961686)
			(xy 402.877776 -308.989642) (xy 402.833314 -309.01074) (xy 402.786043 -309.024432) (xy 402.737188 -309.030364)
			(xy 402.688013 -309.028383) (xy 402.639794 -309.018539) (xy 402.593778 -309.001087) (xy 402.551157 -308.97648)
			(xy 402.513036 -308.945355) (xy 402.480401 -308.908518) (xy 402.454098 -308.866922) (xy 402.434807 -308.821646)
			(xy 402.42303 -308.773862) (xy 402.41907 -308.724808) (xy 402.080222 -308.724808) (xy 402.079727 -308.749415)
			(xy 402.071832 -308.797992) (xy 402.056248 -308.844673) (xy 402.033377 -308.88825) (xy 402.003812 -308.927594)
			(xy 401.968319 -308.961686) (xy 401.927816 -308.989642) (xy 401.883354 -309.01074) (xy 401.836083 -309.024432)
			(xy 401.787228 -309.030364) (xy 401.738053 -309.028383) (xy 401.689834 -309.018539) (xy 401.643818 -309.001087)
			(xy 401.601197 -308.97648) (xy 401.563076 -308.945355) (xy 401.530441 -308.908518) (xy 401.504138 -308.866922)
			(xy 401.484847 -308.821646) (xy 401.47307 -308.773862) (xy 401.46911 -308.724808) (xy 401.130262 -308.724808)
			(xy 401.129767 -308.749415) (xy 401.121872 -308.797992) (xy 401.106288 -308.844673) (xy 401.083417 -308.88825)
			(xy 401.053852 -308.927594) (xy 401.018359 -308.961686) (xy 400.977856 -308.989642) (xy 400.933394 -309.01074)
			(xy 400.886123 -309.024432) (xy 400.837268 -309.030364) (xy 400.788093 -309.028383) (xy 400.739874 -309.018539)
			(xy 400.693858 -309.001087) (xy 400.651237 -308.97648) (xy 400.613116 -308.945355) (xy 400.580481 -308.908518)
			(xy 400.554178 -308.866922) (xy 400.534887 -308.821646) (xy 400.52311 -308.773862) (xy 400.51915 -308.724808)
			(xy 400.180302 -308.724808) (xy 400.179807 -308.749415) (xy 400.171912 -308.797992) (xy 400.156328 -308.844673)
			(xy 400.133457 -308.88825) (xy 400.103892 -308.927594) (xy 400.068399 -308.961686) (xy 400.027896 -308.989642)
			(xy 399.983434 -309.01074) (xy 399.936163 -309.024432) (xy 399.887308 -309.030364) (xy 399.838133 -309.028383)
			(xy 399.789914 -309.018539) (xy 399.743898 -309.001087) (xy 399.701277 -308.97648) (xy 399.663156 -308.945355)
			(xy 399.630521 -308.908518) (xy 399.604218 -308.866922) (xy 399.584927 -308.821646) (xy 399.57315 -308.773862)
			(xy 399.56919 -308.724808) (xy 399.230342 -308.724808) (xy 399.229847 -308.749415) (xy 399.221952 -308.797992)
			(xy 399.206368 -308.844673) (xy 399.183497 -308.88825) (xy 399.153932 -308.927594) (xy 399.118439 -308.961686)
			(xy 399.077936 -308.989642) (xy 399.033474 -309.01074) (xy 398.986203 -309.024432) (xy 398.937348 -309.030364)
			(xy 398.888173 -309.028383) (xy 398.839954 -309.018539) (xy 398.793938 -309.001087) (xy 398.751317 -308.97648)
			(xy 398.713196 -308.945355) (xy 398.680561 -308.908518) (xy 398.654258 -308.866922) (xy 398.634967 -308.821646)
			(xy 398.62319 -308.773862) (xy 398.61923 -308.724808) (xy 398.280128 -308.724808) (xy 398.279633 -308.749415)
			(xy 398.271738 -308.797992) (xy 398.256154 -308.844673) (xy 398.233283 -308.88825) (xy 398.203718 -308.927594)
			(xy 398.168225 -308.961686) (xy 398.127722 -308.989642) (xy 398.08326 -309.01074) (xy 398.035989 -309.024432)
			(xy 397.987134 -309.030364) (xy 397.937959 -309.028383) (xy 397.88974 -309.018539) (xy 397.843724 -309.001087)
			(xy 397.801103 -308.97648) (xy 397.762982 -308.945355) (xy 397.730347 -308.908518) (xy 397.704044 -308.866922)
			(xy 397.684753 -308.821646) (xy 397.672976 -308.773862) (xy 397.669016 -308.724808) (xy 397.330168 -308.724808)
			(xy 397.329673 -308.749415) (xy 397.321778 -308.797992) (xy 397.306194 -308.844673) (xy 397.283323 -308.88825)
			(xy 397.253758 -308.927594) (xy 397.218265 -308.961686) (xy 397.177762 -308.989642) (xy 397.1333 -309.01074)
			(xy 397.086029 -309.024432) (xy 397.037174 -309.030364) (xy 396.987999 -309.028383) (xy 396.93978 -309.018539)
			(xy 396.893764 -309.001087) (xy 396.851143 -308.97648) (xy 396.813022 -308.945355) (xy 396.780387 -308.908518)
			(xy 396.754084 -308.866922) (xy 396.734793 -308.821646) (xy 396.723016 -308.773862) (xy 396.719056 -308.724808)
			(xy 396.380208 -308.724808) (xy 396.379713 -308.749415) (xy 396.371818 -308.797992) (xy 396.356234 -308.844673)
			(xy 396.333363 -308.88825) (xy 396.303798 -308.927594) (xy 396.268305 -308.961686) (xy 396.227802 -308.989642)
			(xy 396.18334 -309.01074) (xy 396.136069 -309.024432) (xy 396.087214 -309.030364) (xy 396.038039 -309.028383)
			(xy 395.98982 -309.018539) (xy 395.943804 -309.001087) (xy 395.901183 -308.97648) (xy 395.863062 -308.945355)
			(xy 395.830427 -308.908518) (xy 395.804124 -308.866922) (xy 395.784833 -308.821646) (xy 395.773056 -308.773862)
			(xy 395.769096 -308.724808) (xy 395.43018 -308.724808) (xy 395.430628 -308.733052) (xy 395.425265 -308.782404)
			(xy 395.41199 -308.830238) (xy 395.39115 -308.875294) (xy 395.363296 -308.916385) (xy 395.329162 -308.952428)
			(xy 395.289646 -308.982475) (xy 395.245789 -309.005733) (xy 395.198748 -309.021589) (xy 395.149761 -309.029627)
			(xy 395.12494 -309.030116) (xy 395.110757 -309.029934) (xy 395.082517 -309.027265) (xy 395.068552 -309.024782)
			(xy 395.054593 -309.02257) (xy 395.026457 -309.02516) (xy 395.000108 -309.03536) (xy 394.977561 -309.052388)
			(xy 394.960541 -309.074941) (xy 394.950352 -309.101295) (xy 394.947772 -309.129432) (xy 394.949934 -309.1434)
			(xy 394.952406 -309.157367) (xy 394.955081 -309.185606) (xy 394.955268 -309.199788) (xy 394.954835 -309.224609)
			(xy 394.946806 -309.273598) (xy 394.930957 -309.320643) (xy 394.907706 -309.364504) (xy 394.877666 -309.404026)
			(xy 394.841627 -309.438167) (xy 394.80054 -309.466028) (xy 394.755487 -309.486876) (xy 394.707655 -309.50016)
			(xy 394.658303 -309.50553) (xy 394.608733 -309.502846) (xy 394.56025 -309.492178) (xy 394.514132 -309.473807)
			(xy 394.471593 -309.448217) (xy 394.433755 -309.416082) (xy 394.401613 -309.378249) (xy 394.376016 -309.335715)
			(xy 394.357637 -309.289599) (xy 394.346961 -309.241118) (xy 394.344268 -309.191549) (xy 394.005142 -309.191549)
			(xy 394.005308 -309.199788) (xy 394.004813 -309.224395) (xy 393.996918 -309.272972) (xy 393.981334 -309.319653)
			(xy 393.958463 -309.36323) (xy 393.928898 -309.402574) (xy 393.893405 -309.436666) (xy 393.852902 -309.464622)
			(xy 393.80844 -309.48572) (xy 393.761169 -309.499412) (xy 393.712314 -309.505344) (xy 393.663139 -309.503363)
			(xy 393.61492 -309.493519) (xy 393.568904 -309.476067) (xy 393.526283 -309.45146) (xy 393.488162 -309.420335)
			(xy 393.455527 -309.383498) (xy 393.429224 -309.341902) (xy 393.409933 -309.296626) (xy 393.398156 -309.248842)
			(xy 393.394196 -309.199788) (xy 393.055094 -309.199788) (xy 393.054599 -309.224395) (xy 393.046704 -309.272972)
			(xy 393.03112 -309.319653) (xy 393.008249 -309.36323) (xy 392.978684 -309.402574) (xy 392.943191 -309.436666)
			(xy 392.902688 -309.464622) (xy 392.858226 -309.48572) (xy 392.810955 -309.499412) (xy 392.7621 -309.505344)
			(xy 392.712925 -309.503363) (xy 392.664706 -309.493519) (xy 392.61869 -309.476067) (xy 392.576069 -309.45146)
			(xy 392.537948 -309.420335) (xy 392.505313 -309.383498) (xy 392.47901 -309.341902) (xy 392.459719 -309.296626)
			(xy 392.447942 -309.248842) (xy 392.443982 -309.199788) (xy 392.105134 -309.199788) (xy 392.104639 -309.224395)
			(xy 392.096744 -309.272972) (xy 392.08116 -309.319653) (xy 392.058289 -309.36323) (xy 392.028724 -309.402574)
			(xy 391.993231 -309.436666) (xy 391.952728 -309.464622) (xy 391.908266 -309.48572) (xy 391.860995 -309.499412)
			(xy 391.81214 -309.505344) (xy 391.762965 -309.503363) (xy 391.714746 -309.493519) (xy 391.66873 -309.476067)
			(xy 391.626109 -309.45146) (xy 391.587988 -309.420335) (xy 391.555353 -309.383498) (xy 391.52905 -309.341902)
			(xy 391.509759 -309.296626) (xy 391.497982 -309.248842) (xy 391.494022 -309.199788) (xy 391.155174 -309.199788)
			(xy 391.154679 -309.224395) (xy 391.146784 -309.272972) (xy 391.1312 -309.319653) (xy 391.108329 -309.36323)
			(xy 391.078764 -309.402574) (xy 391.043271 -309.436666) (xy 391.002768 -309.464622) (xy 390.958306 -309.48572)
			(xy 390.911035 -309.499412) (xy 390.86218 -309.505344) (xy 390.813005 -309.503363) (xy 390.764786 -309.493519)
			(xy 390.71877 -309.476067) (xy 390.676149 -309.45146) (xy 390.638028 -309.420335) (xy 390.605393 -309.383498)
			(xy 390.57909 -309.341902) (xy 390.559799 -309.296626) (xy 390.548022 -309.248842) (xy 390.544062 -309.199788)
			(xy 390.205214 -309.199788) (xy 390.204719 -309.224395) (xy 390.196824 -309.272972) (xy 390.18124 -309.319653)
			(xy 390.158369 -309.36323) (xy 390.128804 -309.402574) (xy 390.093311 -309.436666) (xy 390.052808 -309.464622)
			(xy 390.008346 -309.48572) (xy 389.961075 -309.499412) (xy 389.91222 -309.505344) (xy 389.863045 -309.503363)
			(xy 389.814826 -309.493519) (xy 389.76881 -309.476067) (xy 389.726189 -309.45146) (xy 389.688068 -309.420335)
			(xy 389.655433 -309.383498) (xy 389.62913 -309.341902) (xy 389.609839 -309.296626) (xy 389.598062 -309.248842)
			(xy 389.594102 -309.199788) (xy 389.255254 -309.199788) (xy 389.254759 -309.224395) (xy 389.246864 -309.272972)
			(xy 389.23128 -309.319653) (xy 389.208409 -309.36323) (xy 389.178844 -309.402574) (xy 389.143351 -309.436666)
			(xy 389.102848 -309.464622) (xy 389.058386 -309.48572) (xy 389.011115 -309.499412) (xy 388.96226 -309.505344)
			(xy 388.913085 -309.503363) (xy 388.864866 -309.493519) (xy 388.81885 -309.476067) (xy 388.776229 -309.45146)
			(xy 388.738108 -309.420335) (xy 388.705473 -309.383498) (xy 388.67917 -309.341902) (xy 388.659879 -309.296626)
			(xy 388.648102 -309.248842) (xy 388.644142 -309.199788) (xy 388.305294 -309.199788) (xy 388.304799 -309.224395)
			(xy 388.296904 -309.272972) (xy 388.28132 -309.319653) (xy 388.258449 -309.36323) (xy 388.228884 -309.402574)
			(xy 388.193391 -309.436666) (xy 388.152888 -309.464622) (xy 388.108426 -309.48572) (xy 388.061155 -309.499412)
			(xy 388.0123 -309.505344) (xy 387.963125 -309.503363) (xy 387.914906 -309.493519) (xy 387.86889 -309.476067)
			(xy 387.826269 -309.45146) (xy 387.788148 -309.420335) (xy 387.755513 -309.383498) (xy 387.72921 -309.341902)
			(xy 387.709919 -309.296626) (xy 387.698142 -309.248842) (xy 387.694182 -309.199788) (xy 387.355334 -309.199788)
			(xy 387.354839 -309.224395) (xy 387.346944 -309.272972) (xy 387.33136 -309.319653) (xy 387.308489 -309.36323)
			(xy 387.278924 -309.402574) (xy 387.243431 -309.436666) (xy 387.202928 -309.464622) (xy 387.158466 -309.48572)
			(xy 387.111195 -309.499412) (xy 387.06234 -309.505344) (xy 387.013165 -309.503363) (xy 386.964946 -309.493519)
			(xy 386.91893 -309.476067) (xy 386.876309 -309.45146) (xy 386.838188 -309.420335) (xy 386.805553 -309.383498)
			(xy 386.77925 -309.341902) (xy 386.759959 -309.296626) (xy 386.748182 -309.248842) (xy 386.744222 -309.199788)
			(xy 386.40512 -309.199788) (xy 386.404625 -309.224395) (xy 386.39673 -309.272972) (xy 386.381146 -309.319653)
			(xy 386.358275 -309.36323) (xy 386.32871 -309.402574) (xy 386.293217 -309.436666) (xy 386.252714 -309.464622)
			(xy 386.208252 -309.48572) (xy 386.160981 -309.499412) (xy 386.112126 -309.505344) (xy 386.062951 -309.503363)
			(xy 386.014732 -309.493519) (xy 385.968716 -309.476067) (xy 385.926095 -309.45146) (xy 385.887974 -309.420335)
			(xy 385.855339 -309.383498) (xy 385.829036 -309.341902) (xy 385.809745 -309.296626) (xy 385.797968 -309.248842)
			(xy 385.794008 -309.199788) (xy 385.45516 -309.199788) (xy 385.454665 -309.224395) (xy 385.44677 -309.272972)
			(xy 385.431186 -309.319653) (xy 385.408315 -309.36323) (xy 385.37875 -309.402574) (xy 385.343257 -309.436666)
			(xy 385.302754 -309.464622) (xy 385.258292 -309.48572) (xy 385.211021 -309.499412) (xy 385.162166 -309.505344)
			(xy 385.112991 -309.503363) (xy 385.064772 -309.493519) (xy 385.018756 -309.476067) (xy 384.976135 -309.45146)
			(xy 384.938014 -309.420335) (xy 384.905379 -309.383498) (xy 384.879076 -309.341902) (xy 384.859785 -309.296626)
			(xy 384.848008 -309.248842) (xy 384.844048 -309.199788) (xy 375.996502 -309.199788) (xy 376.015141 -309.22796)
			(xy 376.038813 -309.278457) (xy 376.054881 -309.331864) (xy 376.063001 -309.38704) (xy 376.06351 -309.414926)
			(xy 376.063001 -309.442812) (xy 376.054881 -309.497988) (xy 376.038813 -309.551395) (xy 376.015141 -309.601892)
			(xy 375.984368 -309.648405) (xy 375.947151 -309.689942) (xy 375.904283 -309.725617) (xy 375.856677 -309.754671)
			(xy 375.805348 -309.776483) (xy 375.751391 -309.790589) (xy 375.695954 -309.796689) (xy 375.64022 -309.794652)
			(xy 375.585377 -309.784522) (xy 375.532593 -309.766515) (xy 375.482993 -309.741014) (xy 375.437635 -309.708563)
			(xy 375.397486 -309.669854) (xy 375.3634 -309.625711) (xy 375.336104 -309.577076) (xy 375.316181 -309.524985)
			(xy 375.304055 -309.470548) (xy 375.299984 -309.414926) (xy 352.008694 -309.414926) (xy 351.846134 -309.577486)
			(xy 351.843427 -309.580337) (xy 351.838833 -309.586714) (xy 351.83699 -309.590186) (xy 351.834412 -309.595614)
			(xy 351.831599 -309.607294) (xy 351.831402 -309.6133) (xy 351.831402 -309.897272) (xy 382.740406 -309.897272)
			(xy 382.744477 -309.84165) (xy 382.756603 -309.787213) (xy 382.776526 -309.735122) (xy 382.803822 -309.686487)
			(xy 382.837908 -309.642344) (xy 382.878057 -309.603635) (xy 382.923415 -309.571184) (xy 382.973015 -309.545683)
			(xy 383.025799 -309.527676) (xy 383.080642 -309.517546) (xy 383.136376 -309.515509) (xy 383.191813 -309.521609)
			(xy 383.24577 -309.535715) (xy 383.297099 -309.557527) (xy 383.344705 -309.586581) (xy 383.387573 -309.622256)
			(xy 383.42479 -309.663793) (xy 383.455563 -309.710306) (xy 383.479235 -309.760803) (xy 383.495303 -309.81421)
			(xy 383.503423 -309.869386) (xy 383.503932 -309.897272) (xy 383.503423 -309.925158) (xy 383.495303 -309.980334)
			(xy 383.479235 -310.033741) (xy 383.455563 -310.084238) (xy 383.42479 -310.130751) (xy 383.407541 -310.150002)
			(xy 383.893834 -310.150002) (xy 383.897794 -310.100948) (xy 383.909571 -310.053164) (xy 383.928862 -310.007888)
			(xy 383.955165 -309.966292) (xy 383.9878 -309.929455) (xy 384.025921 -309.89833) (xy 384.068542 -309.873723)
			(xy 384.114558 -309.856271) (xy 384.162777 -309.846427) (xy 384.211952 -309.844446) (xy 384.260807 -309.850378)
			(xy 384.308078 -309.86407) (xy 384.35254 -309.885168) (xy 384.393043 -309.913124) (xy 384.428536 -309.947216)
			(xy 384.458101 -309.98656) (xy 384.480972 -310.030137) (xy 384.496556 -310.076818) (xy 384.504451 -310.125395)
			(xy 384.504941 -310.149748) (xy 384.844048 -310.149748) (xy 384.848008 -310.100694) (xy 384.859785 -310.05291)
			(xy 384.879076 -310.007634) (xy 384.905379 -309.966038) (xy 384.938014 -309.929201) (xy 384.976135 -309.898076)
			(xy 385.018756 -309.873469) (xy 385.064772 -309.856017) (xy 385.112991 -309.846173) (xy 385.162166 -309.844192)
			(xy 385.211021 -309.850124) (xy 385.258292 -309.863816) (xy 385.302754 -309.884914) (xy 385.343257 -309.91287)
			(xy 385.37875 -309.946962) (xy 385.408315 -309.986306) (xy 385.431186 -310.029883) (xy 385.44677 -310.076564)
			(xy 385.454665 -310.125141) (xy 385.45516 -310.149748) (xy 385.794008 -310.149748) (xy 385.797968 -310.100694)
			(xy 385.809745 -310.05291) (xy 385.829036 -310.007634) (xy 385.855339 -309.966038) (xy 385.887974 -309.929201)
			(xy 385.926095 -309.898076) (xy 385.968716 -309.873469) (xy 386.014732 -309.856017) (xy 386.062951 -309.846173)
			(xy 386.112126 -309.844192) (xy 386.160981 -309.850124) (xy 386.208252 -309.863816) (xy 386.252714 -309.884914)
			(xy 386.293217 -309.91287) (xy 386.32871 -309.946962) (xy 386.358275 -309.986306) (xy 386.381146 -310.029883)
			(xy 386.39673 -310.076564) (xy 386.404625 -310.125141) (xy 386.40512 -310.149748) (xy 386.744222 -310.149748)
			(xy 386.748182 -310.100694) (xy 386.759959 -310.05291) (xy 386.77925 -310.007634) (xy 386.805553 -309.966038)
			(xy 386.838188 -309.929201) (xy 386.876309 -309.898076) (xy 386.91893 -309.873469) (xy 386.964946 -309.856017)
			(xy 387.013165 -309.846173) (xy 387.06234 -309.844192) (xy 387.111195 -309.850124) (xy 387.158466 -309.863816)
			(xy 387.202928 -309.884914) (xy 387.243431 -309.91287) (xy 387.278924 -309.946962) (xy 387.308489 -309.986306)
			(xy 387.33136 -310.029883) (xy 387.346944 -310.076564) (xy 387.354839 -310.125141) (xy 387.355334 -310.149748)
			(xy 387.694182 -310.149748) (xy 387.698142 -310.100694) (xy 387.709919 -310.05291) (xy 387.72921 -310.007634)
			(xy 387.755513 -309.966038) (xy 387.788148 -309.929201) (xy 387.826269 -309.898076) (xy 387.86889 -309.873469)
			(xy 387.914906 -309.856017) (xy 387.963125 -309.846173) (xy 388.0123 -309.844192) (xy 388.061155 -309.850124)
			(xy 388.108426 -309.863816) (xy 388.152888 -309.884914) (xy 388.193391 -309.91287) (xy 388.228884 -309.946962)
			(xy 388.258449 -309.986306) (xy 388.28132 -310.029883) (xy 388.296904 -310.076564) (xy 388.304799 -310.125141)
			(xy 388.305294 -310.149748) (xy 388.644142 -310.149748) (xy 388.648102 -310.100694) (xy 388.659879 -310.05291)
			(xy 388.67917 -310.007634) (xy 388.705473 -309.966038) (xy 388.738108 -309.929201) (xy 388.776229 -309.898076)
			(xy 388.81885 -309.873469) (xy 388.864866 -309.856017) (xy 388.913085 -309.846173) (xy 388.96226 -309.844192)
			(xy 389.011115 -309.850124) (xy 389.058386 -309.863816) (xy 389.102848 -309.884914) (xy 389.143351 -309.91287)
			(xy 389.178844 -309.946962) (xy 389.208409 -309.986306) (xy 389.23128 -310.029883) (xy 389.246864 -310.076564)
			(xy 389.254759 -310.125141) (xy 389.255254 -310.149748) (xy 389.594102 -310.149748) (xy 389.598062 -310.100694)
			(xy 389.609839 -310.05291) (xy 389.62913 -310.007634) (xy 389.655433 -309.966038) (xy 389.688068 -309.929201)
			(xy 389.726189 -309.898076) (xy 389.76881 -309.873469) (xy 389.814826 -309.856017) (xy 389.863045 -309.846173)
			(xy 389.91222 -309.844192) (xy 389.961075 -309.850124) (xy 390.008346 -309.863816) (xy 390.052808 -309.884914)
			(xy 390.093311 -309.91287) (xy 390.128804 -309.946962) (xy 390.158369 -309.986306) (xy 390.18124 -310.029883)
			(xy 390.196824 -310.076564) (xy 390.204719 -310.125141) (xy 390.205214 -310.149748) (xy 390.544062 -310.149748)
			(xy 390.548022 -310.100694) (xy 390.559799 -310.05291) (xy 390.57909 -310.007634) (xy 390.605393 -309.966038)
			(xy 390.638028 -309.929201) (xy 390.676149 -309.898076) (xy 390.71877 -309.873469) (xy 390.764786 -309.856017)
			(xy 390.813005 -309.846173) (xy 390.86218 -309.844192) (xy 390.911035 -309.850124) (xy 390.958306 -309.863816)
			(xy 391.002768 -309.884914) (xy 391.043271 -309.91287) (xy 391.078764 -309.946962) (xy 391.108329 -309.986306)
			(xy 391.1312 -310.029883) (xy 391.146784 -310.076564) (xy 391.154679 -310.125141) (xy 391.155174 -310.149748)
			(xy 391.494022 -310.149748) (xy 391.497982 -310.100694) (xy 391.509759 -310.05291) (xy 391.52905 -310.007634)
			(xy 391.555353 -309.966038) (xy 391.587988 -309.929201) (xy 391.626109 -309.898076) (xy 391.66873 -309.873469)
			(xy 391.714746 -309.856017) (xy 391.762965 -309.846173) (xy 391.81214 -309.844192) (xy 391.860995 -309.850124)
			(xy 391.908266 -309.863816) (xy 391.952728 -309.884914) (xy 391.993231 -309.91287) (xy 392.028724 -309.946962)
			(xy 392.058289 -309.986306) (xy 392.08116 -310.029883) (xy 392.096744 -310.076564) (xy 392.104639 -310.125141)
			(xy 392.105134 -310.149748) (xy 392.443982 -310.149748) (xy 392.447942 -310.100694) (xy 392.459719 -310.05291)
			(xy 392.47901 -310.007634) (xy 392.505313 -309.966038) (xy 392.537948 -309.929201) (xy 392.576069 -309.898076)
			(xy 392.61869 -309.873469) (xy 392.664706 -309.856017) (xy 392.712925 -309.846173) (xy 392.7621 -309.844192)
			(xy 392.810955 -309.850124) (xy 392.858226 -309.863816) (xy 392.902688 -309.884914) (xy 392.943191 -309.91287)
			(xy 392.978684 -309.946962) (xy 393.008249 -309.986306) (xy 393.03112 -310.029883) (xy 393.046704 -310.076564)
			(xy 393.054599 -310.125141) (xy 393.055094 -310.149748) (xy 393.394196 -310.149748) (xy 393.398156 -310.100694)
			(xy 393.409933 -310.05291) (xy 393.429224 -310.007634) (xy 393.455527 -309.966038) (xy 393.488162 -309.929201)
			(xy 393.526283 -309.898076) (xy 393.568904 -309.873469) (xy 393.61492 -309.856017) (xy 393.663139 -309.846173)
			(xy 393.712314 -309.844192) (xy 393.761169 -309.850124) (xy 393.80844 -309.863816) (xy 393.852902 -309.884914)
			(xy 393.893405 -309.91287) (xy 393.928898 -309.946962) (xy 393.958463 -309.986306) (xy 393.981334 -310.029883)
			(xy 393.996918 -310.076564) (xy 394.004813 -310.125141) (xy 394.005308 -310.149748) (xy 394.344156 -310.149748)
			(xy 394.348116 -310.100694) (xy 394.359893 -310.05291) (xy 394.379184 -310.007634) (xy 394.405487 -309.966038)
			(xy 394.438122 -309.929201) (xy 394.476243 -309.898076) (xy 394.518864 -309.873469) (xy 394.56488 -309.856017)
			(xy 394.613099 -309.846173) (xy 394.662274 -309.844192) (xy 394.711129 -309.850124) (xy 394.7584 -309.863816)
			(xy 394.802862 -309.884914) (xy 394.843365 -309.91287) (xy 394.878858 -309.946962) (xy 394.908423 -309.986306)
			(xy 394.931294 -310.029883) (xy 394.946878 -310.076564) (xy 394.954773 -310.125141) (xy 394.955268 -310.149748)
			(xy 395.294116 -310.149748) (xy 395.298076 -310.100694) (xy 395.309853 -310.05291) (xy 395.329144 -310.007634)
			(xy 395.355447 -309.966038) (xy 395.388082 -309.929201) (xy 395.426203 -309.898076) (xy 395.468824 -309.873469)
			(xy 395.51484 -309.856017) (xy 395.563059 -309.846173) (xy 395.612234 -309.844192) (xy 395.661089 -309.850124)
			(xy 395.70836 -309.863816) (xy 395.752822 -309.884914) (xy 395.793325 -309.91287) (xy 395.828818 -309.946962)
			(xy 395.858383 -309.986306) (xy 395.881254 -310.029883) (xy 395.896838 -310.076564) (xy 395.904733 -310.125141)
			(xy 395.90506 -310.141417) (xy 396.244229 -310.141417) (xy 396.249595 -310.092077) (xy 396.262873 -310.044254)
			(xy 396.283712 -309.999209) (xy 396.311564 -309.958129) (xy 396.345695 -309.922096) (xy 396.385205 -309.892059)
			(xy 396.429054 -309.868809) (xy 396.476087 -309.85296) (xy 396.525064 -309.844927) (xy 396.54988 -309.84444)
			(xy 396.564063 -309.844619) (xy 396.592303 -309.847289) (xy 396.606268 -309.849774) (xy 396.618714 -309.85206)
			(xy 396.642336 -309.844694) (xy 396.719806 -309.767224) (xy 396.727172 -309.743602) (xy 396.724886 -309.731156)
			(xy 396.722407 -309.71719) (xy 396.719737 -309.688951) (xy 396.719552 -309.674768) (xy 396.720074 -309.649513)
			(xy 396.728387 -309.599691) (xy 396.744788 -309.551917) (xy 396.768829 -309.507494) (xy 396.799853 -309.467634)
			(xy 396.837015 -309.433424) (xy 396.879301 -309.405798) (xy 396.925557 -309.385508) (xy 396.974522 -309.373108)
			(xy 397.02486 -309.368937) (xy 397.075198 -309.373108) (xy 397.124163 -309.385508) (xy 397.170419 -309.405798)
			(xy 397.212705 -309.433424) (xy 397.249867 -309.467634) (xy 397.280891 -309.507494) (xy 397.304932 -309.551917)
			(xy 397.321333 -309.599691) (xy 397.329646 -309.649513) (xy 397.330168 -309.674768) (xy 397.329988 -309.688951)
			(xy 397.327318 -309.717191) (xy 397.324834 -309.731156) (xy 397.322548 -309.743602) (xy 397.329914 -309.767224)
			(xy 397.407384 -309.844694) (xy 397.431006 -309.85206) (xy 397.443452 -309.849774) (xy 397.457417 -309.847294)
			(xy 397.485657 -309.844625) (xy 397.49984 -309.84444) (xy 397.514023 -309.84461) (xy 397.542263 -309.847287)
			(xy 397.556228 -309.849774) (xy 397.568674 -309.85206) (xy 397.592296 -309.844694) (xy 397.669766 -309.767224)
			(xy 397.677132 -309.743602) (xy 397.674846 -309.731156) (xy 397.672368 -309.71719) (xy 397.669697 -309.688951)
			(xy 397.669512 -309.674768) (xy 397.670034 -309.649513) (xy 397.678347 -309.599691) (xy 397.694748 -309.551917)
			(xy 397.718789 -309.507494) (xy 397.749813 -309.467634) (xy 397.786975 -309.433424) (xy 397.829261 -309.405798)
			(xy 397.875517 -309.385508) (xy 397.924482 -309.373108) (xy 397.97482 -309.368937) (xy 398.025158 -309.373108)
			(xy 398.074123 -309.385508) (xy 398.120379 -309.405798) (xy 398.162665 -309.433424) (xy 398.199827 -309.467634)
			(xy 398.230851 -309.507494) (xy 398.254892 -309.551917) (xy 398.271293 -309.599691) (xy 398.279606 -309.649513)
			(xy 398.280128 -309.674768) (xy 398.279947 -309.688951) (xy 398.277278 -309.717191) (xy 398.274794 -309.731156)
			(xy 398.272508 -309.743602) (xy 398.279874 -309.767224) (xy 398.357344 -309.844694) (xy 398.380966 -309.85206)
			(xy 398.393412 -309.849774) (xy 398.407378 -309.8473) (xy 398.435618 -309.844626) (xy 398.4498 -309.84444)
			(xy 398.47462 -309.844878) (xy 398.523606 -309.852908) (xy 398.570648 -309.868758) (xy 398.614506 -309.892009)
			(xy 398.654025 -309.922049) (xy 398.688163 -309.958087) (xy 398.716022 -309.999172) (xy 398.736867 -310.044224)
			(xy 398.750149 -310.092054) (xy 398.755518 -310.141403) (xy 398.755066 -310.149748) (xy 399.09421 -310.149748)
			(xy 399.09817 -310.100694) (xy 399.109947 -310.05291) (xy 399.129238 -310.007634) (xy 399.155541 -309.966038)
			(xy 399.188176 -309.929201) (xy 399.226297 -309.898076) (xy 399.268918 -309.873469) (xy 399.314934 -309.856017)
			(xy 399.363153 -309.846173) (xy 399.412328 -309.844192) (xy 399.461183 -309.850124) (xy 399.508454 -309.863816)
			(xy 399.552916 -309.884914) (xy 399.593419 -309.91287) (xy 399.628912 -309.946962) (xy 399.658477 -309.986306)
			(xy 399.681348 -310.029883) (xy 399.696932 -310.076564) (xy 399.704827 -310.125141) (xy 399.705322 -310.149748)
			(xy 400.04417 -310.149748) (xy 400.04813 -310.100694) (xy 400.059907 -310.05291) (xy 400.079198 -310.007634)
			(xy 400.105501 -309.966038) (xy 400.138136 -309.929201) (xy 400.176257 -309.898076) (xy 400.218878 -309.873469)
			(xy 400.264894 -309.856017) (xy 400.313113 -309.846173) (xy 400.362288 -309.844192) (xy 400.411143 -309.850124)
			(xy 400.458414 -309.863816) (xy 400.502876 -309.884914) (xy 400.543379 -309.91287) (xy 400.578872 -309.946962)
			(xy 400.608437 -309.986306) (xy 400.631308 -310.029883) (xy 400.646892 -310.076564) (xy 400.654787 -310.125141)
			(xy 400.655282 -310.149748) (xy 400.99413 -310.149748) (xy 400.99809 -310.100694) (xy 401.009867 -310.05291)
			(xy 401.029158 -310.007634) (xy 401.055461 -309.966038) (xy 401.088096 -309.929201) (xy 401.126217 -309.898076)
			(xy 401.168838 -309.873469) (xy 401.214854 -309.856017) (xy 401.263073 -309.846173) (xy 401.312248 -309.844192)
			(xy 401.361103 -309.850124) (xy 401.408374 -309.863816) (xy 401.452836 -309.884914) (xy 401.493339 -309.91287)
			(xy 401.528832 -309.946962) (xy 401.558397 -309.986306) (xy 401.581268 -310.029883) (xy 401.596852 -310.076564)
			(xy 401.604747 -310.125141) (xy 401.605242 -310.149748) (xy 401.94409 -310.149748) (xy 401.94805 -310.100694)
			(xy 401.959827 -310.05291) (xy 401.979118 -310.007634) (xy 402.005421 -309.966038) (xy 402.038056 -309.929201)
			(xy 402.076177 -309.898076) (xy 402.118798 -309.873469) (xy 402.164814 -309.856017) (xy 402.213033 -309.846173)
			(xy 402.262208 -309.844192) (xy 402.311063 -309.850124) (xy 402.358334 -309.863816) (xy 402.402796 -309.884914)
			(xy 402.443299 -309.91287) (xy 402.478792 -309.946962) (xy 402.508357 -309.986306) (xy 402.531228 -310.029883)
			(xy 402.546812 -310.076564) (xy 402.554707 -310.125141) (xy 402.555202 -310.149748) (xy 402.89405 -310.149748)
			(xy 402.89801 -310.100694) (xy 402.909787 -310.05291) (xy 402.929078 -310.007634) (xy 402.955381 -309.966038)
			(xy 402.988016 -309.929201) (xy 403.026137 -309.898076) (xy 403.068758 -309.873469) (xy 403.114774 -309.856017)
			(xy 403.162993 -309.846173) (xy 403.212168 -309.844192) (xy 403.261023 -309.850124) (xy 403.308294 -309.863816)
			(xy 403.352756 -309.884914) (xy 403.393259 -309.91287) (xy 403.428752 -309.946962) (xy 403.458317 -309.986306)
			(xy 403.481188 -310.029883) (xy 403.496772 -310.076564) (xy 403.504667 -310.125141) (xy 403.505162 -310.149748)
			(xy 403.504667 -310.174355) (xy 403.496772 -310.222932) (xy 403.481188 -310.269613) (xy 403.458317 -310.31319)
			(xy 403.428752 -310.352534) (xy 403.393259 -310.386626) (xy 403.352756 -310.414582) (xy 403.308294 -310.43568)
			(xy 403.261023 -310.449372) (xy 403.212168 -310.455304) (xy 403.162993 -310.453323) (xy 403.114774 -310.443479)
			(xy 403.068758 -310.426027) (xy 403.026137 -310.40142) (xy 402.988016 -310.370295) (xy 402.955381 -310.333458)
			(xy 402.929078 -310.291862) (xy 402.909787 -310.246586) (xy 402.89801 -310.198802) (xy 402.89405 -310.149748)
			(xy 402.555202 -310.149748) (xy 402.554707 -310.174355) (xy 402.546812 -310.222932) (xy 402.531228 -310.269613)
			(xy 402.508357 -310.31319) (xy 402.478792 -310.352534) (xy 402.443299 -310.386626) (xy 402.402796 -310.414582)
			(xy 402.358334 -310.43568) (xy 402.311063 -310.449372) (xy 402.262208 -310.455304) (xy 402.213033 -310.453323)
			(xy 402.164814 -310.443479) (xy 402.118798 -310.426027) (xy 402.076177 -310.40142) (xy 402.038056 -310.370295)
			(xy 402.005421 -310.333458) (xy 401.979118 -310.291862) (xy 401.959827 -310.246586) (xy 401.94805 -310.198802)
			(xy 401.94409 -310.149748) (xy 401.605242 -310.149748) (xy 401.604747 -310.174355) (xy 401.596852 -310.222932)
			(xy 401.581268 -310.269613) (xy 401.558397 -310.31319) (xy 401.528832 -310.352534) (xy 401.493339 -310.386626)
			(xy 401.452836 -310.414582) (xy 401.408374 -310.43568) (xy 401.361103 -310.449372) (xy 401.312248 -310.455304)
			(xy 401.263073 -310.453323) (xy 401.214854 -310.443479) (xy 401.168838 -310.426027) (xy 401.126217 -310.40142)
			(xy 401.088096 -310.370295) (xy 401.055461 -310.333458) (xy 401.029158 -310.291862) (xy 401.009867 -310.246586)
			(xy 400.99809 -310.198802) (xy 400.99413 -310.149748) (xy 400.655282 -310.149748) (xy 400.654787 -310.174355)
			(xy 400.646892 -310.222932) (xy 400.631308 -310.269613) (xy 400.608437 -310.31319) (xy 400.578872 -310.352534)
			(xy 400.543379 -310.386626) (xy 400.502876 -310.414582) (xy 400.458414 -310.43568) (xy 400.411143 -310.449372)
			(xy 400.362288 -310.455304) (xy 400.313113 -310.453323) (xy 400.264894 -310.443479) (xy 400.218878 -310.426027)
			(xy 400.176257 -310.40142) (xy 400.138136 -310.370295) (xy 400.105501 -310.333458) (xy 400.079198 -310.291862)
			(xy 400.059907 -310.246586) (xy 400.04813 -310.198802) (xy 400.04417 -310.149748) (xy 399.705322 -310.149748)
			(xy 399.704827 -310.174355) (xy 399.696932 -310.222932) (xy 399.681348 -310.269613) (xy 399.658477 -310.31319)
			(xy 399.628912 -310.352534) (xy 399.593419 -310.386626) (xy 399.552916 -310.414582) (xy 399.508454 -310.43568)
			(xy 399.461183 -310.449372) (xy 399.412328 -310.455304) (xy 399.363153 -310.453323) (xy 399.314934 -310.443479)
			(xy 399.268918 -310.426027) (xy 399.226297 -310.40142) (xy 399.188176 -310.370295) (xy 399.155541 -310.333458)
			(xy 399.129238 -310.291862) (xy 399.109947 -310.246586) (xy 399.09817 -310.198802) (xy 399.09421 -310.149748)
			(xy 398.755066 -310.149748) (xy 398.752834 -310.19097) (xy 398.742165 -310.23945) (xy 398.723795 -310.285566)
			(xy 398.698206 -310.328102) (xy 398.666072 -310.365938) (xy 398.628241 -310.398078) (xy 398.585709 -310.423673)
			(xy 398.539596 -310.442051) (xy 398.491118 -310.452727) (xy 398.441551 -310.45542) (xy 398.392201 -310.450058)
			(xy 398.344369 -310.436783) (xy 398.299314 -310.415945) (xy 398.258224 -310.388093) (xy 398.222181 -310.35396)
			(xy 398.192135 -310.314446) (xy 398.168877 -310.270592) (xy 398.15302 -310.223553) (xy 398.144982 -310.174568)
			(xy 398.144492 -310.149748) (xy 398.144675 -310.135565) (xy 398.147343 -310.107325) (xy 398.149826 -310.09336)
			(xy 398.152112 -310.080914) (xy 398.144746 -310.057292) (xy 398.067276 -309.979822) (xy 398.043654 -309.972456)
			(xy 398.031208 -309.974742) (xy 398.017241 -309.977213) (xy 397.989002 -309.979889) (xy 397.97482 -309.980076)
			(xy 397.960637 -309.979897) (xy 397.932397 -309.977227) (xy 397.918432 -309.974742) (xy 397.905986 -309.972456)
			(xy 397.882364 -309.979822) (xy 397.804894 -310.057292) (xy 397.797528 -310.080914) (xy 397.799814 -310.09336)
			(xy 397.802295 -310.107325) (xy 397.804964 -310.135565) (xy 397.805148 -310.149748) (xy 397.804626 -310.175003)
			(xy 397.796313 -310.224825) (xy 397.779912 -310.272599) (xy 397.755871 -310.317022) (xy 397.724847 -310.356882)
			(xy 397.687685 -310.391092) (xy 397.645399 -310.418718) (xy 397.599143 -310.439008) (xy 397.550178 -310.451408)
			(xy 397.49984 -310.455579) (xy 397.449502 -310.451408) (xy 397.400537 -310.439008) (xy 397.354281 -310.418718)
			(xy 397.311995 -310.391092) (xy 397.274833 -310.356882) (xy 397.243809 -310.317022) (xy 397.219768 -310.272599)
			(xy 397.203367 -310.224825) (xy 397.195054 -310.175003) (xy 397.194532 -310.149748) (xy 397.194715 -310.135565)
			(xy 397.197383 -310.107325) (xy 397.199866 -310.09336) (xy 397.202152 -310.080914) (xy 397.194786 -310.057292)
			(xy 397.117316 -309.979822) (xy 397.093694 -309.972456) (xy 397.081248 -309.974742) (xy 397.067283 -309.977221)
			(xy 397.039043 -309.979891) (xy 397.02486 -309.980076) (xy 397.010677 -309.979905) (xy 396.982437 -309.977229)
			(xy 396.968472 -309.974742) (xy 396.956026 -309.972456) (xy 396.932404 -309.979822) (xy 396.854934 -310.057292)
			(xy 396.847568 -310.080914) (xy 396.849854 -310.09336) (xy 396.852334 -310.107325) (xy 396.855004 -310.135565)
			(xy 396.855188 -310.149748) (xy 396.85467 -310.174564) (xy 396.846634 -310.22354) (xy 396.83078 -310.270572)
			(xy 396.807526 -310.314419) (xy 396.777485 -310.353926) (xy 396.741449 -310.388053) (xy 396.700366 -310.415901)
			(xy 396.65532 -310.436737) (xy 396.607496 -310.45001) (xy 396.558155 -310.455372) (xy 396.508596 -310.452681)
			(xy 396.460126 -310.442008) (xy 396.41402 -310.423634) (xy 396.371495 -310.398044) (xy 396.333669 -310.365911)
			(xy 396.30154 -310.328083) (xy 396.275953 -310.285555) (xy 396.257584 -310.239448) (xy 396.246916 -310.190976)
			(xy 396.244229 -310.141417) (xy 395.90506 -310.141417) (xy 395.905228 -310.149748) (xy 395.904733 -310.174355)
			(xy 395.896838 -310.222932) (xy 395.881254 -310.269613) (xy 395.858383 -310.31319) (xy 395.828818 -310.352534)
			(xy 395.793325 -310.386626) (xy 395.752822 -310.414582) (xy 395.70836 -310.43568) (xy 395.661089 -310.449372)
			(xy 395.612234 -310.455304) (xy 395.563059 -310.453323) (xy 395.51484 -310.443479) (xy 395.468824 -310.426027)
			(xy 395.426203 -310.40142) (xy 395.388082 -310.370295) (xy 395.355447 -310.333458) (xy 395.329144 -310.291862)
			(xy 395.309853 -310.246586) (xy 395.298076 -310.198802) (xy 395.294116 -310.149748) (xy 394.955268 -310.149748)
			(xy 394.954773 -310.174355) (xy 394.946878 -310.222932) (xy 394.931294 -310.269613) (xy 394.908423 -310.31319)
			(xy 394.878858 -310.352534) (xy 394.843365 -310.386626) (xy 394.802862 -310.414582) (xy 394.7584 -310.43568)
			(xy 394.711129 -310.449372) (xy 394.662274 -310.455304) (xy 394.613099 -310.453323) (xy 394.56488 -310.443479)
			(xy 394.518864 -310.426027) (xy 394.476243 -310.40142) (xy 394.438122 -310.370295) (xy 394.405487 -310.333458)
			(xy 394.379184 -310.291862) (xy 394.359893 -310.246586) (xy 394.348116 -310.198802) (xy 394.344156 -310.149748)
			(xy 394.005308 -310.149748) (xy 394.004813 -310.174355) (xy 393.996918 -310.222932) (xy 393.981334 -310.269613)
			(xy 393.958463 -310.31319) (xy 393.928898 -310.352534) (xy 393.893405 -310.386626) (xy 393.852902 -310.414582)
			(xy 393.80844 -310.43568) (xy 393.761169 -310.449372) (xy 393.712314 -310.455304) (xy 393.663139 -310.453323)
			(xy 393.61492 -310.443479) (xy 393.568904 -310.426027) (xy 393.526283 -310.40142) (xy 393.488162 -310.370295)
			(xy 393.455527 -310.333458) (xy 393.429224 -310.291862) (xy 393.409933 -310.246586) (xy 393.398156 -310.198802)
			(xy 393.394196 -310.149748) (xy 393.055094 -310.149748) (xy 393.054599 -310.174355) (xy 393.046704 -310.222932)
			(xy 393.03112 -310.269613) (xy 393.008249 -310.31319) (xy 392.978684 -310.352534) (xy 392.943191 -310.386626)
			(xy 392.902688 -310.414582) (xy 392.858226 -310.43568) (xy 392.810955 -310.449372) (xy 392.7621 -310.455304)
			(xy 392.712925 -310.453323) (xy 392.664706 -310.443479) (xy 392.61869 -310.426027) (xy 392.576069 -310.40142)
			(xy 392.537948 -310.370295) (xy 392.505313 -310.333458) (xy 392.47901 -310.291862) (xy 392.459719 -310.246586)
			(xy 392.447942 -310.198802) (xy 392.443982 -310.149748) (xy 392.105134 -310.149748) (xy 392.104639 -310.174355)
			(xy 392.096744 -310.222932) (xy 392.08116 -310.269613) (xy 392.058289 -310.31319) (xy 392.028724 -310.352534)
			(xy 391.993231 -310.386626) (xy 391.952728 -310.414582) (xy 391.908266 -310.43568) (xy 391.860995 -310.449372)
			(xy 391.81214 -310.455304) (xy 391.762965 -310.453323) (xy 391.714746 -310.443479) (xy 391.66873 -310.426027)
			(xy 391.626109 -310.40142) (xy 391.587988 -310.370295) (xy 391.555353 -310.333458) (xy 391.52905 -310.291862)
			(xy 391.509759 -310.246586) (xy 391.497982 -310.198802) (xy 391.494022 -310.149748) (xy 391.155174 -310.149748)
			(xy 391.154679 -310.174355) (xy 391.146784 -310.222932) (xy 391.1312 -310.269613) (xy 391.108329 -310.31319)
			(xy 391.078764 -310.352534) (xy 391.043271 -310.386626) (xy 391.002768 -310.414582) (xy 390.958306 -310.43568)
			(xy 390.911035 -310.449372) (xy 390.86218 -310.455304) (xy 390.813005 -310.453323) (xy 390.764786 -310.443479)
			(xy 390.71877 -310.426027) (xy 390.676149 -310.40142) (xy 390.638028 -310.370295) (xy 390.605393 -310.333458)
			(xy 390.57909 -310.291862) (xy 390.559799 -310.246586) (xy 390.548022 -310.198802) (xy 390.544062 -310.149748)
			(xy 390.205214 -310.149748) (xy 390.204719 -310.174355) (xy 390.196824 -310.222932) (xy 390.18124 -310.269613)
			(xy 390.158369 -310.31319) (xy 390.128804 -310.352534) (xy 390.093311 -310.386626) (xy 390.052808 -310.414582)
			(xy 390.008346 -310.43568) (xy 389.961075 -310.449372) (xy 389.91222 -310.455304) (xy 389.863045 -310.453323)
			(xy 389.814826 -310.443479) (xy 389.76881 -310.426027) (xy 389.726189 -310.40142) (xy 389.688068 -310.370295)
			(xy 389.655433 -310.333458) (xy 389.62913 -310.291862) (xy 389.609839 -310.246586) (xy 389.598062 -310.198802)
			(xy 389.594102 -310.149748) (xy 389.255254 -310.149748) (xy 389.254759 -310.174355) (xy 389.246864 -310.222932)
			(xy 389.23128 -310.269613) (xy 389.208409 -310.31319) (xy 389.178844 -310.352534) (xy 389.143351 -310.386626)
			(xy 389.102848 -310.414582) (xy 389.058386 -310.43568) (xy 389.011115 -310.449372) (xy 388.96226 -310.455304)
			(xy 388.913085 -310.453323) (xy 388.864866 -310.443479) (xy 388.81885 -310.426027) (xy 388.776229 -310.40142)
			(xy 388.738108 -310.370295) (xy 388.705473 -310.333458) (xy 388.67917 -310.291862) (xy 388.659879 -310.246586)
			(xy 388.648102 -310.198802) (xy 388.644142 -310.149748) (xy 388.305294 -310.149748) (xy 388.304799 -310.174355)
			(xy 388.296904 -310.222932) (xy 388.28132 -310.269613) (xy 388.258449 -310.31319) (xy 388.228884 -310.352534)
			(xy 388.193391 -310.386626) (xy 388.152888 -310.414582) (xy 388.108426 -310.43568) (xy 388.061155 -310.449372)
			(xy 388.0123 -310.455304) (xy 387.963125 -310.453323) (xy 387.914906 -310.443479) (xy 387.86889 -310.426027)
			(xy 387.826269 -310.40142) (xy 387.788148 -310.370295) (xy 387.755513 -310.333458) (xy 387.72921 -310.291862)
			(xy 387.709919 -310.246586) (xy 387.698142 -310.198802) (xy 387.694182 -310.149748) (xy 387.355334 -310.149748)
			(xy 387.354839 -310.174355) (xy 387.346944 -310.222932) (xy 387.33136 -310.269613) (xy 387.308489 -310.31319)
			(xy 387.278924 -310.352534) (xy 387.243431 -310.386626) (xy 387.202928 -310.414582) (xy 387.158466 -310.43568)
			(xy 387.111195 -310.449372) (xy 387.06234 -310.455304) (xy 387.013165 -310.453323) (xy 386.964946 -310.443479)
			(xy 386.91893 -310.426027) (xy 386.876309 -310.40142) (xy 386.838188 -310.370295) (xy 386.805553 -310.333458)
			(xy 386.77925 -310.291862) (xy 386.759959 -310.246586) (xy 386.748182 -310.198802) (xy 386.744222 -310.149748)
			(xy 386.40512 -310.149748) (xy 386.404625 -310.174355) (xy 386.39673 -310.222932) (xy 386.381146 -310.269613)
			(xy 386.358275 -310.31319) (xy 386.32871 -310.352534) (xy 386.293217 -310.386626) (xy 386.252714 -310.414582)
			(xy 386.208252 -310.43568) (xy 386.160981 -310.449372) (xy 386.112126 -310.455304) (xy 386.062951 -310.453323)
			(xy 386.014732 -310.443479) (xy 385.968716 -310.426027) (xy 385.926095 -310.40142) (xy 385.887974 -310.370295)
			(xy 385.855339 -310.333458) (xy 385.829036 -310.291862) (xy 385.809745 -310.246586) (xy 385.797968 -310.198802)
			(xy 385.794008 -310.149748) (xy 385.45516 -310.149748) (xy 385.454665 -310.174355) (xy 385.44677 -310.222932)
			(xy 385.431186 -310.269613) (xy 385.408315 -310.31319) (xy 385.37875 -310.352534) (xy 385.343257 -310.386626)
			(xy 385.302754 -310.414582) (xy 385.258292 -310.43568) (xy 385.211021 -310.449372) (xy 385.162166 -310.455304)
			(xy 385.112991 -310.453323) (xy 385.064772 -310.443479) (xy 385.018756 -310.426027) (xy 384.976135 -310.40142)
			(xy 384.938014 -310.370295) (xy 384.905379 -310.333458) (xy 384.879076 -310.291862) (xy 384.859785 -310.246586)
			(xy 384.848008 -310.198802) (xy 384.844048 -310.149748) (xy 384.504941 -310.149748) (xy 384.504946 -310.150002)
			(xy 384.504451 -310.174609) (xy 384.496556 -310.223186) (xy 384.480972 -310.269867) (xy 384.458101 -310.313444)
			(xy 384.428536 -310.352788) (xy 384.393043 -310.38688) (xy 384.35254 -310.414836) (xy 384.308078 -310.435934)
			(xy 384.260807 -310.449626) (xy 384.211952 -310.455558) (xy 384.162777 -310.453577) (xy 384.114558 -310.443733)
			(xy 384.068542 -310.426281) (xy 384.025921 -310.401674) (xy 383.9878 -310.370549) (xy 383.955165 -310.333712)
			(xy 383.928862 -310.292116) (xy 383.909571 -310.24684) (xy 383.897794 -310.199056) (xy 383.893834 -310.150002)
			(xy 383.407541 -310.150002) (xy 383.387573 -310.172288) (xy 383.344705 -310.207963) (xy 383.297099 -310.237017)
			(xy 383.24577 -310.258829) (xy 383.191813 -310.272935) (xy 383.136376 -310.279035) (xy 383.080642 -310.276998)
			(xy 383.025799 -310.266868) (xy 382.973015 -310.248861) (xy 382.923415 -310.22336) (xy 382.878057 -310.190909)
			(xy 382.837908 -310.1522) (xy 382.803822 -310.108057) (xy 382.776526 -310.059422) (xy 382.756603 -310.007331)
			(xy 382.744477 -309.952894) (xy 382.740406 -309.897272) (xy 351.831402 -309.897272) (xy 351.831402 -310.437276)
			(xy 357.436926 -310.437276) (xy 357.440997 -310.381654) (xy 357.453123 -310.327217) (xy 357.473046 -310.275126)
			(xy 357.500342 -310.226491) (xy 357.534428 -310.182348) (xy 357.574577 -310.143639) (xy 357.619935 -310.111188)
			(xy 357.669535 -310.085687) (xy 357.722319 -310.06768) (xy 357.777162 -310.05755) (xy 357.832896 -310.055513)
			(xy 357.888333 -310.061613) (xy 357.94229 -310.075719) (xy 357.993619 -310.097531) (xy 358.041225 -310.126585)
			(xy 358.084093 -310.16226) (xy 358.12131 -310.203797) (xy 358.152083 -310.25031) (xy 358.175755 -310.300807)
			(xy 358.191823 -310.354214) (xy 358.199943 -310.40939) (xy 358.200452 -310.437276) (xy 358.452926 -310.437276)
			(xy 358.456997 -310.381654) (xy 358.469123 -310.327217) (xy 358.489046 -310.275126) (xy 358.516342 -310.226491)
			(xy 358.550428 -310.182348) (xy 358.590577 -310.143639) (xy 358.635935 -310.111188) (xy 358.685535 -310.085687)
			(xy 358.738319 -310.06768) (xy 358.793162 -310.05755) (xy 358.848896 -310.055513) (xy 358.904333 -310.061613)
			(xy 358.95829 -310.075719) (xy 359.009619 -310.097531) (xy 359.057225 -310.126585) (xy 359.100093 -310.16226)
			(xy 359.13731 -310.203797) (xy 359.168083 -310.25031) (xy 359.191755 -310.300807) (xy 359.207823 -310.354214)
			(xy 359.215943 -310.40939) (xy 359.216452 -310.437276) (xy 359.468926 -310.437276) (xy 359.472997 -310.381654)
			(xy 359.485123 -310.327217) (xy 359.505046 -310.275126) (xy 359.532342 -310.226491) (xy 359.566428 -310.182348)
			(xy 359.606577 -310.143639) (xy 359.651935 -310.111188) (xy 359.701535 -310.085687) (xy 359.754319 -310.06768)
			(xy 359.809162 -310.05755) (xy 359.864896 -310.055513) (xy 359.920333 -310.061613) (xy 359.97429 -310.075719)
			(xy 360.025619 -310.097531) (xy 360.073225 -310.126585) (xy 360.116093 -310.16226) (xy 360.15331 -310.203797)
			(xy 360.184083 -310.25031) (xy 360.207755 -310.300807) (xy 360.223823 -310.354214) (xy 360.231943 -310.40939)
			(xy 360.232452 -310.437276) (xy 360.484926 -310.437276) (xy 360.488997 -310.381654) (xy 360.501123 -310.327217)
			(xy 360.521046 -310.275126) (xy 360.548342 -310.226491) (xy 360.582428 -310.182348) (xy 360.622577 -310.143639)
			(xy 360.667935 -310.111188) (xy 360.717535 -310.085687) (xy 360.770319 -310.06768) (xy 360.825162 -310.05755)
			(xy 360.880896 -310.055513) (xy 360.936333 -310.061613) (xy 360.99029 -310.075719) (xy 361.041619 -310.097531)
			(xy 361.089225 -310.126585) (xy 361.132093 -310.16226) (xy 361.16931 -310.203797) (xy 361.200083 -310.25031)
			(xy 361.223755 -310.300807) (xy 361.239823 -310.354214) (xy 361.247943 -310.40939) (xy 361.248452 -310.437276)
			(xy 361.500926 -310.437276) (xy 361.504997 -310.381654) (xy 361.517123 -310.327217) (xy 361.537046 -310.275126)
			(xy 361.564342 -310.226491) (xy 361.598428 -310.182348) (xy 361.638577 -310.143639) (xy 361.683935 -310.111188)
			(xy 361.733535 -310.085687) (xy 361.786319 -310.06768) (xy 361.841162 -310.05755) (xy 361.896896 -310.055513)
			(xy 361.952333 -310.061613) (xy 362.00629 -310.075719) (xy 362.057619 -310.097531) (xy 362.105225 -310.126585)
			(xy 362.148093 -310.16226) (xy 362.18531 -310.203797) (xy 362.216083 -310.25031) (xy 362.239755 -310.300807)
			(xy 362.255823 -310.354214) (xy 362.263943 -310.40939) (xy 362.264452 -310.437276) (xy 362.516926 -310.437276)
			(xy 362.520997 -310.381654) (xy 362.533123 -310.327217) (xy 362.553046 -310.275126) (xy 362.580342 -310.226491)
			(xy 362.614428 -310.182348) (xy 362.654577 -310.143639) (xy 362.699935 -310.111188) (xy 362.749535 -310.085687)
			(xy 362.802319 -310.06768) (xy 362.857162 -310.05755) (xy 362.912896 -310.055513) (xy 362.968333 -310.061613)
			(xy 363.02229 -310.075719) (xy 363.073619 -310.097531) (xy 363.121225 -310.126585) (xy 363.164093 -310.16226)
			(xy 363.20131 -310.203797) (xy 363.232083 -310.25031) (xy 363.255755 -310.300807) (xy 363.271823 -310.354214)
			(xy 363.279943 -310.40939) (xy 363.280452 -310.437276) (xy 363.532926 -310.437276) (xy 363.536997 -310.381654)
			(xy 363.549123 -310.327217) (xy 363.569046 -310.275126) (xy 363.596342 -310.226491) (xy 363.630428 -310.182348)
			(xy 363.670577 -310.143639) (xy 363.715935 -310.111188) (xy 363.765535 -310.085687) (xy 363.818319 -310.06768)
			(xy 363.873162 -310.05755) (xy 363.928896 -310.055513) (xy 363.984333 -310.061613) (xy 364.03829 -310.075719)
			(xy 364.089619 -310.097531) (xy 364.137225 -310.126585) (xy 364.180093 -310.16226) (xy 364.21731 -310.203797)
			(xy 364.248083 -310.25031) (xy 364.271755 -310.300807) (xy 364.287823 -310.354214) (xy 364.295943 -310.40939)
			(xy 364.296452 -310.437276) (xy 364.548926 -310.437276) (xy 364.552997 -310.381654) (xy 364.565123 -310.327217)
			(xy 364.585046 -310.275126) (xy 364.612342 -310.226491) (xy 364.646428 -310.182348) (xy 364.686577 -310.143639)
			(xy 364.731935 -310.111188) (xy 364.781535 -310.085687) (xy 364.834319 -310.06768) (xy 364.889162 -310.05755)
			(xy 364.944896 -310.055513) (xy 365.000333 -310.061613) (xy 365.05429 -310.075719) (xy 365.105619 -310.097531)
			(xy 365.153225 -310.126585) (xy 365.196093 -310.16226) (xy 365.23331 -310.203797) (xy 365.264083 -310.25031)
			(xy 365.287755 -310.300807) (xy 365.303823 -310.354214) (xy 365.311943 -310.40939) (xy 365.312452 -310.437276)
			(xy 365.311943 -310.465162) (xy 365.303823 -310.520338) (xy 365.287755 -310.573745) (xy 365.264083 -310.624242)
			(xy 365.23331 -310.670755) (xy 365.196093 -310.712292) (xy 365.153225 -310.747967) (xy 365.105619 -310.777021)
			(xy 365.05429 -310.798833) (xy 365.000333 -310.812939) (xy 364.944896 -310.819039) (xy 364.889162 -310.817002)
			(xy 364.834319 -310.806872) (xy 364.781535 -310.788865) (xy 364.731935 -310.763364) (xy 364.686577 -310.730913)
			(xy 364.646428 -310.692204) (xy 364.612342 -310.648061) (xy 364.585046 -310.599426) (xy 364.565123 -310.547335)
			(xy 364.552997 -310.492898) (xy 364.548926 -310.437276) (xy 364.296452 -310.437276) (xy 364.295943 -310.465162)
			(xy 364.287823 -310.520338) (xy 364.271755 -310.573745) (xy 364.248083 -310.624242) (xy 364.21731 -310.670755)
			(xy 364.180093 -310.712292) (xy 364.137225 -310.747967) (xy 364.089619 -310.777021) (xy 364.03829 -310.798833)
			(xy 363.984333 -310.812939) (xy 363.928896 -310.819039) (xy 363.873162 -310.817002) (xy 363.818319 -310.806872)
			(xy 363.765535 -310.788865) (xy 363.715935 -310.763364) (xy 363.670577 -310.730913) (xy 363.630428 -310.692204)
			(xy 363.596342 -310.648061) (xy 363.569046 -310.599426) (xy 363.549123 -310.547335) (xy 363.536997 -310.492898)
			(xy 363.532926 -310.437276) (xy 363.280452 -310.437276) (xy 363.279943 -310.465162) (xy 363.271823 -310.520338)
			(xy 363.255755 -310.573745) (xy 363.232083 -310.624242) (xy 363.20131 -310.670755) (xy 363.164093 -310.712292)
			(xy 363.121225 -310.747967) (xy 363.073619 -310.777021) (xy 363.02229 -310.798833) (xy 362.968333 -310.812939)
			(xy 362.912896 -310.819039) (xy 362.857162 -310.817002) (xy 362.802319 -310.806872) (xy 362.749535 -310.788865)
			(xy 362.699935 -310.763364) (xy 362.654577 -310.730913) (xy 362.614428 -310.692204) (xy 362.580342 -310.648061)
			(xy 362.553046 -310.599426) (xy 362.533123 -310.547335) (xy 362.520997 -310.492898) (xy 362.516926 -310.437276)
			(xy 362.264452 -310.437276) (xy 362.263943 -310.465162) (xy 362.255823 -310.520338) (xy 362.239755 -310.573745)
			(xy 362.216083 -310.624242) (xy 362.18531 -310.670755) (xy 362.148093 -310.712292) (xy 362.105225 -310.747967)
			(xy 362.057619 -310.777021) (xy 362.00629 -310.798833) (xy 361.952333 -310.812939) (xy 361.896896 -310.819039)
			(xy 361.841162 -310.817002) (xy 361.786319 -310.806872) (xy 361.733535 -310.788865) (xy 361.683935 -310.763364)
			(xy 361.638577 -310.730913) (xy 361.598428 -310.692204) (xy 361.564342 -310.648061) (xy 361.537046 -310.599426)
			(xy 361.517123 -310.547335) (xy 361.504997 -310.492898) (xy 361.500926 -310.437276) (xy 361.248452 -310.437276)
			(xy 361.247943 -310.465162) (xy 361.239823 -310.520338) (xy 361.223755 -310.573745) (xy 361.200083 -310.624242)
			(xy 361.16931 -310.670755) (xy 361.132093 -310.712292) (xy 361.089225 -310.747967) (xy 361.041619 -310.777021)
			(xy 360.99029 -310.798833) (xy 360.936333 -310.812939) (xy 360.880896 -310.819039) (xy 360.825162 -310.817002)
			(xy 360.770319 -310.806872) (xy 360.717535 -310.788865) (xy 360.667935 -310.763364) (xy 360.622577 -310.730913)
			(xy 360.582428 -310.692204) (xy 360.548342 -310.648061) (xy 360.521046 -310.599426) (xy 360.501123 -310.547335)
			(xy 360.488997 -310.492898) (xy 360.484926 -310.437276) (xy 360.232452 -310.437276) (xy 360.231943 -310.465162)
			(xy 360.223823 -310.520338) (xy 360.207755 -310.573745) (xy 360.184083 -310.624242) (xy 360.15331 -310.670755)
			(xy 360.116093 -310.712292) (xy 360.073225 -310.747967) (xy 360.025619 -310.777021) (xy 359.97429 -310.798833)
			(xy 359.920333 -310.812939) (xy 359.864896 -310.819039) (xy 359.809162 -310.817002) (xy 359.754319 -310.806872)
			(xy 359.701535 -310.788865) (xy 359.651935 -310.763364) (xy 359.606577 -310.730913) (xy 359.566428 -310.692204)
			(xy 359.532342 -310.648061) (xy 359.505046 -310.599426) (xy 359.485123 -310.547335) (xy 359.472997 -310.492898)
			(xy 359.468926 -310.437276) (xy 359.216452 -310.437276) (xy 359.215943 -310.465162) (xy 359.207823 -310.520338)
			(xy 359.191755 -310.573745) (xy 359.168083 -310.624242) (xy 359.13731 -310.670755) (xy 359.100093 -310.712292)
			(xy 359.057225 -310.747967) (xy 359.009619 -310.777021) (xy 358.95829 -310.798833) (xy 358.904333 -310.812939)
			(xy 358.848896 -310.819039) (xy 358.793162 -310.817002) (xy 358.738319 -310.806872) (xy 358.685535 -310.788865)
			(xy 358.635935 -310.763364) (xy 358.590577 -310.730913) (xy 358.550428 -310.692204) (xy 358.516342 -310.648061)
			(xy 358.489046 -310.599426) (xy 358.469123 -310.547335) (xy 358.456997 -310.492898) (xy 358.452926 -310.437276)
			(xy 358.200452 -310.437276) (xy 358.199943 -310.465162) (xy 358.191823 -310.520338) (xy 358.175755 -310.573745)
			(xy 358.152083 -310.624242) (xy 358.12131 -310.670755) (xy 358.084093 -310.712292) (xy 358.041225 -310.747967)
			(xy 357.993619 -310.777021) (xy 357.94229 -310.798833) (xy 357.888333 -310.812939) (xy 357.832896 -310.819039)
			(xy 357.777162 -310.817002) (xy 357.722319 -310.806872) (xy 357.669535 -310.788865) (xy 357.619935 -310.763364)
			(xy 357.574577 -310.730913) (xy 357.534428 -310.692204) (xy 357.500342 -310.648061) (xy 357.473046 -310.599426)
			(xy 357.453123 -310.547335) (xy 357.440997 -310.492898) (xy 357.436926 -310.437276) (xy 351.831402 -310.437276)
			(xy 351.831402 -310.832246) (xy 376.567952 -310.832246) (xy 376.572023 -310.776624) (xy 376.584149 -310.722187)
			(xy 376.604072 -310.670096) (xy 376.631368 -310.621461) (xy 376.665454 -310.577318) (xy 376.705603 -310.538609)
			(xy 376.750961 -310.506158) (xy 376.800561 -310.480657) (xy 376.853345 -310.46265) (xy 376.908188 -310.45252)
			(xy 376.963922 -310.450483) (xy 377.019359 -310.456583) (xy 377.073316 -310.470689) (xy 377.124645 -310.492501)
			(xy 377.172251 -310.521555) (xy 377.215119 -310.55723) (xy 377.252336 -310.598767) (xy 377.283109 -310.64528)
			(xy 377.306781 -310.695777) (xy 377.322849 -310.749184) (xy 377.330969 -310.80436) (xy 377.331478 -310.832246)
			(xy 377.330969 -310.860132) (xy 377.322849 -310.915308) (xy 377.306781 -310.968715) (xy 377.284667 -311.015888)
			(xy 382.57175 -311.015888) (xy 382.575821 -310.960266) (xy 382.587947 -310.905829) (xy 382.60787 -310.853738)
			(xy 382.635166 -310.805103) (xy 382.669252 -310.76096) (xy 382.709401 -310.722251) (xy 382.754759 -310.6898)
			(xy 382.804359 -310.664299) (xy 382.857143 -310.646292) (xy 382.911986 -310.636162) (xy 382.96772 -310.634125)
			(xy 383.023157 -310.640225) (xy 383.077114 -310.654331) (xy 383.128443 -310.676143) (xy 383.176049 -310.705197)
			(xy 383.218917 -310.740872) (xy 383.256134 -310.782409) (xy 383.286907 -310.828922) (xy 383.310579 -310.879419)
			(xy 383.326647 -310.932826) (xy 383.334767 -310.988002) (xy 383.335276 -311.015888) (xy 383.334767 -311.043774)
			(xy 383.326647 -311.09895) (xy 383.326343 -311.099962) (xy 384.844048 -311.099962) (xy 384.848008 -311.050908)
			(xy 384.859785 -311.003124) (xy 384.879076 -310.957848) (xy 384.905379 -310.916252) (xy 384.938014 -310.879415)
			(xy 384.976135 -310.84829) (xy 385.018756 -310.823683) (xy 385.064772 -310.806231) (xy 385.112991 -310.796387)
			(xy 385.162166 -310.794406) (xy 385.211021 -310.800338) (xy 385.258292 -310.81403) (xy 385.302754 -310.835128)
			(xy 385.343257 -310.863084) (xy 385.37875 -310.897176) (xy 385.408315 -310.93652) (xy 385.431186 -310.980097)
			(xy 385.44677 -311.026778) (xy 385.454665 -311.075355) (xy 385.45516 -311.099962) (xy 385.794008 -311.099962)
			(xy 385.797968 -311.050908) (xy 385.809745 -311.003124) (xy 385.829036 -310.957848) (xy 385.855339 -310.916252)
			(xy 385.887974 -310.879415) (xy 385.926095 -310.84829) (xy 385.968716 -310.823683) (xy 386.014732 -310.806231)
			(xy 386.062951 -310.796387) (xy 386.112126 -310.794406) (xy 386.160981 -310.800338) (xy 386.208252 -310.81403)
			(xy 386.252714 -310.835128) (xy 386.293217 -310.863084) (xy 386.32871 -310.897176) (xy 386.358275 -310.93652)
			(xy 386.381146 -310.980097) (xy 386.39673 -311.026778) (xy 386.404625 -311.075355) (xy 386.40512 -311.099962)
			(xy 386.744222 -311.099962) (xy 386.748182 -311.050908) (xy 386.759959 -311.003124) (xy 386.77925 -310.957848)
			(xy 386.805553 -310.916252) (xy 386.838188 -310.879415) (xy 386.876309 -310.84829) (xy 386.91893 -310.823683)
			(xy 386.964946 -310.806231) (xy 387.013165 -310.796387) (xy 387.06234 -310.794406) (xy 387.111195 -310.800338)
			(xy 387.158466 -310.81403) (xy 387.202928 -310.835128) (xy 387.243431 -310.863084) (xy 387.278924 -310.897176)
			(xy 387.308489 -310.93652) (xy 387.33136 -310.980097) (xy 387.346944 -311.026778) (xy 387.354839 -311.075355)
			(xy 387.355334 -311.099962) (xy 387.694182 -311.099962) (xy 387.698142 -311.050908) (xy 387.709919 -311.003124)
			(xy 387.72921 -310.957848) (xy 387.755513 -310.916252) (xy 387.788148 -310.879415) (xy 387.826269 -310.84829)
			(xy 387.86889 -310.823683) (xy 387.914906 -310.806231) (xy 387.963125 -310.796387) (xy 388.0123 -310.794406)
			(xy 388.061155 -310.800338) (xy 388.108426 -310.81403) (xy 388.152888 -310.835128) (xy 388.193391 -310.863084)
			(xy 388.228884 -310.897176) (xy 388.258449 -310.93652) (xy 388.28132 -310.980097) (xy 388.296904 -311.026778)
			(xy 388.304799 -311.075355) (xy 388.305294 -311.099962) (xy 388.644142 -311.099962) (xy 388.648102 -311.050908)
			(xy 388.659879 -311.003124) (xy 388.67917 -310.957848) (xy 388.705473 -310.916252) (xy 388.738108 -310.879415)
			(xy 388.776229 -310.84829) (xy 388.81885 -310.823683) (xy 388.864866 -310.806231) (xy 388.913085 -310.796387)
			(xy 388.96226 -310.794406) (xy 389.011115 -310.800338) (xy 389.058386 -310.81403) (xy 389.102848 -310.835128)
			(xy 389.143351 -310.863084) (xy 389.178844 -310.897176) (xy 389.208409 -310.93652) (xy 389.23128 -310.980097)
			(xy 389.246864 -311.026778) (xy 389.254759 -311.075355) (xy 389.255254 -311.099962) (xy 389.594102 -311.099962)
			(xy 389.598062 -311.050908) (xy 389.609839 -311.003124) (xy 389.62913 -310.957848) (xy 389.655433 -310.916252)
			(xy 389.688068 -310.879415) (xy 389.726189 -310.84829) (xy 389.76881 -310.823683) (xy 389.814826 -310.806231)
			(xy 389.863045 -310.796387) (xy 389.91222 -310.794406) (xy 389.961075 -310.800338) (xy 390.008346 -310.81403)
			(xy 390.052808 -310.835128) (xy 390.093311 -310.863084) (xy 390.128804 -310.897176) (xy 390.158369 -310.93652)
			(xy 390.18124 -310.980097) (xy 390.196824 -311.026778) (xy 390.204719 -311.075355) (xy 390.205214 -311.099962)
			(xy 390.544062 -311.099962) (xy 390.548022 -311.050908) (xy 390.559799 -311.003124) (xy 390.57909 -310.957848)
			(xy 390.605393 -310.916252) (xy 390.638028 -310.879415) (xy 390.676149 -310.84829) (xy 390.71877 -310.823683)
			(xy 390.764786 -310.806231) (xy 390.813005 -310.796387) (xy 390.86218 -310.794406) (xy 390.911035 -310.800338)
			(xy 390.958306 -310.81403) (xy 391.002768 -310.835128) (xy 391.043271 -310.863084) (xy 391.078764 -310.897176)
			(xy 391.108329 -310.93652) (xy 391.1312 -310.980097) (xy 391.146784 -311.026778) (xy 391.154679 -311.075355)
			(xy 391.155174 -311.099962) (xy 391.494022 -311.099962) (xy 391.497982 -311.050908) (xy 391.509759 -311.003124)
			(xy 391.52905 -310.957848) (xy 391.555353 -310.916252) (xy 391.587988 -310.879415) (xy 391.626109 -310.84829)
			(xy 391.66873 -310.823683) (xy 391.714746 -310.806231) (xy 391.762965 -310.796387) (xy 391.81214 -310.794406)
			(xy 391.860995 -310.800338) (xy 391.908266 -310.81403) (xy 391.952728 -310.835128) (xy 391.993231 -310.863084)
			(xy 392.028724 -310.897176) (xy 392.058289 -310.93652) (xy 392.08116 -310.980097) (xy 392.096744 -311.026778)
			(xy 392.104639 -311.075355) (xy 392.105134 -311.099962) (xy 392.443982 -311.099962) (xy 392.447942 -311.050908)
			(xy 392.459719 -311.003124) (xy 392.47901 -310.957848) (xy 392.505313 -310.916252) (xy 392.537948 -310.879415)
			(xy 392.576069 -310.84829) (xy 392.61869 -310.823683) (xy 392.664706 -310.806231) (xy 392.712925 -310.796387)
			(xy 392.7621 -310.794406) (xy 392.810955 -310.800338) (xy 392.858226 -310.81403) (xy 392.902688 -310.835128)
			(xy 392.943191 -310.863084) (xy 392.978684 -310.897176) (xy 393.008249 -310.93652) (xy 393.03112 -310.980097)
			(xy 393.046704 -311.026778) (xy 393.054599 -311.075355) (xy 393.055094 -311.099962) (xy 393.394196 -311.099962)
			(xy 393.398156 -311.050908) (xy 393.409933 -311.003124) (xy 393.429224 -310.957848) (xy 393.455527 -310.916252)
			(xy 393.488162 -310.879415) (xy 393.526283 -310.84829) (xy 393.568904 -310.823683) (xy 393.61492 -310.806231)
			(xy 393.663139 -310.796387) (xy 393.712314 -310.794406) (xy 393.761169 -310.800338) (xy 393.80844 -310.81403)
			(xy 393.852902 -310.835128) (xy 393.893405 -310.863084) (xy 393.928898 -310.897176) (xy 393.958463 -310.93652)
			(xy 393.981334 -310.980097) (xy 393.996918 -311.026778) (xy 394.004813 -311.075355) (xy 394.005308 -311.099962)
			(xy 394.344156 -311.099962) (xy 394.348116 -311.050908) (xy 394.359893 -311.003124) (xy 394.379184 -310.957848)
			(xy 394.405487 -310.916252) (xy 394.438122 -310.879415) (xy 394.476243 -310.84829) (xy 394.518864 -310.823683)
			(xy 394.56488 -310.806231) (xy 394.613099 -310.796387) (xy 394.662274 -310.794406) (xy 394.711129 -310.800338)
			(xy 394.7584 -310.81403) (xy 394.802862 -310.835128) (xy 394.843365 -310.863084) (xy 394.878858 -310.897176)
			(xy 394.908423 -310.93652) (xy 394.931294 -310.980097) (xy 394.946878 -311.026778) (xy 394.954773 -311.075355)
			(xy 394.955268 -311.099962) (xy 395.294116 -311.099962) (xy 395.298076 -311.050908) (xy 395.309853 -311.003124)
			(xy 395.329144 -310.957848) (xy 395.355447 -310.916252) (xy 395.388082 -310.879415) (xy 395.426203 -310.84829)
			(xy 395.468824 -310.823683) (xy 395.51484 -310.806231) (xy 395.563059 -310.796387) (xy 395.612234 -310.794406)
			(xy 395.661089 -310.800338) (xy 395.70836 -310.81403) (xy 395.752822 -310.835128) (xy 395.793325 -310.863084)
			(xy 395.828818 -310.897176) (xy 395.858383 -310.93652) (xy 395.881254 -310.980097) (xy 395.896838 -311.026778)
			(xy 395.904733 -311.075355) (xy 395.905228 -311.099962) (xy 396.244076 -311.099962) (xy 396.248036 -311.050908)
			(xy 396.259813 -311.003124) (xy 396.279104 -310.957848) (xy 396.305407 -310.916252) (xy 396.338042 -310.879415)
			(xy 396.376163 -310.84829) (xy 396.418784 -310.823683) (xy 396.4648 -310.806231) (xy 396.513019 -310.796387)
			(xy 396.562194 -310.794406) (xy 396.611049 -310.800338) (xy 396.65832 -310.81403) (xy 396.702782 -310.835128)
			(xy 396.743285 -310.863084) (xy 396.778778 -310.897176) (xy 396.808343 -310.93652) (xy 396.831214 -310.980097)
			(xy 396.846798 -311.026778) (xy 396.854693 -311.075355) (xy 396.855188 -311.099962) (xy 397.194036 -311.099962)
			(xy 397.197996 -311.050908) (xy 397.209773 -311.003124) (xy 397.229064 -310.957848) (xy 397.255367 -310.916252)
			(xy 397.288002 -310.879415) (xy 397.326123 -310.84829) (xy 397.368744 -310.823683) (xy 397.41476 -310.806231)
			(xy 397.462979 -310.796387) (xy 397.512154 -310.794406) (xy 397.561009 -310.800338) (xy 397.60828 -310.81403)
			(xy 397.652742 -310.835128) (xy 397.693245 -310.863084) (xy 397.728738 -310.897176) (xy 397.758303 -310.93652)
			(xy 397.781174 -310.980097) (xy 397.796758 -311.026778) (xy 397.804653 -311.075355) (xy 397.805148 -311.099962)
			(xy 398.143996 -311.099962) (xy 398.147956 -311.050908) (xy 398.159733 -311.003124) (xy 398.179024 -310.957848)
			(xy 398.205327 -310.916252) (xy 398.237962 -310.879415) (xy 398.276083 -310.84829) (xy 398.318704 -310.823683)
			(xy 398.36472 -310.806231) (xy 398.412939 -310.796387) (xy 398.462114 -310.794406) (xy 398.510969 -310.800338)
			(xy 398.55824 -310.81403) (xy 398.602702 -310.835128) (xy 398.643205 -310.863084) (xy 398.678698 -310.897176)
			(xy 398.708263 -310.93652) (xy 398.731134 -310.980097) (xy 398.746718 -311.026778) (xy 398.754613 -311.075355)
			(xy 398.755108 -311.099962) (xy 399.09421 -311.099962) (xy 399.09817 -311.050908) (xy 399.109947 -311.003124)
			(xy 399.129238 -310.957848) (xy 399.155541 -310.916252) (xy 399.188176 -310.879415) (xy 399.226297 -310.84829)
			(xy 399.268918 -310.823683) (xy 399.314934 -310.806231) (xy 399.363153 -310.796387) (xy 399.412328 -310.794406)
			(xy 399.461183 -310.800338) (xy 399.508454 -310.81403) (xy 399.552916 -310.835128) (xy 399.593419 -310.863084)
			(xy 399.628912 -310.897176) (xy 399.658477 -310.93652) (xy 399.681348 -310.980097) (xy 399.696932 -311.026778)
			(xy 399.704827 -311.075355) (xy 399.705322 -311.099962) (xy 400.04417 -311.099962) (xy 400.04813 -311.050908)
			(xy 400.059907 -311.003124) (xy 400.079198 -310.957848) (xy 400.105501 -310.916252) (xy 400.138136 -310.879415)
			(xy 400.176257 -310.84829) (xy 400.218878 -310.823683) (xy 400.264894 -310.806231) (xy 400.313113 -310.796387)
			(xy 400.362288 -310.794406) (xy 400.411143 -310.800338) (xy 400.458414 -310.81403) (xy 400.502876 -310.835128)
			(xy 400.543379 -310.863084) (xy 400.578872 -310.897176) (xy 400.608437 -310.93652) (xy 400.631308 -310.980097)
			(xy 400.646892 -311.026778) (xy 400.654787 -311.075355) (xy 400.655282 -311.099962) (xy 400.99413 -311.099962)
			(xy 400.99809 -311.050908) (xy 401.009867 -311.003124) (xy 401.029158 -310.957848) (xy 401.055461 -310.916252)
			(xy 401.088096 -310.879415) (xy 401.126217 -310.84829) (xy 401.168838 -310.823683) (xy 401.214854 -310.806231)
			(xy 401.263073 -310.796387) (xy 401.312248 -310.794406) (xy 401.361103 -310.800338) (xy 401.408374 -310.81403)
			(xy 401.452836 -310.835128) (xy 401.493339 -310.863084) (xy 401.528832 -310.897176) (xy 401.558397 -310.93652)
			(xy 401.581268 -310.980097) (xy 401.596852 -311.026778) (xy 401.604747 -311.075355) (xy 401.605242 -311.099962)
			(xy 401.94409 -311.099962) (xy 401.94805 -311.050908) (xy 401.959827 -311.003124) (xy 401.979118 -310.957848)
			(xy 402.005421 -310.916252) (xy 402.038056 -310.879415) (xy 402.076177 -310.84829) (xy 402.118798 -310.823683)
			(xy 402.164814 -310.806231) (xy 402.213033 -310.796387) (xy 402.262208 -310.794406) (xy 402.311063 -310.800338)
			(xy 402.358334 -310.81403) (xy 402.402796 -310.835128) (xy 402.443299 -310.863084) (xy 402.478792 -310.897176)
			(xy 402.508357 -310.93652) (xy 402.531228 -310.980097) (xy 402.546812 -311.026778) (xy 402.554707 -311.075355)
			(xy 402.555202 -311.099962) (xy 402.89405 -311.099962) (xy 402.89801 -311.050908) (xy 402.909787 -311.003124)
			(xy 402.929078 -310.957848) (xy 402.955381 -310.916252) (xy 402.988016 -310.879415) (xy 403.026137 -310.84829)
			(xy 403.068758 -310.823683) (xy 403.114774 -310.806231) (xy 403.162993 -310.796387) (xy 403.212168 -310.794406)
			(xy 403.261023 -310.800338) (xy 403.308294 -310.81403) (xy 403.352756 -310.835128) (xy 403.393259 -310.863084)
			(xy 403.428752 -310.897176) (xy 403.458317 -310.93652) (xy 403.481188 -310.980097) (xy 403.496772 -311.026778)
			(xy 403.504667 -311.075355) (xy 403.505162 -311.099962) (xy 403.84401 -311.099962) (xy 403.84797 -311.050908)
			(xy 403.859747 -311.003124) (xy 403.879038 -310.957848) (xy 403.905341 -310.916252) (xy 403.937976 -310.879415)
			(xy 403.976097 -310.84829) (xy 404.018718 -310.823683) (xy 404.064734 -310.806231) (xy 404.112953 -310.796387)
			(xy 404.162128 -310.794406) (xy 404.210983 -310.800338) (xy 404.258254 -310.81403) (xy 404.302716 -310.835128)
			(xy 404.343219 -310.863084) (xy 404.378712 -310.897176) (xy 404.408277 -310.93652) (xy 404.431148 -310.980097)
			(xy 404.446732 -311.026778) (xy 404.454627 -311.075355) (xy 404.455122 -311.099962) (xy 404.794224 -311.099962)
			(xy 404.798184 -311.050908) (xy 404.809961 -311.003124) (xy 404.829252 -310.957848) (xy 404.855555 -310.916252)
			(xy 404.88819 -310.879415) (xy 404.926311 -310.84829) (xy 404.968932 -310.823683) (xy 405.014948 -310.806231)
			(xy 405.063167 -310.796387) (xy 405.112342 -310.794406) (xy 405.161197 -310.800338) (xy 405.208468 -310.81403)
			(xy 405.25293 -310.835128) (xy 405.293433 -310.863084) (xy 405.328926 -310.897176) (xy 405.358491 -310.93652)
			(xy 405.381362 -310.980097) (xy 405.396946 -311.026778) (xy 405.404841 -311.075355) (xy 405.405336 -311.099962)
			(xy 405.744184 -311.099962) (xy 405.748144 -311.050908) (xy 405.759921 -311.003124) (xy 405.779212 -310.957848)
			(xy 405.805515 -310.916252) (xy 405.83815 -310.879415) (xy 405.876271 -310.84829) (xy 405.918892 -310.823683)
			(xy 405.964908 -310.806231) (xy 406.013127 -310.796387) (xy 406.062302 -310.794406) (xy 406.111157 -310.800338)
			(xy 406.158428 -310.81403) (xy 406.20289 -310.835128) (xy 406.243393 -310.863084) (xy 406.278886 -310.897176)
			(xy 406.308451 -310.93652) (xy 406.331322 -310.980097) (xy 406.346906 -311.026778) (xy 406.354801 -311.075355)
			(xy 406.355296 -311.099962) (xy 406.694144 -311.099962) (xy 406.698104 -311.050908) (xy 406.709881 -311.003124)
			(xy 406.729172 -310.957848) (xy 406.755475 -310.916252) (xy 406.78811 -310.879415) (xy 406.826231 -310.84829)
			(xy 406.868852 -310.823683) (xy 406.914868 -310.806231) (xy 406.963087 -310.796387) (xy 407.012262 -310.794406)
			(xy 407.061117 -310.800338) (xy 407.108388 -310.81403) (xy 407.15285 -310.835128) (xy 407.193353 -310.863084)
			(xy 407.228846 -310.897176) (xy 407.258411 -310.93652) (xy 407.281282 -310.980097) (xy 407.296866 -311.026778)
			(xy 407.304761 -311.075355) (xy 407.305256 -311.099962) (xy 407.644104 -311.099962) (xy 407.648064 -311.050908)
			(xy 407.659841 -311.003124) (xy 407.679132 -310.957848) (xy 407.705435 -310.916252) (xy 407.73807 -310.879415)
			(xy 407.776191 -310.84829) (xy 407.818812 -310.823683) (xy 407.864828 -310.806231) (xy 407.913047 -310.796387)
			(xy 407.962222 -310.794406) (xy 408.011077 -310.800338) (xy 408.058348 -310.81403) (xy 408.10281 -310.835128)
			(xy 408.143313 -310.863084) (xy 408.178806 -310.897176) (xy 408.208371 -310.93652) (xy 408.231242 -310.980097)
			(xy 408.246826 -311.026778) (xy 408.254721 -311.075355) (xy 408.255216 -311.099962) (xy 408.254721 -311.124569)
			(xy 408.246826 -311.173146) (xy 408.231242 -311.219827) (xy 408.208371 -311.263404) (xy 408.178806 -311.302748)
			(xy 408.143313 -311.33684) (xy 408.10281 -311.364796) (xy 408.058348 -311.385894) (xy 408.011077 -311.399586)
			(xy 407.962222 -311.405518) (xy 407.913047 -311.403537) (xy 407.864828 -311.393693) (xy 407.818812 -311.376241)
			(xy 407.776191 -311.351634) (xy 407.73807 -311.320509) (xy 407.705435 -311.283672) (xy 407.679132 -311.242076)
			(xy 407.659841 -311.1968) (xy 407.648064 -311.149016) (xy 407.644104 -311.099962) (xy 407.305256 -311.099962)
			(xy 407.304761 -311.124569) (xy 407.296866 -311.173146) (xy 407.281282 -311.219827) (xy 407.258411 -311.263404)
			(xy 407.228846 -311.302748) (xy 407.193353 -311.33684) (xy 407.15285 -311.364796) (xy 407.108388 -311.385894)
			(xy 407.061117 -311.399586) (xy 407.012262 -311.405518) (xy 406.963087 -311.403537) (xy 406.914868 -311.393693)
			(xy 406.868852 -311.376241) (xy 406.826231 -311.351634) (xy 406.78811 -311.320509) (xy 406.755475 -311.283672)
			(xy 406.729172 -311.242076) (xy 406.709881 -311.1968) (xy 406.698104 -311.149016) (xy 406.694144 -311.099962)
			(xy 406.355296 -311.099962) (xy 406.354801 -311.124569) (xy 406.346906 -311.173146) (xy 406.331322 -311.219827)
			(xy 406.308451 -311.263404) (xy 406.278886 -311.302748) (xy 406.243393 -311.33684) (xy 406.20289 -311.364796)
			(xy 406.158428 -311.385894) (xy 406.111157 -311.399586) (xy 406.062302 -311.405518) (xy 406.013127 -311.403537)
			(xy 405.964908 -311.393693) (xy 405.918892 -311.376241) (xy 405.876271 -311.351634) (xy 405.83815 -311.320509)
			(xy 405.805515 -311.283672) (xy 405.779212 -311.242076) (xy 405.759921 -311.1968) (xy 405.748144 -311.149016)
			(xy 405.744184 -311.099962) (xy 405.405336 -311.099962) (xy 405.404841 -311.124569) (xy 405.396946 -311.173146)
			(xy 405.381362 -311.219827) (xy 405.358491 -311.263404) (xy 405.328926 -311.302748) (xy 405.293433 -311.33684)
			(xy 405.25293 -311.364796) (xy 405.208468 -311.385894) (xy 405.161197 -311.399586) (xy 405.112342 -311.405518)
			(xy 405.063167 -311.403537) (xy 405.014948 -311.393693) (xy 404.968932 -311.376241) (xy 404.926311 -311.351634)
			(xy 404.88819 -311.320509) (xy 404.855555 -311.283672) (xy 404.829252 -311.242076) (xy 404.809961 -311.1968)
			(xy 404.798184 -311.149016) (xy 404.794224 -311.099962) (xy 404.455122 -311.099962) (xy 404.454627 -311.124569)
			(xy 404.446732 -311.173146) (xy 404.431148 -311.219827) (xy 404.408277 -311.263404) (xy 404.378712 -311.302748)
			(xy 404.343219 -311.33684) (xy 404.302716 -311.364796) (xy 404.258254 -311.385894) (xy 404.210983 -311.399586)
			(xy 404.162128 -311.405518) (xy 404.112953 -311.403537) (xy 404.064734 -311.393693) (xy 404.018718 -311.376241)
			(xy 403.976097 -311.351634) (xy 403.937976 -311.320509) (xy 403.905341 -311.283672) (xy 403.879038 -311.242076)
			(xy 403.859747 -311.1968) (xy 403.84797 -311.149016) (xy 403.84401 -311.099962) (xy 403.505162 -311.099962)
			(xy 403.504667 -311.124569) (xy 403.496772 -311.173146) (xy 403.481188 -311.219827) (xy 403.458317 -311.263404)
			(xy 403.428752 -311.302748) (xy 403.393259 -311.33684) (xy 403.352756 -311.364796) (xy 403.308294 -311.385894)
			(xy 403.261023 -311.399586) (xy 403.212168 -311.405518) (xy 403.162993 -311.403537) (xy 403.114774 -311.393693)
			(xy 403.068758 -311.376241) (xy 403.026137 -311.351634) (xy 402.988016 -311.320509) (xy 402.955381 -311.283672)
			(xy 402.929078 -311.242076) (xy 402.909787 -311.1968) (xy 402.89801 -311.149016) (xy 402.89405 -311.099962)
			(xy 402.555202 -311.099962) (xy 402.554707 -311.124569) (xy 402.546812 -311.173146) (xy 402.531228 -311.219827)
			(xy 402.508357 -311.263404) (xy 402.478792 -311.302748) (xy 402.443299 -311.33684) (xy 402.402796 -311.364796)
			(xy 402.358334 -311.385894) (xy 402.311063 -311.399586) (xy 402.262208 -311.405518) (xy 402.213033 -311.403537)
			(xy 402.164814 -311.393693) (xy 402.118798 -311.376241) (xy 402.076177 -311.351634) (xy 402.038056 -311.320509)
			(xy 402.005421 -311.283672) (xy 401.979118 -311.242076) (xy 401.959827 -311.1968) (xy 401.94805 -311.149016)
			(xy 401.94409 -311.099962) (xy 401.605242 -311.099962) (xy 401.604747 -311.124569) (xy 401.596852 -311.173146)
			(xy 401.581268 -311.219827) (xy 401.558397 -311.263404) (xy 401.528832 -311.302748) (xy 401.493339 -311.33684)
			(xy 401.452836 -311.364796) (xy 401.408374 -311.385894) (xy 401.361103 -311.399586) (xy 401.312248 -311.405518)
			(xy 401.263073 -311.403537) (xy 401.214854 -311.393693) (xy 401.168838 -311.376241) (xy 401.126217 -311.351634)
			(xy 401.088096 -311.320509) (xy 401.055461 -311.283672) (xy 401.029158 -311.242076) (xy 401.009867 -311.1968)
			(xy 400.99809 -311.149016) (xy 400.99413 -311.099962) (xy 400.655282 -311.099962) (xy 400.654787 -311.124569)
			(xy 400.646892 -311.173146) (xy 400.631308 -311.219827) (xy 400.608437 -311.263404) (xy 400.578872 -311.302748)
			(xy 400.543379 -311.33684) (xy 400.502876 -311.364796) (xy 400.458414 -311.385894) (xy 400.411143 -311.399586)
			(xy 400.362288 -311.405518) (xy 400.313113 -311.403537) (xy 400.264894 -311.393693) (xy 400.218878 -311.376241)
			(xy 400.176257 -311.351634) (xy 400.138136 -311.320509) (xy 400.105501 -311.283672) (xy 400.079198 -311.242076)
			(xy 400.059907 -311.1968) (xy 400.04813 -311.149016) (xy 400.04417 -311.099962) (xy 399.705322 -311.099962)
			(xy 399.704827 -311.124569) (xy 399.696932 -311.173146) (xy 399.681348 -311.219827) (xy 399.658477 -311.263404)
			(xy 399.628912 -311.302748) (xy 399.593419 -311.33684) (xy 399.552916 -311.364796) (xy 399.508454 -311.385894)
			(xy 399.461183 -311.399586) (xy 399.412328 -311.405518) (xy 399.363153 -311.403537) (xy 399.314934 -311.393693)
			(xy 399.268918 -311.376241) (xy 399.226297 -311.351634) (xy 399.188176 -311.320509) (xy 399.155541 -311.283672)
			(xy 399.129238 -311.242076) (xy 399.109947 -311.1968) (xy 399.09817 -311.149016) (xy 399.09421 -311.099962)
			(xy 398.755108 -311.099962) (xy 398.754613 -311.124569) (xy 398.746718 -311.173146) (xy 398.731134 -311.219827)
			(xy 398.708263 -311.263404) (xy 398.678698 -311.302748) (xy 398.643205 -311.33684) (xy 398.602702 -311.364796)
			(xy 398.55824 -311.385894) (xy 398.510969 -311.399586) (xy 398.462114 -311.405518) (xy 398.412939 -311.403537)
			(xy 398.36472 -311.393693) (xy 398.318704 -311.376241) (xy 398.276083 -311.351634) (xy 398.237962 -311.320509)
			(xy 398.205327 -311.283672) (xy 398.179024 -311.242076) (xy 398.159733 -311.1968) (xy 398.147956 -311.149016)
			(xy 398.143996 -311.099962) (xy 397.805148 -311.099962) (xy 397.804653 -311.124569) (xy 397.796758 -311.173146)
			(xy 397.781174 -311.219827) (xy 397.758303 -311.263404) (xy 397.728738 -311.302748) (xy 397.693245 -311.33684)
			(xy 397.652742 -311.364796) (xy 397.60828 -311.385894) (xy 397.561009 -311.399586) (xy 397.512154 -311.405518)
			(xy 397.462979 -311.403537) (xy 397.41476 -311.393693) (xy 397.368744 -311.376241) (xy 397.326123 -311.351634)
			(xy 397.288002 -311.320509) (xy 397.255367 -311.283672) (xy 397.229064 -311.242076) (xy 397.209773 -311.1968)
			(xy 397.197996 -311.149016) (xy 397.194036 -311.099962) (xy 396.855188 -311.099962) (xy 396.854693 -311.124569)
			(xy 396.846798 -311.173146) (xy 396.831214 -311.219827) (xy 396.808343 -311.263404) (xy 396.778778 -311.302748)
			(xy 396.743285 -311.33684) (xy 396.702782 -311.364796) (xy 396.65832 -311.385894) (xy 396.611049 -311.399586)
			(xy 396.562194 -311.405518) (xy 396.513019 -311.403537) (xy 396.4648 -311.393693) (xy 396.418784 -311.376241)
			(xy 396.376163 -311.351634) (xy 396.338042 -311.320509) (xy 396.305407 -311.283672) (xy 396.279104 -311.242076)
			(xy 396.259813 -311.1968) (xy 396.248036 -311.149016) (xy 396.244076 -311.099962) (xy 395.905228 -311.099962)
			(xy 395.904733 -311.124569) (xy 395.896838 -311.173146) (xy 395.881254 -311.219827) (xy 395.858383 -311.263404)
			(xy 395.828818 -311.302748) (xy 395.793325 -311.33684) (xy 395.752822 -311.364796) (xy 395.70836 -311.385894)
			(xy 395.661089 -311.399586) (xy 395.612234 -311.405518) (xy 395.563059 -311.403537) (xy 395.51484 -311.393693)
			(xy 395.468824 -311.376241) (xy 395.426203 -311.351634) (xy 395.388082 -311.320509) (xy 395.355447 -311.283672)
			(xy 395.329144 -311.242076) (xy 395.309853 -311.1968) (xy 395.298076 -311.149016) (xy 395.294116 -311.099962)
			(xy 394.955268 -311.099962) (xy 394.954773 -311.124569) (xy 394.946878 -311.173146) (xy 394.931294 -311.219827)
			(xy 394.908423 -311.263404) (xy 394.878858 -311.302748) (xy 394.843365 -311.33684) (xy 394.802862 -311.364796)
			(xy 394.7584 -311.385894) (xy 394.711129 -311.399586) (xy 394.662274 -311.405518) (xy 394.613099 -311.403537)
			(xy 394.56488 -311.393693) (xy 394.518864 -311.376241) (xy 394.476243 -311.351634) (xy 394.438122 -311.320509)
			(xy 394.405487 -311.283672) (xy 394.379184 -311.242076) (xy 394.359893 -311.1968) (xy 394.348116 -311.149016)
			(xy 394.344156 -311.099962) (xy 394.005308 -311.099962) (xy 394.004813 -311.124569) (xy 393.996918 -311.173146)
			(xy 393.981334 -311.219827) (xy 393.958463 -311.263404) (xy 393.928898 -311.302748) (xy 393.893405 -311.33684)
			(xy 393.852902 -311.364796) (xy 393.80844 -311.385894) (xy 393.761169 -311.399586) (xy 393.712314 -311.405518)
			(xy 393.663139 -311.403537) (xy 393.61492 -311.393693) (xy 393.568904 -311.376241) (xy 393.526283 -311.351634)
			(xy 393.488162 -311.320509) (xy 393.455527 -311.283672) (xy 393.429224 -311.242076) (xy 393.409933 -311.1968)
			(xy 393.398156 -311.149016) (xy 393.394196 -311.099962) (xy 393.055094 -311.099962) (xy 393.054599 -311.124569)
			(xy 393.046704 -311.173146) (xy 393.03112 -311.219827) (xy 393.008249 -311.263404) (xy 392.978684 -311.302748)
			(xy 392.943191 -311.33684) (xy 392.902688 -311.364796) (xy 392.858226 -311.385894) (xy 392.810955 -311.399586)
			(xy 392.7621 -311.405518) (xy 392.712925 -311.403537) (xy 392.664706 -311.393693) (xy 392.61869 -311.376241)
			(xy 392.576069 -311.351634) (xy 392.537948 -311.320509) (xy 392.505313 -311.283672) (xy 392.47901 -311.242076)
			(xy 392.459719 -311.1968) (xy 392.447942 -311.149016) (xy 392.443982 -311.099962) (xy 392.105134 -311.099962)
			(xy 392.104639 -311.124569) (xy 392.096744 -311.173146) (xy 392.08116 -311.219827) (xy 392.058289 -311.263404)
			(xy 392.028724 -311.302748) (xy 391.993231 -311.33684) (xy 391.952728 -311.364796) (xy 391.908266 -311.385894)
			(xy 391.860995 -311.399586) (xy 391.81214 -311.405518) (xy 391.762965 -311.403537) (xy 391.714746 -311.393693)
			(xy 391.66873 -311.376241) (xy 391.626109 -311.351634) (xy 391.587988 -311.320509) (xy 391.555353 -311.283672)
			(xy 391.52905 -311.242076) (xy 391.509759 -311.1968) (xy 391.497982 -311.149016) (xy 391.494022 -311.099962)
			(xy 391.155174 -311.099962) (xy 391.154679 -311.124569) (xy 391.146784 -311.173146) (xy 391.1312 -311.219827)
			(xy 391.108329 -311.263404) (xy 391.078764 -311.302748) (xy 391.043271 -311.33684) (xy 391.002768 -311.364796)
			(xy 390.958306 -311.385894) (xy 390.911035 -311.399586) (xy 390.86218 -311.405518) (xy 390.813005 -311.403537)
			(xy 390.764786 -311.393693) (xy 390.71877 -311.376241) (xy 390.676149 -311.351634) (xy 390.638028 -311.320509)
			(xy 390.605393 -311.283672) (xy 390.57909 -311.242076) (xy 390.559799 -311.1968) (xy 390.548022 -311.149016)
			(xy 390.544062 -311.099962) (xy 390.205214 -311.099962) (xy 390.204719 -311.124569) (xy 390.196824 -311.173146)
			(xy 390.18124 -311.219827) (xy 390.158369 -311.263404) (xy 390.128804 -311.302748) (xy 390.093311 -311.33684)
			(xy 390.052808 -311.364796) (xy 390.008346 -311.385894) (xy 389.961075 -311.399586) (xy 389.91222 -311.405518)
			(xy 389.863045 -311.403537) (xy 389.814826 -311.393693) (xy 389.76881 -311.376241) (xy 389.726189 -311.351634)
			(xy 389.688068 -311.320509) (xy 389.655433 -311.283672) (xy 389.62913 -311.242076) (xy 389.609839 -311.1968)
			(xy 389.598062 -311.149016) (xy 389.594102 -311.099962) (xy 389.255254 -311.099962) (xy 389.254759 -311.124569)
			(xy 389.246864 -311.173146) (xy 389.23128 -311.219827) (xy 389.208409 -311.263404) (xy 389.178844 -311.302748)
			(xy 389.143351 -311.33684) (xy 389.102848 -311.364796) (xy 389.058386 -311.385894) (xy 389.011115 -311.399586)
			(xy 388.96226 -311.405518) (xy 388.913085 -311.403537) (xy 388.864866 -311.393693) (xy 388.81885 -311.376241)
			(xy 388.776229 -311.351634) (xy 388.738108 -311.320509) (xy 388.705473 -311.283672) (xy 388.67917 -311.242076)
			(xy 388.659879 -311.1968) (xy 388.648102 -311.149016) (xy 388.644142 -311.099962) (xy 388.305294 -311.099962)
			(xy 388.304799 -311.124569) (xy 388.296904 -311.173146) (xy 388.28132 -311.219827) (xy 388.258449 -311.263404)
			(xy 388.228884 -311.302748) (xy 388.193391 -311.33684) (xy 388.152888 -311.364796) (xy 388.108426 -311.385894)
			(xy 388.061155 -311.399586) (xy 388.0123 -311.405518) (xy 387.963125 -311.403537) (xy 387.914906 -311.393693)
			(xy 387.86889 -311.376241) (xy 387.826269 -311.351634) (xy 387.788148 -311.320509) (xy 387.755513 -311.283672)
			(xy 387.72921 -311.242076) (xy 387.709919 -311.1968) (xy 387.698142 -311.149016) (xy 387.694182 -311.099962)
			(xy 387.355334 -311.099962) (xy 387.354839 -311.124569) (xy 387.346944 -311.173146) (xy 387.33136 -311.219827)
			(xy 387.308489 -311.263404) (xy 387.278924 -311.302748) (xy 387.243431 -311.33684) (xy 387.202928 -311.364796)
			(xy 387.158466 -311.385894) (xy 387.111195 -311.399586) (xy 387.06234 -311.405518) (xy 387.013165 -311.403537)
			(xy 386.964946 -311.393693) (xy 386.91893 -311.376241) (xy 386.876309 -311.351634) (xy 386.838188 -311.320509)
			(xy 386.805553 -311.283672) (xy 386.77925 -311.242076) (xy 386.759959 -311.1968) (xy 386.748182 -311.149016)
			(xy 386.744222 -311.099962) (xy 386.40512 -311.099962) (xy 386.404625 -311.124569) (xy 386.39673 -311.173146)
			(xy 386.381146 -311.219827) (xy 386.358275 -311.263404) (xy 386.32871 -311.302748) (xy 386.293217 -311.33684)
			(xy 386.252714 -311.364796) (xy 386.208252 -311.385894) (xy 386.160981 -311.399586) (xy 386.112126 -311.405518)
			(xy 386.062951 -311.403537) (xy 386.014732 -311.393693) (xy 385.968716 -311.376241) (xy 385.926095 -311.351634)
			(xy 385.887974 -311.320509) (xy 385.855339 -311.283672) (xy 385.829036 -311.242076) (xy 385.809745 -311.1968)
			(xy 385.797968 -311.149016) (xy 385.794008 -311.099962) (xy 385.45516 -311.099962) (xy 385.454665 -311.124569)
			(xy 385.44677 -311.173146) (xy 385.431186 -311.219827) (xy 385.408315 -311.263404) (xy 385.37875 -311.302748)
			(xy 385.343257 -311.33684) (xy 385.302754 -311.364796) (xy 385.258292 -311.385894) (xy 385.211021 -311.399586)
			(xy 385.162166 -311.405518) (xy 385.112991 -311.403537) (xy 385.064772 -311.393693) (xy 385.018756 -311.376241)
			(xy 384.976135 -311.351634) (xy 384.938014 -311.320509) (xy 384.905379 -311.283672) (xy 384.879076 -311.242076)
			(xy 384.859785 -311.1968) (xy 384.848008 -311.149016) (xy 384.844048 -311.099962) (xy 383.326343 -311.099962)
			(xy 383.310579 -311.152357) (xy 383.286907 -311.202854) (xy 383.256134 -311.249367) (xy 383.218917 -311.290904)
			(xy 383.176049 -311.326579) (xy 383.128443 -311.355633) (xy 383.077114 -311.377445) (xy 383.023157 -311.391551)
			(xy 382.96772 -311.397651) (xy 382.911986 -311.395614) (xy 382.857143 -311.385484) (xy 382.804359 -311.367477)
			(xy 382.754759 -311.341976) (xy 382.709401 -311.309525) (xy 382.669252 -311.270816) (xy 382.635166 -311.226673)
			(xy 382.60787 -311.178038) (xy 382.587947 -311.125947) (xy 382.575821 -311.07151) (xy 382.57175 -311.015888)
			(xy 377.284667 -311.015888) (xy 377.283109 -311.019212) (xy 377.252336 -311.065725) (xy 377.215119 -311.107262)
			(xy 377.172251 -311.142937) (xy 377.124645 -311.171991) (xy 377.073316 -311.193803) (xy 377.019359 -311.207909)
			(xy 376.963922 -311.214009) (xy 376.908188 -311.211972) (xy 376.853345 -311.201842) (xy 376.800561 -311.183835)
			(xy 376.750961 -311.158334) (xy 376.705603 -311.125883) (xy 376.665454 -311.087174) (xy 376.631368 -311.043031)
			(xy 376.604072 -310.994396) (xy 376.584149 -310.942305) (xy 376.572023 -310.887868) (xy 376.567952 -310.832246)
			(xy 351.831402 -310.832246) (xy 351.831402 -311.453276) (xy 357.436926 -311.453276) (xy 357.440997 -311.397654)
			(xy 357.453123 -311.343217) (xy 357.473046 -311.291126) (xy 357.500342 -311.242491) (xy 357.534428 -311.198348)
			(xy 357.574577 -311.159639) (xy 357.619935 -311.127188) (xy 357.669535 -311.101687) (xy 357.722319 -311.08368)
			(xy 357.777162 -311.07355) (xy 357.832896 -311.071513) (xy 357.888333 -311.077613) (xy 357.94229 -311.091719)
			(xy 357.993619 -311.113531) (xy 358.041225 -311.142585) (xy 358.084093 -311.17826) (xy 358.12131 -311.219797)
			(xy 358.152083 -311.26631) (xy 358.175755 -311.316807) (xy 358.191823 -311.370214) (xy 358.199943 -311.42539)
			(xy 358.200452 -311.453276) (xy 358.452926 -311.453276) (xy 358.456997 -311.397654) (xy 358.469123 -311.343217)
			(xy 358.489046 -311.291126) (xy 358.516342 -311.242491) (xy 358.550428 -311.198348) (xy 358.590577 -311.159639)
			(xy 358.635935 -311.127188) (xy 358.685535 -311.101687) (xy 358.738319 -311.08368) (xy 358.793162 -311.07355)
			(xy 358.848896 -311.071513) (xy 358.904333 -311.077613) (xy 358.95829 -311.091719) (xy 359.009619 -311.113531)
			(xy 359.057225 -311.142585) (xy 359.100093 -311.17826) (xy 359.13731 -311.219797) (xy 359.168083 -311.26631)
			(xy 359.191755 -311.316807) (xy 359.207823 -311.370214) (xy 359.215943 -311.42539) (xy 359.216452 -311.453276)
			(xy 359.468926 -311.453276) (xy 359.472997 -311.397654) (xy 359.485123 -311.343217) (xy 359.505046 -311.291126)
			(xy 359.532342 -311.242491) (xy 359.566428 -311.198348) (xy 359.606577 -311.159639) (xy 359.651935 -311.127188)
			(xy 359.701535 -311.101687) (xy 359.754319 -311.08368) (xy 359.809162 -311.07355) (xy 359.864896 -311.071513)
			(xy 359.920333 -311.077613) (xy 359.97429 -311.091719) (xy 360.025619 -311.113531) (xy 360.073225 -311.142585)
			(xy 360.116093 -311.17826) (xy 360.15331 -311.219797) (xy 360.184083 -311.26631) (xy 360.207755 -311.316807)
			(xy 360.223823 -311.370214) (xy 360.231943 -311.42539) (xy 360.232452 -311.453276) (xy 360.484926 -311.453276)
			(xy 360.488997 -311.397654) (xy 360.501123 -311.343217) (xy 360.521046 -311.291126) (xy 360.548342 -311.242491)
			(xy 360.582428 -311.198348) (xy 360.622577 -311.159639) (xy 360.667935 -311.127188) (xy 360.717535 -311.101687)
			(xy 360.770319 -311.08368) (xy 360.825162 -311.07355) (xy 360.880896 -311.071513) (xy 360.936333 -311.077613)
			(xy 360.99029 -311.091719) (xy 361.041619 -311.113531) (xy 361.089225 -311.142585) (xy 361.132093 -311.17826)
			(xy 361.16931 -311.219797) (xy 361.200083 -311.26631) (xy 361.223755 -311.316807) (xy 361.239823 -311.370214)
			(xy 361.247943 -311.42539) (xy 361.248452 -311.453276) (xy 361.500926 -311.453276) (xy 361.504997 -311.397654)
			(xy 361.517123 -311.343217) (xy 361.537046 -311.291126) (xy 361.564342 -311.242491) (xy 361.598428 -311.198348)
			(xy 361.638577 -311.159639) (xy 361.683935 -311.127188) (xy 361.733535 -311.101687) (xy 361.786319 -311.08368)
			(xy 361.841162 -311.07355) (xy 361.896896 -311.071513) (xy 361.952333 -311.077613) (xy 362.00629 -311.091719)
			(xy 362.057619 -311.113531) (xy 362.105225 -311.142585) (xy 362.148093 -311.17826) (xy 362.18531 -311.219797)
			(xy 362.216083 -311.26631) (xy 362.239755 -311.316807) (xy 362.255823 -311.370214) (xy 362.263943 -311.42539)
			(xy 362.264452 -311.453276) (xy 362.516926 -311.453276) (xy 362.520997 -311.397654) (xy 362.533123 -311.343217)
			(xy 362.553046 -311.291126) (xy 362.580342 -311.242491) (xy 362.614428 -311.198348) (xy 362.654577 -311.159639)
			(xy 362.699935 -311.127188) (xy 362.749535 -311.101687) (xy 362.802319 -311.08368) (xy 362.857162 -311.07355)
			(xy 362.912896 -311.071513) (xy 362.968333 -311.077613) (xy 363.02229 -311.091719) (xy 363.073619 -311.113531)
			(xy 363.121225 -311.142585) (xy 363.164093 -311.17826) (xy 363.20131 -311.219797) (xy 363.232083 -311.26631)
			(xy 363.255755 -311.316807) (xy 363.271823 -311.370214) (xy 363.279943 -311.42539) (xy 363.280452 -311.453276)
			(xy 363.532926 -311.453276) (xy 363.536997 -311.397654) (xy 363.549123 -311.343217) (xy 363.569046 -311.291126)
			(xy 363.596342 -311.242491) (xy 363.630428 -311.198348) (xy 363.670577 -311.159639) (xy 363.715935 -311.127188)
			(xy 363.765535 -311.101687) (xy 363.818319 -311.08368) (xy 363.873162 -311.07355) (xy 363.928896 -311.071513)
			(xy 363.984333 -311.077613) (xy 364.03829 -311.091719) (xy 364.089619 -311.113531) (xy 364.137225 -311.142585)
			(xy 364.180093 -311.17826) (xy 364.21731 -311.219797) (xy 364.248083 -311.26631) (xy 364.271755 -311.316807)
			(xy 364.287823 -311.370214) (xy 364.295943 -311.42539) (xy 364.296452 -311.453276) (xy 364.548926 -311.453276)
			(xy 364.552997 -311.397654) (xy 364.565123 -311.343217) (xy 364.585046 -311.291126) (xy 364.612342 -311.242491)
			(xy 364.646428 -311.198348) (xy 364.686577 -311.159639) (xy 364.731935 -311.127188) (xy 364.781535 -311.101687)
			(xy 364.834319 -311.08368) (xy 364.889162 -311.07355) (xy 364.944896 -311.071513) (xy 365.000333 -311.077613)
			(xy 365.05429 -311.091719) (xy 365.105619 -311.113531) (xy 365.153225 -311.142585) (xy 365.196093 -311.17826)
			(xy 365.23331 -311.219797) (xy 365.264083 -311.26631) (xy 365.287755 -311.316807) (xy 365.303823 -311.370214)
			(xy 365.311943 -311.42539) (xy 365.312452 -311.453276) (xy 365.311943 -311.481162) (xy 365.303823 -311.536338)
			(xy 365.287755 -311.589745) (xy 365.264083 -311.640242) (xy 365.23331 -311.686755) (xy 365.196093 -311.728292)
			(xy 365.188994 -311.7342) (xy 380.789432 -311.7342) (xy 380.793503 -311.678578) (xy 380.805629 -311.624141)
			(xy 380.825552 -311.57205) (xy 380.852848 -311.523415) (xy 380.886934 -311.479272) (xy 380.927083 -311.440563)
			(xy 380.972441 -311.408112) (xy 381.022041 -311.382611) (xy 381.074825 -311.364604) (xy 381.129668 -311.354474)
			(xy 381.185402 -311.352437) (xy 381.240839 -311.358537) (xy 381.294796 -311.372643) (xy 381.346125 -311.394455)
			(xy 381.393731 -311.423509) (xy 381.436599 -311.459184) (xy 381.473816 -311.500721) (xy 381.504589 -311.547234)
			(xy 381.528261 -311.597731) (xy 381.544329 -311.651138) (xy 381.552449 -311.706314) (xy 381.552958 -311.7342)
			(xy 381.552449 -311.762086) (xy 381.544329 -311.817262) (xy 381.528261 -311.870669) (xy 381.504589 -311.921166)
			(xy 381.473816 -311.967679) (xy 381.436599 -312.009216) (xy 381.393731 -312.044891) (xy 381.346125 -312.073945)
			(xy 381.294796 -312.095757) (xy 381.240839 -312.109863) (xy 381.185402 -312.115963) (xy 381.129668 -312.113926)
			(xy 381.074825 -312.103796) (xy 381.022041 -312.085789) (xy 380.972441 -312.060288) (xy 380.927083 -312.027837)
			(xy 380.886934 -311.989128) (xy 380.852848 -311.944985) (xy 380.825552 -311.89635) (xy 380.805629 -311.844259)
			(xy 380.793503 -311.789822) (xy 380.789432 -311.7342) (xy 365.188994 -311.7342) (xy 365.153225 -311.763967)
			(xy 365.105619 -311.793021) (xy 365.05429 -311.814833) (xy 365.000333 -311.828939) (xy 364.944896 -311.835039)
			(xy 364.889162 -311.833002) (xy 364.834319 -311.822872) (xy 364.781535 -311.804865) (xy 364.731935 -311.779364)
			(xy 364.686577 -311.746913) (xy 364.646428 -311.708204) (xy 364.612342 -311.664061) (xy 364.585046 -311.615426)
			(xy 364.565123 -311.563335) (xy 364.552997 -311.508898) (xy 364.548926 -311.453276) (xy 364.296452 -311.453276)
			(xy 364.295943 -311.481162) (xy 364.287823 -311.536338) (xy 364.271755 -311.589745) (xy 364.248083 -311.640242)
			(xy 364.21731 -311.686755) (xy 364.180093 -311.728292) (xy 364.137225 -311.763967) (xy 364.089619 -311.793021)
			(xy 364.03829 -311.814833) (xy 363.984333 -311.828939) (xy 363.928896 -311.835039) (xy 363.873162 -311.833002)
			(xy 363.818319 -311.822872) (xy 363.765535 -311.804865) (xy 363.715935 -311.779364) (xy 363.670577 -311.746913)
			(xy 363.630428 -311.708204) (xy 363.596342 -311.664061) (xy 363.569046 -311.615426) (xy 363.549123 -311.563335)
			(xy 363.536997 -311.508898) (xy 363.532926 -311.453276) (xy 363.280452 -311.453276) (xy 363.279943 -311.481162)
			(xy 363.271823 -311.536338) (xy 363.255755 -311.589745) (xy 363.232083 -311.640242) (xy 363.20131 -311.686755)
			(xy 363.164093 -311.728292) (xy 363.121225 -311.763967) (xy 363.073619 -311.793021) (xy 363.02229 -311.814833)
			(xy 362.968333 -311.828939) (xy 362.912896 -311.835039) (xy 362.857162 -311.833002) (xy 362.802319 -311.822872)
			(xy 362.749535 -311.804865) (xy 362.699935 -311.779364) (xy 362.654577 -311.746913) (xy 362.614428 -311.708204)
			(xy 362.580342 -311.664061) (xy 362.553046 -311.615426) (xy 362.533123 -311.563335) (xy 362.520997 -311.508898)
			(xy 362.516926 -311.453276) (xy 362.264452 -311.453276) (xy 362.263943 -311.481162) (xy 362.255823 -311.536338)
			(xy 362.239755 -311.589745) (xy 362.216083 -311.640242) (xy 362.18531 -311.686755) (xy 362.148093 -311.728292)
			(xy 362.105225 -311.763967) (xy 362.057619 -311.793021) (xy 362.00629 -311.814833) (xy 361.952333 -311.828939)
			(xy 361.896896 -311.835039) (xy 361.841162 -311.833002) (xy 361.786319 -311.822872) (xy 361.733535 -311.804865)
			(xy 361.683935 -311.779364) (xy 361.638577 -311.746913) (xy 361.598428 -311.708204) (xy 361.564342 -311.664061)
			(xy 361.537046 -311.615426) (xy 361.517123 -311.563335) (xy 361.504997 -311.508898) (xy 361.500926 -311.453276)
			(xy 361.248452 -311.453276) (xy 361.247943 -311.481162) (xy 361.239823 -311.536338) (xy 361.223755 -311.589745)
			(xy 361.200083 -311.640242) (xy 361.16931 -311.686755) (xy 361.132093 -311.728292) (xy 361.089225 -311.763967)
			(xy 361.041619 -311.793021) (xy 360.99029 -311.814833) (xy 360.936333 -311.828939) (xy 360.880896 -311.835039)
			(xy 360.825162 -311.833002) (xy 360.770319 -311.822872) (xy 360.717535 -311.804865) (xy 360.667935 -311.779364)
			(xy 360.622577 -311.746913) (xy 360.582428 -311.708204) (xy 360.548342 -311.664061) (xy 360.521046 -311.615426)
			(xy 360.501123 -311.563335) (xy 360.488997 -311.508898) (xy 360.484926 -311.453276) (xy 360.232452 -311.453276)
			(xy 360.231943 -311.481162) (xy 360.223823 -311.536338) (xy 360.207755 -311.589745) (xy 360.184083 -311.640242)
			(xy 360.15331 -311.686755) (xy 360.116093 -311.728292) (xy 360.073225 -311.763967) (xy 360.025619 -311.793021)
			(xy 359.97429 -311.814833) (xy 359.920333 -311.828939) (xy 359.864896 -311.835039) (xy 359.809162 -311.833002)
			(xy 359.754319 -311.822872) (xy 359.701535 -311.804865) (xy 359.651935 -311.779364) (xy 359.606577 -311.746913)
			(xy 359.566428 -311.708204) (xy 359.532342 -311.664061) (xy 359.505046 -311.615426) (xy 359.485123 -311.563335)
			(xy 359.472997 -311.508898) (xy 359.468926 -311.453276) (xy 359.216452 -311.453276) (xy 359.215943 -311.481162)
			(xy 359.207823 -311.536338) (xy 359.191755 -311.589745) (xy 359.168083 -311.640242) (xy 359.13731 -311.686755)
			(xy 359.100093 -311.728292) (xy 359.057225 -311.763967) (xy 359.009619 -311.793021) (xy 358.95829 -311.814833)
			(xy 358.904333 -311.828939) (xy 358.848896 -311.835039) (xy 358.793162 -311.833002) (xy 358.738319 -311.822872)
			(xy 358.685535 -311.804865) (xy 358.635935 -311.779364) (xy 358.590577 -311.746913) (xy 358.550428 -311.708204)
			(xy 358.516342 -311.664061) (xy 358.489046 -311.615426) (xy 358.469123 -311.563335) (xy 358.456997 -311.508898)
			(xy 358.452926 -311.453276) (xy 358.200452 -311.453276) (xy 358.199943 -311.481162) (xy 358.191823 -311.536338)
			(xy 358.175755 -311.589745) (xy 358.152083 -311.640242) (xy 358.12131 -311.686755) (xy 358.084093 -311.728292)
			(xy 358.041225 -311.763967) (xy 357.993619 -311.793021) (xy 357.94229 -311.814833) (xy 357.888333 -311.828939)
			(xy 357.832896 -311.835039) (xy 357.777162 -311.833002) (xy 357.722319 -311.822872) (xy 357.669535 -311.804865)
			(xy 357.619935 -311.779364) (xy 357.574577 -311.746913) (xy 357.534428 -311.708204) (xy 357.500342 -311.664061)
			(xy 357.473046 -311.615426) (xy 357.453123 -311.563335) (xy 357.440997 -311.508898) (xy 357.436926 -311.453276)
			(xy 351.831402 -311.453276) (xy 351.831402 -312.469276) (xy 357.436926 -312.469276) (xy 357.440997 -312.413654)
			(xy 357.453123 -312.359217) (xy 357.473046 -312.307126) (xy 357.500342 -312.258491) (xy 357.534428 -312.214348)
			(xy 357.574577 -312.175639) (xy 357.619935 -312.143188) (xy 357.669535 -312.117687) (xy 357.722319 -312.09968)
			(xy 357.777162 -312.08955) (xy 357.832896 -312.087513) (xy 357.888333 -312.093613) (xy 357.94229 -312.107719)
			(xy 357.993619 -312.129531) (xy 358.041225 -312.158585) (xy 358.084093 -312.19426) (xy 358.12131 -312.235797)
			(xy 358.152083 -312.28231) (xy 358.175755 -312.332807) (xy 358.191823 -312.386214) (xy 358.199943 -312.44139)
			(xy 358.200452 -312.469276) (xy 358.452926 -312.469276) (xy 358.456997 -312.413654) (xy 358.469123 -312.359217)
			(xy 358.489046 -312.307126) (xy 358.516342 -312.258491) (xy 358.550428 -312.214348) (xy 358.590577 -312.175639)
			(xy 358.635935 -312.143188) (xy 358.685535 -312.117687) (xy 358.738319 -312.09968) (xy 358.793162 -312.08955)
			(xy 358.848896 -312.087513) (xy 358.904333 -312.093613) (xy 358.95829 -312.107719) (xy 359.009619 -312.129531)
			(xy 359.057225 -312.158585) (xy 359.100093 -312.19426) (xy 359.13731 -312.235797) (xy 359.168083 -312.28231)
			(xy 359.191755 -312.332807) (xy 359.207823 -312.386214) (xy 359.215943 -312.44139) (xy 359.216452 -312.469276)
			(xy 359.468926 -312.469276) (xy 359.472997 -312.413654) (xy 359.485123 -312.359217) (xy 359.505046 -312.307126)
			(xy 359.532342 -312.258491) (xy 359.566428 -312.214348) (xy 359.606577 -312.175639) (xy 359.651935 -312.143188)
			(xy 359.701535 -312.117687) (xy 359.754319 -312.09968) (xy 359.809162 -312.08955) (xy 359.864896 -312.087513)
			(xy 359.920333 -312.093613) (xy 359.97429 -312.107719) (xy 360.025619 -312.129531) (xy 360.073225 -312.158585)
			(xy 360.116093 -312.19426) (xy 360.15331 -312.235797) (xy 360.184083 -312.28231) (xy 360.207755 -312.332807)
			(xy 360.223823 -312.386214) (xy 360.231943 -312.44139) (xy 360.232452 -312.469276) (xy 360.484926 -312.469276)
			(xy 360.488997 -312.413654) (xy 360.501123 -312.359217) (xy 360.521046 -312.307126) (xy 360.548342 -312.258491)
			(xy 360.582428 -312.214348) (xy 360.622577 -312.175639) (xy 360.667935 -312.143188) (xy 360.717535 -312.117687)
			(xy 360.770319 -312.09968) (xy 360.825162 -312.08955) (xy 360.880896 -312.087513) (xy 360.936333 -312.093613)
			(xy 360.99029 -312.107719) (xy 361.041619 -312.129531) (xy 361.089225 -312.158585) (xy 361.132093 -312.19426)
			(xy 361.16931 -312.235797) (xy 361.200083 -312.28231) (xy 361.223755 -312.332807) (xy 361.239823 -312.386214)
			(xy 361.247943 -312.44139) (xy 361.248452 -312.469276) (xy 361.500926 -312.469276) (xy 361.504997 -312.413654)
			(xy 361.517123 -312.359217) (xy 361.537046 -312.307126) (xy 361.564342 -312.258491) (xy 361.598428 -312.214348)
			(xy 361.638577 -312.175639) (xy 361.683935 -312.143188) (xy 361.733535 -312.117687) (xy 361.786319 -312.09968)
			(xy 361.841162 -312.08955) (xy 361.896896 -312.087513) (xy 361.952333 -312.093613) (xy 362.00629 -312.107719)
			(xy 362.057619 -312.129531) (xy 362.105225 -312.158585) (xy 362.148093 -312.19426) (xy 362.18531 -312.235797)
			(xy 362.216083 -312.28231) (xy 362.239755 -312.332807) (xy 362.255823 -312.386214) (xy 362.263943 -312.44139)
			(xy 362.264452 -312.469276) (xy 362.516926 -312.469276) (xy 362.520997 -312.413654) (xy 362.533123 -312.359217)
			(xy 362.553046 -312.307126) (xy 362.580342 -312.258491) (xy 362.614428 -312.214348) (xy 362.654577 -312.175639)
			(xy 362.699935 -312.143188) (xy 362.749535 -312.117687) (xy 362.802319 -312.09968) (xy 362.857162 -312.08955)
			(xy 362.912896 -312.087513) (xy 362.968333 -312.093613) (xy 363.02229 -312.107719) (xy 363.073619 -312.129531)
			(xy 363.121225 -312.158585) (xy 363.164093 -312.19426) (xy 363.20131 -312.235797) (xy 363.232083 -312.28231)
			(xy 363.255755 -312.332807) (xy 363.271823 -312.386214) (xy 363.279943 -312.44139) (xy 363.280452 -312.469276)
			(xy 363.532926 -312.469276) (xy 363.536997 -312.413654) (xy 363.549123 -312.359217) (xy 363.569046 -312.307126)
			(xy 363.596342 -312.258491) (xy 363.630428 -312.214348) (xy 363.670577 -312.175639) (xy 363.715935 -312.143188)
			(xy 363.765535 -312.117687) (xy 363.818319 -312.09968) (xy 363.873162 -312.08955) (xy 363.928896 -312.087513)
			(xy 363.984333 -312.093613) (xy 364.03829 -312.107719) (xy 364.089619 -312.129531) (xy 364.137225 -312.158585)
			(xy 364.180093 -312.19426) (xy 364.21731 -312.235797) (xy 364.248083 -312.28231) (xy 364.271755 -312.332807)
			(xy 364.287823 -312.386214) (xy 364.295943 -312.44139) (xy 364.296452 -312.469276) (xy 364.295943 -312.497162)
			(xy 364.292085 -312.523378) (xy 380.032004 -312.523378) (xy 380.036075 -312.467756) (xy 380.048201 -312.413319)
			(xy 380.068124 -312.361228) (xy 380.09542 -312.312593) (xy 380.129506 -312.26845) (xy 380.169655 -312.229741)
			(xy 380.215013 -312.19729) (xy 380.264613 -312.171789) (xy 380.317397 -312.153782) (xy 380.37224 -312.143652)
			(xy 380.427974 -312.141615) (xy 380.483411 -312.147715) (xy 380.537368 -312.161821) (xy 380.588697 -312.183633)
			(xy 380.636303 -312.212687) (xy 380.679171 -312.248362) (xy 380.696863 -312.268108) (xy 382.410714 -312.268108)
			(xy 382.414785 -312.212486) (xy 382.426911 -312.158049) (xy 382.446834 -312.105958) (xy 382.47413 -312.057323)
			(xy 382.508216 -312.01318) (xy 382.548365 -311.974471) (xy 382.593723 -311.94202) (xy 382.643323 -311.916519)
			(xy 382.696107 -311.898512) (xy 382.75095 -311.888382) (xy 382.806684 -311.886345) (xy 382.862121 -311.892445)
			(xy 382.916078 -311.906551) (xy 382.967407 -311.928363) (xy 383.015013 -311.957417) (xy 383.057881 -311.993092)
			(xy 383.095098 -312.034629) (xy 383.105048 -312.049668) (xy 383.893834 -312.049668) (xy 383.897794 -312.000614)
			(xy 383.909571 -311.95283) (xy 383.928862 -311.907554) (xy 383.955165 -311.865958) (xy 383.9878 -311.829121)
			(xy 384.025921 -311.797996) (xy 384.068542 -311.773389) (xy 384.114558 -311.755937) (xy 384.162777 -311.746093)
			(xy 384.211952 -311.744112) (xy 384.260807 -311.750044) (xy 384.308078 -311.763736) (xy 384.35254 -311.784834)
			(xy 384.393043 -311.81279) (xy 384.428536 -311.846882) (xy 384.458101 -311.886226) (xy 384.480972 -311.929803)
			(xy 384.496556 -311.976484) (xy 384.504451 -312.025061) (xy 384.504946 -312.049668) (xy 384.504941 -312.049922)
			(xy 384.844048 -312.049922) (xy 384.848008 -312.000868) (xy 384.859785 -311.953084) (xy 384.879076 -311.907808)
			(xy 384.905379 -311.866212) (xy 384.938014 -311.829375) (xy 384.976135 -311.79825) (xy 385.018756 -311.773643)
			(xy 385.064772 -311.756191) (xy 385.112991 -311.746347) (xy 385.162166 -311.744366) (xy 385.211021 -311.750298)
			(xy 385.258292 -311.76399) (xy 385.302754 -311.785088) (xy 385.343257 -311.813044) (xy 385.37875 -311.847136)
			(xy 385.408315 -311.88648) (xy 385.431186 -311.930057) (xy 385.44677 -311.976738) (xy 385.454665 -312.025315)
			(xy 385.45516 -312.049922) (xy 385.794008 -312.049922) (xy 385.797968 -312.000868) (xy 385.809745 -311.953084)
			(xy 385.829036 -311.907808) (xy 385.855339 -311.866212) (xy 385.887974 -311.829375) (xy 385.926095 -311.79825)
			(xy 385.968716 -311.773643) (xy 386.014732 -311.756191) (xy 386.062951 -311.746347) (xy 386.112126 -311.744366)
			(xy 386.160981 -311.750298) (xy 386.208252 -311.76399) (xy 386.252714 -311.785088) (xy 386.293217 -311.813044)
			(xy 386.32871 -311.847136) (xy 386.358275 -311.88648) (xy 386.381146 -311.930057) (xy 386.39673 -311.976738)
			(xy 386.404625 -312.025315) (xy 386.40512 -312.049922) (xy 386.744222 -312.049922) (xy 386.748182 -312.000868)
			(xy 386.759959 -311.953084) (xy 386.77925 -311.907808) (xy 386.805553 -311.866212) (xy 386.838188 -311.829375)
			(xy 386.876309 -311.79825) (xy 386.91893 -311.773643) (xy 386.964946 -311.756191) (xy 387.013165 -311.746347)
			(xy 387.06234 -311.744366) (xy 387.111195 -311.750298) (xy 387.158466 -311.76399) (xy 387.202928 -311.785088)
			(xy 387.243431 -311.813044) (xy 387.278924 -311.847136) (xy 387.308489 -311.88648) (xy 387.33136 -311.930057)
			(xy 387.346944 -311.976738) (xy 387.354839 -312.025315) (xy 387.355334 -312.049922) (xy 387.694182 -312.049922)
			(xy 387.698142 -312.000868) (xy 387.709919 -311.953084) (xy 387.72921 -311.907808) (xy 387.755513 -311.866212)
			(xy 387.788148 -311.829375) (xy 387.826269 -311.79825) (xy 387.86889 -311.773643) (xy 387.914906 -311.756191)
			(xy 387.963125 -311.746347) (xy 388.0123 -311.744366) (xy 388.061155 -311.750298) (xy 388.108426 -311.76399)
			(xy 388.152888 -311.785088) (xy 388.193391 -311.813044) (xy 388.228884 -311.847136) (xy 388.258449 -311.88648)
			(xy 388.28132 -311.930057) (xy 388.296904 -311.976738) (xy 388.304799 -312.025315) (xy 388.305294 -312.049922)
			(xy 388.644142 -312.049922) (xy 388.648102 -312.000868) (xy 388.659879 -311.953084) (xy 388.67917 -311.907808)
			(xy 388.705473 -311.866212) (xy 388.738108 -311.829375) (xy 388.776229 -311.79825) (xy 388.81885 -311.773643)
			(xy 388.864866 -311.756191) (xy 388.913085 -311.746347) (xy 388.96226 -311.744366) (xy 389.011115 -311.750298)
			(xy 389.058386 -311.76399) (xy 389.102848 -311.785088) (xy 389.143351 -311.813044) (xy 389.178844 -311.847136)
			(xy 389.208409 -311.88648) (xy 389.23128 -311.930057) (xy 389.246864 -311.976738) (xy 389.254759 -312.025315)
			(xy 389.255254 -312.049922) (xy 389.594102 -312.049922) (xy 389.598062 -312.000868) (xy 389.609839 -311.953084)
			(xy 389.62913 -311.907808) (xy 389.655433 -311.866212) (xy 389.688068 -311.829375) (xy 389.726189 -311.79825)
			(xy 389.76881 -311.773643) (xy 389.814826 -311.756191) (xy 389.863045 -311.746347) (xy 389.91222 -311.744366)
			(xy 389.961075 -311.750298) (xy 390.008346 -311.76399) (xy 390.052808 -311.785088) (xy 390.093311 -311.813044)
			(xy 390.128804 -311.847136) (xy 390.158369 -311.88648) (xy 390.18124 -311.930057) (xy 390.196824 -311.976738)
			(xy 390.204719 -312.025315) (xy 390.205214 -312.049922) (xy 390.544062 -312.049922) (xy 390.548022 -312.000868)
			(xy 390.559799 -311.953084) (xy 390.57909 -311.907808) (xy 390.605393 -311.866212) (xy 390.638028 -311.829375)
			(xy 390.676149 -311.79825) (xy 390.71877 -311.773643) (xy 390.764786 -311.756191) (xy 390.813005 -311.746347)
			(xy 390.86218 -311.744366) (xy 390.911035 -311.750298) (xy 390.958306 -311.76399) (xy 391.002768 -311.785088)
			(xy 391.043271 -311.813044) (xy 391.078764 -311.847136) (xy 391.108329 -311.88648) (xy 391.1312 -311.930057)
			(xy 391.146784 -311.976738) (xy 391.154679 -312.025315) (xy 391.155174 -312.049922) (xy 391.494022 -312.049922)
			(xy 391.497982 -312.000868) (xy 391.509759 -311.953084) (xy 391.52905 -311.907808) (xy 391.555353 -311.866212)
			(xy 391.587988 -311.829375) (xy 391.626109 -311.79825) (xy 391.66873 -311.773643) (xy 391.714746 -311.756191)
			(xy 391.762965 -311.746347) (xy 391.81214 -311.744366) (xy 391.860995 -311.750298) (xy 391.908266 -311.76399)
			(xy 391.952728 -311.785088) (xy 391.993231 -311.813044) (xy 392.028724 -311.847136) (xy 392.058289 -311.88648)
			(xy 392.08116 -311.930057) (xy 392.096744 -311.976738) (xy 392.104639 -312.025315) (xy 392.105134 -312.049922)
			(xy 392.443982 -312.049922) (xy 392.447942 -312.000868) (xy 392.459719 -311.953084) (xy 392.47901 -311.907808)
			(xy 392.505313 -311.866212) (xy 392.537948 -311.829375) (xy 392.576069 -311.79825) (xy 392.61869 -311.773643)
			(xy 392.664706 -311.756191) (xy 392.712925 -311.746347) (xy 392.7621 -311.744366) (xy 392.810955 -311.750298)
			(xy 392.858226 -311.76399) (xy 392.902688 -311.785088) (xy 392.943191 -311.813044) (xy 392.978684 -311.847136)
			(xy 393.008249 -311.88648) (xy 393.03112 -311.930057) (xy 393.046704 -311.976738) (xy 393.054599 -312.025315)
			(xy 393.055094 -312.049922) (xy 393.394196 -312.049922) (xy 393.398156 -312.000868) (xy 393.409933 -311.953084)
			(xy 393.429224 -311.907808) (xy 393.455527 -311.866212) (xy 393.488162 -311.829375) (xy 393.526283 -311.79825)
			(xy 393.568904 -311.773643) (xy 393.61492 -311.756191) (xy 393.663139 -311.746347) (xy 393.712314 -311.744366)
			(xy 393.761169 -311.750298) (xy 393.80844 -311.76399) (xy 393.852902 -311.785088) (xy 393.893405 -311.813044)
			(xy 393.928898 -311.847136) (xy 393.958463 -311.88648) (xy 393.981334 -311.930057) (xy 393.996918 -311.976738)
			(xy 394.004813 -312.025315) (xy 394.005308 -312.049922) (xy 394.344156 -312.049922) (xy 394.348116 -312.000868)
			(xy 394.359893 -311.953084) (xy 394.379184 -311.907808) (xy 394.405487 -311.866212) (xy 394.438122 -311.829375)
			(xy 394.476243 -311.79825) (xy 394.518864 -311.773643) (xy 394.56488 -311.756191) (xy 394.613099 -311.746347)
			(xy 394.662274 -311.744366) (xy 394.711129 -311.750298) (xy 394.7584 -311.76399) (xy 394.802862 -311.785088)
			(xy 394.843365 -311.813044) (xy 394.878858 -311.847136) (xy 394.908423 -311.88648) (xy 394.931294 -311.930057)
			(xy 394.946878 -311.976738) (xy 394.954773 -312.025315) (xy 394.955268 -312.049922) (xy 395.294116 -312.049922)
			(xy 395.298076 -312.000868) (xy 395.309853 -311.953084) (xy 395.329144 -311.907808) (xy 395.355447 -311.866212)
			(xy 395.388082 -311.829375) (xy 395.426203 -311.79825) (xy 395.468824 -311.773643) (xy 395.51484 -311.756191)
			(xy 395.563059 -311.746347) (xy 395.612234 -311.744366) (xy 395.661089 -311.750298) (xy 395.70836 -311.76399)
			(xy 395.752822 -311.785088) (xy 395.793325 -311.813044) (xy 395.828818 -311.847136) (xy 395.858383 -311.88648)
			(xy 395.881254 -311.930057) (xy 395.896838 -311.976738) (xy 395.904733 -312.025315) (xy 395.905228 -312.049922)
			(xy 396.244076 -312.049922) (xy 396.248036 -312.000868) (xy 396.259813 -311.953084) (xy 396.279104 -311.907808)
			(xy 396.305407 -311.866212) (xy 396.338042 -311.829375) (xy 396.376163 -311.79825) (xy 396.418784 -311.773643)
			(xy 396.4648 -311.756191) (xy 396.513019 -311.746347) (xy 396.562194 -311.744366) (xy 396.611049 -311.750298)
			(xy 396.65832 -311.76399) (xy 396.702782 -311.785088) (xy 396.743285 -311.813044) (xy 396.778778 -311.847136)
			(xy 396.808343 -311.88648) (xy 396.831214 -311.930057) (xy 396.846798 -311.976738) (xy 396.854693 -312.025315)
			(xy 396.855188 -312.049922) (xy 397.194036 -312.049922) (xy 397.197996 -312.000868) (xy 397.209773 -311.953084)
			(xy 397.229064 -311.907808) (xy 397.255367 -311.866212) (xy 397.288002 -311.829375) (xy 397.326123 -311.79825)
			(xy 397.368744 -311.773643) (xy 397.41476 -311.756191) (xy 397.462979 -311.746347) (xy 397.512154 -311.744366)
			(xy 397.561009 -311.750298) (xy 397.60828 -311.76399) (xy 397.652742 -311.785088) (xy 397.693245 -311.813044)
			(xy 397.728738 -311.847136) (xy 397.758303 -311.88648) (xy 397.781174 -311.930057) (xy 397.796758 -311.976738)
			(xy 397.804653 -312.025315) (xy 397.805148 -312.049922) (xy 398.143996 -312.049922) (xy 398.147956 -312.000868)
			(xy 398.159733 -311.953084) (xy 398.179024 -311.907808) (xy 398.205327 -311.866212) (xy 398.237962 -311.829375)
			(xy 398.276083 -311.79825) (xy 398.318704 -311.773643) (xy 398.36472 -311.756191) (xy 398.412939 -311.746347)
			(xy 398.462114 -311.744366) (xy 398.510969 -311.750298) (xy 398.55824 -311.76399) (xy 398.602702 -311.785088)
			(xy 398.643205 -311.813044) (xy 398.678698 -311.847136) (xy 398.708263 -311.88648) (xy 398.731134 -311.930057)
			(xy 398.746718 -311.976738) (xy 398.754613 -312.025315) (xy 398.755108 -312.049922) (xy 399.09421 -312.049922)
			(xy 399.09817 -312.000868) (xy 399.109947 -311.953084) (xy 399.129238 -311.907808) (xy 399.155541 -311.866212)
			(xy 399.188176 -311.829375) (xy 399.226297 -311.79825) (xy 399.268918 -311.773643) (xy 399.314934 -311.756191)
			(xy 399.363153 -311.746347) (xy 399.412328 -311.744366) (xy 399.461183 -311.750298) (xy 399.508454 -311.76399)
			(xy 399.552916 -311.785088) (xy 399.593419 -311.813044) (xy 399.628912 -311.847136) (xy 399.658477 -311.88648)
			(xy 399.681348 -311.930057) (xy 399.696932 -311.976738) (xy 399.704827 -312.025315) (xy 399.705322 -312.049922)
			(xy 400.04417 -312.049922) (xy 400.04813 -312.000868) (xy 400.059907 -311.953084) (xy 400.079198 -311.907808)
			(xy 400.105501 -311.866212) (xy 400.138136 -311.829375) (xy 400.176257 -311.79825) (xy 400.218878 -311.773643)
			(xy 400.264894 -311.756191) (xy 400.313113 -311.746347) (xy 400.362288 -311.744366) (xy 400.411143 -311.750298)
			(xy 400.458414 -311.76399) (xy 400.502876 -311.785088) (xy 400.543379 -311.813044) (xy 400.578872 -311.847136)
			(xy 400.608437 -311.88648) (xy 400.631308 -311.930057) (xy 400.646892 -311.976738) (xy 400.654787 -312.025315)
			(xy 400.655282 -312.049922) (xy 400.99413 -312.049922) (xy 400.99809 -312.000868) (xy 401.009867 -311.953084)
			(xy 401.029158 -311.907808) (xy 401.055461 -311.866212) (xy 401.088096 -311.829375) (xy 401.126217 -311.79825)
			(xy 401.168838 -311.773643) (xy 401.214854 -311.756191) (xy 401.263073 -311.746347) (xy 401.312248 -311.744366)
			(xy 401.361103 -311.750298) (xy 401.408374 -311.76399) (xy 401.452836 -311.785088) (xy 401.493339 -311.813044)
			(xy 401.528832 -311.847136) (xy 401.558397 -311.88648) (xy 401.581268 -311.930057) (xy 401.596852 -311.976738)
			(xy 401.604747 -312.025315) (xy 401.605242 -312.049922) (xy 401.94409 -312.049922) (xy 401.94805 -312.000868)
			(xy 401.959827 -311.953084) (xy 401.979118 -311.907808) (xy 402.005421 -311.866212) (xy 402.038056 -311.829375)
			(xy 402.076177 -311.79825) (xy 402.118798 -311.773643) (xy 402.164814 -311.756191) (xy 402.213033 -311.746347)
			(xy 402.262208 -311.744366) (xy 402.311063 -311.750298) (xy 402.358334 -311.76399) (xy 402.402796 -311.785088)
			(xy 402.443299 -311.813044) (xy 402.478792 -311.847136) (xy 402.508357 -311.88648) (xy 402.531228 -311.930057)
			(xy 402.546812 -311.976738) (xy 402.554707 -312.025315) (xy 402.555202 -312.049922) (xy 402.89405 -312.049922)
			(xy 402.89801 -312.000868) (xy 402.909787 -311.953084) (xy 402.929078 -311.907808) (xy 402.955381 -311.866212)
			(xy 402.988016 -311.829375) (xy 403.026137 -311.79825) (xy 403.068758 -311.773643) (xy 403.114774 -311.756191)
			(xy 403.162993 -311.746347) (xy 403.212168 -311.744366) (xy 403.261023 -311.750298) (xy 403.308294 -311.76399)
			(xy 403.352756 -311.785088) (xy 403.393259 -311.813044) (xy 403.428752 -311.847136) (xy 403.458317 -311.88648)
			(xy 403.481188 -311.930057) (xy 403.496772 -311.976738) (xy 403.504667 -312.025315) (xy 403.505162 -312.049922)
			(xy 403.84401 -312.049922) (xy 403.84797 -312.000868) (xy 403.859747 -311.953084) (xy 403.879038 -311.907808)
			(xy 403.905341 -311.866212) (xy 403.937976 -311.829375) (xy 403.976097 -311.79825) (xy 404.018718 -311.773643)
			(xy 404.064734 -311.756191) (xy 404.112953 -311.746347) (xy 404.162128 -311.744366) (xy 404.210983 -311.750298)
			(xy 404.258254 -311.76399) (xy 404.302716 -311.785088) (xy 404.343219 -311.813044) (xy 404.378712 -311.847136)
			(xy 404.408277 -311.88648) (xy 404.431148 -311.930057) (xy 404.446732 -311.976738) (xy 404.454627 -312.025315)
			(xy 404.455122 -312.049922) (xy 404.794224 -312.049922) (xy 404.798184 -312.000868) (xy 404.809961 -311.953084)
			(xy 404.829252 -311.907808) (xy 404.855555 -311.866212) (xy 404.88819 -311.829375) (xy 404.926311 -311.79825)
			(xy 404.968932 -311.773643) (xy 405.014948 -311.756191) (xy 405.063167 -311.746347) (xy 405.112342 -311.744366)
			(xy 405.161197 -311.750298) (xy 405.208468 -311.76399) (xy 405.25293 -311.785088) (xy 405.293433 -311.813044)
			(xy 405.328926 -311.847136) (xy 405.358491 -311.88648) (xy 405.381362 -311.930057) (xy 405.396946 -311.976738)
			(xy 405.404841 -312.025315) (xy 405.405336 -312.049922) (xy 405.744184 -312.049922) (xy 405.748144 -312.000868)
			(xy 405.759921 -311.953084) (xy 405.779212 -311.907808) (xy 405.805515 -311.866212) (xy 405.83815 -311.829375)
			(xy 405.876271 -311.79825) (xy 405.918892 -311.773643) (xy 405.964908 -311.756191) (xy 406.013127 -311.746347)
			(xy 406.062302 -311.744366) (xy 406.111157 -311.750298) (xy 406.158428 -311.76399) (xy 406.20289 -311.785088)
			(xy 406.243393 -311.813044) (xy 406.278886 -311.847136) (xy 406.308451 -311.88648) (xy 406.331322 -311.930057)
			(xy 406.346906 -311.976738) (xy 406.354801 -312.025315) (xy 406.355296 -312.049922) (xy 406.694144 -312.049922)
			(xy 406.698104 -312.000868) (xy 406.709881 -311.953084) (xy 406.729172 -311.907808) (xy 406.755475 -311.866212)
			(xy 406.78811 -311.829375) (xy 406.826231 -311.79825) (xy 406.868852 -311.773643) (xy 406.914868 -311.756191)
			(xy 406.963087 -311.746347) (xy 407.012262 -311.744366) (xy 407.061117 -311.750298) (xy 407.108388 -311.76399)
			(xy 407.15285 -311.785088) (xy 407.193353 -311.813044) (xy 407.228846 -311.847136) (xy 407.258411 -311.88648)
			(xy 407.281282 -311.930057) (xy 407.296866 -311.976738) (xy 407.304761 -312.025315) (xy 407.305256 -312.049922)
			(xy 407.644104 -312.049922) (xy 407.648064 -312.000868) (xy 407.659841 -311.953084) (xy 407.679132 -311.907808)
			(xy 407.705435 -311.866212) (xy 407.73807 -311.829375) (xy 407.776191 -311.79825) (xy 407.818812 -311.773643)
			(xy 407.864828 -311.756191) (xy 407.913047 -311.746347) (xy 407.962222 -311.744366) (xy 408.011077 -311.750298)
			(xy 408.058348 -311.76399) (xy 408.10281 -311.785088) (xy 408.143313 -311.813044) (xy 408.178806 -311.847136)
			(xy 408.208371 -311.88648) (xy 408.231242 -311.930057) (xy 408.246826 -311.976738) (xy 408.254721 -312.025315)
			(xy 408.255216 -312.049922) (xy 408.254721 -312.074529) (xy 408.246826 -312.123106) (xy 408.231242 -312.169787)
			(xy 408.208371 -312.213364) (xy 408.178806 -312.252708) (xy 408.143313 -312.2868) (xy 408.10281 -312.314756)
			(xy 408.058348 -312.335854) (xy 408.011077 -312.349546) (xy 407.962222 -312.355478) (xy 407.913047 -312.353497)
			(xy 407.864828 -312.343653) (xy 407.818812 -312.326201) (xy 407.776191 -312.301594) (xy 407.73807 -312.270469)
			(xy 407.705435 -312.233632) (xy 407.679132 -312.192036) (xy 407.659841 -312.14676) (xy 407.648064 -312.098976)
			(xy 407.644104 -312.049922) (xy 407.305256 -312.049922) (xy 407.304761 -312.074529) (xy 407.296866 -312.123106)
			(xy 407.281282 -312.169787) (xy 407.258411 -312.213364) (xy 407.228846 -312.252708) (xy 407.193353 -312.2868)
			(xy 407.15285 -312.314756) (xy 407.108388 -312.335854) (xy 407.061117 -312.349546) (xy 407.012262 -312.355478)
			(xy 406.963087 -312.353497) (xy 406.914868 -312.343653) (xy 406.868852 -312.326201) (xy 406.826231 -312.301594)
			(xy 406.78811 -312.270469) (xy 406.755475 -312.233632) (xy 406.729172 -312.192036) (xy 406.709881 -312.14676)
			(xy 406.698104 -312.098976) (xy 406.694144 -312.049922) (xy 406.355296 -312.049922) (xy 406.354801 -312.074529)
			(xy 406.346906 -312.123106) (xy 406.331322 -312.169787) (xy 406.308451 -312.213364) (xy 406.278886 -312.252708)
			(xy 406.243393 -312.2868) (xy 406.20289 -312.314756) (xy 406.158428 -312.335854) (xy 406.111157 -312.349546)
			(xy 406.062302 -312.355478) (xy 406.013127 -312.353497) (xy 405.964908 -312.343653) (xy 405.918892 -312.326201)
			(xy 405.876271 -312.301594) (xy 405.83815 -312.270469) (xy 405.805515 -312.233632) (xy 405.779212 -312.192036)
			(xy 405.759921 -312.14676) (xy 405.748144 -312.098976) (xy 405.744184 -312.049922) (xy 405.405336 -312.049922)
			(xy 405.404841 -312.074529) (xy 405.396946 -312.123106) (xy 405.381362 -312.169787) (xy 405.358491 -312.213364)
			(xy 405.328926 -312.252708) (xy 405.293433 -312.2868) (xy 405.25293 -312.314756) (xy 405.208468 -312.335854)
			(xy 405.161197 -312.349546) (xy 405.112342 -312.355478) (xy 405.063167 -312.353497) (xy 405.014948 -312.343653)
			(xy 404.968932 -312.326201) (xy 404.926311 -312.301594) (xy 404.88819 -312.270469) (xy 404.855555 -312.233632)
			(xy 404.829252 -312.192036) (xy 404.809961 -312.14676) (xy 404.798184 -312.098976) (xy 404.794224 -312.049922)
			(xy 404.455122 -312.049922) (xy 404.454627 -312.074529) (xy 404.446732 -312.123106) (xy 404.431148 -312.169787)
			(xy 404.408277 -312.213364) (xy 404.378712 -312.252708) (xy 404.343219 -312.2868) (xy 404.302716 -312.314756)
			(xy 404.258254 -312.335854) (xy 404.210983 -312.349546) (xy 404.162128 -312.355478) (xy 404.112953 -312.353497)
			(xy 404.064734 -312.343653) (xy 404.018718 -312.326201) (xy 403.976097 -312.301594) (xy 403.937976 -312.270469)
			(xy 403.905341 -312.233632) (xy 403.879038 -312.192036) (xy 403.859747 -312.14676) (xy 403.84797 -312.098976)
			(xy 403.84401 -312.049922) (xy 403.505162 -312.049922) (xy 403.504667 -312.074529) (xy 403.496772 -312.123106)
			(xy 403.481188 -312.169787) (xy 403.458317 -312.213364) (xy 403.428752 -312.252708) (xy 403.393259 -312.2868)
			(xy 403.352756 -312.314756) (xy 403.308294 -312.335854) (xy 403.261023 -312.349546) (xy 403.212168 -312.355478)
			(xy 403.162993 -312.353497) (xy 403.114774 -312.343653) (xy 403.068758 -312.326201) (xy 403.026137 -312.301594)
			(xy 402.988016 -312.270469) (xy 402.955381 -312.233632) (xy 402.929078 -312.192036) (xy 402.909787 -312.14676)
			(xy 402.89801 -312.098976) (xy 402.89405 -312.049922) (xy 402.555202 -312.049922) (xy 402.554707 -312.074529)
			(xy 402.546812 -312.123106) (xy 402.531228 -312.169787) (xy 402.508357 -312.213364) (xy 402.478792 -312.252708)
			(xy 402.443299 -312.2868) (xy 402.402796 -312.314756) (xy 402.358334 -312.335854) (xy 402.311063 -312.349546)
			(xy 402.262208 -312.355478) (xy 402.213033 -312.353497) (xy 402.164814 -312.343653) (xy 402.118798 -312.326201)
			(xy 402.076177 -312.301594) (xy 402.038056 -312.270469) (xy 402.005421 -312.233632) (xy 401.979118 -312.192036)
			(xy 401.959827 -312.14676) (xy 401.94805 -312.098976) (xy 401.94409 -312.049922) (xy 401.605242 -312.049922)
			(xy 401.604747 -312.074529) (xy 401.596852 -312.123106) (xy 401.581268 -312.169787) (xy 401.558397 -312.213364)
			(xy 401.528832 -312.252708) (xy 401.493339 -312.2868) (xy 401.452836 -312.314756) (xy 401.408374 -312.335854)
			(xy 401.361103 -312.349546) (xy 401.312248 -312.355478) (xy 401.263073 -312.353497) (xy 401.214854 -312.343653)
			(xy 401.168838 -312.326201) (xy 401.126217 -312.301594) (xy 401.088096 -312.270469) (xy 401.055461 -312.233632)
			(xy 401.029158 -312.192036) (xy 401.009867 -312.14676) (xy 400.99809 -312.098976) (xy 400.99413 -312.049922)
			(xy 400.655282 -312.049922) (xy 400.654787 -312.074529) (xy 400.646892 -312.123106) (xy 400.631308 -312.169787)
			(xy 400.608437 -312.213364) (xy 400.578872 -312.252708) (xy 400.543379 -312.2868) (xy 400.502876 -312.314756)
			(xy 400.458414 -312.335854) (xy 400.411143 -312.349546) (xy 400.362288 -312.355478) (xy 400.313113 -312.353497)
			(xy 400.264894 -312.343653) (xy 400.218878 -312.326201) (xy 400.176257 -312.301594) (xy 400.138136 -312.270469)
			(xy 400.105501 -312.233632) (xy 400.079198 -312.192036) (xy 400.059907 -312.14676) (xy 400.04813 -312.098976)
			(xy 400.04417 -312.049922) (xy 399.705322 -312.049922) (xy 399.704827 -312.074529) (xy 399.696932 -312.123106)
			(xy 399.681348 -312.169787) (xy 399.658477 -312.213364) (xy 399.628912 -312.252708) (xy 399.593419 -312.2868)
			(xy 399.552916 -312.314756) (xy 399.508454 -312.335854) (xy 399.461183 -312.349546) (xy 399.412328 -312.355478)
			(xy 399.363153 -312.353497) (xy 399.314934 -312.343653) (xy 399.268918 -312.326201) (xy 399.226297 -312.301594)
			(xy 399.188176 -312.270469) (xy 399.155541 -312.233632) (xy 399.129238 -312.192036) (xy 399.109947 -312.14676)
			(xy 399.09817 -312.098976) (xy 399.09421 -312.049922) (xy 398.755108 -312.049922) (xy 398.754613 -312.074529)
			(xy 398.746718 -312.123106) (xy 398.731134 -312.169787) (xy 398.708263 -312.213364) (xy 398.678698 -312.252708)
			(xy 398.643205 -312.2868) (xy 398.602702 -312.314756) (xy 398.55824 -312.335854) (xy 398.510969 -312.349546)
			(xy 398.462114 -312.355478) (xy 398.412939 -312.353497) (xy 398.36472 -312.343653) (xy 398.318704 -312.326201)
			(xy 398.276083 -312.301594) (xy 398.237962 -312.270469) (xy 398.205327 -312.233632) (xy 398.179024 -312.192036)
			(xy 398.159733 -312.14676) (xy 398.147956 -312.098976) (xy 398.143996 -312.049922) (xy 397.805148 -312.049922)
			(xy 397.804653 -312.074529) (xy 397.796758 -312.123106) (xy 397.781174 -312.169787) (xy 397.758303 -312.213364)
			(xy 397.728738 -312.252708) (xy 397.693245 -312.2868) (xy 397.652742 -312.314756) (xy 397.60828 -312.335854)
			(xy 397.561009 -312.349546) (xy 397.512154 -312.355478) (xy 397.462979 -312.353497) (xy 397.41476 -312.343653)
			(xy 397.368744 -312.326201) (xy 397.326123 -312.301594) (xy 397.288002 -312.270469) (xy 397.255367 -312.233632)
			(xy 397.229064 -312.192036) (xy 397.209773 -312.14676) (xy 397.197996 -312.098976) (xy 397.194036 -312.049922)
			(xy 396.855188 -312.049922) (xy 396.854693 -312.074529) (xy 396.846798 -312.123106) (xy 396.831214 -312.169787)
			(xy 396.808343 -312.213364) (xy 396.778778 -312.252708) (xy 396.743285 -312.2868) (xy 396.702782 -312.314756)
			(xy 396.65832 -312.335854) (xy 396.611049 -312.349546) (xy 396.562194 -312.355478) (xy 396.513019 -312.353497)
			(xy 396.4648 -312.343653) (xy 396.418784 -312.326201) (xy 396.376163 -312.301594) (xy 396.338042 -312.270469)
			(xy 396.305407 -312.233632) (xy 396.279104 -312.192036) (xy 396.259813 -312.14676) (xy 396.248036 -312.098976)
			(xy 396.244076 -312.049922) (xy 395.905228 -312.049922) (xy 395.904733 -312.074529) (xy 395.896838 -312.123106)
			(xy 395.881254 -312.169787) (xy 395.858383 -312.213364) (xy 395.828818 -312.252708) (xy 395.793325 -312.2868)
			(xy 395.752822 -312.314756) (xy 395.70836 -312.335854) (xy 395.661089 -312.349546) (xy 395.612234 -312.355478)
			(xy 395.563059 -312.353497) (xy 395.51484 -312.343653) (xy 395.468824 -312.326201) (xy 395.426203 -312.301594)
			(xy 395.388082 -312.270469) (xy 395.355447 -312.233632) (xy 395.329144 -312.192036) (xy 395.309853 -312.14676)
			(xy 395.298076 -312.098976) (xy 395.294116 -312.049922) (xy 394.955268 -312.049922) (xy 394.954773 -312.074529)
			(xy 394.946878 -312.123106) (xy 394.931294 -312.169787) (xy 394.908423 -312.213364) (xy 394.878858 -312.252708)
			(xy 394.843365 -312.2868) (xy 394.802862 -312.314756) (xy 394.7584 -312.335854) (xy 394.711129 -312.349546)
			(xy 394.662274 -312.355478) (xy 394.613099 -312.353497) (xy 394.56488 -312.343653) (xy 394.518864 -312.326201)
			(xy 394.476243 -312.301594) (xy 394.438122 -312.270469) (xy 394.405487 -312.233632) (xy 394.379184 -312.192036)
			(xy 394.359893 -312.14676) (xy 394.348116 -312.098976) (xy 394.344156 -312.049922) (xy 394.005308 -312.049922)
			(xy 394.004813 -312.074529) (xy 393.996918 -312.123106) (xy 393.981334 -312.169787) (xy 393.958463 -312.213364)
			(xy 393.928898 -312.252708) (xy 393.893405 -312.2868) (xy 393.852902 -312.314756) (xy 393.80844 -312.335854)
			(xy 393.761169 -312.349546) (xy 393.712314 -312.355478) (xy 393.663139 -312.353497) (xy 393.61492 -312.343653)
			(xy 393.568904 -312.326201) (xy 393.526283 -312.301594) (xy 393.488162 -312.270469) (xy 393.455527 -312.233632)
			(xy 393.429224 -312.192036) (xy 393.409933 -312.14676) (xy 393.398156 -312.098976) (xy 393.394196 -312.049922)
			(xy 393.055094 -312.049922) (xy 393.054599 -312.074529) (xy 393.046704 -312.123106) (xy 393.03112 -312.169787)
			(xy 393.008249 -312.213364) (xy 392.978684 -312.252708) (xy 392.943191 -312.2868) (xy 392.902688 -312.314756)
			(xy 392.858226 -312.335854) (xy 392.810955 -312.349546) (xy 392.7621 -312.355478) (xy 392.712925 -312.353497)
			(xy 392.664706 -312.343653) (xy 392.61869 -312.326201) (xy 392.576069 -312.301594) (xy 392.537948 -312.270469)
			(xy 392.505313 -312.233632) (xy 392.47901 -312.192036) (xy 392.459719 -312.14676) (xy 392.447942 -312.098976)
			(xy 392.443982 -312.049922) (xy 392.105134 -312.049922) (xy 392.104639 -312.074529) (xy 392.096744 -312.123106)
			(xy 392.08116 -312.169787) (xy 392.058289 -312.213364) (xy 392.028724 -312.252708) (xy 391.993231 -312.2868)
			(xy 391.952728 -312.314756) (xy 391.908266 -312.335854) (xy 391.860995 -312.349546) (xy 391.81214 -312.355478)
			(xy 391.762965 -312.353497) (xy 391.714746 -312.343653) (xy 391.66873 -312.326201) (xy 391.626109 -312.301594)
			(xy 391.587988 -312.270469) (xy 391.555353 -312.233632) (xy 391.52905 -312.192036) (xy 391.509759 -312.14676)
			(xy 391.497982 -312.098976) (xy 391.494022 -312.049922) (xy 391.155174 -312.049922) (xy 391.154679 -312.074529)
			(xy 391.146784 -312.123106) (xy 391.1312 -312.169787) (xy 391.108329 -312.213364) (xy 391.078764 -312.252708)
			(xy 391.043271 -312.2868) (xy 391.002768 -312.314756) (xy 390.958306 -312.335854) (xy 390.911035 -312.349546)
			(xy 390.86218 -312.355478) (xy 390.813005 -312.353497) (xy 390.764786 -312.343653) (xy 390.71877 -312.326201)
			(xy 390.676149 -312.301594) (xy 390.638028 -312.270469) (xy 390.605393 -312.233632) (xy 390.57909 -312.192036)
			(xy 390.559799 -312.14676) (xy 390.548022 -312.098976) (xy 390.544062 -312.049922) (xy 390.205214 -312.049922)
			(xy 390.204719 -312.074529) (xy 390.196824 -312.123106) (xy 390.18124 -312.169787) (xy 390.158369 -312.213364)
			(xy 390.128804 -312.252708) (xy 390.093311 -312.2868) (xy 390.052808 -312.314756) (xy 390.008346 -312.335854)
			(xy 389.961075 -312.349546) (xy 389.91222 -312.355478) (xy 389.863045 -312.353497) (xy 389.814826 -312.343653)
			(xy 389.76881 -312.326201) (xy 389.726189 -312.301594) (xy 389.688068 -312.270469) (xy 389.655433 -312.233632)
			(xy 389.62913 -312.192036) (xy 389.609839 -312.14676) (xy 389.598062 -312.098976) (xy 389.594102 -312.049922)
			(xy 389.255254 -312.049922) (xy 389.254759 -312.074529) (xy 389.246864 -312.123106) (xy 389.23128 -312.169787)
			(xy 389.208409 -312.213364) (xy 389.178844 -312.252708) (xy 389.143351 -312.2868) (xy 389.102848 -312.314756)
			(xy 389.058386 -312.335854) (xy 389.011115 -312.349546) (xy 388.96226 -312.355478) (xy 388.913085 -312.353497)
			(xy 388.864866 -312.343653) (xy 388.81885 -312.326201) (xy 388.776229 -312.301594) (xy 388.738108 -312.270469)
			(xy 388.705473 -312.233632) (xy 388.67917 -312.192036) (xy 388.659879 -312.14676) (xy 388.648102 -312.098976)
			(xy 388.644142 -312.049922) (xy 388.305294 -312.049922) (xy 388.304799 -312.074529) (xy 388.296904 -312.123106)
			(xy 388.28132 -312.169787) (xy 388.258449 -312.213364) (xy 388.228884 -312.252708) (xy 388.193391 -312.2868)
			(xy 388.152888 -312.314756) (xy 388.108426 -312.335854) (xy 388.061155 -312.349546) (xy 388.0123 -312.355478)
			(xy 387.963125 -312.353497) (xy 387.914906 -312.343653) (xy 387.86889 -312.326201) (xy 387.826269 -312.301594)
			(xy 387.788148 -312.270469) (xy 387.755513 -312.233632) (xy 387.72921 -312.192036) (xy 387.709919 -312.14676)
			(xy 387.698142 -312.098976) (xy 387.694182 -312.049922) (xy 387.355334 -312.049922) (xy 387.354839 -312.074529)
			(xy 387.346944 -312.123106) (xy 387.33136 -312.169787) (xy 387.308489 -312.213364) (xy 387.278924 -312.252708)
			(xy 387.243431 -312.2868) (xy 387.202928 -312.314756) (xy 387.158466 -312.335854) (xy 387.111195 -312.349546)
			(xy 387.06234 -312.355478) (xy 387.013165 -312.353497) (xy 386.964946 -312.343653) (xy 386.91893 -312.326201)
			(xy 386.876309 -312.301594) (xy 386.838188 -312.270469) (xy 386.805553 -312.233632) (xy 386.77925 -312.192036)
			(xy 386.759959 -312.14676) (xy 386.748182 -312.098976) (xy 386.744222 -312.049922) (xy 386.40512 -312.049922)
			(xy 386.404625 -312.074529) (xy 386.39673 -312.123106) (xy 386.381146 -312.169787) (xy 386.358275 -312.213364)
			(xy 386.32871 -312.252708) (xy 386.293217 -312.2868) (xy 386.252714 -312.314756) (xy 386.208252 -312.335854)
			(xy 386.160981 -312.349546) (xy 386.112126 -312.355478) (xy 386.062951 -312.353497) (xy 386.014732 -312.343653)
			(xy 385.968716 -312.326201) (xy 385.926095 -312.301594) (xy 385.887974 -312.270469) (xy 385.855339 -312.233632)
			(xy 385.829036 -312.192036) (xy 385.809745 -312.14676) (xy 385.797968 -312.098976) (xy 385.794008 -312.049922)
			(xy 385.45516 -312.049922) (xy 385.454665 -312.074529) (xy 385.44677 -312.123106) (xy 385.431186 -312.169787)
			(xy 385.408315 -312.213364) (xy 385.37875 -312.252708) (xy 385.343257 -312.2868) (xy 385.302754 -312.314756)
			(xy 385.258292 -312.335854) (xy 385.211021 -312.349546) (xy 385.162166 -312.355478) (xy 385.112991 -312.353497)
			(xy 385.064772 -312.343653) (xy 385.018756 -312.326201) (xy 384.976135 -312.301594) (xy 384.938014 -312.270469)
			(xy 384.905379 -312.233632) (xy 384.879076 -312.192036) (xy 384.859785 -312.14676) (xy 384.848008 -312.098976)
			(xy 384.844048 -312.049922) (xy 384.504941 -312.049922) (xy 384.504451 -312.074275) (xy 384.496556 -312.122852)
			(xy 384.480972 -312.169533) (xy 384.458101 -312.21311) (xy 384.428536 -312.252454) (xy 384.393043 -312.286546)
			(xy 384.35254 -312.314502) (xy 384.308078 -312.3356) (xy 384.260807 -312.349292) (xy 384.211952 -312.355224)
			(xy 384.162777 -312.353243) (xy 384.114558 -312.343399) (xy 384.068542 -312.325947) (xy 384.025921 -312.30134)
			(xy 383.9878 -312.270215) (xy 383.955165 -312.233378) (xy 383.928862 -312.191782) (xy 383.909571 -312.146506)
			(xy 383.897794 -312.098722) (xy 383.893834 -312.049668) (xy 383.105048 -312.049668) (xy 383.125871 -312.081142)
			(xy 383.149543 -312.131639) (xy 383.165611 -312.185046) (xy 383.173731 -312.240222) (xy 383.17424 -312.268108)
			(xy 383.173731 -312.295994) (xy 383.165611 -312.35117) (xy 383.149543 -312.404577) (xy 383.125871 -312.455074)
			(xy 383.095098 -312.501587) (xy 383.057881 -312.543124) (xy 383.015013 -312.578799) (xy 382.967407 -312.607853)
			(xy 382.916078 -312.629665) (xy 382.862121 -312.643771) (xy 382.806684 -312.649871) (xy 382.75095 -312.647834)
			(xy 382.696107 -312.637704) (xy 382.643323 -312.619697) (xy 382.593723 -312.594196) (xy 382.548365 -312.561745)
			(xy 382.508216 -312.523036) (xy 382.47413 -312.478893) (xy 382.446834 -312.430258) (xy 382.426911 -312.378167)
			(xy 382.414785 -312.32373) (xy 382.410714 -312.268108) (xy 380.696863 -312.268108) (xy 380.716388 -312.289899)
			(xy 380.747161 -312.336412) (xy 380.770833 -312.386909) (xy 380.786901 -312.440316) (xy 380.795021 -312.495492)
			(xy 380.79553 -312.523378) (xy 380.795021 -312.551264) (xy 380.786901 -312.60644) (xy 380.770833 -312.659847)
			(xy 380.747161 -312.710344) (xy 380.716388 -312.756857) (xy 380.679171 -312.798394) (xy 380.636303 -312.834069)
			(xy 380.588697 -312.863123) (xy 380.537368 -312.884935) (xy 380.483411 -312.899041) (xy 380.427974 -312.905141)
			(xy 380.37224 -312.903104) (xy 380.317397 -312.892974) (xy 380.264613 -312.874967) (xy 380.215013 -312.849466)
			(xy 380.169655 -312.817015) (xy 380.129506 -312.778306) (xy 380.09542 -312.734163) (xy 380.068124 -312.685528)
			(xy 380.048201 -312.633437) (xy 380.036075 -312.579) (xy 380.032004 -312.523378) (xy 364.292085 -312.523378)
			(xy 364.287823 -312.552338) (xy 364.271755 -312.605745) (xy 364.248083 -312.656242) (xy 364.21731 -312.702755)
			(xy 364.180093 -312.744292) (xy 364.137225 -312.779967) (xy 364.089619 -312.809021) (xy 364.03829 -312.830833)
			(xy 363.984333 -312.844939) (xy 363.928896 -312.851039) (xy 363.873162 -312.849002) (xy 363.818319 -312.838872)
			(xy 363.765535 -312.820865) (xy 363.715935 -312.795364) (xy 363.670577 -312.762913) (xy 363.630428 -312.724204)
			(xy 363.596342 -312.680061) (xy 363.569046 -312.631426) (xy 363.549123 -312.579335) (xy 363.536997 -312.524898)
			(xy 363.532926 -312.469276) (xy 363.280452 -312.469276) (xy 363.279943 -312.497162) (xy 363.271823 -312.552338)
			(xy 363.255755 -312.605745) (xy 363.232083 -312.656242) (xy 363.20131 -312.702755) (xy 363.164093 -312.744292)
			(xy 363.121225 -312.779967) (xy 363.073619 -312.809021) (xy 363.02229 -312.830833) (xy 362.968333 -312.844939)
			(xy 362.912896 -312.851039) (xy 362.857162 -312.849002) (xy 362.802319 -312.838872) (xy 362.749535 -312.820865)
			(xy 362.699935 -312.795364) (xy 362.654577 -312.762913) (xy 362.614428 -312.724204) (xy 362.580342 -312.680061)
			(xy 362.553046 -312.631426) (xy 362.533123 -312.579335) (xy 362.520997 -312.524898) (xy 362.516926 -312.469276)
			(xy 362.264452 -312.469276) (xy 362.263943 -312.497162) (xy 362.255823 -312.552338) (xy 362.239755 -312.605745)
			(xy 362.216083 -312.656242) (xy 362.18531 -312.702755) (xy 362.148093 -312.744292) (xy 362.105225 -312.779967)
			(xy 362.057619 -312.809021) (xy 362.00629 -312.830833) (xy 361.952333 -312.844939) (xy 361.896896 -312.851039)
			(xy 361.841162 -312.849002) (xy 361.786319 -312.838872) (xy 361.733535 -312.820865) (xy 361.683935 -312.795364)
			(xy 361.638577 -312.762913) (xy 361.598428 -312.724204) (xy 361.564342 -312.680061) (xy 361.537046 -312.631426)
			(xy 361.517123 -312.579335) (xy 361.504997 -312.524898) (xy 361.500926 -312.469276) (xy 361.248452 -312.469276)
			(xy 361.247943 -312.497162) (xy 361.239823 -312.552338) (xy 361.223755 -312.605745) (xy 361.200083 -312.656242)
			(xy 361.16931 -312.702755) (xy 361.132093 -312.744292) (xy 361.089225 -312.779967) (xy 361.041619 -312.809021)
			(xy 360.99029 -312.830833) (xy 360.936333 -312.844939) (xy 360.880896 -312.851039) (xy 360.825162 -312.849002)
			(xy 360.770319 -312.838872) (xy 360.717535 -312.820865) (xy 360.667935 -312.795364) (xy 360.622577 -312.762913)
			(xy 360.582428 -312.724204) (xy 360.548342 -312.680061) (xy 360.521046 -312.631426) (xy 360.501123 -312.579335)
			(xy 360.488997 -312.524898) (xy 360.484926 -312.469276) (xy 360.232452 -312.469276) (xy 360.231943 -312.497162)
			(xy 360.223823 -312.552338) (xy 360.207755 -312.605745) (xy 360.184083 -312.656242) (xy 360.15331 -312.702755)
			(xy 360.116093 -312.744292) (xy 360.073225 -312.779967) (xy 360.025619 -312.809021) (xy 359.97429 -312.830833)
			(xy 359.920333 -312.844939) (xy 359.864896 -312.851039) (xy 359.809162 -312.849002) (xy 359.754319 -312.838872)
			(xy 359.701535 -312.820865) (xy 359.651935 -312.795364) (xy 359.606577 -312.762913) (xy 359.566428 -312.724204)
			(xy 359.532342 -312.680061) (xy 359.505046 -312.631426) (xy 359.485123 -312.579335) (xy 359.472997 -312.524898)
			(xy 359.468926 -312.469276) (xy 359.216452 -312.469276) (xy 359.215943 -312.497162) (xy 359.207823 -312.552338)
			(xy 359.191755 -312.605745) (xy 359.168083 -312.656242) (xy 359.13731 -312.702755) (xy 359.100093 -312.744292)
			(xy 359.057225 -312.779967) (xy 359.009619 -312.809021) (xy 358.95829 -312.830833) (xy 358.904333 -312.844939)
			(xy 358.848896 -312.851039) (xy 358.793162 -312.849002) (xy 358.738319 -312.838872) (xy 358.685535 -312.820865)
			(xy 358.635935 -312.795364) (xy 358.590577 -312.762913) (xy 358.550428 -312.724204) (xy 358.516342 -312.680061)
			(xy 358.489046 -312.631426) (xy 358.469123 -312.579335) (xy 358.456997 -312.524898) (xy 358.452926 -312.469276)
			(xy 358.200452 -312.469276) (xy 358.199943 -312.497162) (xy 358.191823 -312.552338) (xy 358.175755 -312.605745)
			(xy 358.152083 -312.656242) (xy 358.12131 -312.702755) (xy 358.084093 -312.744292) (xy 358.041225 -312.779967)
			(xy 357.993619 -312.809021) (xy 357.94229 -312.830833) (xy 357.888333 -312.844939) (xy 357.832896 -312.851039)
			(xy 357.777162 -312.849002) (xy 357.722319 -312.838872) (xy 357.669535 -312.820865) (xy 357.619935 -312.795364)
			(xy 357.574577 -312.762913) (xy 357.534428 -312.724204) (xy 357.500342 -312.680061) (xy 357.473046 -312.631426)
			(xy 357.453123 -312.579335) (xy 357.440997 -312.524898) (xy 357.436926 -312.469276) (xy 351.831402 -312.469276)
			(xy 351.831402 -312.999882) (xy 384.844048 -312.999882) (xy 384.848008 -312.950828) (xy 384.859785 -312.903044)
			(xy 384.879076 -312.857768) (xy 384.905379 -312.816172) (xy 384.938014 -312.779335) (xy 384.976135 -312.74821)
			(xy 385.018756 -312.723603) (xy 385.064772 -312.706151) (xy 385.112991 -312.696307) (xy 385.162166 -312.694326)
			(xy 385.211021 -312.700258) (xy 385.258292 -312.71395) (xy 385.302754 -312.735048) (xy 385.343257 -312.763004)
			(xy 385.37875 -312.797096) (xy 385.408315 -312.83644) (xy 385.431186 -312.880017) (xy 385.44677 -312.926698)
			(xy 385.454665 -312.975275) (xy 385.45516 -312.999882) (xy 385.794008 -312.999882) (xy 385.797968 -312.950828)
			(xy 385.809745 -312.903044) (xy 385.829036 -312.857768) (xy 385.855339 -312.816172) (xy 385.887974 -312.779335)
			(xy 385.926095 -312.74821) (xy 385.968716 -312.723603) (xy 386.014732 -312.706151) (xy 386.062951 -312.696307)
			(xy 386.112126 -312.694326) (xy 386.160981 -312.700258) (xy 386.208252 -312.71395) (xy 386.252714 -312.735048)
			(xy 386.293217 -312.763004) (xy 386.32871 -312.797096) (xy 386.358275 -312.83644) (xy 386.381146 -312.880017)
			(xy 386.39673 -312.926698) (xy 386.404625 -312.975275) (xy 386.40512 -312.999882) (xy 386.744222 -312.999882)
			(xy 386.748182 -312.950828) (xy 386.759959 -312.903044) (xy 386.77925 -312.857768) (xy 386.805553 -312.816172)
			(xy 386.838188 -312.779335) (xy 386.876309 -312.74821) (xy 386.91893 -312.723603) (xy 386.964946 -312.706151)
			(xy 387.013165 -312.696307) (xy 387.06234 -312.694326) (xy 387.111195 -312.700258) (xy 387.158466 -312.71395)
			(xy 387.202928 -312.735048) (xy 387.243431 -312.763004) (xy 387.278924 -312.797096) (xy 387.308489 -312.83644)
			(xy 387.33136 -312.880017) (xy 387.346944 -312.926698) (xy 387.354839 -312.975275) (xy 387.355334 -312.999882)
			(xy 387.694182 -312.999882) (xy 387.698142 -312.950828) (xy 387.709919 -312.903044) (xy 387.72921 -312.857768)
			(xy 387.755513 -312.816172) (xy 387.788148 -312.779335) (xy 387.826269 -312.74821) (xy 387.86889 -312.723603)
			(xy 387.914906 -312.706151) (xy 387.963125 -312.696307) (xy 388.0123 -312.694326) (xy 388.061155 -312.700258)
			(xy 388.108426 -312.71395) (xy 388.152888 -312.735048) (xy 388.193391 -312.763004) (xy 388.228884 -312.797096)
			(xy 388.258449 -312.83644) (xy 388.28132 -312.880017) (xy 388.296904 -312.926698) (xy 388.304799 -312.975275)
			(xy 388.305294 -312.999882) (xy 388.644142 -312.999882) (xy 388.648102 -312.950828) (xy 388.659879 -312.903044)
			(xy 388.67917 -312.857768) (xy 388.705473 -312.816172) (xy 388.738108 -312.779335) (xy 388.776229 -312.74821)
			(xy 388.81885 -312.723603) (xy 388.864866 -312.706151) (xy 388.913085 -312.696307) (xy 388.96226 -312.694326)
			(xy 389.011115 -312.700258) (xy 389.058386 -312.71395) (xy 389.102848 -312.735048) (xy 389.143351 -312.763004)
			(xy 389.178844 -312.797096) (xy 389.208409 -312.83644) (xy 389.23128 -312.880017) (xy 389.246864 -312.926698)
			(xy 389.254759 -312.975275) (xy 389.255254 -312.999882) (xy 389.594102 -312.999882) (xy 389.598062 -312.950828)
			(xy 389.609839 -312.903044) (xy 389.62913 -312.857768) (xy 389.655433 -312.816172) (xy 389.688068 -312.779335)
			(xy 389.726189 -312.74821) (xy 389.76881 -312.723603) (xy 389.814826 -312.706151) (xy 389.863045 -312.696307)
			(xy 389.91222 -312.694326) (xy 389.961075 -312.700258) (xy 390.008346 -312.71395) (xy 390.052808 -312.735048)
			(xy 390.093311 -312.763004) (xy 390.128804 -312.797096) (xy 390.158369 -312.83644) (xy 390.18124 -312.880017)
			(xy 390.196824 -312.926698) (xy 390.204719 -312.975275) (xy 390.205214 -312.999882) (xy 390.544062 -312.999882)
			(xy 390.548022 -312.950828) (xy 390.559799 -312.903044) (xy 390.57909 -312.857768) (xy 390.605393 -312.816172)
			(xy 390.638028 -312.779335) (xy 390.676149 -312.74821) (xy 390.71877 -312.723603) (xy 390.764786 -312.706151)
			(xy 390.813005 -312.696307) (xy 390.86218 -312.694326) (xy 390.911035 -312.700258) (xy 390.958306 -312.71395)
			(xy 391.002768 -312.735048) (xy 391.043271 -312.763004) (xy 391.078764 -312.797096) (xy 391.108329 -312.83644)
			(xy 391.1312 -312.880017) (xy 391.146784 -312.926698) (xy 391.154679 -312.975275) (xy 391.155174 -312.999882)
			(xy 391.494022 -312.999882) (xy 391.497982 -312.950828) (xy 391.509759 -312.903044) (xy 391.52905 -312.857768)
			(xy 391.555353 -312.816172) (xy 391.587988 -312.779335) (xy 391.626109 -312.74821) (xy 391.66873 -312.723603)
			(xy 391.714746 -312.706151) (xy 391.762965 -312.696307) (xy 391.81214 -312.694326) (xy 391.860995 -312.700258)
			(xy 391.908266 -312.71395) (xy 391.952728 -312.735048) (xy 391.993231 -312.763004) (xy 392.028724 -312.797096)
			(xy 392.058289 -312.83644) (xy 392.08116 -312.880017) (xy 392.096744 -312.926698) (xy 392.104639 -312.975275)
			(xy 392.105134 -312.999882) (xy 392.443982 -312.999882) (xy 392.447942 -312.950828) (xy 392.459719 -312.903044)
			(xy 392.47901 -312.857768) (xy 392.505313 -312.816172) (xy 392.537948 -312.779335) (xy 392.576069 -312.74821)
			(xy 392.61869 -312.723603) (xy 392.664706 -312.706151) (xy 392.712925 -312.696307) (xy 392.7621 -312.694326)
			(xy 392.810955 -312.700258) (xy 392.858226 -312.71395) (xy 392.902688 -312.735048) (xy 392.943191 -312.763004)
			(xy 392.978684 -312.797096) (xy 393.008249 -312.83644) (xy 393.03112 -312.880017) (xy 393.046704 -312.926698)
			(xy 393.054599 -312.975275) (xy 393.055094 -312.999882) (xy 393.394196 -312.999882) (xy 393.398156 -312.950828)
			(xy 393.409933 -312.903044) (xy 393.429224 -312.857768) (xy 393.455527 -312.816172) (xy 393.488162 -312.779335)
			(xy 393.526283 -312.74821) (xy 393.568904 -312.723603) (xy 393.61492 -312.706151) (xy 393.663139 -312.696307)
			(xy 393.712314 -312.694326) (xy 393.761169 -312.700258) (xy 393.80844 -312.71395) (xy 393.852902 -312.735048)
			(xy 393.893405 -312.763004) (xy 393.928898 -312.797096) (xy 393.958463 -312.83644) (xy 393.981334 -312.880017)
			(xy 393.996918 -312.926698) (xy 394.004813 -312.975275) (xy 394.005308 -312.999882) (xy 394.344156 -312.999882)
			(xy 394.348116 -312.950828) (xy 394.359893 -312.903044) (xy 394.379184 -312.857768) (xy 394.405487 -312.816172)
			(xy 394.438122 -312.779335) (xy 394.476243 -312.74821) (xy 394.518864 -312.723603) (xy 394.56488 -312.706151)
			(xy 394.613099 -312.696307) (xy 394.662274 -312.694326) (xy 394.711129 -312.700258) (xy 394.7584 -312.71395)
			(xy 394.802862 -312.735048) (xy 394.843365 -312.763004) (xy 394.878858 -312.797096) (xy 394.908423 -312.83644)
			(xy 394.931294 -312.880017) (xy 394.946878 -312.926698) (xy 394.954773 -312.975275) (xy 394.955268 -312.999882)
			(xy 394.954773 -313.024489) (xy 394.946878 -313.073066) (xy 394.931294 -313.119747) (xy 394.908423 -313.163324)
			(xy 394.878858 -313.202668) (xy 394.843365 -313.23676) (xy 394.802862 -313.264716) (xy 394.7584 -313.285814)
			(xy 394.711129 -313.299506) (xy 394.662274 -313.305438) (xy 394.613099 -313.303457) (xy 394.56488 -313.293613)
			(xy 394.518864 -313.276161) (xy 394.476243 -313.251554) (xy 394.438122 -313.220429) (xy 394.405487 -313.183592)
			(xy 394.379184 -313.141996) (xy 394.359893 -313.09672) (xy 394.348116 -313.048936) (xy 394.344156 -312.999882)
			(xy 394.005308 -312.999882) (xy 394.004813 -313.024489) (xy 393.996918 -313.073066) (xy 393.981334 -313.119747)
			(xy 393.958463 -313.163324) (xy 393.928898 -313.202668) (xy 393.893405 -313.23676) (xy 393.852902 -313.264716)
			(xy 393.80844 -313.285814) (xy 393.761169 -313.299506) (xy 393.712314 -313.305438) (xy 393.663139 -313.303457)
			(xy 393.61492 -313.293613) (xy 393.568904 -313.276161) (xy 393.526283 -313.251554) (xy 393.488162 -313.220429)
			(xy 393.455527 -313.183592) (xy 393.429224 -313.141996) (xy 393.409933 -313.09672) (xy 393.398156 -313.048936)
			(xy 393.394196 -312.999882) (xy 393.055094 -312.999882) (xy 393.054599 -313.024489) (xy 393.046704 -313.073066)
			(xy 393.03112 -313.119747) (xy 393.008249 -313.163324) (xy 392.978684 -313.202668) (xy 392.943191 -313.23676)
			(xy 392.902688 -313.264716) (xy 392.858226 -313.285814) (xy 392.810955 -313.299506) (xy 392.7621 -313.305438)
			(xy 392.712925 -313.303457) (xy 392.664706 -313.293613) (xy 392.61869 -313.276161) (xy 392.576069 -313.251554)
			(xy 392.537948 -313.220429) (xy 392.505313 -313.183592) (xy 392.47901 -313.141996) (xy 392.459719 -313.09672)
			(xy 392.447942 -313.048936) (xy 392.443982 -312.999882) (xy 392.105134 -312.999882) (xy 392.104639 -313.024489)
			(xy 392.096744 -313.073066) (xy 392.08116 -313.119747) (xy 392.058289 -313.163324) (xy 392.028724 -313.202668)
			(xy 391.993231 -313.23676) (xy 391.952728 -313.264716) (xy 391.908266 -313.285814) (xy 391.860995 -313.299506)
			(xy 391.81214 -313.305438) (xy 391.762965 -313.303457) (xy 391.714746 -313.293613) (xy 391.66873 -313.276161)
			(xy 391.626109 -313.251554) (xy 391.587988 -313.220429) (xy 391.555353 -313.183592) (xy 391.52905 -313.141996)
			(xy 391.509759 -313.09672) (xy 391.497982 -313.048936) (xy 391.494022 -312.999882) (xy 391.155174 -312.999882)
			(xy 391.154679 -313.024489) (xy 391.146784 -313.073066) (xy 391.1312 -313.119747) (xy 391.108329 -313.163324)
			(xy 391.078764 -313.202668) (xy 391.043271 -313.23676) (xy 391.002768 -313.264716) (xy 390.958306 -313.285814)
			(xy 390.911035 -313.299506) (xy 390.86218 -313.305438) (xy 390.813005 -313.303457) (xy 390.764786 -313.293613)
			(xy 390.71877 -313.276161) (xy 390.676149 -313.251554) (xy 390.638028 -313.220429) (xy 390.605393 -313.183592)
			(xy 390.57909 -313.141996) (xy 390.559799 -313.09672) (xy 390.548022 -313.048936) (xy 390.544062 -312.999882)
			(xy 390.205214 -312.999882) (xy 390.204719 -313.024489) (xy 390.196824 -313.073066) (xy 390.18124 -313.119747)
			(xy 390.158369 -313.163324) (xy 390.128804 -313.202668) (xy 390.093311 -313.23676) (xy 390.052808 -313.264716)
			(xy 390.008346 -313.285814) (xy 389.961075 -313.299506) (xy 389.91222 -313.305438) (xy 389.863045 -313.303457)
			(xy 389.814826 -313.293613) (xy 389.76881 -313.276161) (xy 389.726189 -313.251554) (xy 389.688068 -313.220429)
			(xy 389.655433 -313.183592) (xy 389.62913 -313.141996) (xy 389.609839 -313.09672) (xy 389.598062 -313.048936)
			(xy 389.594102 -312.999882) (xy 389.255254 -312.999882) (xy 389.254759 -313.024489) (xy 389.246864 -313.073066)
			(xy 389.23128 -313.119747) (xy 389.208409 -313.163324) (xy 389.178844 -313.202668) (xy 389.143351 -313.23676)
			(xy 389.102848 -313.264716) (xy 389.058386 -313.285814) (xy 389.011115 -313.299506) (xy 388.96226 -313.305438)
			(xy 388.913085 -313.303457) (xy 388.864866 -313.293613) (xy 388.81885 -313.276161) (xy 388.776229 -313.251554)
			(xy 388.738108 -313.220429) (xy 388.705473 -313.183592) (xy 388.67917 -313.141996) (xy 388.659879 -313.09672)
			(xy 388.648102 -313.048936) (xy 388.644142 -312.999882) (xy 388.305294 -312.999882) (xy 388.304799 -313.024489)
			(xy 388.296904 -313.073066) (xy 388.28132 -313.119747) (xy 388.258449 -313.163324) (xy 388.228884 -313.202668)
			(xy 388.193391 -313.23676) (xy 388.152888 -313.264716) (xy 388.108426 -313.285814) (xy 388.061155 -313.299506)
			(xy 388.0123 -313.305438) (xy 387.963125 -313.303457) (xy 387.914906 -313.293613) (xy 387.86889 -313.276161)
			(xy 387.826269 -313.251554) (xy 387.788148 -313.220429) (xy 387.755513 -313.183592) (xy 387.72921 -313.141996)
			(xy 387.709919 -313.09672) (xy 387.698142 -313.048936) (xy 387.694182 -312.999882) (xy 387.355334 -312.999882)
			(xy 387.354839 -313.024489) (xy 387.346944 -313.073066) (xy 387.33136 -313.119747) (xy 387.308489 -313.163324)
			(xy 387.278924 -313.202668) (xy 387.243431 -313.23676) (xy 387.202928 -313.264716) (xy 387.158466 -313.285814)
			(xy 387.111195 -313.299506) (xy 387.06234 -313.305438) (xy 387.013165 -313.303457) (xy 386.964946 -313.293613)
			(xy 386.91893 -313.276161) (xy 386.876309 -313.251554) (xy 386.838188 -313.220429) (xy 386.805553 -313.183592)
			(xy 386.77925 -313.141996) (xy 386.759959 -313.09672) (xy 386.748182 -313.048936) (xy 386.744222 -312.999882)
			(xy 386.40512 -312.999882) (xy 386.404625 -313.024489) (xy 386.39673 -313.073066) (xy 386.381146 -313.119747)
			(xy 386.358275 -313.163324) (xy 386.32871 -313.202668) (xy 386.293217 -313.23676) (xy 386.252714 -313.264716)
			(xy 386.208252 -313.285814) (xy 386.160981 -313.299506) (xy 386.112126 -313.305438) (xy 386.062951 -313.303457)
			(xy 386.014732 -313.293613) (xy 385.968716 -313.276161) (xy 385.926095 -313.251554) (xy 385.887974 -313.220429)
			(xy 385.855339 -313.183592) (xy 385.829036 -313.141996) (xy 385.809745 -313.09672) (xy 385.797968 -313.048936)
			(xy 385.794008 -312.999882) (xy 385.45516 -312.999882) (xy 385.454665 -313.024489) (xy 385.44677 -313.073066)
			(xy 385.431186 -313.119747) (xy 385.408315 -313.163324) (xy 385.37875 -313.202668) (xy 385.343257 -313.23676)
			(xy 385.302754 -313.264716) (xy 385.258292 -313.285814) (xy 385.211021 -313.299506) (xy 385.162166 -313.305438)
			(xy 385.112991 -313.303457) (xy 385.064772 -313.293613) (xy 385.018756 -313.276161) (xy 384.976135 -313.251554)
			(xy 384.938014 -313.220429) (xy 384.905379 -313.183592) (xy 384.879076 -313.141996) (xy 384.859785 -313.09672)
			(xy 384.848008 -313.048936) (xy 384.844048 -312.999882) (xy 351.831402 -312.999882) (xy 351.831402 -313.485276)
			(xy 357.436926 -313.485276) (xy 357.440997 -313.429654) (xy 357.453123 -313.375217) (xy 357.473046 -313.323126)
			(xy 357.500342 -313.274491) (xy 357.534428 -313.230348) (xy 357.574577 -313.191639) (xy 357.619935 -313.159188)
			(xy 357.669535 -313.133687) (xy 357.722319 -313.11568) (xy 357.777162 -313.10555) (xy 357.832896 -313.103513)
			(xy 357.888333 -313.109613) (xy 357.94229 -313.123719) (xy 357.993619 -313.145531) (xy 358.041225 -313.174585)
			(xy 358.084093 -313.21026) (xy 358.12131 -313.251797) (xy 358.152083 -313.29831) (xy 358.175755 -313.348807)
			(xy 358.191823 -313.402214) (xy 358.199943 -313.45739) (xy 358.200452 -313.485276) (xy 358.452926 -313.485276)
			(xy 358.456997 -313.429654) (xy 358.469123 -313.375217) (xy 358.489046 -313.323126) (xy 358.516342 -313.274491)
			(xy 358.550428 -313.230348) (xy 358.590577 -313.191639) (xy 358.635935 -313.159188) (xy 358.685535 -313.133687)
			(xy 358.738319 -313.11568) (xy 358.793162 -313.10555) (xy 358.848896 -313.103513) (xy 358.904333 -313.109613)
			(xy 358.95829 -313.123719) (xy 359.009619 -313.145531) (xy 359.057225 -313.174585) (xy 359.100093 -313.21026)
			(xy 359.13731 -313.251797) (xy 359.168083 -313.29831) (xy 359.191755 -313.348807) (xy 359.207823 -313.402214)
			(xy 359.215943 -313.45739) (xy 359.216452 -313.485276) (xy 359.468926 -313.485276) (xy 359.472997 -313.429654)
			(xy 359.485123 -313.375217) (xy 359.505046 -313.323126) (xy 359.532342 -313.274491) (xy 359.566428 -313.230348)
			(xy 359.606577 -313.191639) (xy 359.651935 -313.159188) (xy 359.701535 -313.133687) (xy 359.754319 -313.11568)
			(xy 359.809162 -313.10555) (xy 359.864896 -313.103513) (xy 359.920333 -313.109613) (xy 359.97429 -313.123719)
			(xy 360.025619 -313.145531) (xy 360.073225 -313.174585) (xy 360.116093 -313.21026) (xy 360.15331 -313.251797)
			(xy 360.184083 -313.29831) (xy 360.207755 -313.348807) (xy 360.223823 -313.402214) (xy 360.231943 -313.45739)
			(xy 360.232452 -313.485276) (xy 360.484926 -313.485276) (xy 360.488997 -313.429654) (xy 360.501123 -313.375217)
			(xy 360.521046 -313.323126) (xy 360.548342 -313.274491) (xy 360.582428 -313.230348) (xy 360.622577 -313.191639)
			(xy 360.667935 -313.159188) (xy 360.717535 -313.133687) (xy 360.770319 -313.11568) (xy 360.825162 -313.10555)
			(xy 360.880896 -313.103513) (xy 360.936333 -313.109613) (xy 360.99029 -313.123719) (xy 361.041619 -313.145531)
			(xy 361.089225 -313.174585) (xy 361.132093 -313.21026) (xy 361.16931 -313.251797) (xy 361.200083 -313.29831)
			(xy 361.223755 -313.348807) (xy 361.239823 -313.402214) (xy 361.247943 -313.45739) (xy 361.248452 -313.485276)
			(xy 361.500926 -313.485276) (xy 361.504997 -313.429654) (xy 361.517123 -313.375217) (xy 361.537046 -313.323126)
			(xy 361.564342 -313.274491) (xy 361.598428 -313.230348) (xy 361.638577 -313.191639) (xy 361.683935 -313.159188)
			(xy 361.733535 -313.133687) (xy 361.786319 -313.11568) (xy 361.841162 -313.10555) (xy 361.896896 -313.103513)
			(xy 361.952333 -313.109613) (xy 362.00629 -313.123719) (xy 362.057619 -313.145531) (xy 362.105225 -313.174585)
			(xy 362.148093 -313.21026) (xy 362.18531 -313.251797) (xy 362.216083 -313.29831) (xy 362.239755 -313.348807)
			(xy 362.255823 -313.402214) (xy 362.263943 -313.45739) (xy 362.264452 -313.485276) (xy 362.516926 -313.485276)
			(xy 362.520997 -313.429654) (xy 362.533123 -313.375217) (xy 362.553046 -313.323126) (xy 362.580342 -313.274491)
			(xy 362.614428 -313.230348) (xy 362.654577 -313.191639) (xy 362.699935 -313.159188) (xy 362.749535 -313.133687)
			(xy 362.802319 -313.11568) (xy 362.857162 -313.10555) (xy 362.912896 -313.103513) (xy 362.968333 -313.109613)
			(xy 363.02229 -313.123719) (xy 363.073619 -313.145531) (xy 363.121225 -313.174585) (xy 363.164093 -313.21026)
			(xy 363.20131 -313.251797) (xy 363.232083 -313.29831) (xy 363.255755 -313.348807) (xy 363.271823 -313.402214)
			(xy 363.279943 -313.45739) (xy 363.280452 -313.485276) (xy 363.532926 -313.485276) (xy 363.536997 -313.429654)
			(xy 363.549123 -313.375217) (xy 363.569046 -313.323126) (xy 363.596342 -313.274491) (xy 363.630428 -313.230348)
			(xy 363.670577 -313.191639) (xy 363.715935 -313.159188) (xy 363.765535 -313.133687) (xy 363.818319 -313.11568)
			(xy 363.873162 -313.10555) (xy 363.928896 -313.103513) (xy 363.984333 -313.109613) (xy 364.03829 -313.123719)
			(xy 364.089619 -313.145531) (xy 364.137225 -313.174585) (xy 364.180093 -313.21026) (xy 364.21731 -313.251797)
			(xy 364.248083 -313.29831) (xy 364.271755 -313.348807) (xy 364.287823 -313.402214) (xy 364.295943 -313.45739)
			(xy 364.296452 -313.485276) (xy 364.295943 -313.513162) (xy 364.287823 -313.568338) (xy 364.271755 -313.621745)
			(xy 364.249165 -313.669934) (xy 382.34696 -313.669934) (xy 382.351031 -313.614312) (xy 382.363157 -313.559875)
			(xy 382.38308 -313.507784) (xy 382.410376 -313.459149) (xy 382.444462 -313.415006) (xy 382.484611 -313.376297)
			(xy 382.529969 -313.343846) (xy 382.579569 -313.318345) (xy 382.632353 -313.300338) (xy 382.687196 -313.290208)
			(xy 382.74293 -313.288171) (xy 382.798367 -313.294271) (xy 382.852324 -313.308377) (xy 382.903653 -313.330189)
			(xy 382.951259 -313.359243) (xy 382.994127 -313.394918) (xy 383.031344 -313.436455) (xy 383.062117 -313.482968)
			(xy 383.085789 -313.533465) (xy 383.101857 -313.586872) (xy 383.109977 -313.642048) (xy 383.110486 -313.669934)
			(xy 383.109977 -313.69782) (xy 383.101857 -313.752996) (xy 383.085789 -313.806403) (xy 383.062117 -313.8569)
			(xy 383.031344 -313.903413) (xy 382.994127 -313.94495) (xy 382.988249 -313.949842) (xy 384.844048 -313.949842)
			(xy 384.848008 -313.900788) (xy 384.859785 -313.853004) (xy 384.879076 -313.807728) (xy 384.905379 -313.766132)
			(xy 384.938014 -313.729295) (xy 384.976135 -313.69817) (xy 385.018756 -313.673563) (xy 385.064772 -313.656111)
			(xy 385.112991 -313.646267) (xy 385.162166 -313.644286) (xy 385.211021 -313.650218) (xy 385.258292 -313.66391)
			(xy 385.302754 -313.685008) (xy 385.343257 -313.712964) (xy 385.37875 -313.747056) (xy 385.408315 -313.7864)
			(xy 385.431186 -313.829977) (xy 385.44677 -313.876658) (xy 385.454665 -313.925235) (xy 385.45516 -313.949842)
			(xy 385.794008 -313.949842) (xy 385.797968 -313.900788) (xy 385.809745 -313.853004) (xy 385.829036 -313.807728)
			(xy 385.855339 -313.766132) (xy 385.887974 -313.729295) (xy 385.926095 -313.69817) (xy 385.968716 -313.673563)
			(xy 386.014732 -313.656111) (xy 386.062951 -313.646267) (xy 386.112126 -313.644286) (xy 386.160981 -313.650218)
			(xy 386.208252 -313.66391) (xy 386.252714 -313.685008) (xy 386.293217 -313.712964) (xy 386.32871 -313.747056)
			(xy 386.358275 -313.7864) (xy 386.381146 -313.829977) (xy 386.39673 -313.876658) (xy 386.404625 -313.925235)
			(xy 386.40512 -313.949842) (xy 386.744222 -313.949842) (xy 386.748182 -313.900788) (xy 386.759959 -313.853004)
			(xy 386.77925 -313.807728) (xy 386.805553 -313.766132) (xy 386.838188 -313.729295) (xy 386.876309 -313.69817)
			(xy 386.91893 -313.673563) (xy 386.964946 -313.656111) (xy 387.013165 -313.646267) (xy 387.06234 -313.644286)
			(xy 387.111195 -313.650218) (xy 387.158466 -313.66391) (xy 387.202928 -313.685008) (xy 387.243431 -313.712964)
			(xy 387.278924 -313.747056) (xy 387.308489 -313.7864) (xy 387.33136 -313.829977) (xy 387.346944 -313.876658)
			(xy 387.354839 -313.925235) (xy 387.355334 -313.949842) (xy 387.694182 -313.949842) (xy 387.698142 -313.900788)
			(xy 387.709919 -313.853004) (xy 387.72921 -313.807728) (xy 387.755513 -313.766132) (xy 387.788148 -313.729295)
			(xy 387.826269 -313.69817) (xy 387.86889 -313.673563) (xy 387.914906 -313.656111) (xy 387.963125 -313.646267)
			(xy 388.0123 -313.644286) (xy 388.061155 -313.650218) (xy 388.108426 -313.66391) (xy 388.152888 -313.685008)
			(xy 388.193391 -313.712964) (xy 388.228884 -313.747056) (xy 388.258449 -313.7864) (xy 388.28132 -313.829977)
			(xy 388.296904 -313.876658) (xy 388.304799 -313.925235) (xy 388.305294 -313.949842) (xy 388.644142 -313.949842)
			(xy 388.648102 -313.900788) (xy 388.659879 -313.853004) (xy 388.67917 -313.807728) (xy 388.705473 -313.766132)
			(xy 388.738108 -313.729295) (xy 388.776229 -313.69817) (xy 388.81885 -313.673563) (xy 388.864866 -313.656111)
			(xy 388.913085 -313.646267) (xy 388.96226 -313.644286) (xy 389.011115 -313.650218) (xy 389.058386 -313.66391)
			(xy 389.102848 -313.685008) (xy 389.143351 -313.712964) (xy 389.178844 -313.747056) (xy 389.208409 -313.7864)
			(xy 389.23128 -313.829977) (xy 389.246864 -313.876658) (xy 389.254759 -313.925235) (xy 389.255254 -313.949842)
			(xy 389.594102 -313.949842) (xy 389.598062 -313.900788) (xy 389.609839 -313.853004) (xy 389.62913 -313.807728)
			(xy 389.655433 -313.766132) (xy 389.688068 -313.729295) (xy 389.726189 -313.69817) (xy 389.76881 -313.673563)
			(xy 389.814826 -313.656111) (xy 389.863045 -313.646267) (xy 389.91222 -313.644286) (xy 389.961075 -313.650218)
			(xy 390.008346 -313.66391) (xy 390.052808 -313.685008) (xy 390.093311 -313.712964) (xy 390.128804 -313.747056)
			(xy 390.158369 -313.7864) (xy 390.18124 -313.829977) (xy 390.196824 -313.876658) (xy 390.204719 -313.925235)
			(xy 390.205214 -313.949842) (xy 390.544062 -313.949842) (xy 390.548022 -313.900788) (xy 390.559799 -313.853004)
			(xy 390.57909 -313.807728) (xy 390.605393 -313.766132) (xy 390.638028 -313.729295) (xy 390.676149 -313.69817)
			(xy 390.71877 -313.673563) (xy 390.764786 -313.656111) (xy 390.813005 -313.646267) (xy 390.86218 -313.644286)
			(xy 390.911035 -313.650218) (xy 390.958306 -313.66391) (xy 391.002768 -313.685008) (xy 391.043271 -313.712964)
			(xy 391.078764 -313.747056) (xy 391.108329 -313.7864) (xy 391.1312 -313.829977) (xy 391.146784 -313.876658)
			(xy 391.154679 -313.925235) (xy 391.155174 -313.949842) (xy 391.494022 -313.949842) (xy 391.497982 -313.900788)
			(xy 391.509759 -313.853004) (xy 391.52905 -313.807728) (xy 391.555353 -313.766132) (xy 391.587988 -313.729295)
			(xy 391.626109 -313.69817) (xy 391.66873 -313.673563) (xy 391.714746 -313.656111) (xy 391.762965 -313.646267)
			(xy 391.81214 -313.644286) (xy 391.860995 -313.650218) (xy 391.908266 -313.66391) (xy 391.952728 -313.685008)
			(xy 391.993231 -313.712964) (xy 392.028724 -313.747056) (xy 392.058289 -313.7864) (xy 392.08116 -313.829977)
			(xy 392.096744 -313.876658) (xy 392.104639 -313.925235) (xy 392.105134 -313.949842) (xy 392.443982 -313.949842)
			(xy 392.447942 -313.900788) (xy 392.459719 -313.853004) (xy 392.47901 -313.807728) (xy 392.505313 -313.766132)
			(xy 392.537948 -313.729295) (xy 392.576069 -313.69817) (xy 392.61869 -313.673563) (xy 392.664706 -313.656111)
			(xy 392.712925 -313.646267) (xy 392.7621 -313.644286) (xy 392.810955 -313.650218) (xy 392.858226 -313.66391)
			(xy 392.902688 -313.685008) (xy 392.943191 -313.712964) (xy 392.978684 -313.747056) (xy 393.008249 -313.7864)
			(xy 393.03112 -313.829977) (xy 393.046704 -313.876658) (xy 393.054599 -313.925235) (xy 393.055094 -313.949842)
			(xy 393.394196 -313.949842) (xy 393.398156 -313.900788) (xy 393.409933 -313.853004) (xy 393.429224 -313.807728)
			(xy 393.455527 -313.766132) (xy 393.488162 -313.729295) (xy 393.526283 -313.69817) (xy 393.568904 -313.673563)
			(xy 393.61492 -313.656111) (xy 393.663139 -313.646267) (xy 393.712314 -313.644286) (xy 393.761169 -313.650218)
			(xy 393.80844 -313.66391) (xy 393.852902 -313.685008) (xy 393.893405 -313.712964) (xy 393.928898 -313.747056)
			(xy 393.958463 -313.7864) (xy 393.981334 -313.829977) (xy 393.996918 -313.876658) (xy 394.004813 -313.925235)
			(xy 394.005308 -313.949842) (xy 394.344156 -313.949842) (xy 394.348116 -313.900788) (xy 394.359893 -313.853004)
			(xy 394.379184 -313.807728) (xy 394.405487 -313.766132) (xy 394.438122 -313.729295) (xy 394.476243 -313.69817)
			(xy 394.518864 -313.673563) (xy 394.56488 -313.656111) (xy 394.613099 -313.646267) (xy 394.662274 -313.644286)
			(xy 394.711129 -313.650218) (xy 394.7584 -313.66391) (xy 394.802862 -313.685008) (xy 394.843365 -313.712964)
			(xy 394.878858 -313.747056) (xy 394.908423 -313.7864) (xy 394.931294 -313.829977) (xy 394.946878 -313.876658)
			(xy 394.954773 -313.925235) (xy 394.955268 -313.949842) (xy 394.954773 -313.974449) (xy 394.946878 -314.023026)
			(xy 394.931294 -314.069707) (xy 394.908423 -314.113284) (xy 394.878858 -314.152628) (xy 394.843365 -314.18672)
			(xy 394.802862 -314.214676) (xy 394.7584 -314.235774) (xy 394.711129 -314.249466) (xy 394.662274 -314.255398)
			(xy 394.613099 -314.253417) (xy 394.56488 -314.243573) (xy 394.518864 -314.226121) (xy 394.476243 -314.201514)
			(xy 394.438122 -314.170389) (xy 394.405487 -314.133552) (xy 394.379184 -314.091956) (xy 394.359893 -314.04668)
			(xy 394.348116 -313.998896) (xy 394.344156 -313.949842) (xy 394.005308 -313.949842) (xy 394.004813 -313.974449)
			(xy 393.996918 -314.023026) (xy 393.981334 -314.069707) (xy 393.958463 -314.113284) (xy 393.928898 -314.152628)
			(xy 393.893405 -314.18672) (xy 393.852902 -314.214676) (xy 393.80844 -314.235774) (xy 393.761169 -314.249466)
			(xy 393.712314 -314.255398) (xy 393.663139 -314.253417) (xy 393.61492 -314.243573) (xy 393.568904 -314.226121)
			(xy 393.526283 -314.201514) (xy 393.488162 -314.170389) (xy 393.455527 -314.133552) (xy 393.429224 -314.091956)
			(xy 393.409933 -314.04668) (xy 393.398156 -313.998896) (xy 393.394196 -313.949842) (xy 393.055094 -313.949842)
			(xy 393.054599 -313.974449) (xy 393.046704 -314.023026) (xy 393.03112 -314.069707) (xy 393.008249 -314.113284)
			(xy 392.978684 -314.152628) (xy 392.943191 -314.18672) (xy 392.902688 -314.214676) (xy 392.858226 -314.235774)
			(xy 392.810955 -314.249466) (xy 392.7621 -314.255398) (xy 392.712925 -314.253417) (xy 392.664706 -314.243573)
			(xy 392.61869 -314.226121) (xy 392.576069 -314.201514) (xy 392.537948 -314.170389) (xy 392.505313 -314.133552)
			(xy 392.47901 -314.091956) (xy 392.459719 -314.04668) (xy 392.447942 -313.998896) (xy 392.443982 -313.949842)
			(xy 392.105134 -313.949842) (xy 392.104639 -313.974449) (xy 392.096744 -314.023026) (xy 392.08116 -314.069707)
			(xy 392.058289 -314.113284) (xy 392.028724 -314.152628) (xy 391.993231 -314.18672) (xy 391.952728 -314.214676)
			(xy 391.908266 -314.235774) (xy 391.860995 -314.249466) (xy 391.81214 -314.255398) (xy 391.762965 -314.253417)
			(xy 391.714746 -314.243573) (xy 391.66873 -314.226121) (xy 391.626109 -314.201514) (xy 391.587988 -314.170389)
			(xy 391.555353 -314.133552) (xy 391.52905 -314.091956) (xy 391.509759 -314.04668) (xy 391.497982 -313.998896)
			(xy 391.494022 -313.949842) (xy 391.155174 -313.949842) (xy 391.154679 -313.974449) (xy 391.146784 -314.023026)
			(xy 391.1312 -314.069707) (xy 391.108329 -314.113284) (xy 391.078764 -314.152628) (xy 391.043271 -314.18672)
			(xy 391.002768 -314.214676) (xy 390.958306 -314.235774) (xy 390.911035 -314.249466) (xy 390.86218 -314.255398)
			(xy 390.813005 -314.253417) (xy 390.764786 -314.243573) (xy 390.71877 -314.226121) (xy 390.676149 -314.201514)
			(xy 390.638028 -314.170389) (xy 390.605393 -314.133552) (xy 390.57909 -314.091956) (xy 390.559799 -314.04668)
			(xy 390.548022 -313.998896) (xy 390.544062 -313.949842) (xy 390.205214 -313.949842) (xy 390.204719 -313.974449)
			(xy 390.196824 -314.023026) (xy 390.18124 -314.069707) (xy 390.158369 -314.113284) (xy 390.128804 -314.152628)
			(xy 390.093311 -314.18672) (xy 390.052808 -314.214676) (xy 390.008346 -314.235774) (xy 389.961075 -314.249466)
			(xy 389.91222 -314.255398) (xy 389.863045 -314.253417) (xy 389.814826 -314.243573) (xy 389.76881 -314.226121)
			(xy 389.726189 -314.201514) (xy 389.688068 -314.170389) (xy 389.655433 -314.133552) (xy 389.62913 -314.091956)
			(xy 389.609839 -314.04668) (xy 389.598062 -313.998896) (xy 389.594102 -313.949842) (xy 389.255254 -313.949842)
			(xy 389.254759 -313.974449) (xy 389.246864 -314.023026) (xy 389.23128 -314.069707) (xy 389.208409 -314.113284)
			(xy 389.178844 -314.152628) (xy 389.143351 -314.18672) (xy 389.102848 -314.214676) (xy 389.058386 -314.235774)
			(xy 389.011115 -314.249466) (xy 388.96226 -314.255398) (xy 388.913085 -314.253417) (xy 388.864866 -314.243573)
			(xy 388.81885 -314.226121) (xy 388.776229 -314.201514) (xy 388.738108 -314.170389) (xy 388.705473 -314.133552)
			(xy 388.67917 -314.091956) (xy 388.659879 -314.04668) (xy 388.648102 -313.998896) (xy 388.644142 -313.949842)
			(xy 388.305294 -313.949842) (xy 388.304799 -313.974449) (xy 388.296904 -314.023026) (xy 388.28132 -314.069707)
			(xy 388.258449 -314.113284) (xy 388.228884 -314.152628) (xy 388.193391 -314.18672) (xy 388.152888 -314.214676)
			(xy 388.108426 -314.235774) (xy 388.061155 -314.249466) (xy 388.0123 -314.255398) (xy 387.963125 -314.253417)
			(xy 387.914906 -314.243573) (xy 387.86889 -314.226121) (xy 387.826269 -314.201514) (xy 387.788148 -314.170389)
			(xy 387.755513 -314.133552) (xy 387.72921 -314.091956) (xy 387.709919 -314.04668) (xy 387.698142 -313.998896)
			(xy 387.694182 -313.949842) (xy 387.355334 -313.949842) (xy 387.354839 -313.974449) (xy 387.346944 -314.023026)
			(xy 387.33136 -314.069707) (xy 387.308489 -314.113284) (xy 387.278924 -314.152628) (xy 387.243431 -314.18672)
			(xy 387.202928 -314.214676) (xy 387.158466 -314.235774) (xy 387.111195 -314.249466) (xy 387.06234 -314.255398)
			(xy 387.013165 -314.253417) (xy 386.964946 -314.243573) (xy 386.91893 -314.226121) (xy 386.876309 -314.201514)
			(xy 386.838188 -314.170389) (xy 386.805553 -314.133552) (xy 386.77925 -314.091956) (xy 386.759959 -314.04668)
			(xy 386.748182 -313.998896) (xy 386.744222 -313.949842) (xy 386.40512 -313.949842) (xy 386.404625 -313.974449)
			(xy 386.39673 -314.023026) (xy 386.381146 -314.069707) (xy 386.358275 -314.113284) (xy 386.32871 -314.152628)
			(xy 386.293217 -314.18672) (xy 386.252714 -314.214676) (xy 386.208252 -314.235774) (xy 386.160981 -314.249466)
			(xy 386.112126 -314.255398) (xy 386.062951 -314.253417) (xy 386.014732 -314.243573) (xy 385.968716 -314.226121)
			(xy 385.926095 -314.201514) (xy 385.887974 -314.170389) (xy 385.855339 -314.133552) (xy 385.829036 -314.091956)
			(xy 385.809745 -314.04668) (xy 385.797968 -313.998896) (xy 385.794008 -313.949842) (xy 385.45516 -313.949842)
			(xy 385.454665 -313.974449) (xy 385.44677 -314.023026) (xy 385.431186 -314.069707) (xy 385.408315 -314.113284)
			(xy 385.37875 -314.152628) (xy 385.343257 -314.18672) (xy 385.302754 -314.214676) (xy 385.258292 -314.235774)
			(xy 385.211021 -314.249466) (xy 385.162166 -314.255398) (xy 385.112991 -314.253417) (xy 385.064772 -314.243573)
			(xy 385.018756 -314.226121) (xy 384.976135 -314.201514) (xy 384.938014 -314.170389) (xy 384.905379 -314.133552)
			(xy 384.879076 -314.091956) (xy 384.859785 -314.04668) (xy 384.848008 -313.998896) (xy 384.844048 -313.949842)
			(xy 382.988249 -313.949842) (xy 382.951259 -313.980625) (xy 382.903653 -314.009679) (xy 382.852324 -314.031491)
			(xy 382.798367 -314.045597) (xy 382.74293 -314.051697) (xy 382.687196 -314.04966) (xy 382.632353 -314.03953)
			(xy 382.579569 -314.021523) (xy 382.529969 -313.996022) (xy 382.484611 -313.963571) (xy 382.444462 -313.924862)
			(xy 382.410376 -313.880719) (xy 382.38308 -313.832084) (xy 382.363157 -313.779993) (xy 382.351031 -313.725556)
			(xy 382.34696 -313.669934) (xy 364.249165 -313.669934) (xy 364.248083 -313.672242) (xy 364.21731 -313.718755)
			(xy 364.180093 -313.760292) (xy 364.137225 -313.795967) (xy 364.089619 -313.825021) (xy 364.03829 -313.846833)
			(xy 363.984333 -313.860939) (xy 363.928896 -313.867039) (xy 363.873162 -313.865002) (xy 363.818319 -313.854872)
			(xy 363.765535 -313.836865) (xy 363.715935 -313.811364) (xy 363.670577 -313.778913) (xy 363.630428 -313.740204)
			(xy 363.596342 -313.696061) (xy 363.569046 -313.647426) (xy 363.549123 -313.595335) (xy 363.536997 -313.540898)
			(xy 363.532926 -313.485276) (xy 363.280452 -313.485276) (xy 363.279943 -313.513162) (xy 363.271823 -313.568338)
			(xy 363.255755 -313.621745) (xy 363.232083 -313.672242) (xy 363.20131 -313.718755) (xy 363.164093 -313.760292)
			(xy 363.121225 -313.795967) (xy 363.073619 -313.825021) (xy 363.02229 -313.846833) (xy 362.968333 -313.860939)
			(xy 362.912896 -313.867039) (xy 362.857162 -313.865002) (xy 362.802319 -313.854872) (xy 362.749535 -313.836865)
			(xy 362.699935 -313.811364) (xy 362.654577 -313.778913) (xy 362.614428 -313.740204) (xy 362.580342 -313.696061)
			(xy 362.553046 -313.647426) (xy 362.533123 -313.595335) (xy 362.520997 -313.540898) (xy 362.516926 -313.485276)
			(xy 362.264452 -313.485276) (xy 362.263943 -313.513162) (xy 362.255823 -313.568338) (xy 362.239755 -313.621745)
			(xy 362.216083 -313.672242) (xy 362.18531 -313.718755) (xy 362.148093 -313.760292) (xy 362.105225 -313.795967)
			(xy 362.057619 -313.825021) (xy 362.00629 -313.846833) (xy 361.952333 -313.860939) (xy 361.896896 -313.867039)
			(xy 361.841162 -313.865002) (xy 361.786319 -313.854872) (xy 361.733535 -313.836865) (xy 361.683935 -313.811364)
			(xy 361.638577 -313.778913) (xy 361.598428 -313.740204) (xy 361.564342 -313.696061) (xy 361.537046 -313.647426)
			(xy 361.517123 -313.595335) (xy 361.504997 -313.540898) (xy 361.500926 -313.485276) (xy 361.248452 -313.485276)
			(xy 361.247943 -313.513162) (xy 361.239823 -313.568338) (xy 361.223755 -313.621745) (xy 361.200083 -313.672242)
			(xy 361.16931 -313.718755) (xy 361.132093 -313.760292) (xy 361.089225 -313.795967) (xy 361.041619 -313.825021)
			(xy 360.99029 -313.846833) (xy 360.936333 -313.860939) (xy 360.880896 -313.867039) (xy 360.825162 -313.865002)
			(xy 360.770319 -313.854872) (xy 360.717535 -313.836865) (xy 360.667935 -313.811364) (xy 360.622577 -313.778913)
			(xy 360.582428 -313.740204) (xy 360.548342 -313.696061) (xy 360.521046 -313.647426) (xy 360.501123 -313.595335)
			(xy 360.488997 -313.540898) (xy 360.484926 -313.485276) (xy 360.232452 -313.485276) (xy 360.231943 -313.513162)
			(xy 360.223823 -313.568338) (xy 360.207755 -313.621745) (xy 360.184083 -313.672242) (xy 360.15331 -313.718755)
			(xy 360.116093 -313.760292) (xy 360.073225 -313.795967) (xy 360.025619 -313.825021) (xy 359.97429 -313.846833)
			(xy 359.920333 -313.860939) (xy 359.864896 -313.867039) (xy 359.809162 -313.865002) (xy 359.754319 -313.854872)
			(xy 359.701535 -313.836865) (xy 359.651935 -313.811364) (xy 359.606577 -313.778913) (xy 359.566428 -313.740204)
			(xy 359.532342 -313.696061) (xy 359.505046 -313.647426) (xy 359.485123 -313.595335) (xy 359.472997 -313.540898)
			(xy 359.468926 -313.485276) (xy 359.216452 -313.485276) (xy 359.215943 -313.513162) (xy 359.207823 -313.568338)
			(xy 359.191755 -313.621745) (xy 359.168083 -313.672242) (xy 359.13731 -313.718755) (xy 359.100093 -313.760292)
			(xy 359.057225 -313.795967) (xy 359.009619 -313.825021) (xy 358.95829 -313.846833) (xy 358.904333 -313.860939)
			(xy 358.848896 -313.867039) (xy 358.793162 -313.865002) (xy 358.738319 -313.854872) (xy 358.685535 -313.836865)
			(xy 358.635935 -313.811364) (xy 358.590577 -313.778913) (xy 358.550428 -313.740204) (xy 358.516342 -313.696061)
			(xy 358.489046 -313.647426) (xy 358.469123 -313.595335) (xy 358.456997 -313.540898) (xy 358.452926 -313.485276)
			(xy 358.200452 -313.485276) (xy 358.199943 -313.513162) (xy 358.191823 -313.568338) (xy 358.175755 -313.621745)
			(xy 358.152083 -313.672242) (xy 358.12131 -313.718755) (xy 358.084093 -313.760292) (xy 358.041225 -313.795967)
			(xy 357.993619 -313.825021) (xy 357.94229 -313.846833) (xy 357.888333 -313.860939) (xy 357.832896 -313.867039)
			(xy 357.777162 -313.865002) (xy 357.722319 -313.854872) (xy 357.669535 -313.836865) (xy 357.619935 -313.811364)
			(xy 357.574577 -313.778913) (xy 357.534428 -313.740204) (xy 357.500342 -313.696061) (xy 357.473046 -313.647426)
			(xy 357.453123 -313.595335) (xy 357.440997 -313.540898) (xy 357.436926 -313.485276) (xy 351.831402 -313.485276)
			(xy 351.831402 -314.501276) (xy 357.436926 -314.501276) (xy 357.440997 -314.445654) (xy 357.453123 -314.391217)
			(xy 357.473046 -314.339126) (xy 357.500342 -314.290491) (xy 357.534428 -314.246348) (xy 357.574577 -314.207639)
			(xy 357.619935 -314.175188) (xy 357.669535 -314.149687) (xy 357.722319 -314.13168) (xy 357.777162 -314.12155)
			(xy 357.832896 -314.119513) (xy 357.888333 -314.125613) (xy 357.94229 -314.139719) (xy 357.993619 -314.161531)
			(xy 358.041225 -314.190585) (xy 358.084093 -314.22626) (xy 358.12131 -314.267797) (xy 358.152083 -314.31431)
			(xy 358.175755 -314.364807) (xy 358.191823 -314.418214) (xy 358.199943 -314.47339) (xy 358.200452 -314.501276)
			(xy 358.452926 -314.501276) (xy 358.456997 -314.445654) (xy 358.469123 -314.391217) (xy 358.489046 -314.339126)
			(xy 358.516342 -314.290491) (xy 358.550428 -314.246348) (xy 358.590577 -314.207639) (xy 358.635935 -314.175188)
			(xy 358.685535 -314.149687) (xy 358.738319 -314.13168) (xy 358.793162 -314.12155) (xy 358.848896 -314.119513)
			(xy 358.904333 -314.125613) (xy 358.95829 -314.139719) (xy 359.009619 -314.161531) (xy 359.057225 -314.190585)
			(xy 359.100093 -314.22626) (xy 359.13731 -314.267797) (xy 359.168083 -314.31431) (xy 359.191755 -314.364807)
			(xy 359.207823 -314.418214) (xy 359.215943 -314.47339) (xy 359.216452 -314.501276) (xy 359.468926 -314.501276)
			(xy 359.472997 -314.445654) (xy 359.485123 -314.391217) (xy 359.505046 -314.339126) (xy 359.532342 -314.290491)
			(xy 359.566428 -314.246348) (xy 359.606577 -314.207639) (xy 359.651935 -314.175188) (xy 359.701535 -314.149687)
			(xy 359.754319 -314.13168) (xy 359.809162 -314.12155) (xy 359.864896 -314.119513) (xy 359.920333 -314.125613)
			(xy 359.97429 -314.139719) (xy 360.025619 -314.161531) (xy 360.073225 -314.190585) (xy 360.116093 -314.22626)
			(xy 360.15331 -314.267797) (xy 360.184083 -314.31431) (xy 360.207755 -314.364807) (xy 360.223823 -314.418214)
			(xy 360.231943 -314.47339) (xy 360.232452 -314.501276) (xy 360.484926 -314.501276) (xy 360.488997 -314.445654)
			(xy 360.501123 -314.391217) (xy 360.521046 -314.339126) (xy 360.548342 -314.290491) (xy 360.582428 -314.246348)
			(xy 360.622577 -314.207639) (xy 360.667935 -314.175188) (xy 360.717535 -314.149687) (xy 360.770319 -314.13168)
			(xy 360.825162 -314.12155) (xy 360.880896 -314.119513) (xy 360.936333 -314.125613) (xy 360.99029 -314.139719)
			(xy 361.041619 -314.161531) (xy 361.089225 -314.190585) (xy 361.132093 -314.22626) (xy 361.16931 -314.267797)
			(xy 361.200083 -314.31431) (xy 361.223755 -314.364807) (xy 361.239823 -314.418214) (xy 361.247943 -314.47339)
			(xy 361.248452 -314.501276) (xy 361.500926 -314.501276) (xy 361.504997 -314.445654) (xy 361.517123 -314.391217)
			(xy 361.537046 -314.339126) (xy 361.564342 -314.290491) (xy 361.598428 -314.246348) (xy 361.638577 -314.207639)
			(xy 361.683935 -314.175188) (xy 361.733535 -314.149687) (xy 361.786319 -314.13168) (xy 361.841162 -314.12155)
			(xy 361.896896 -314.119513) (xy 361.952333 -314.125613) (xy 362.00629 -314.139719) (xy 362.057619 -314.161531)
			(xy 362.105225 -314.190585) (xy 362.148093 -314.22626) (xy 362.18531 -314.267797) (xy 362.216083 -314.31431)
			(xy 362.239755 -314.364807) (xy 362.255823 -314.418214) (xy 362.263943 -314.47339) (xy 362.264452 -314.501276)
			(xy 362.516926 -314.501276) (xy 362.520997 -314.445654) (xy 362.533123 -314.391217) (xy 362.553046 -314.339126)
			(xy 362.580342 -314.290491) (xy 362.614428 -314.246348) (xy 362.654577 -314.207639) (xy 362.699935 -314.175188)
			(xy 362.749535 -314.149687) (xy 362.802319 -314.13168) (xy 362.857162 -314.12155) (xy 362.912896 -314.119513)
			(xy 362.968333 -314.125613) (xy 363.02229 -314.139719) (xy 363.073619 -314.161531) (xy 363.121225 -314.190585)
			(xy 363.164093 -314.22626) (xy 363.20131 -314.267797) (xy 363.232083 -314.31431) (xy 363.255755 -314.364807)
			(xy 363.271823 -314.418214) (xy 363.279943 -314.47339) (xy 363.280452 -314.501276) (xy 363.279943 -314.529162)
			(xy 363.271823 -314.584338) (xy 363.255755 -314.637745) (xy 363.232083 -314.688242) (xy 363.20131 -314.734755)
			(xy 363.164093 -314.776292) (xy 363.121225 -314.811967) (xy 363.073619 -314.841021) (xy 363.02229 -314.862833)
			(xy 362.968333 -314.876939) (xy 362.912896 -314.883039) (xy 362.857162 -314.881002) (xy 362.802319 -314.870872)
			(xy 362.749535 -314.852865) (xy 362.699935 -314.827364) (xy 362.654577 -314.794913) (xy 362.614428 -314.756204)
			(xy 362.580342 -314.712061) (xy 362.553046 -314.663426) (xy 362.533123 -314.611335) (xy 362.520997 -314.556898)
			(xy 362.516926 -314.501276) (xy 362.264452 -314.501276) (xy 362.263943 -314.529162) (xy 362.255823 -314.584338)
			(xy 362.239755 -314.637745) (xy 362.216083 -314.688242) (xy 362.18531 -314.734755) (xy 362.148093 -314.776292)
			(xy 362.105225 -314.811967) (xy 362.057619 -314.841021) (xy 362.00629 -314.862833) (xy 361.952333 -314.876939)
			(xy 361.896896 -314.883039) (xy 361.841162 -314.881002) (xy 361.786319 -314.870872) (xy 361.733535 -314.852865)
			(xy 361.683935 -314.827364) (xy 361.638577 -314.794913) (xy 361.598428 -314.756204) (xy 361.564342 -314.712061)
			(xy 361.537046 -314.663426) (xy 361.517123 -314.611335) (xy 361.504997 -314.556898) (xy 361.500926 -314.501276)
			(xy 361.248452 -314.501276) (xy 361.247943 -314.529162) (xy 361.239823 -314.584338) (xy 361.223755 -314.637745)
			(xy 361.200083 -314.688242) (xy 361.16931 -314.734755) (xy 361.132093 -314.776292) (xy 361.089225 -314.811967)
			(xy 361.041619 -314.841021) (xy 360.99029 -314.862833) (xy 360.936333 -314.876939) (xy 360.880896 -314.883039)
			(xy 360.825162 -314.881002) (xy 360.770319 -314.870872) (xy 360.717535 -314.852865) (xy 360.667935 -314.827364)
			(xy 360.622577 -314.794913) (xy 360.582428 -314.756204) (xy 360.548342 -314.712061) (xy 360.521046 -314.663426)
			(xy 360.501123 -314.611335) (xy 360.488997 -314.556898) (xy 360.484926 -314.501276) (xy 360.232452 -314.501276)
			(xy 360.231943 -314.529162) (xy 360.223823 -314.584338) (xy 360.207755 -314.637745) (xy 360.184083 -314.688242)
			(xy 360.15331 -314.734755) (xy 360.116093 -314.776292) (xy 360.073225 -314.811967) (xy 360.025619 -314.841021)
			(xy 359.97429 -314.862833) (xy 359.920333 -314.876939) (xy 359.864896 -314.883039) (xy 359.809162 -314.881002)
			(xy 359.754319 -314.870872) (xy 359.701535 -314.852865) (xy 359.651935 -314.827364) (xy 359.606577 -314.794913)
			(xy 359.566428 -314.756204) (xy 359.532342 -314.712061) (xy 359.505046 -314.663426) (xy 359.485123 -314.611335)
			(xy 359.472997 -314.556898) (xy 359.468926 -314.501276) (xy 359.216452 -314.501276) (xy 359.215943 -314.529162)
			(xy 359.207823 -314.584338) (xy 359.191755 -314.637745) (xy 359.168083 -314.688242) (xy 359.13731 -314.734755)
			(xy 359.100093 -314.776292) (xy 359.057225 -314.811967) (xy 359.009619 -314.841021) (xy 358.95829 -314.862833)
			(xy 358.904333 -314.876939) (xy 358.848896 -314.883039) (xy 358.793162 -314.881002) (xy 358.738319 -314.870872)
			(xy 358.685535 -314.852865) (xy 358.635935 -314.827364) (xy 358.590577 -314.794913) (xy 358.550428 -314.756204)
			(xy 358.516342 -314.712061) (xy 358.489046 -314.663426) (xy 358.469123 -314.611335) (xy 358.456997 -314.556898)
			(xy 358.452926 -314.501276) (xy 358.200452 -314.501276) (xy 358.199943 -314.529162) (xy 358.191823 -314.584338)
			(xy 358.175755 -314.637745) (xy 358.152083 -314.688242) (xy 358.12131 -314.734755) (xy 358.084093 -314.776292)
			(xy 358.041225 -314.811967) (xy 357.993619 -314.841021) (xy 357.94229 -314.862833) (xy 357.888333 -314.876939)
			(xy 357.832896 -314.883039) (xy 357.777162 -314.881002) (xy 357.722319 -314.870872) (xy 357.669535 -314.852865)
			(xy 357.619935 -314.827364) (xy 357.574577 -314.794913) (xy 357.534428 -314.756204) (xy 357.500342 -314.712061)
			(xy 357.473046 -314.663426) (xy 357.453123 -314.611335) (xy 357.440997 -314.556898) (xy 357.436926 -314.501276)
			(xy 351.831402 -314.501276) (xy 351.831402 -314.899548) (xy 383.89358 -314.899548) (xy 383.89754 -314.850494)
			(xy 383.909317 -314.80271) (xy 383.928608 -314.757434) (xy 383.954911 -314.715838) (xy 383.987546 -314.679001)
			(xy 384.025667 -314.647876) (xy 384.068288 -314.623269) (xy 384.114304 -314.605817) (xy 384.162523 -314.595973)
			(xy 384.211698 -314.593992) (xy 384.260553 -314.599924) (xy 384.307824 -314.613616) (xy 384.352286 -314.634714)
			(xy 384.392789 -314.66267) (xy 384.428282 -314.696762) (xy 384.457847 -314.736106) (xy 384.480718 -314.779683)
			(xy 384.496302 -314.826364) (xy 384.504197 -314.874941) (xy 384.504692 -314.899548) (xy 384.504687 -314.899802)
			(xy 384.844048 -314.899802) (xy 384.848008 -314.850748) (xy 384.859785 -314.802964) (xy 384.879076 -314.757688)
			(xy 384.905379 -314.716092) (xy 384.938014 -314.679255) (xy 384.976135 -314.64813) (xy 385.018756 -314.623523)
			(xy 385.064772 -314.606071) (xy 385.112991 -314.596227) (xy 385.162166 -314.594246) (xy 385.211021 -314.600178)
			(xy 385.258292 -314.61387) (xy 385.302754 -314.634968) (xy 385.343257 -314.662924) (xy 385.37875 -314.697016)
			(xy 385.408315 -314.73636) (xy 385.431186 -314.779937) (xy 385.44677 -314.826618) (xy 385.454665 -314.875195)
			(xy 385.45516 -314.899802) (xy 385.794008 -314.899802) (xy 385.797968 -314.850748) (xy 385.809745 -314.802964)
			(xy 385.829036 -314.757688) (xy 385.855339 -314.716092) (xy 385.887974 -314.679255) (xy 385.926095 -314.64813)
			(xy 385.968716 -314.623523) (xy 386.014732 -314.606071) (xy 386.062951 -314.596227) (xy 386.112126 -314.594246)
			(xy 386.160981 -314.600178) (xy 386.208252 -314.61387) (xy 386.252714 -314.634968) (xy 386.293217 -314.662924)
			(xy 386.32871 -314.697016) (xy 386.358275 -314.73636) (xy 386.381146 -314.779937) (xy 386.39673 -314.826618)
			(xy 386.404625 -314.875195) (xy 386.40512 -314.899802) (xy 386.744222 -314.899802) (xy 386.748182 -314.850748)
			(xy 386.759959 -314.802964) (xy 386.77925 -314.757688) (xy 386.805553 -314.716092) (xy 386.838188 -314.679255)
			(xy 386.876309 -314.64813) (xy 386.91893 -314.623523) (xy 386.964946 -314.606071) (xy 387.013165 -314.596227)
			(xy 387.06234 -314.594246) (xy 387.111195 -314.600178) (xy 387.158466 -314.61387) (xy 387.202928 -314.634968)
			(xy 387.243431 -314.662924) (xy 387.278924 -314.697016) (xy 387.308489 -314.73636) (xy 387.33136 -314.779937)
			(xy 387.346944 -314.826618) (xy 387.354839 -314.875195) (xy 387.355334 -314.899802) (xy 387.694182 -314.899802)
			(xy 387.698142 -314.850748) (xy 387.709919 -314.802964) (xy 387.72921 -314.757688) (xy 387.755513 -314.716092)
			(xy 387.788148 -314.679255) (xy 387.826269 -314.64813) (xy 387.86889 -314.623523) (xy 387.914906 -314.606071)
			(xy 387.963125 -314.596227) (xy 388.0123 -314.594246) (xy 388.061155 -314.600178) (xy 388.108426 -314.61387)
			(xy 388.152888 -314.634968) (xy 388.193391 -314.662924) (xy 388.228884 -314.697016) (xy 388.258449 -314.73636)
			(xy 388.28132 -314.779937) (xy 388.296904 -314.826618) (xy 388.304799 -314.875195) (xy 388.305294 -314.899802)
			(xy 388.644142 -314.899802) (xy 388.648102 -314.850748) (xy 388.659879 -314.802964) (xy 388.67917 -314.757688)
			(xy 388.705473 -314.716092) (xy 388.738108 -314.679255) (xy 388.776229 -314.64813) (xy 388.81885 -314.623523)
			(xy 388.864866 -314.606071) (xy 388.913085 -314.596227) (xy 388.96226 -314.594246) (xy 389.011115 -314.600178)
			(xy 389.058386 -314.61387) (xy 389.102848 -314.634968) (xy 389.143351 -314.662924) (xy 389.178844 -314.697016)
			(xy 389.208409 -314.73636) (xy 389.23128 -314.779937) (xy 389.246864 -314.826618) (xy 389.254759 -314.875195)
			(xy 389.255254 -314.899802) (xy 389.594102 -314.899802) (xy 389.598062 -314.850748) (xy 389.609839 -314.802964)
			(xy 389.62913 -314.757688) (xy 389.655433 -314.716092) (xy 389.688068 -314.679255) (xy 389.726189 -314.64813)
			(xy 389.76881 -314.623523) (xy 389.814826 -314.606071) (xy 389.863045 -314.596227) (xy 389.91222 -314.594246)
			(xy 389.961075 -314.600178) (xy 390.008346 -314.61387) (xy 390.052808 -314.634968) (xy 390.093311 -314.662924)
			(xy 390.128804 -314.697016) (xy 390.158369 -314.73636) (xy 390.18124 -314.779937) (xy 390.196824 -314.826618)
			(xy 390.204719 -314.875195) (xy 390.205214 -314.899802) (xy 390.544062 -314.899802) (xy 390.548022 -314.850748)
			(xy 390.559799 -314.802964) (xy 390.57909 -314.757688) (xy 390.605393 -314.716092) (xy 390.638028 -314.679255)
			(xy 390.676149 -314.64813) (xy 390.71877 -314.623523) (xy 390.764786 -314.606071) (xy 390.813005 -314.596227)
			(xy 390.86218 -314.594246) (xy 390.911035 -314.600178) (xy 390.958306 -314.61387) (xy 391.002768 -314.634968)
			(xy 391.043271 -314.662924) (xy 391.078764 -314.697016) (xy 391.108329 -314.73636) (xy 391.1312 -314.779937)
			(xy 391.146784 -314.826618) (xy 391.154679 -314.875195) (xy 391.155174 -314.899802) (xy 391.494022 -314.899802)
			(xy 391.497982 -314.850748) (xy 391.509759 -314.802964) (xy 391.52905 -314.757688) (xy 391.555353 -314.716092)
			(xy 391.587988 -314.679255) (xy 391.626109 -314.64813) (xy 391.66873 -314.623523) (xy 391.714746 -314.606071)
			(xy 391.762965 -314.596227) (xy 391.81214 -314.594246) (xy 391.860995 -314.600178) (xy 391.908266 -314.61387)
			(xy 391.952728 -314.634968) (xy 391.993231 -314.662924) (xy 392.028724 -314.697016) (xy 392.058289 -314.73636)
			(xy 392.08116 -314.779937) (xy 392.096744 -314.826618) (xy 392.104639 -314.875195) (xy 392.105134 -314.899802)
			(xy 392.443982 -314.899802) (xy 392.447942 -314.850748) (xy 392.459719 -314.802964) (xy 392.47901 -314.757688)
			(xy 392.505313 -314.716092) (xy 392.537948 -314.679255) (xy 392.576069 -314.64813) (xy 392.61869 -314.623523)
			(xy 392.664706 -314.606071) (xy 392.712925 -314.596227) (xy 392.7621 -314.594246) (xy 392.810955 -314.600178)
			(xy 392.858226 -314.61387) (xy 392.902688 -314.634968) (xy 392.943191 -314.662924) (xy 392.978684 -314.697016)
			(xy 393.008249 -314.73636) (xy 393.03112 -314.779937) (xy 393.046704 -314.826618) (xy 393.054599 -314.875195)
			(xy 393.055094 -314.899802) (xy 393.394196 -314.899802) (xy 393.398156 -314.850748) (xy 393.409933 -314.802964)
			(xy 393.429224 -314.757688) (xy 393.455527 -314.716092) (xy 393.488162 -314.679255) (xy 393.526283 -314.64813)
			(xy 393.568904 -314.623523) (xy 393.61492 -314.606071) (xy 393.663139 -314.596227) (xy 393.712314 -314.594246)
			(xy 393.761169 -314.600178) (xy 393.80844 -314.61387) (xy 393.852902 -314.634968) (xy 393.893405 -314.662924)
			(xy 393.928898 -314.697016) (xy 393.958463 -314.73636) (xy 393.981334 -314.779937) (xy 393.996918 -314.826618)
			(xy 394.004813 -314.875195) (xy 394.005308 -314.899802) (xy 394.004813 -314.924409) (xy 393.996918 -314.972986)
			(xy 393.981334 -315.019667) (xy 393.958463 -315.063244) (xy 393.928898 -315.102588) (xy 393.893405 -315.13668)
			(xy 393.852902 -315.164636) (xy 393.80844 -315.185734) (xy 393.761169 -315.199426) (xy 393.712314 -315.205358)
			(xy 393.663139 -315.203377) (xy 393.61492 -315.193533) (xy 393.568904 -315.176081) (xy 393.526283 -315.151474)
			(xy 393.488162 -315.120349) (xy 393.455527 -315.083512) (xy 393.429224 -315.041916) (xy 393.409933 -314.99664)
			(xy 393.398156 -314.948856) (xy 393.394196 -314.899802) (xy 393.055094 -314.899802) (xy 393.054599 -314.924409)
			(xy 393.046704 -314.972986) (xy 393.03112 -315.019667) (xy 393.008249 -315.063244) (xy 392.978684 -315.102588)
			(xy 392.943191 -315.13668) (xy 392.902688 -315.164636) (xy 392.858226 -315.185734) (xy 392.810955 -315.199426)
			(xy 392.7621 -315.205358) (xy 392.712925 -315.203377) (xy 392.664706 -315.193533) (xy 392.61869 -315.176081)
			(xy 392.576069 -315.151474) (xy 392.537948 -315.120349) (xy 392.505313 -315.083512) (xy 392.47901 -315.041916)
			(xy 392.459719 -314.99664) (xy 392.447942 -314.948856) (xy 392.443982 -314.899802) (xy 392.105134 -314.899802)
			(xy 392.104639 -314.924409) (xy 392.096744 -314.972986) (xy 392.08116 -315.019667) (xy 392.058289 -315.063244)
			(xy 392.028724 -315.102588) (xy 391.993231 -315.13668) (xy 391.952728 -315.164636) (xy 391.908266 -315.185734)
			(xy 391.860995 -315.199426) (xy 391.81214 -315.205358) (xy 391.762965 -315.203377) (xy 391.714746 -315.193533)
			(xy 391.66873 -315.176081) (xy 391.626109 -315.151474) (xy 391.587988 -315.120349) (xy 391.555353 -315.083512)
			(xy 391.52905 -315.041916) (xy 391.509759 -314.99664) (xy 391.497982 -314.948856) (xy 391.494022 -314.899802)
			(xy 391.155174 -314.899802) (xy 391.154679 -314.924409) (xy 391.146784 -314.972986) (xy 391.1312 -315.019667)
			(xy 391.108329 -315.063244) (xy 391.078764 -315.102588) (xy 391.043271 -315.13668) (xy 391.002768 -315.164636)
			(xy 390.958306 -315.185734) (xy 390.911035 -315.199426) (xy 390.86218 -315.205358) (xy 390.813005 -315.203377)
			(xy 390.764786 -315.193533) (xy 390.71877 -315.176081) (xy 390.676149 -315.151474) (xy 390.638028 -315.120349)
			(xy 390.605393 -315.083512) (xy 390.57909 -315.041916) (xy 390.559799 -314.99664) (xy 390.548022 -314.948856)
			(xy 390.544062 -314.899802) (xy 390.205214 -314.899802) (xy 390.204719 -314.924409) (xy 390.196824 -314.972986)
			(xy 390.18124 -315.019667) (xy 390.158369 -315.063244) (xy 390.128804 -315.102588) (xy 390.093311 -315.13668)
			(xy 390.052808 -315.164636) (xy 390.008346 -315.185734) (xy 389.961075 -315.199426) (xy 389.91222 -315.205358)
			(xy 389.863045 -315.203377) (xy 389.814826 -315.193533) (xy 389.76881 -315.176081) (xy 389.726189 -315.151474)
			(xy 389.688068 -315.120349) (xy 389.655433 -315.083512) (xy 389.62913 -315.041916) (xy 389.609839 -314.99664)
			(xy 389.598062 -314.948856) (xy 389.594102 -314.899802) (xy 389.255254 -314.899802) (xy 389.254759 -314.924409)
			(xy 389.246864 -314.972986) (xy 389.23128 -315.019667) (xy 389.208409 -315.063244) (xy 389.178844 -315.102588)
			(xy 389.143351 -315.13668) (xy 389.102848 -315.164636) (xy 389.058386 -315.185734) (xy 389.011115 -315.199426)
			(xy 388.96226 -315.205358) (xy 388.913085 -315.203377) (xy 388.864866 -315.193533) (xy 388.81885 -315.176081)
			(xy 388.776229 -315.151474) (xy 388.738108 -315.120349) (xy 388.705473 -315.083512) (xy 388.67917 -315.041916)
			(xy 388.659879 -314.99664) (xy 388.648102 -314.948856) (xy 388.644142 -314.899802) (xy 388.305294 -314.899802)
			(xy 388.304799 -314.924409) (xy 388.296904 -314.972986) (xy 388.28132 -315.019667) (xy 388.258449 -315.063244)
			(xy 388.228884 -315.102588) (xy 388.193391 -315.13668) (xy 388.152888 -315.164636) (xy 388.108426 -315.185734)
			(xy 388.061155 -315.199426) (xy 388.0123 -315.205358) (xy 387.963125 -315.203377) (xy 387.914906 -315.193533)
			(xy 387.86889 -315.176081) (xy 387.826269 -315.151474) (xy 387.788148 -315.120349) (xy 387.755513 -315.083512)
			(xy 387.72921 -315.041916) (xy 387.709919 -314.99664) (xy 387.698142 -314.948856) (xy 387.694182 -314.899802)
			(xy 387.355334 -314.899802) (xy 387.354839 -314.924409) (xy 387.346944 -314.972986) (xy 387.33136 -315.019667)
			(xy 387.308489 -315.063244) (xy 387.278924 -315.102588) (xy 387.243431 -315.13668) (xy 387.202928 -315.164636)
			(xy 387.158466 -315.185734) (xy 387.111195 -315.199426) (xy 387.06234 -315.205358) (xy 387.013165 -315.203377)
			(xy 386.964946 -315.193533) (xy 386.91893 -315.176081) (xy 386.876309 -315.151474) (xy 386.838188 -315.120349)
			(xy 386.805553 -315.083512) (xy 386.77925 -315.041916) (xy 386.759959 -314.99664) (xy 386.748182 -314.948856)
			(xy 386.744222 -314.899802) (xy 386.40512 -314.899802) (xy 386.404625 -314.924409) (xy 386.39673 -314.972986)
			(xy 386.381146 -315.019667) (xy 386.358275 -315.063244) (xy 386.32871 -315.102588) (xy 386.293217 -315.13668)
			(xy 386.252714 -315.164636) (xy 386.208252 -315.185734) (xy 386.160981 -315.199426) (xy 386.112126 -315.205358)
			(xy 386.062951 -315.203377) (xy 386.014732 -315.193533) (xy 385.968716 -315.176081) (xy 385.926095 -315.151474)
			(xy 385.887974 -315.120349) (xy 385.855339 -315.083512) (xy 385.829036 -315.041916) (xy 385.809745 -314.99664)
			(xy 385.797968 -314.948856) (xy 385.794008 -314.899802) (xy 385.45516 -314.899802) (xy 385.454665 -314.924409)
			(xy 385.44677 -314.972986) (xy 385.431186 -315.019667) (xy 385.408315 -315.063244) (xy 385.37875 -315.102588)
			(xy 385.343257 -315.13668) (xy 385.302754 -315.164636) (xy 385.258292 -315.185734) (xy 385.211021 -315.199426)
			(xy 385.162166 -315.205358) (xy 385.112991 -315.203377) (xy 385.064772 -315.193533) (xy 385.018756 -315.176081)
			(xy 384.976135 -315.151474) (xy 384.938014 -315.120349) (xy 384.905379 -315.083512) (xy 384.879076 -315.041916)
			(xy 384.859785 -314.99664) (xy 384.848008 -314.948856) (xy 384.844048 -314.899802) (xy 384.504687 -314.899802)
			(xy 384.504197 -314.924155) (xy 384.496302 -314.972732) (xy 384.480718 -315.019413) (xy 384.457847 -315.06299)
			(xy 384.428282 -315.102334) (xy 384.392789 -315.136426) (xy 384.352286 -315.164382) (xy 384.307824 -315.18548)
			(xy 384.260553 -315.199172) (xy 384.211698 -315.205104) (xy 384.162523 -315.203123) (xy 384.114304 -315.193279)
			(xy 384.068288 -315.175827) (xy 384.025667 -315.15122) (xy 383.987546 -315.120095) (xy 383.954911 -315.083258)
			(xy 383.928608 -315.041662) (xy 383.909317 -314.996386) (xy 383.89754 -314.948602) (xy 383.89358 -314.899548)
			(xy 351.831402 -314.899548) (xy 351.831402 -315.517276) (xy 357.436926 -315.517276) (xy 357.440997 -315.461654)
			(xy 357.453123 -315.407217) (xy 357.473046 -315.355126) (xy 357.500342 -315.306491) (xy 357.534428 -315.262348)
			(xy 357.574577 -315.223639) (xy 357.619935 -315.191188) (xy 357.669535 -315.165687) (xy 357.722319 -315.14768)
			(xy 357.777162 -315.13755) (xy 357.832896 -315.135513) (xy 357.888333 -315.141613) (xy 357.94229 -315.155719)
			(xy 357.993619 -315.177531) (xy 358.041225 -315.206585) (xy 358.084093 -315.24226) (xy 358.12131 -315.283797)
			(xy 358.152083 -315.33031) (xy 358.175755 -315.380807) (xy 358.191823 -315.434214) (xy 358.199943 -315.48939)
			(xy 358.200452 -315.517276) (xy 358.452926 -315.517276) (xy 358.456997 -315.461654) (xy 358.469123 -315.407217)
			(xy 358.489046 -315.355126) (xy 358.516342 -315.306491) (xy 358.550428 -315.262348) (xy 358.590577 -315.223639)
			(xy 358.635935 -315.191188) (xy 358.685535 -315.165687) (xy 358.738319 -315.14768) (xy 358.793162 -315.13755)
			(xy 358.848896 -315.135513) (xy 358.904333 -315.141613) (xy 358.95829 -315.155719) (xy 359.009619 -315.177531)
			(xy 359.057225 -315.206585) (xy 359.100093 -315.24226) (xy 359.13731 -315.283797) (xy 359.168083 -315.33031)
			(xy 359.191755 -315.380807) (xy 359.207823 -315.434214) (xy 359.215943 -315.48939) (xy 359.216452 -315.517276)
			(xy 359.468926 -315.517276) (xy 359.472997 -315.461654) (xy 359.485123 -315.407217) (xy 359.505046 -315.355126)
			(xy 359.532342 -315.306491) (xy 359.566428 -315.262348) (xy 359.606577 -315.223639) (xy 359.651935 -315.191188)
			(xy 359.701535 -315.165687) (xy 359.754319 -315.14768) (xy 359.809162 -315.13755) (xy 359.864896 -315.135513)
			(xy 359.920333 -315.141613) (xy 359.97429 -315.155719) (xy 360.025619 -315.177531) (xy 360.073225 -315.206585)
			(xy 360.116093 -315.24226) (xy 360.15331 -315.283797) (xy 360.184083 -315.33031) (xy 360.207755 -315.380807)
			(xy 360.223823 -315.434214) (xy 360.231943 -315.48939) (xy 360.232452 -315.517276) (xy 360.484926 -315.517276)
			(xy 360.488997 -315.461654) (xy 360.501123 -315.407217) (xy 360.521046 -315.355126) (xy 360.548342 -315.306491)
			(xy 360.582428 -315.262348) (xy 360.622577 -315.223639) (xy 360.667935 -315.191188) (xy 360.717535 -315.165687)
			(xy 360.770319 -315.14768) (xy 360.825162 -315.13755) (xy 360.880896 -315.135513) (xy 360.936333 -315.141613)
			(xy 360.99029 -315.155719) (xy 361.041619 -315.177531) (xy 361.089225 -315.206585) (xy 361.132093 -315.24226)
			(xy 361.16931 -315.283797) (xy 361.200083 -315.33031) (xy 361.223755 -315.380807) (xy 361.239823 -315.434214)
			(xy 361.247943 -315.48939) (xy 361.248452 -315.517276) (xy 361.500926 -315.517276) (xy 361.504997 -315.461654)
			(xy 361.517123 -315.407217) (xy 361.537046 -315.355126) (xy 361.564342 -315.306491) (xy 361.598428 -315.262348)
			(xy 361.638577 -315.223639) (xy 361.683935 -315.191188) (xy 361.733535 -315.165687) (xy 361.786319 -315.14768)
			(xy 361.841162 -315.13755) (xy 361.896896 -315.135513) (xy 361.952333 -315.141613) (xy 362.00629 -315.155719)
			(xy 362.057619 -315.177531) (xy 362.105225 -315.206585) (xy 362.148093 -315.24226) (xy 362.18531 -315.283797)
			(xy 362.216083 -315.33031) (xy 362.239755 -315.380807) (xy 362.255823 -315.434214) (xy 362.263943 -315.48939)
			(xy 362.264452 -315.517276) (xy 362.516926 -315.517276) (xy 362.520997 -315.461654) (xy 362.533123 -315.407217)
			(xy 362.553046 -315.355126) (xy 362.580342 -315.306491) (xy 362.614428 -315.262348) (xy 362.654577 -315.223639)
			(xy 362.699935 -315.191188) (xy 362.749535 -315.165687) (xy 362.802319 -315.14768) (xy 362.857162 -315.13755)
			(xy 362.912896 -315.135513) (xy 362.968333 -315.141613) (xy 363.02229 -315.155719) (xy 363.073619 -315.177531)
			(xy 363.121225 -315.206585) (xy 363.164093 -315.24226) (xy 363.20131 -315.283797) (xy 363.232083 -315.33031)
			(xy 363.255755 -315.380807) (xy 363.271823 -315.434214) (xy 363.279943 -315.48939) (xy 363.280452 -315.517276)
			(xy 363.279943 -315.545162) (xy 363.271823 -315.600338) (xy 363.255755 -315.653745) (xy 363.232083 -315.704242)
			(xy 363.20131 -315.750755) (xy 363.164093 -315.792292) (xy 363.121225 -315.827967) (xy 363.085513 -315.849762)
			(xy 384.844048 -315.849762) (xy 384.848008 -315.800708) (xy 384.859785 -315.752924) (xy 384.879076 -315.707648)
			(xy 384.905379 -315.666052) (xy 384.938014 -315.629215) (xy 384.976135 -315.59809) (xy 385.018756 -315.573483)
			(xy 385.064772 -315.556031) (xy 385.112991 -315.546187) (xy 385.162166 -315.544206) (xy 385.211021 -315.550138)
			(xy 385.258292 -315.56383) (xy 385.302754 -315.584928) (xy 385.343257 -315.612884) (xy 385.37875 -315.646976)
			(xy 385.408315 -315.68632) (xy 385.431186 -315.729897) (xy 385.44677 -315.776578) (xy 385.454665 -315.825155)
			(xy 385.45516 -315.849762) (xy 385.794008 -315.849762) (xy 385.797968 -315.800708) (xy 385.809745 -315.752924)
			(xy 385.829036 -315.707648) (xy 385.855339 -315.666052) (xy 385.887974 -315.629215) (xy 385.926095 -315.59809)
			(xy 385.968716 -315.573483) (xy 386.014732 -315.556031) (xy 386.062951 -315.546187) (xy 386.112126 -315.544206)
			(xy 386.160981 -315.550138) (xy 386.208252 -315.56383) (xy 386.252714 -315.584928) (xy 386.293217 -315.612884)
			(xy 386.32871 -315.646976) (xy 386.358275 -315.68632) (xy 386.381146 -315.729897) (xy 386.39673 -315.776578)
			(xy 386.404625 -315.825155) (xy 386.40512 -315.849762) (xy 386.744222 -315.849762) (xy 386.748182 -315.800708)
			(xy 386.759959 -315.752924) (xy 386.77925 -315.707648) (xy 386.805553 -315.666052) (xy 386.838188 -315.629215)
			(xy 386.876309 -315.59809) (xy 386.91893 -315.573483) (xy 386.964946 -315.556031) (xy 387.013165 -315.546187)
			(xy 387.06234 -315.544206) (xy 387.111195 -315.550138) (xy 387.158466 -315.56383) (xy 387.202928 -315.584928)
			(xy 387.243431 -315.612884) (xy 387.278924 -315.646976) (xy 387.308489 -315.68632) (xy 387.33136 -315.729897)
			(xy 387.346944 -315.776578) (xy 387.354839 -315.825155) (xy 387.355334 -315.849762) (xy 387.694182 -315.849762)
			(xy 387.698142 -315.800708) (xy 387.709919 -315.752924) (xy 387.72921 -315.707648) (xy 387.755513 -315.666052)
			(xy 387.788148 -315.629215) (xy 387.826269 -315.59809) (xy 387.86889 -315.573483) (xy 387.914906 -315.556031)
			(xy 387.963125 -315.546187) (xy 388.0123 -315.544206) (xy 388.061155 -315.550138) (xy 388.108426 -315.56383)
			(xy 388.152888 -315.584928) (xy 388.193391 -315.612884) (xy 388.228884 -315.646976) (xy 388.258449 -315.68632)
			(xy 388.28132 -315.729897) (xy 388.296904 -315.776578) (xy 388.304799 -315.825155) (xy 388.305294 -315.849762)
			(xy 388.644142 -315.849762) (xy 388.648102 -315.800708) (xy 388.659879 -315.752924) (xy 388.67917 -315.707648)
			(xy 388.705473 -315.666052) (xy 388.738108 -315.629215) (xy 388.776229 -315.59809) (xy 388.81885 -315.573483)
			(xy 388.864866 -315.556031) (xy 388.913085 -315.546187) (xy 388.96226 -315.544206) (xy 389.011115 -315.550138)
			(xy 389.058386 -315.56383) (xy 389.102848 -315.584928) (xy 389.143351 -315.612884) (xy 389.178844 -315.646976)
			(xy 389.208409 -315.68632) (xy 389.23128 -315.729897) (xy 389.246864 -315.776578) (xy 389.254759 -315.825155)
			(xy 389.255254 -315.849762) (xy 389.594102 -315.849762) (xy 389.598062 -315.800708) (xy 389.609839 -315.752924)
			(xy 389.62913 -315.707648) (xy 389.655433 -315.666052) (xy 389.688068 -315.629215) (xy 389.726189 -315.59809)
			(xy 389.76881 -315.573483) (xy 389.814826 -315.556031) (xy 389.863045 -315.546187) (xy 389.91222 -315.544206)
			(xy 389.961075 -315.550138) (xy 390.008346 -315.56383) (xy 390.052808 -315.584928) (xy 390.093311 -315.612884)
			(xy 390.128804 -315.646976) (xy 390.158369 -315.68632) (xy 390.18124 -315.729897) (xy 390.196824 -315.776578)
			(xy 390.204719 -315.825155) (xy 390.205214 -315.849762) (xy 390.544062 -315.849762) (xy 390.548022 -315.800708)
			(xy 390.559799 -315.752924) (xy 390.57909 -315.707648) (xy 390.605393 -315.666052) (xy 390.638028 -315.629215)
			(xy 390.676149 -315.59809) (xy 390.71877 -315.573483) (xy 390.764786 -315.556031) (xy 390.813005 -315.546187)
			(xy 390.86218 -315.544206) (xy 390.911035 -315.550138) (xy 390.958306 -315.56383) (xy 391.002768 -315.584928)
			(xy 391.043271 -315.612884) (xy 391.078764 -315.646976) (xy 391.108329 -315.68632) (xy 391.1312 -315.729897)
			(xy 391.146784 -315.776578) (xy 391.154679 -315.825155) (xy 391.155174 -315.849762) (xy 391.494022 -315.849762)
			(xy 391.497982 -315.800708) (xy 391.509759 -315.752924) (xy 391.52905 -315.707648) (xy 391.555353 -315.666052)
			(xy 391.587988 -315.629215) (xy 391.626109 -315.59809) (xy 391.66873 -315.573483) (xy 391.714746 -315.556031)
			(xy 391.762965 -315.546187) (xy 391.81214 -315.544206) (xy 391.860995 -315.550138) (xy 391.908266 -315.56383)
			(xy 391.952728 -315.584928) (xy 391.993231 -315.612884) (xy 392.028724 -315.646976) (xy 392.058289 -315.68632)
			(xy 392.08116 -315.729897) (xy 392.096744 -315.776578) (xy 392.104639 -315.825155) (xy 392.105134 -315.849762)
			(xy 392.443982 -315.849762) (xy 392.447942 -315.800708) (xy 392.459719 -315.752924) (xy 392.47901 -315.707648)
			(xy 392.505313 -315.666052) (xy 392.537948 -315.629215) (xy 392.576069 -315.59809) (xy 392.61869 -315.573483)
			(xy 392.664706 -315.556031) (xy 392.712925 -315.546187) (xy 392.7621 -315.544206) (xy 392.810955 -315.550138)
			(xy 392.858226 -315.56383) (xy 392.902688 -315.584928) (xy 392.943191 -315.612884) (xy 392.978684 -315.646976)
			(xy 393.008249 -315.68632) (xy 393.03112 -315.729897) (xy 393.046704 -315.776578) (xy 393.054599 -315.825155)
			(xy 393.055094 -315.849762) (xy 393.394196 -315.849762) (xy 393.398156 -315.800708) (xy 393.409933 -315.752924)
			(xy 393.429224 -315.707648) (xy 393.455527 -315.666052) (xy 393.488162 -315.629215) (xy 393.526283 -315.59809)
			(xy 393.568904 -315.573483) (xy 393.61492 -315.556031) (xy 393.663139 -315.546187) (xy 393.712314 -315.544206)
			(xy 393.761169 -315.550138) (xy 393.80844 -315.56383) (xy 393.852902 -315.584928) (xy 393.893405 -315.612884)
			(xy 393.928898 -315.646976) (xy 393.958463 -315.68632) (xy 393.981334 -315.729897) (xy 393.996918 -315.776578)
			(xy 394.004813 -315.825155) (xy 394.005308 -315.849762) (xy 394.004813 -315.874369) (xy 393.996918 -315.922946)
			(xy 393.981334 -315.969627) (xy 393.958463 -316.013204) (xy 393.928898 -316.052548) (xy 393.893405 -316.08664)
			(xy 393.852902 -316.114596) (xy 393.80844 -316.135694) (xy 393.761169 -316.149386) (xy 393.712314 -316.155318)
			(xy 393.663139 -316.153337) (xy 393.61492 -316.143493) (xy 393.568904 -316.126041) (xy 393.526283 -316.101434)
			(xy 393.488162 -316.070309) (xy 393.455527 -316.033472) (xy 393.429224 -315.991876) (xy 393.409933 -315.9466)
			(xy 393.398156 -315.898816) (xy 393.394196 -315.849762) (xy 393.055094 -315.849762) (xy 393.054599 -315.874369)
			(xy 393.046704 -315.922946) (xy 393.03112 -315.969627) (xy 393.008249 -316.013204) (xy 392.978684 -316.052548)
			(xy 392.943191 -316.08664) (xy 392.902688 -316.114596) (xy 392.858226 -316.135694) (xy 392.810955 -316.149386)
			(xy 392.7621 -316.155318) (xy 392.712925 -316.153337) (xy 392.664706 -316.143493) (xy 392.61869 -316.126041)
			(xy 392.576069 -316.101434) (xy 392.537948 -316.070309) (xy 392.505313 -316.033472) (xy 392.47901 -315.991876)
			(xy 392.459719 -315.9466) (xy 392.447942 -315.898816) (xy 392.443982 -315.849762) (xy 392.105134 -315.849762)
			(xy 392.104639 -315.874369) (xy 392.096744 -315.922946) (xy 392.08116 -315.969627) (xy 392.058289 -316.013204)
			(xy 392.028724 -316.052548) (xy 391.993231 -316.08664) (xy 391.952728 -316.114596) (xy 391.908266 -316.135694)
			(xy 391.860995 -316.149386) (xy 391.81214 -316.155318) (xy 391.762965 -316.153337) (xy 391.714746 -316.143493)
			(xy 391.66873 -316.126041) (xy 391.626109 -316.101434) (xy 391.587988 -316.070309) (xy 391.555353 -316.033472)
			(xy 391.52905 -315.991876) (xy 391.509759 -315.9466) (xy 391.497982 -315.898816) (xy 391.494022 -315.849762)
			(xy 391.155174 -315.849762) (xy 391.154679 -315.874369) (xy 391.146784 -315.922946) (xy 391.1312 -315.969627)
			(xy 391.108329 -316.013204) (xy 391.078764 -316.052548) (xy 391.043271 -316.08664) (xy 391.002768 -316.114596)
			(xy 390.958306 -316.135694) (xy 390.911035 -316.149386) (xy 390.86218 -316.155318) (xy 390.813005 -316.153337)
			(xy 390.764786 -316.143493) (xy 390.71877 -316.126041) (xy 390.676149 -316.101434) (xy 390.638028 -316.070309)
			(xy 390.605393 -316.033472) (xy 390.57909 -315.991876) (xy 390.559799 -315.9466) (xy 390.548022 -315.898816)
			(xy 390.544062 -315.849762) (xy 390.205214 -315.849762) (xy 390.204719 -315.874369) (xy 390.196824 -315.922946)
			(xy 390.18124 -315.969627) (xy 390.158369 -316.013204) (xy 390.128804 -316.052548) (xy 390.093311 -316.08664)
			(xy 390.052808 -316.114596) (xy 390.008346 -316.135694) (xy 389.961075 -316.149386) (xy 389.91222 -316.155318)
			(xy 389.863045 -316.153337) (xy 389.814826 -316.143493) (xy 389.76881 -316.126041) (xy 389.726189 -316.101434)
			(xy 389.688068 -316.070309) (xy 389.655433 -316.033472) (xy 389.62913 -315.991876) (xy 389.609839 -315.9466)
			(xy 389.598062 -315.898816) (xy 389.594102 -315.849762) (xy 389.255254 -315.849762) (xy 389.254759 -315.874369)
			(xy 389.246864 -315.922946) (xy 389.23128 -315.969627) (xy 389.208409 -316.013204) (xy 389.178844 -316.052548)
			(xy 389.143351 -316.08664) (xy 389.102848 -316.114596) (xy 389.058386 -316.135694) (xy 389.011115 -316.149386)
			(xy 388.96226 -316.155318) (xy 388.913085 -316.153337) (xy 388.864866 -316.143493) (xy 388.81885 -316.126041)
			(xy 388.776229 -316.101434) (xy 388.738108 -316.070309) (xy 388.705473 -316.033472) (xy 388.67917 -315.991876)
			(xy 388.659879 -315.9466) (xy 388.648102 -315.898816) (xy 388.644142 -315.849762) (xy 388.305294 -315.849762)
			(xy 388.304799 -315.874369) (xy 388.296904 -315.922946) (xy 388.28132 -315.969627) (xy 388.258449 -316.013204)
			(xy 388.228884 -316.052548) (xy 388.193391 -316.08664) (xy 388.152888 -316.114596) (xy 388.108426 -316.135694)
			(xy 388.061155 -316.149386) (xy 388.0123 -316.155318) (xy 387.963125 -316.153337) (xy 387.914906 -316.143493)
			(xy 387.86889 -316.126041) (xy 387.826269 -316.101434) (xy 387.788148 -316.070309) (xy 387.755513 -316.033472)
			(xy 387.72921 -315.991876) (xy 387.709919 -315.9466) (xy 387.698142 -315.898816) (xy 387.694182 -315.849762)
			(xy 387.355334 -315.849762) (xy 387.354839 -315.874369) (xy 387.346944 -315.922946) (xy 387.33136 -315.969627)
			(xy 387.308489 -316.013204) (xy 387.278924 -316.052548) (xy 387.243431 -316.08664) (xy 387.202928 -316.114596)
			(xy 387.158466 -316.135694) (xy 387.111195 -316.149386) (xy 387.06234 -316.155318) (xy 387.013165 -316.153337)
			(xy 386.964946 -316.143493) (xy 386.91893 -316.126041) (xy 386.876309 -316.101434) (xy 386.838188 -316.070309)
			(xy 386.805553 -316.033472) (xy 386.77925 -315.991876) (xy 386.759959 -315.9466) (xy 386.748182 -315.898816)
			(xy 386.744222 -315.849762) (xy 386.40512 -315.849762) (xy 386.404625 -315.874369) (xy 386.39673 -315.922946)
			(xy 386.381146 -315.969627) (xy 386.358275 -316.013204) (xy 386.32871 -316.052548) (xy 386.293217 -316.08664)
			(xy 386.252714 -316.114596) (xy 386.208252 -316.135694) (xy 386.160981 -316.149386) (xy 386.112126 -316.155318)
			(xy 386.062951 -316.153337) (xy 386.014732 -316.143493) (xy 385.968716 -316.126041) (xy 385.926095 -316.101434)
			(xy 385.887974 -316.070309) (xy 385.855339 -316.033472) (xy 385.829036 -315.991876) (xy 385.809745 -315.9466)
			(xy 385.797968 -315.898816) (xy 385.794008 -315.849762) (xy 385.45516 -315.849762) (xy 385.454665 -315.874369)
			(xy 385.44677 -315.922946) (xy 385.431186 -315.969627) (xy 385.408315 -316.013204) (xy 385.37875 -316.052548)
			(xy 385.343257 -316.08664) (xy 385.302754 -316.114596) (xy 385.258292 -316.135694) (xy 385.211021 -316.149386)
			(xy 385.162166 -316.155318) (xy 385.112991 -316.153337) (xy 385.064772 -316.143493) (xy 385.018756 -316.126041)
			(xy 384.976135 -316.101434) (xy 384.938014 -316.070309) (xy 384.905379 -316.033472) (xy 384.879076 -315.991876)
			(xy 384.859785 -315.9466) (xy 384.848008 -315.898816) (xy 384.844048 -315.849762) (xy 363.085513 -315.849762)
			(xy 363.073619 -315.857021) (xy 363.02229 -315.878833) (xy 362.968333 -315.892939) (xy 362.912896 -315.899039)
			(xy 362.857162 -315.897002) (xy 362.802319 -315.886872) (xy 362.749535 -315.868865) (xy 362.699935 -315.843364)
			(xy 362.654577 -315.810913) (xy 362.614428 -315.772204) (xy 362.580342 -315.728061) (xy 362.553046 -315.679426)
			(xy 362.533123 -315.627335) (xy 362.520997 -315.572898) (xy 362.516926 -315.517276) (xy 362.264452 -315.517276)
			(xy 362.263943 -315.545162) (xy 362.255823 -315.600338) (xy 362.239755 -315.653745) (xy 362.216083 -315.704242)
			(xy 362.18531 -315.750755) (xy 362.148093 -315.792292) (xy 362.105225 -315.827967) (xy 362.057619 -315.857021)
			(xy 362.00629 -315.878833) (xy 361.952333 -315.892939) (xy 361.896896 -315.899039) (xy 361.841162 -315.897002)
			(xy 361.786319 -315.886872) (xy 361.733535 -315.868865) (xy 361.683935 -315.843364) (xy 361.638577 -315.810913)
			(xy 361.598428 -315.772204) (xy 361.564342 -315.728061) (xy 361.537046 -315.679426) (xy 361.517123 -315.627335)
			(xy 361.504997 -315.572898) (xy 361.500926 -315.517276) (xy 361.248452 -315.517276) (xy 361.247943 -315.545162)
			(xy 361.239823 -315.600338) (xy 361.223755 -315.653745) (xy 361.200083 -315.704242) (xy 361.16931 -315.750755)
			(xy 361.132093 -315.792292) (xy 361.089225 -315.827967) (xy 361.041619 -315.857021) (xy 360.99029 -315.878833)
			(xy 360.936333 -315.892939) (xy 360.880896 -315.899039) (xy 360.825162 -315.897002) (xy 360.770319 -315.886872)
			(xy 360.717535 -315.868865) (xy 360.667935 -315.843364) (xy 360.622577 -315.810913) (xy 360.582428 -315.772204)
			(xy 360.548342 -315.728061) (xy 360.521046 -315.679426) (xy 360.501123 -315.627335) (xy 360.488997 -315.572898)
			(xy 360.484926 -315.517276) (xy 360.232452 -315.517276) (xy 360.231943 -315.545162) (xy 360.223823 -315.600338)
			(xy 360.207755 -315.653745) (xy 360.184083 -315.704242) (xy 360.15331 -315.750755) (xy 360.116093 -315.792292)
			(xy 360.073225 -315.827967) (xy 360.025619 -315.857021) (xy 359.97429 -315.878833) (xy 359.920333 -315.892939)
			(xy 359.864896 -315.899039) (xy 359.809162 -315.897002) (xy 359.754319 -315.886872) (xy 359.701535 -315.868865)
			(xy 359.651935 -315.843364) (xy 359.606577 -315.810913) (xy 359.566428 -315.772204) (xy 359.532342 -315.728061)
			(xy 359.505046 -315.679426) (xy 359.485123 -315.627335) (xy 359.472997 -315.572898) (xy 359.468926 -315.517276)
			(xy 359.216452 -315.517276) (xy 359.215943 -315.545162) (xy 359.207823 -315.600338) (xy 359.191755 -315.653745)
			(xy 359.168083 -315.704242) (xy 359.13731 -315.750755) (xy 359.100093 -315.792292) (xy 359.057225 -315.827967)
			(xy 359.009619 -315.857021) (xy 358.95829 -315.878833) (xy 358.904333 -315.892939) (xy 358.848896 -315.899039)
			(xy 358.793162 -315.897002) (xy 358.738319 -315.886872) (xy 358.685535 -315.868865) (xy 358.635935 -315.843364)
			(xy 358.590577 -315.810913) (xy 358.550428 -315.772204) (xy 358.516342 -315.728061) (xy 358.489046 -315.679426)
			(xy 358.469123 -315.627335) (xy 358.456997 -315.572898) (xy 358.452926 -315.517276) (xy 358.200452 -315.517276)
			(xy 358.199943 -315.545162) (xy 358.191823 -315.600338) (xy 358.175755 -315.653745) (xy 358.152083 -315.704242)
			(xy 358.12131 -315.750755) (xy 358.084093 -315.792292) (xy 358.041225 -315.827967) (xy 357.993619 -315.857021)
			(xy 357.94229 -315.878833) (xy 357.888333 -315.892939) (xy 357.832896 -315.899039) (xy 357.777162 -315.897002)
			(xy 357.722319 -315.886872) (xy 357.669535 -315.868865) (xy 357.619935 -315.843364) (xy 357.574577 -315.810913)
			(xy 357.534428 -315.772204) (xy 357.500342 -315.728061) (xy 357.473046 -315.679426) (xy 357.453123 -315.627335)
			(xy 357.440997 -315.572898) (xy 357.436926 -315.517276) (xy 351.831402 -315.517276) (xy 351.831402 -316.533276)
			(xy 357.436926 -316.533276) (xy 357.440997 -316.477654) (xy 357.453123 -316.423217) (xy 357.473046 -316.371126)
			(xy 357.500342 -316.322491) (xy 357.534428 -316.278348) (xy 357.574577 -316.239639) (xy 357.619935 -316.207188)
			(xy 357.669535 -316.181687) (xy 357.722319 -316.16368) (xy 357.777162 -316.15355) (xy 357.832896 -316.151513)
			(xy 357.888333 -316.157613) (xy 357.94229 -316.171719) (xy 357.993619 -316.193531) (xy 358.041225 -316.222585)
			(xy 358.084093 -316.25826) (xy 358.12131 -316.299797) (xy 358.152083 -316.34631) (xy 358.175755 -316.396807)
			(xy 358.191823 -316.450214) (xy 358.199943 -316.50539) (xy 358.200452 -316.533276) (xy 358.452926 -316.533276)
			(xy 358.456997 -316.477654) (xy 358.469123 -316.423217) (xy 358.489046 -316.371126) (xy 358.516342 -316.322491)
			(xy 358.550428 -316.278348) (xy 358.590577 -316.239639) (xy 358.635935 -316.207188) (xy 358.685535 -316.181687)
			(xy 358.738319 -316.16368) (xy 358.793162 -316.15355) (xy 358.848896 -316.151513) (xy 358.904333 -316.157613)
			(xy 358.95829 -316.171719) (xy 359.009619 -316.193531) (xy 359.057225 -316.222585) (xy 359.100093 -316.25826)
			(xy 359.13731 -316.299797) (xy 359.168083 -316.34631) (xy 359.191755 -316.396807) (xy 359.207823 -316.450214)
			(xy 359.215943 -316.50539) (xy 359.216452 -316.533276) (xy 359.468926 -316.533276) (xy 359.472997 -316.477654)
			(xy 359.485123 -316.423217) (xy 359.505046 -316.371126) (xy 359.532342 -316.322491) (xy 359.566428 -316.278348)
			(xy 359.606577 -316.239639) (xy 359.651935 -316.207188) (xy 359.701535 -316.181687) (xy 359.754319 -316.16368)
			(xy 359.809162 -316.15355) (xy 359.864896 -316.151513) (xy 359.920333 -316.157613) (xy 359.97429 -316.171719)
			(xy 360.025619 -316.193531) (xy 360.073225 -316.222585) (xy 360.116093 -316.25826) (xy 360.15331 -316.299797)
			(xy 360.184083 -316.34631) (xy 360.207755 -316.396807) (xy 360.223823 -316.450214) (xy 360.231943 -316.50539)
			(xy 360.232452 -316.533276) (xy 360.484926 -316.533276) (xy 360.488997 -316.477654) (xy 360.501123 -316.423217)
			(xy 360.521046 -316.371126) (xy 360.548342 -316.322491) (xy 360.582428 -316.278348) (xy 360.622577 -316.239639)
			(xy 360.667935 -316.207188) (xy 360.717535 -316.181687) (xy 360.770319 -316.16368) (xy 360.825162 -316.15355)
			(xy 360.880896 -316.151513) (xy 360.936333 -316.157613) (xy 360.99029 -316.171719) (xy 361.041619 -316.193531)
			(xy 361.089225 -316.222585) (xy 361.132093 -316.25826) (xy 361.16931 -316.299797) (xy 361.200083 -316.34631)
			(xy 361.223755 -316.396807) (xy 361.239823 -316.450214) (xy 361.247943 -316.50539) (xy 361.248452 -316.533276)
			(xy 361.500926 -316.533276) (xy 361.504997 -316.477654) (xy 361.517123 -316.423217) (xy 361.537046 -316.371126)
			(xy 361.564342 -316.322491) (xy 361.598428 -316.278348) (xy 361.638577 -316.239639) (xy 361.683935 -316.207188)
			(xy 361.733535 -316.181687) (xy 361.786319 -316.16368) (xy 361.841162 -316.15355) (xy 361.896896 -316.151513)
			(xy 361.952333 -316.157613) (xy 362.00629 -316.171719) (xy 362.057619 -316.193531) (xy 362.105225 -316.222585)
			(xy 362.148093 -316.25826) (xy 362.18531 -316.299797) (xy 362.216083 -316.34631) (xy 362.239755 -316.396807)
			(xy 362.255823 -316.450214) (xy 362.263943 -316.50539) (xy 362.264452 -316.533276) (xy 362.516926 -316.533276)
			(xy 362.520997 -316.477654) (xy 362.533123 -316.423217) (xy 362.553046 -316.371126) (xy 362.580342 -316.322491)
			(xy 362.614428 -316.278348) (xy 362.654577 -316.239639) (xy 362.699935 -316.207188) (xy 362.749535 -316.181687)
			(xy 362.802319 -316.16368) (xy 362.857162 -316.15355) (xy 362.912896 -316.151513) (xy 362.968333 -316.157613)
			(xy 363.02229 -316.171719) (xy 363.073619 -316.193531) (xy 363.121225 -316.222585) (xy 363.164093 -316.25826)
			(xy 363.20131 -316.299797) (xy 363.232083 -316.34631) (xy 363.255755 -316.396807) (xy 363.271823 -316.450214)
			(xy 363.279943 -316.50539) (xy 363.280452 -316.533276) (xy 363.279943 -316.561162) (xy 363.271823 -316.616338)
			(xy 363.255755 -316.669745) (xy 363.232083 -316.720242) (xy 363.20131 -316.766755) (xy 363.164093 -316.808292)
			(xy 363.121225 -316.843967) (xy 363.073619 -316.873021) (xy 363.02229 -316.894833) (xy 362.968333 -316.908939)
			(xy 362.912896 -316.915039) (xy 362.857162 -316.913002) (xy 362.802319 -316.902872) (xy 362.749535 -316.884865)
			(xy 362.699935 -316.859364) (xy 362.654577 -316.826913) (xy 362.614428 -316.788204) (xy 362.580342 -316.744061)
			(xy 362.553046 -316.695426) (xy 362.533123 -316.643335) (xy 362.520997 -316.588898) (xy 362.516926 -316.533276)
			(xy 362.264452 -316.533276) (xy 362.263943 -316.561162) (xy 362.255823 -316.616338) (xy 362.239755 -316.669745)
			(xy 362.216083 -316.720242) (xy 362.18531 -316.766755) (xy 362.148093 -316.808292) (xy 362.105225 -316.843967)
			(xy 362.057619 -316.873021) (xy 362.00629 -316.894833) (xy 361.952333 -316.908939) (xy 361.896896 -316.915039)
			(xy 361.841162 -316.913002) (xy 361.786319 -316.902872) (xy 361.733535 -316.884865) (xy 361.683935 -316.859364)
			(xy 361.638577 -316.826913) (xy 361.598428 -316.788204) (xy 361.564342 -316.744061) (xy 361.537046 -316.695426)
			(xy 361.517123 -316.643335) (xy 361.504997 -316.588898) (xy 361.500926 -316.533276) (xy 361.248452 -316.533276)
			(xy 361.247943 -316.561162) (xy 361.239823 -316.616338) (xy 361.223755 -316.669745) (xy 361.200083 -316.720242)
			(xy 361.16931 -316.766755) (xy 361.132093 -316.808292) (xy 361.089225 -316.843967) (xy 361.041619 -316.873021)
			(xy 360.99029 -316.894833) (xy 360.936333 -316.908939) (xy 360.880896 -316.915039) (xy 360.825162 -316.913002)
			(xy 360.770319 -316.902872) (xy 360.717535 -316.884865) (xy 360.667935 -316.859364) (xy 360.622577 -316.826913)
			(xy 360.582428 -316.788204) (xy 360.548342 -316.744061) (xy 360.521046 -316.695426) (xy 360.501123 -316.643335)
			(xy 360.488997 -316.588898) (xy 360.484926 -316.533276) (xy 360.232452 -316.533276) (xy 360.231943 -316.561162)
			(xy 360.223823 -316.616338) (xy 360.207755 -316.669745) (xy 360.184083 -316.720242) (xy 360.15331 -316.766755)
			(xy 360.116093 -316.808292) (xy 360.073225 -316.843967) (xy 360.025619 -316.873021) (xy 359.97429 -316.894833)
			(xy 359.920333 -316.908939) (xy 359.864896 -316.915039) (xy 359.809162 -316.913002) (xy 359.754319 -316.902872)
			(xy 359.701535 -316.884865) (xy 359.651935 -316.859364) (xy 359.606577 -316.826913) (xy 359.566428 -316.788204)
			(xy 359.532342 -316.744061) (xy 359.505046 -316.695426) (xy 359.485123 -316.643335) (xy 359.472997 -316.588898)
			(xy 359.468926 -316.533276) (xy 359.216452 -316.533276) (xy 359.215943 -316.561162) (xy 359.207823 -316.616338)
			(xy 359.191755 -316.669745) (xy 359.168083 -316.720242) (xy 359.13731 -316.766755) (xy 359.100093 -316.808292)
			(xy 359.057225 -316.843967) (xy 359.009619 -316.873021) (xy 358.95829 -316.894833) (xy 358.904333 -316.908939)
			(xy 358.848896 -316.915039) (xy 358.793162 -316.913002) (xy 358.738319 -316.902872) (xy 358.685535 -316.884865)
			(xy 358.635935 -316.859364) (xy 358.590577 -316.826913) (xy 358.550428 -316.788204) (xy 358.516342 -316.744061)
			(xy 358.489046 -316.695426) (xy 358.469123 -316.643335) (xy 358.456997 -316.588898) (xy 358.452926 -316.533276)
			(xy 358.200452 -316.533276) (xy 358.199943 -316.561162) (xy 358.191823 -316.616338) (xy 358.175755 -316.669745)
			(xy 358.152083 -316.720242) (xy 358.12131 -316.766755) (xy 358.084093 -316.808292) (xy 358.041225 -316.843967)
			(xy 357.993619 -316.873021) (xy 357.94229 -316.894833) (xy 357.888333 -316.908939) (xy 357.832896 -316.915039)
			(xy 357.777162 -316.913002) (xy 357.722319 -316.902872) (xy 357.669535 -316.884865) (xy 357.619935 -316.859364)
			(xy 357.574577 -316.826913) (xy 357.534428 -316.788204) (xy 357.500342 -316.744061) (xy 357.473046 -316.695426)
			(xy 357.453123 -316.643335) (xy 357.440997 -316.588898) (xy 357.436926 -316.533276) (xy 351.831402 -316.533276)
			(xy 351.831402 -320.900044) (xy 373.198651 -320.900044) (xy 373.202657 -320.704989) (xy 373.214667 -320.510263)
			(xy 373.234662 -320.316194) (xy 373.262607 -320.12311) (xy 373.298456 -319.931335) (xy 373.342148 -319.741195)
			(xy 373.393609 -319.553008) (xy 373.452753 -319.367093) (xy 373.51948 -319.183762) (xy 373.593677 -319.003326)
			(xy 373.675219 -318.826088) (xy 373.76397 -318.652347) (xy 373.859778 -318.482396) (xy 373.962483 -318.316522)
			(xy 374.071911 -318.155004) (xy 374.187878 -317.998115) (xy 374.310189 -317.84612) (xy 374.438636 -317.699274)
			(xy 374.573004 -317.557825) (xy 374.713066 -317.422012) (xy 374.858585 -317.292063) (xy 375.009317 -317.168199)
			(xy 375.165007 -317.050627) (xy 375.325393 -316.939547) (xy 375.490204 -316.835144) (xy 375.659162 -316.737596)
			(xy 375.831983 -316.647067) (xy 376.008375 -316.563709) (xy 376.18804 -316.487663) (xy 376.370675 -316.419058)
			(xy 376.555974 -316.358008) (xy 376.743622 -316.304618) (xy 376.933304 -316.258976) (xy 377.124701 -316.22116)
			(xy 377.317488 -316.191234) (xy 377.511341 -316.169248) (xy 377.705934 -316.155239) (xy 377.900937 -316.149231)
			(xy 378.096023 -316.151234) (xy 378.290862 -316.161245) (xy 378.485126 -316.179246) (xy 378.678487 -316.205208)
			(xy 378.87062 -316.239086) (xy 379.061199 -316.280823) (xy 379.249904 -316.33035) (xy 379.436417 -316.387582)
			(xy 379.620423 -316.452423) (xy 379.801611 -316.524764) (xy 379.979677 -316.604482) (xy 380.15432 -316.691444)
			(xy 380.325246 -316.785503) (xy 380.348326 -316.799468) (xy 383.89358 -316.799468) (xy 383.89754 -316.750414)
			(xy 383.909317 -316.70263) (xy 383.928608 -316.657354) (xy 383.954911 -316.615758) (xy 383.987546 -316.578921)
			(xy 384.025667 -316.547796) (xy 384.068288 -316.523189) (xy 384.114304 -316.505737) (xy 384.162523 -316.495893)
			(xy 384.211698 -316.493912) (xy 384.260553 -316.499844) (xy 384.307824 -316.513536) (xy 384.352286 -316.534634)
			(xy 384.392789 -316.56259) (xy 384.428282 -316.596682) (xy 384.457847 -316.636026) (xy 384.480718 -316.679603)
			(xy 384.496302 -316.726284) (xy 384.504197 -316.774861) (xy 384.504692 -316.799468) (xy 384.504687 -316.799722)
			(xy 384.844048 -316.799722) (xy 384.848008 -316.750668) (xy 384.859785 -316.702884) (xy 384.879076 -316.657608)
			(xy 384.905379 -316.616012) (xy 384.938014 -316.579175) (xy 384.976135 -316.54805) (xy 385.018756 -316.523443)
			(xy 385.064772 -316.505991) (xy 385.112991 -316.496147) (xy 385.162166 -316.494166) (xy 385.211021 -316.500098)
			(xy 385.258292 -316.51379) (xy 385.302754 -316.534888) (xy 385.343257 -316.562844) (xy 385.37875 -316.596936)
			(xy 385.408315 -316.63628) (xy 385.431186 -316.679857) (xy 385.44677 -316.726538) (xy 385.454665 -316.775115)
			(xy 385.45516 -316.799722) (xy 385.794008 -316.799722) (xy 385.797968 -316.750668) (xy 385.809745 -316.702884)
			(xy 385.829036 -316.657608) (xy 385.855339 -316.616012) (xy 385.887974 -316.579175) (xy 385.926095 -316.54805)
			(xy 385.968716 -316.523443) (xy 386.014732 -316.505991) (xy 386.062951 -316.496147) (xy 386.112126 -316.494166)
			(xy 386.160981 -316.500098) (xy 386.208252 -316.51379) (xy 386.252714 -316.534888) (xy 386.293217 -316.562844)
			(xy 386.32871 -316.596936) (xy 386.358275 -316.63628) (xy 386.381146 -316.679857) (xy 386.39673 -316.726538)
			(xy 386.404625 -316.775115) (xy 386.40512 -316.799722) (xy 386.744222 -316.799722) (xy 386.748182 -316.750668)
			(xy 386.759959 -316.702884) (xy 386.77925 -316.657608) (xy 386.805553 -316.616012) (xy 386.838188 -316.579175)
			(xy 386.876309 -316.54805) (xy 386.91893 -316.523443) (xy 386.964946 -316.505991) (xy 387.013165 -316.496147)
			(xy 387.06234 -316.494166) (xy 387.111195 -316.500098) (xy 387.158466 -316.51379) (xy 387.202928 -316.534888)
			(xy 387.243431 -316.562844) (xy 387.278924 -316.596936) (xy 387.308489 -316.63628) (xy 387.33136 -316.679857)
			(xy 387.346944 -316.726538) (xy 387.354839 -316.775115) (xy 387.355334 -316.799722) (xy 387.694182 -316.799722)
			(xy 387.698142 -316.750668) (xy 387.709919 -316.702884) (xy 387.72921 -316.657608) (xy 387.755513 -316.616012)
			(xy 387.788148 -316.579175) (xy 387.826269 -316.54805) (xy 387.86889 -316.523443) (xy 387.914906 -316.505991)
			(xy 387.963125 -316.496147) (xy 388.0123 -316.494166) (xy 388.061155 -316.500098) (xy 388.108426 -316.51379)
			(xy 388.152888 -316.534888) (xy 388.193391 -316.562844) (xy 388.228884 -316.596936) (xy 388.258449 -316.63628)
			(xy 388.28132 -316.679857) (xy 388.296904 -316.726538) (xy 388.304799 -316.775115) (xy 388.305294 -316.799722)
			(xy 388.644142 -316.799722) (xy 388.648102 -316.750668) (xy 388.659879 -316.702884) (xy 388.67917 -316.657608)
			(xy 388.705473 -316.616012) (xy 388.738108 -316.579175) (xy 388.776229 -316.54805) (xy 388.81885 -316.523443)
			(xy 388.864866 -316.505991) (xy 388.913085 -316.496147) (xy 388.96226 -316.494166) (xy 389.011115 -316.500098)
			(xy 389.058386 -316.51379) (xy 389.102848 -316.534888) (xy 389.143351 -316.562844) (xy 389.178844 -316.596936)
			(xy 389.208409 -316.63628) (xy 389.23128 -316.679857) (xy 389.246864 -316.726538) (xy 389.254759 -316.775115)
			(xy 389.255254 -316.799722) (xy 389.594102 -316.799722) (xy 389.598062 -316.750668) (xy 389.609839 -316.702884)
			(xy 389.62913 -316.657608) (xy 389.655433 -316.616012) (xy 389.688068 -316.579175) (xy 389.726189 -316.54805)
			(xy 389.76881 -316.523443) (xy 389.814826 -316.505991) (xy 389.863045 -316.496147) (xy 389.91222 -316.494166)
			(xy 389.961075 -316.500098) (xy 390.008346 -316.51379) (xy 390.052808 -316.534888) (xy 390.093311 -316.562844)
			(xy 390.128804 -316.596936) (xy 390.158369 -316.63628) (xy 390.18124 -316.679857) (xy 390.196824 -316.726538)
			(xy 390.204719 -316.775115) (xy 390.205214 -316.799722) (xy 390.544062 -316.799722) (xy 390.548022 -316.750668)
			(xy 390.559799 -316.702884) (xy 390.57909 -316.657608) (xy 390.605393 -316.616012) (xy 390.638028 -316.579175)
			(xy 390.676149 -316.54805) (xy 390.71877 -316.523443) (xy 390.764786 -316.505991) (xy 390.813005 -316.496147)
			(xy 390.86218 -316.494166) (xy 390.911035 -316.500098) (xy 390.958306 -316.51379) (xy 391.002768 -316.534888)
			(xy 391.043271 -316.562844) (xy 391.078764 -316.596936) (xy 391.108329 -316.63628) (xy 391.1312 -316.679857)
			(xy 391.146784 -316.726538) (xy 391.154679 -316.775115) (xy 391.155174 -316.799722) (xy 391.494022 -316.799722)
			(xy 391.497982 -316.750668) (xy 391.509759 -316.702884) (xy 391.52905 -316.657608) (xy 391.555353 -316.616012)
			(xy 391.587988 -316.579175) (xy 391.626109 -316.54805) (xy 391.66873 -316.523443) (xy 391.714746 -316.505991)
			(xy 391.762965 -316.496147) (xy 391.81214 -316.494166) (xy 391.860995 -316.500098) (xy 391.908266 -316.51379)
			(xy 391.952728 -316.534888) (xy 391.993231 -316.562844) (xy 392.028724 -316.596936) (xy 392.058289 -316.63628)
			(xy 392.08116 -316.679857) (xy 392.096744 -316.726538) (xy 392.104639 -316.775115) (xy 392.105134 -316.799722)
			(xy 392.443982 -316.799722) (xy 392.447942 -316.750668) (xy 392.459719 -316.702884) (xy 392.47901 -316.657608)
			(xy 392.505313 -316.616012) (xy 392.537948 -316.579175) (xy 392.576069 -316.54805) (xy 392.61869 -316.523443)
			(xy 392.664706 -316.505991) (xy 392.712925 -316.496147) (xy 392.7621 -316.494166) (xy 392.810955 -316.500098)
			(xy 392.858226 -316.51379) (xy 392.902688 -316.534888) (xy 392.943191 -316.562844) (xy 392.978684 -316.596936)
			(xy 393.008249 -316.63628) (xy 393.03112 -316.679857) (xy 393.046704 -316.726538) (xy 393.054599 -316.775115)
			(xy 393.055094 -316.799722) (xy 393.394196 -316.799722) (xy 393.398156 -316.750668) (xy 393.409933 -316.702884)
			(xy 393.429224 -316.657608) (xy 393.455527 -316.616012) (xy 393.488162 -316.579175) (xy 393.526283 -316.54805)
			(xy 393.568904 -316.523443) (xy 393.61492 -316.505991) (xy 393.663139 -316.496147) (xy 393.712314 -316.494166)
			(xy 393.761169 -316.500098) (xy 393.80844 -316.51379) (xy 393.852902 -316.534888) (xy 393.893405 -316.562844)
			(xy 393.928898 -316.596936) (xy 393.958463 -316.63628) (xy 393.981334 -316.679857) (xy 393.996918 -316.726538)
			(xy 394.004813 -316.775115) (xy 394.005308 -316.799722) (xy 394.004813 -316.824329) (xy 393.996918 -316.872906)
			(xy 393.981334 -316.919587) (xy 393.958463 -316.963164) (xy 393.928898 -317.002508) (xy 393.893405 -317.0366)
			(xy 393.852902 -317.064556) (xy 393.80844 -317.085654) (xy 393.761169 -317.099346) (xy 393.712314 -317.105278)
			(xy 393.663139 -317.103297) (xy 393.61492 -317.093453) (xy 393.568904 -317.076001) (xy 393.526283 -317.051394)
			(xy 393.488162 -317.020269) (xy 393.455527 -316.983432) (xy 393.429224 -316.941836) (xy 393.409933 -316.89656)
			(xy 393.398156 -316.848776) (xy 393.394196 -316.799722) (xy 393.055094 -316.799722) (xy 393.054599 -316.824329)
			(xy 393.046704 -316.872906) (xy 393.03112 -316.919587) (xy 393.008249 -316.963164) (xy 392.978684 -317.002508)
			(xy 392.943191 -317.0366) (xy 392.902688 -317.064556) (xy 392.858226 -317.085654) (xy 392.810955 -317.099346)
			(xy 392.7621 -317.105278) (xy 392.712925 -317.103297) (xy 392.664706 -317.093453) (xy 392.61869 -317.076001)
			(xy 392.576069 -317.051394) (xy 392.537948 -317.020269) (xy 392.505313 -316.983432) (xy 392.47901 -316.941836)
			(xy 392.459719 -316.89656) (xy 392.447942 -316.848776) (xy 392.443982 -316.799722) (xy 392.105134 -316.799722)
			(xy 392.104639 -316.824329) (xy 392.096744 -316.872906) (xy 392.08116 -316.919587) (xy 392.058289 -316.963164)
			(xy 392.028724 -317.002508) (xy 391.993231 -317.0366) (xy 391.952728 -317.064556) (xy 391.908266 -317.085654)
			(xy 391.860995 -317.099346) (xy 391.81214 -317.105278) (xy 391.762965 -317.103297) (xy 391.714746 -317.093453)
			(xy 391.66873 -317.076001) (xy 391.626109 -317.051394) (xy 391.587988 -317.020269) (xy 391.555353 -316.983432)
			(xy 391.52905 -316.941836) (xy 391.509759 -316.89656) (xy 391.497982 -316.848776) (xy 391.494022 -316.799722)
			(xy 391.155174 -316.799722) (xy 391.154679 -316.824329) (xy 391.146784 -316.872906) (xy 391.1312 -316.919587)
			(xy 391.108329 -316.963164) (xy 391.078764 -317.002508) (xy 391.043271 -317.0366) (xy 391.002768 -317.064556)
			(xy 390.958306 -317.085654) (xy 390.911035 -317.099346) (xy 390.86218 -317.105278) (xy 390.813005 -317.103297)
			(xy 390.764786 -317.093453) (xy 390.71877 -317.076001) (xy 390.676149 -317.051394) (xy 390.638028 -317.020269)
			(xy 390.605393 -316.983432) (xy 390.57909 -316.941836) (xy 390.559799 -316.89656) (xy 390.548022 -316.848776)
			(xy 390.544062 -316.799722) (xy 390.205214 -316.799722) (xy 390.204719 -316.824329) (xy 390.196824 -316.872906)
			(xy 390.18124 -316.919587) (xy 390.158369 -316.963164) (xy 390.128804 -317.002508) (xy 390.093311 -317.0366)
			(xy 390.052808 -317.064556) (xy 390.008346 -317.085654) (xy 389.961075 -317.099346) (xy 389.91222 -317.105278)
			(xy 389.863045 -317.103297) (xy 389.814826 -317.093453) (xy 389.76881 -317.076001) (xy 389.726189 -317.051394)
			(xy 389.688068 -317.020269) (xy 389.655433 -316.983432) (xy 389.62913 -316.941836) (xy 389.609839 -316.89656)
			(xy 389.598062 -316.848776) (xy 389.594102 -316.799722) (xy 389.255254 -316.799722) (xy 389.254759 -316.824329)
			(xy 389.246864 -316.872906) (xy 389.23128 -316.919587) (xy 389.208409 -316.963164) (xy 389.178844 -317.002508)
			(xy 389.143351 -317.0366) (xy 389.102848 -317.064556) (xy 389.058386 -317.085654) (xy 389.011115 -317.099346)
			(xy 388.96226 -317.105278) (xy 388.913085 -317.103297) (xy 388.864866 -317.093453) (xy 388.81885 -317.076001)
			(xy 388.776229 -317.051394) (xy 388.738108 -317.020269) (xy 388.705473 -316.983432) (xy 388.67917 -316.941836)
			(xy 388.659879 -316.89656) (xy 388.648102 -316.848776) (xy 388.644142 -316.799722) (xy 388.305294 -316.799722)
			(xy 388.304799 -316.824329) (xy 388.296904 -316.872906) (xy 388.28132 -316.919587) (xy 388.258449 -316.963164)
			(xy 388.228884 -317.002508) (xy 388.193391 -317.0366) (xy 388.152888 -317.064556) (xy 388.108426 -317.085654)
			(xy 388.061155 -317.099346) (xy 388.0123 -317.105278) (xy 387.963125 -317.103297) (xy 387.914906 -317.093453)
			(xy 387.86889 -317.076001) (xy 387.826269 -317.051394) (xy 387.788148 -317.020269) (xy 387.755513 -316.983432)
			(xy 387.72921 -316.941836) (xy 387.709919 -316.89656) (xy 387.698142 -316.848776) (xy 387.694182 -316.799722)
			(xy 387.355334 -316.799722) (xy 387.354839 -316.824329) (xy 387.346944 -316.872906) (xy 387.33136 -316.919587)
			(xy 387.308489 -316.963164) (xy 387.278924 -317.002508) (xy 387.243431 -317.0366) (xy 387.202928 -317.064556)
			(xy 387.158466 -317.085654) (xy 387.111195 -317.099346) (xy 387.06234 -317.105278) (xy 387.013165 -317.103297)
			(xy 386.964946 -317.093453) (xy 386.91893 -317.076001) (xy 386.876309 -317.051394) (xy 386.838188 -317.020269)
			(xy 386.805553 -316.983432) (xy 386.77925 -316.941836) (xy 386.759959 -316.89656) (xy 386.748182 -316.848776)
			(xy 386.744222 -316.799722) (xy 386.40512 -316.799722) (xy 386.404625 -316.824329) (xy 386.39673 -316.872906)
			(xy 386.381146 -316.919587) (xy 386.358275 -316.963164) (xy 386.32871 -317.002508) (xy 386.293217 -317.0366)
			(xy 386.252714 -317.064556) (xy 386.208252 -317.085654) (xy 386.160981 -317.099346) (xy 386.112126 -317.105278)
			(xy 386.062951 -317.103297) (xy 386.014732 -317.093453) (xy 385.968716 -317.076001) (xy 385.926095 -317.051394)
			(xy 385.887974 -317.020269) (xy 385.855339 -316.983432) (xy 385.829036 -316.941836) (xy 385.809745 -316.89656)
			(xy 385.797968 -316.848776) (xy 385.794008 -316.799722) (xy 385.45516 -316.799722) (xy 385.454665 -316.824329)
			(xy 385.44677 -316.872906) (xy 385.431186 -316.919587) (xy 385.408315 -316.963164) (xy 385.37875 -317.002508)
			(xy 385.343257 -317.0366) (xy 385.302754 -317.064556) (xy 385.258292 -317.085654) (xy 385.211021 -317.099346)
			(xy 385.162166 -317.105278) (xy 385.112991 -317.103297) (xy 385.064772 -317.093453) (xy 385.018756 -317.076001)
			(xy 384.976135 -317.051394) (xy 384.938014 -317.020269) (xy 384.905379 -316.983432) (xy 384.879076 -316.941836)
			(xy 384.859785 -316.89656) (xy 384.848008 -316.848776) (xy 384.844048 -316.799722) (xy 384.504687 -316.799722)
			(xy 384.504197 -316.824075) (xy 384.496302 -316.872652) (xy 384.480718 -316.919333) (xy 384.457847 -316.96291)
			(xy 384.428282 -317.002254) (xy 384.392789 -317.036346) (xy 384.352286 -317.064302) (xy 384.307824 -317.0854)
			(xy 384.260553 -317.099092) (xy 384.211698 -317.105024) (xy 384.162523 -317.103043) (xy 384.114304 -317.093199)
			(xy 384.068288 -317.075747) (xy 384.025667 -317.05114) (xy 383.987546 -317.020015) (xy 383.954911 -316.983178)
			(xy 383.928608 -316.941582) (xy 383.909317 -316.896306) (xy 383.89754 -316.848522) (xy 383.89358 -316.799468)
			(xy 380.348326 -316.799468) (xy 380.492165 -316.886499) (xy 380.654798 -316.994264) (xy 380.812869 -317.108614)
			(xy 380.966112 -317.229357) (xy 381.114269 -317.356291) (xy 381.25709 -317.489199) (xy 381.394334 -317.627859)
			(xy 381.505622 -317.749936) (xy 384.844048 -317.749936) (xy 384.848008 -317.700882) (xy 384.859785 -317.653098)
			(xy 384.879076 -317.607822) (xy 384.905379 -317.566226) (xy 384.938014 -317.529389) (xy 384.976135 -317.498264)
			(xy 385.018756 -317.473657) (xy 385.064772 -317.456205) (xy 385.112991 -317.446361) (xy 385.162166 -317.44438)
			(xy 385.211021 -317.450312) (xy 385.258292 -317.464004) (xy 385.302754 -317.485102) (xy 385.343257 -317.513058)
			(xy 385.37875 -317.54715) (xy 385.408315 -317.586494) (xy 385.431186 -317.630071) (xy 385.44677 -317.676752)
			(xy 385.454665 -317.725329) (xy 385.45516 -317.749936) (xy 385.794008 -317.749936) (xy 385.797968 -317.700882)
			(xy 385.809745 -317.653098) (xy 385.829036 -317.607822) (xy 385.855339 -317.566226) (xy 385.887974 -317.529389)
			(xy 385.926095 -317.498264) (xy 385.968716 -317.473657) (xy 386.014732 -317.456205) (xy 386.062951 -317.446361)
			(xy 386.112126 -317.44438) (xy 386.160981 -317.450312) (xy 386.208252 -317.464004) (xy 386.252714 -317.485102)
			(xy 386.293217 -317.513058) (xy 386.32871 -317.54715) (xy 386.358275 -317.586494) (xy 386.381146 -317.630071)
			(xy 386.39673 -317.676752) (xy 386.404625 -317.725329) (xy 386.40512 -317.749936) (xy 386.744222 -317.749936)
			(xy 386.748182 -317.700882) (xy 386.759959 -317.653098) (xy 386.77925 -317.607822) (xy 386.805553 -317.566226)
			(xy 386.838188 -317.529389) (xy 386.876309 -317.498264) (xy 386.91893 -317.473657) (xy 386.964946 -317.456205)
			(xy 387.013165 -317.446361) (xy 387.06234 -317.44438) (xy 387.111195 -317.450312) (xy 387.158466 -317.464004)
			(xy 387.202928 -317.485102) (xy 387.243431 -317.513058) (xy 387.278924 -317.54715) (xy 387.308489 -317.586494)
			(xy 387.33136 -317.630071) (xy 387.346944 -317.676752) (xy 387.354839 -317.725329) (xy 387.355334 -317.749936)
			(xy 387.694182 -317.749936) (xy 387.698142 -317.700882) (xy 387.709919 -317.653098) (xy 387.72921 -317.607822)
			(xy 387.755513 -317.566226) (xy 387.788148 -317.529389) (xy 387.826269 -317.498264) (xy 387.86889 -317.473657)
			(xy 387.914906 -317.456205) (xy 387.963125 -317.446361) (xy 388.0123 -317.44438) (xy 388.061155 -317.450312)
			(xy 388.108426 -317.464004) (xy 388.152888 -317.485102) (xy 388.193391 -317.513058) (xy 388.228884 -317.54715)
			(xy 388.258449 -317.586494) (xy 388.28132 -317.630071) (xy 388.296904 -317.676752) (xy 388.304799 -317.725329)
			(xy 388.305294 -317.749936) (xy 388.644142 -317.749936) (xy 388.648102 -317.700882) (xy 388.659879 -317.653098)
			(xy 388.67917 -317.607822) (xy 388.705473 -317.566226) (xy 388.738108 -317.529389) (xy 388.776229 -317.498264)
			(xy 388.81885 -317.473657) (xy 388.864866 -317.456205) (xy 388.913085 -317.446361) (xy 388.96226 -317.44438)
			(xy 389.011115 -317.450312) (xy 389.058386 -317.464004) (xy 389.102848 -317.485102) (xy 389.143351 -317.513058)
			(xy 389.178844 -317.54715) (xy 389.208409 -317.586494) (xy 389.23128 -317.630071) (xy 389.246864 -317.676752)
			(xy 389.254759 -317.725329) (xy 389.255254 -317.749936) (xy 389.594102 -317.749936) (xy 389.598062 -317.700882)
			(xy 389.609839 -317.653098) (xy 389.62913 -317.607822) (xy 389.655433 -317.566226) (xy 389.688068 -317.529389)
			(xy 389.726189 -317.498264) (xy 389.76881 -317.473657) (xy 389.814826 -317.456205) (xy 389.863045 -317.446361)
			(xy 389.91222 -317.44438) (xy 389.961075 -317.450312) (xy 390.008346 -317.464004) (xy 390.052808 -317.485102)
			(xy 390.093311 -317.513058) (xy 390.128804 -317.54715) (xy 390.158369 -317.586494) (xy 390.18124 -317.630071)
			(xy 390.196824 -317.676752) (xy 390.204719 -317.725329) (xy 390.205214 -317.749936) (xy 390.544062 -317.749936)
			(xy 390.548022 -317.700882) (xy 390.559799 -317.653098) (xy 390.57909 -317.607822) (xy 390.605393 -317.566226)
			(xy 390.638028 -317.529389) (xy 390.676149 -317.498264) (xy 390.71877 -317.473657) (xy 390.764786 -317.456205)
			(xy 390.813005 -317.446361) (xy 390.86218 -317.44438) (xy 390.911035 -317.450312) (xy 390.958306 -317.464004)
			(xy 391.002768 -317.485102) (xy 391.043271 -317.513058) (xy 391.078764 -317.54715) (xy 391.108329 -317.586494)
			(xy 391.1312 -317.630071) (xy 391.146784 -317.676752) (xy 391.154679 -317.725329) (xy 391.155174 -317.749936)
			(xy 391.494022 -317.749936) (xy 391.497982 -317.700882) (xy 391.509759 -317.653098) (xy 391.52905 -317.607822)
			(xy 391.555353 -317.566226) (xy 391.587988 -317.529389) (xy 391.626109 -317.498264) (xy 391.66873 -317.473657)
			(xy 391.714746 -317.456205) (xy 391.762965 -317.446361) (xy 391.81214 -317.44438) (xy 391.860995 -317.450312)
			(xy 391.908266 -317.464004) (xy 391.952728 -317.485102) (xy 391.993231 -317.513058) (xy 392.028724 -317.54715)
			(xy 392.058289 -317.586494) (xy 392.08116 -317.630071) (xy 392.096744 -317.676752) (xy 392.104639 -317.725329)
			(xy 392.105134 -317.749936) (xy 392.443982 -317.749936) (xy 392.447942 -317.700882) (xy 392.459719 -317.653098)
			(xy 392.47901 -317.607822) (xy 392.505313 -317.566226) (xy 392.537948 -317.529389) (xy 392.576069 -317.498264)
			(xy 392.61869 -317.473657) (xy 392.664706 -317.456205) (xy 392.712925 -317.446361) (xy 392.7621 -317.44438)
			(xy 392.810955 -317.450312) (xy 392.858226 -317.464004) (xy 392.902688 -317.485102) (xy 392.943191 -317.513058)
			(xy 392.978684 -317.54715) (xy 393.008249 -317.586494) (xy 393.03112 -317.630071) (xy 393.046704 -317.676752)
			(xy 393.054599 -317.725329) (xy 393.055094 -317.749936) (xy 393.394196 -317.749936) (xy 393.398156 -317.700882)
			(xy 393.409933 -317.653098) (xy 393.429224 -317.607822) (xy 393.455527 -317.566226) (xy 393.488162 -317.529389)
			(xy 393.526283 -317.498264) (xy 393.568904 -317.473657) (xy 393.61492 -317.456205) (xy 393.663139 -317.446361)
			(xy 393.712314 -317.44438) (xy 393.761169 -317.450312) (xy 393.80844 -317.464004) (xy 393.852902 -317.485102)
			(xy 393.893405 -317.513058) (xy 393.928898 -317.54715) (xy 393.958463 -317.586494) (xy 393.981334 -317.630071)
			(xy 393.996918 -317.676752) (xy 394.004813 -317.725329) (xy 394.005308 -317.749936) (xy 394.004813 -317.774543)
			(xy 393.996918 -317.82312) (xy 393.981334 -317.869801) (xy 393.958463 -317.913378) (xy 393.928898 -317.952722)
			(xy 393.893405 -317.986814) (xy 393.852902 -318.01477) (xy 393.80844 -318.035868) (xy 393.761169 -318.04956)
			(xy 393.712314 -318.055492) (xy 393.663139 -318.053511) (xy 393.61492 -318.043667) (xy 393.568904 -318.026215)
			(xy 393.526283 -318.001608) (xy 393.488162 -317.970483) (xy 393.455527 -317.933646) (xy 393.429224 -317.89205)
			(xy 393.409933 -317.846774) (xy 393.398156 -317.79899) (xy 393.394196 -317.749936) (xy 393.055094 -317.749936)
			(xy 393.054599 -317.774543) (xy 393.046704 -317.82312) (xy 393.03112 -317.869801) (xy 393.008249 -317.913378)
			(xy 392.978684 -317.952722) (xy 392.943191 -317.986814) (xy 392.902688 -318.01477) (xy 392.858226 -318.035868)
			(xy 392.810955 -318.04956) (xy 392.7621 -318.055492) (xy 392.712925 -318.053511) (xy 392.664706 -318.043667)
			(xy 392.61869 -318.026215) (xy 392.576069 -318.001608) (xy 392.537948 -317.970483) (xy 392.505313 -317.933646)
			(xy 392.47901 -317.89205) (xy 392.459719 -317.846774) (xy 392.447942 -317.79899) (xy 392.443982 -317.749936)
			(xy 392.105134 -317.749936) (xy 392.104639 -317.774543) (xy 392.096744 -317.82312) (xy 392.08116 -317.869801)
			(xy 392.058289 -317.913378) (xy 392.028724 -317.952722) (xy 391.993231 -317.986814) (xy 391.952728 -318.01477)
			(xy 391.908266 -318.035868) (xy 391.860995 -318.04956) (xy 391.81214 -318.055492) (xy 391.762965 -318.053511)
			(xy 391.714746 -318.043667) (xy 391.66873 -318.026215) (xy 391.626109 -318.001608) (xy 391.587988 -317.970483)
			(xy 391.555353 -317.933646) (xy 391.52905 -317.89205) (xy 391.509759 -317.846774) (xy 391.497982 -317.79899)
			(xy 391.494022 -317.749936) (xy 391.155174 -317.749936) (xy 391.154679 -317.774543) (xy 391.146784 -317.82312)
			(xy 391.1312 -317.869801) (xy 391.108329 -317.913378) (xy 391.078764 -317.952722) (xy 391.043271 -317.986814)
			(xy 391.002768 -318.01477) (xy 390.958306 -318.035868) (xy 390.911035 -318.04956) (xy 390.86218 -318.055492)
			(xy 390.813005 -318.053511) (xy 390.764786 -318.043667) (xy 390.71877 -318.026215) (xy 390.676149 -318.001608)
			(xy 390.638028 -317.970483) (xy 390.605393 -317.933646) (xy 390.57909 -317.89205) (xy 390.559799 -317.846774)
			(xy 390.548022 -317.79899) (xy 390.544062 -317.749936) (xy 390.205214 -317.749936) (xy 390.204719 -317.774543)
			(xy 390.196824 -317.82312) (xy 390.18124 -317.869801) (xy 390.158369 -317.913378) (xy 390.128804 -317.952722)
			(xy 390.093311 -317.986814) (xy 390.052808 -318.01477) (xy 390.008346 -318.035868) (xy 389.961075 -318.04956)
			(xy 389.91222 -318.055492) (xy 389.863045 -318.053511) (xy 389.814826 -318.043667) (xy 389.76881 -318.026215)
			(xy 389.726189 -318.001608) (xy 389.688068 -317.970483) (xy 389.655433 -317.933646) (xy 389.62913 -317.89205)
			(xy 389.609839 -317.846774) (xy 389.598062 -317.79899) (xy 389.594102 -317.749936) (xy 389.255254 -317.749936)
			(xy 389.254759 -317.774543) (xy 389.246864 -317.82312) (xy 389.23128 -317.869801) (xy 389.208409 -317.913378)
			(xy 389.178844 -317.952722) (xy 389.143351 -317.986814) (xy 389.102848 -318.01477) (xy 389.058386 -318.035868)
			(xy 389.011115 -318.04956) (xy 388.96226 -318.055492) (xy 388.913085 -318.053511) (xy 388.864866 -318.043667)
			(xy 388.81885 -318.026215) (xy 388.776229 -318.001608) (xy 388.738108 -317.970483) (xy 388.705473 -317.933646)
			(xy 388.67917 -317.89205) (xy 388.659879 -317.846774) (xy 388.648102 -317.79899) (xy 388.644142 -317.749936)
			(xy 388.305294 -317.749936) (xy 388.304799 -317.774543) (xy 388.296904 -317.82312) (xy 388.28132 -317.869801)
			(xy 388.258449 -317.913378) (xy 388.228884 -317.952722) (xy 388.193391 -317.986814) (xy 388.152888 -318.01477)
			(xy 388.108426 -318.035868) (xy 388.061155 -318.04956) (xy 388.0123 -318.055492) (xy 387.963125 -318.053511)
			(xy 387.914906 -318.043667) (xy 387.86889 -318.026215) (xy 387.826269 -318.001608) (xy 387.788148 -317.970483)
			(xy 387.755513 -317.933646) (xy 387.72921 -317.89205) (xy 387.709919 -317.846774) (xy 387.698142 -317.79899)
			(xy 387.694182 -317.749936) (xy 387.355334 -317.749936) (xy 387.354839 -317.774543) (xy 387.346944 -317.82312)
			(xy 387.33136 -317.869801) (xy 387.308489 -317.913378) (xy 387.278924 -317.952722) (xy 387.243431 -317.986814)
			(xy 387.202928 -318.01477) (xy 387.158466 -318.035868) (xy 387.111195 -318.04956) (xy 387.06234 -318.055492)
			(xy 387.013165 -318.053511) (xy 386.964946 -318.043667) (xy 386.91893 -318.026215) (xy 386.876309 -318.001608)
			(xy 386.838188 -317.970483) (xy 386.805553 -317.933646) (xy 386.77925 -317.89205) (xy 386.759959 -317.846774)
			(xy 386.748182 -317.79899) (xy 386.744222 -317.749936) (xy 386.40512 -317.749936) (xy 386.404625 -317.774543)
			(xy 386.39673 -317.82312) (xy 386.381146 -317.869801) (xy 386.358275 -317.913378) (xy 386.32871 -317.952722)
			(xy 386.293217 -317.986814) (xy 386.252714 -318.01477) (xy 386.208252 -318.035868) (xy 386.160981 -318.04956)
			(xy 386.112126 -318.055492) (xy 386.062951 -318.053511) (xy 386.014732 -318.043667) (xy 385.968716 -318.026215)
			(xy 385.926095 -318.001608) (xy 385.887974 -317.970483) (xy 385.855339 -317.933646) (xy 385.829036 -317.89205)
			(xy 385.809745 -317.846774) (xy 385.797968 -317.79899) (xy 385.794008 -317.749936) (xy 385.45516 -317.749936)
			(xy 385.454665 -317.774543) (xy 385.44677 -317.82312) (xy 385.431186 -317.869801) (xy 385.408315 -317.913378)
			(xy 385.37875 -317.952722) (xy 385.343257 -317.986814) (xy 385.302754 -318.01477) (xy 385.258292 -318.035868)
			(xy 385.211021 -318.04956) (xy 385.162166 -318.055492) (xy 385.112991 -318.053511) (xy 385.064772 -318.043667)
			(xy 385.018756 -318.026215) (xy 384.976135 -318.001608) (xy 384.938014 -317.970483) (xy 384.905379 -317.933646)
			(xy 384.879076 -317.89205) (xy 384.859785 -317.846774) (xy 384.848008 -317.79899) (xy 384.844048 -317.749936)
			(xy 381.505622 -317.749936) (xy 381.52577 -317.772037) (xy 381.651175 -317.92149) (xy 381.770339 -318.075964)
			(xy 381.88306 -318.235201) (xy 381.989149 -318.398932) (xy 382.088427 -318.566879) (xy 382.159855 -318.699896)
			(xy 385.794008 -318.699896) (xy 385.797968 -318.650842) (xy 385.809745 -318.603058) (xy 385.829036 -318.557782)
			(xy 385.855339 -318.516186) (xy 385.887974 -318.479349) (xy 385.926095 -318.448224) (xy 385.968716 -318.423617)
			(xy 386.014732 -318.406165) (xy 386.062951 -318.396321) (xy 386.112126 -318.39434) (xy 386.160981 -318.400272)
			(xy 386.208252 -318.413964) (xy 386.252714 -318.435062) (xy 386.293217 -318.463018) (xy 386.32871 -318.49711)
			(xy 386.358275 -318.536454) (xy 386.381146 -318.580031) (xy 386.39673 -318.626712) (xy 386.404625 -318.675289)
			(xy 386.40512 -318.699896) (xy 386.744222 -318.699896) (xy 386.748182 -318.650842) (xy 386.759959 -318.603058)
			(xy 386.77925 -318.557782) (xy 386.805553 -318.516186) (xy 386.838188 -318.479349) (xy 386.876309 -318.448224)
			(xy 386.91893 -318.423617) (xy 386.964946 -318.406165) (xy 387.013165 -318.396321) (xy 387.06234 -318.39434)
			(xy 387.111195 -318.400272) (xy 387.158466 -318.413964) (xy 387.202928 -318.435062) (xy 387.243431 -318.463018)
			(xy 387.278924 -318.49711) (xy 387.308489 -318.536454) (xy 387.33136 -318.580031) (xy 387.346944 -318.626712)
			(xy 387.354839 -318.675289) (xy 387.355334 -318.699896) (xy 387.694182 -318.699896) (xy 387.698142 -318.650842)
			(xy 387.709919 -318.603058) (xy 387.72921 -318.557782) (xy 387.755513 -318.516186) (xy 387.788148 -318.479349)
			(xy 387.826269 -318.448224) (xy 387.86889 -318.423617) (xy 387.914906 -318.406165) (xy 387.963125 -318.396321)
			(xy 388.0123 -318.39434) (xy 388.061155 -318.400272) (xy 388.108426 -318.413964) (xy 388.152888 -318.435062)
			(xy 388.193391 -318.463018) (xy 388.228884 -318.49711) (xy 388.258449 -318.536454) (xy 388.28132 -318.580031)
			(xy 388.296904 -318.626712) (xy 388.304799 -318.675289) (xy 388.305294 -318.699896) (xy 388.644142 -318.699896)
			(xy 388.648102 -318.650842) (xy 388.659879 -318.603058) (xy 388.67917 -318.557782) (xy 388.705473 -318.516186)
			(xy 388.738108 -318.479349) (xy 388.776229 -318.448224) (xy 388.81885 -318.423617) (xy 388.864866 -318.406165)
			(xy 388.913085 -318.396321) (xy 388.96226 -318.39434) (xy 389.011115 -318.400272) (xy 389.058386 -318.413964)
			(xy 389.102848 -318.435062) (xy 389.143351 -318.463018) (xy 389.178844 -318.49711) (xy 389.208409 -318.536454)
			(xy 389.23128 -318.580031) (xy 389.246864 -318.626712) (xy 389.254759 -318.675289) (xy 389.255254 -318.699896)
			(xy 389.594102 -318.699896) (xy 389.598062 -318.650842) (xy 389.609839 -318.603058) (xy 389.62913 -318.557782)
			(xy 389.655433 -318.516186) (xy 389.688068 -318.479349) (xy 389.726189 -318.448224) (xy 389.76881 -318.423617)
			(xy 389.814826 -318.406165) (xy 389.863045 -318.396321) (xy 389.91222 -318.39434) (xy 389.961075 -318.400272)
			(xy 390.008346 -318.413964) (xy 390.052808 -318.435062) (xy 390.093311 -318.463018) (xy 390.128804 -318.49711)
			(xy 390.158369 -318.536454) (xy 390.18124 -318.580031) (xy 390.196824 -318.626712) (xy 390.204719 -318.675289)
			(xy 390.205214 -318.699896) (xy 390.544062 -318.699896) (xy 390.548022 -318.650842) (xy 390.559799 -318.603058)
			(xy 390.57909 -318.557782) (xy 390.605393 -318.516186) (xy 390.638028 -318.479349) (xy 390.676149 -318.448224)
			(xy 390.71877 -318.423617) (xy 390.764786 -318.406165) (xy 390.813005 -318.396321) (xy 390.86218 -318.39434)
			(xy 390.911035 -318.400272) (xy 390.958306 -318.413964) (xy 391.002768 -318.435062) (xy 391.043271 -318.463018)
			(xy 391.078764 -318.49711) (xy 391.108329 -318.536454) (xy 391.1312 -318.580031) (xy 391.146784 -318.626712)
			(xy 391.154679 -318.675289) (xy 391.155174 -318.699896) (xy 391.494022 -318.699896) (xy 391.497982 -318.650842)
			(xy 391.509759 -318.603058) (xy 391.52905 -318.557782) (xy 391.555353 -318.516186) (xy 391.587988 -318.479349)
			(xy 391.626109 -318.448224) (xy 391.66873 -318.423617) (xy 391.714746 -318.406165) (xy 391.762965 -318.396321)
			(xy 391.81214 -318.39434) (xy 391.860995 -318.400272) (xy 391.908266 -318.413964) (xy 391.952728 -318.435062)
			(xy 391.993231 -318.463018) (xy 392.028724 -318.49711) (xy 392.058289 -318.536454) (xy 392.08116 -318.580031)
			(xy 392.096744 -318.626712) (xy 392.104639 -318.675289) (xy 392.105134 -318.699896) (xy 392.443982 -318.699896)
			(xy 392.447942 -318.650842) (xy 392.459719 -318.603058) (xy 392.47901 -318.557782) (xy 392.505313 -318.516186)
			(xy 392.537948 -318.479349) (xy 392.576069 -318.448224) (xy 392.61869 -318.423617) (xy 392.664706 -318.406165)
			(xy 392.712925 -318.396321) (xy 392.7621 -318.39434) (xy 392.810955 -318.400272) (xy 392.858226 -318.413964)
			(xy 392.902688 -318.435062) (xy 392.943191 -318.463018) (xy 392.978684 -318.49711) (xy 393.008249 -318.536454)
			(xy 393.03112 -318.580031) (xy 393.046704 -318.626712) (xy 393.054599 -318.675289) (xy 393.055094 -318.699896)
			(xy 393.394196 -318.699896) (xy 393.398156 -318.650842) (xy 393.409933 -318.603058) (xy 393.429224 -318.557782)
			(xy 393.455527 -318.516186) (xy 393.488162 -318.479349) (xy 393.526283 -318.448224) (xy 393.568904 -318.423617)
			(xy 393.61492 -318.406165) (xy 393.663139 -318.396321) (xy 393.712314 -318.39434) (xy 393.761169 -318.400272)
			(xy 393.80844 -318.413964) (xy 393.852902 -318.435062) (xy 393.893405 -318.463018) (xy 393.928898 -318.49711)
			(xy 393.958463 -318.536454) (xy 393.981334 -318.580031) (xy 393.996918 -318.626712) (xy 394.004813 -318.675289)
			(xy 394.005308 -318.699896) (xy 394.004813 -318.724503) (xy 393.996918 -318.77308) (xy 393.981334 -318.819761)
			(xy 393.958463 -318.863338) (xy 393.928898 -318.902682) (xy 393.893405 -318.936774) (xy 393.852902 -318.96473)
			(xy 393.80844 -318.985828) (xy 393.761169 -318.99952) (xy 393.712314 -319.005452) (xy 393.663139 -319.003471)
			(xy 393.61492 -318.993627) (xy 393.568904 -318.976175) (xy 393.526283 -318.951568) (xy 393.488162 -318.920443)
			(xy 393.455527 -318.883606) (xy 393.429224 -318.84201) (xy 393.409933 -318.796734) (xy 393.398156 -318.74895)
			(xy 393.394196 -318.699896) (xy 393.055094 -318.699896) (xy 393.054599 -318.724503) (xy 393.046704 -318.77308)
			(xy 393.03112 -318.819761) (xy 393.008249 -318.863338) (xy 392.978684 -318.902682) (xy 392.943191 -318.936774)
			(xy 392.902688 -318.96473) (xy 392.858226 -318.985828) (xy 392.810955 -318.99952) (xy 392.7621 -319.005452)
			(xy 392.712925 -319.003471) (xy 392.664706 -318.993627) (xy 392.61869 -318.976175) (xy 392.576069 -318.951568)
			(xy 392.537948 -318.920443) (xy 392.505313 -318.883606) (xy 392.47901 -318.84201) (xy 392.459719 -318.796734)
			(xy 392.447942 -318.74895) (xy 392.443982 -318.699896) (xy 392.105134 -318.699896) (xy 392.104639 -318.724503)
			(xy 392.096744 -318.77308) (xy 392.08116 -318.819761) (xy 392.058289 -318.863338) (xy 392.028724 -318.902682)
			(xy 391.993231 -318.936774) (xy 391.952728 -318.96473) (xy 391.908266 -318.985828) (xy 391.860995 -318.99952)
			(xy 391.81214 -319.005452) (xy 391.762965 -319.003471) (xy 391.714746 -318.993627) (xy 391.66873 -318.976175)
			(xy 391.626109 -318.951568) (xy 391.587988 -318.920443) (xy 391.555353 -318.883606) (xy 391.52905 -318.84201)
			(xy 391.509759 -318.796734) (xy 391.497982 -318.74895) (xy 391.494022 -318.699896) (xy 391.155174 -318.699896)
			(xy 391.154679 -318.724503) (xy 391.146784 -318.77308) (xy 391.1312 -318.819761) (xy 391.108329 -318.863338)
			(xy 391.078764 -318.902682) (xy 391.043271 -318.936774) (xy 391.002768 -318.96473) (xy 390.958306 -318.985828)
			(xy 390.911035 -318.99952) (xy 390.86218 -319.005452) (xy 390.813005 -319.003471) (xy 390.764786 -318.993627)
			(xy 390.71877 -318.976175) (xy 390.676149 -318.951568) (xy 390.638028 -318.920443) (xy 390.605393 -318.883606)
			(xy 390.57909 -318.84201) (xy 390.559799 -318.796734) (xy 390.548022 -318.74895) (xy 390.544062 -318.699896)
			(xy 390.205214 -318.699896) (xy 390.204719 -318.724503) (xy 390.196824 -318.77308) (xy 390.18124 -318.819761)
			(xy 390.158369 -318.863338) (xy 390.128804 -318.902682) (xy 390.093311 -318.936774) (xy 390.052808 -318.96473)
			(xy 390.008346 -318.985828) (xy 389.961075 -318.99952) (xy 389.91222 -319.005452) (xy 389.863045 -319.003471)
			(xy 389.814826 -318.993627) (xy 389.76881 -318.976175) (xy 389.726189 -318.951568) (xy 389.688068 -318.920443)
			(xy 389.655433 -318.883606) (xy 389.62913 -318.84201) (xy 389.609839 -318.796734) (xy 389.598062 -318.74895)
			(xy 389.594102 -318.699896) (xy 389.255254 -318.699896) (xy 389.254759 -318.724503) (xy 389.246864 -318.77308)
			(xy 389.23128 -318.819761) (xy 389.208409 -318.863338) (xy 389.178844 -318.902682) (xy 389.143351 -318.936774)
			(xy 389.102848 -318.96473) (xy 389.058386 -318.985828) (xy 389.011115 -318.99952) (xy 388.96226 -319.005452)
			(xy 388.913085 -319.003471) (xy 388.864866 -318.993627) (xy 388.81885 -318.976175) (xy 388.776229 -318.951568)
			(xy 388.738108 -318.920443) (xy 388.705473 -318.883606) (xy 388.67917 -318.84201) (xy 388.659879 -318.796734)
			(xy 388.648102 -318.74895) (xy 388.644142 -318.699896) (xy 388.305294 -318.699896) (xy 388.304799 -318.724503)
			(xy 388.296904 -318.77308) (xy 388.28132 -318.819761) (xy 388.258449 -318.863338) (xy 388.228884 -318.902682)
			(xy 388.193391 -318.936774) (xy 388.152888 -318.96473) (xy 388.108426 -318.985828) (xy 388.061155 -318.99952)
			(xy 388.0123 -319.005452) (xy 387.963125 -319.003471) (xy 387.914906 -318.993627) (xy 387.86889 -318.976175)
			(xy 387.826269 -318.951568) (xy 387.788148 -318.920443) (xy 387.755513 -318.883606) (xy 387.72921 -318.84201)
			(xy 387.709919 -318.796734) (xy 387.698142 -318.74895) (xy 387.694182 -318.699896) (xy 387.355334 -318.699896)
			(xy 387.354839 -318.724503) (xy 387.346944 -318.77308) (xy 387.33136 -318.819761) (xy 387.308489 -318.863338)
			(xy 387.278924 -318.902682) (xy 387.243431 -318.936774) (xy 387.202928 -318.96473) (xy 387.158466 -318.985828)
			(xy 387.111195 -318.99952) (xy 387.06234 -319.005452) (xy 387.013165 -319.003471) (xy 386.964946 -318.993627)
			(xy 386.91893 -318.976175) (xy 386.876309 -318.951568) (xy 386.838188 -318.920443) (xy 386.805553 -318.883606)
			(xy 386.77925 -318.84201) (xy 386.759959 -318.796734) (xy 386.748182 -318.74895) (xy 386.744222 -318.699896)
			(xy 386.40512 -318.699896) (xy 386.404625 -318.724503) (xy 386.39673 -318.77308) (xy 386.381146 -318.819761)
			(xy 386.358275 -318.863338) (xy 386.32871 -318.902682) (xy 386.293217 -318.936774) (xy 386.252714 -318.96473)
			(xy 386.208252 -318.985828) (xy 386.160981 -318.99952) (xy 386.112126 -319.005452) (xy 386.062951 -319.003471)
			(xy 386.014732 -318.993627) (xy 385.968716 -318.976175) (xy 385.926095 -318.951568) (xy 385.887974 -318.920443)
			(xy 385.855339 -318.883606) (xy 385.829036 -318.84201) (xy 385.809745 -318.796734) (xy 385.797968 -318.74895)
			(xy 385.794008 -318.699896) (xy 382.159855 -318.699896) (xy 382.180725 -318.738762) (xy 382.26589 -318.914288)
			(xy 382.343776 -319.093163) (xy 382.414253 -319.275085) (xy 382.477201 -319.459747) (xy 382.532516 -319.646837)
			(xy 382.533339 -319.65011) (xy 386.744222 -319.65011) (xy 386.748182 -319.601056) (xy 386.759959 -319.553272)
			(xy 386.77925 -319.507996) (xy 386.805553 -319.4664) (xy 386.838188 -319.429563) (xy 386.876309 -319.398438)
			(xy 386.91893 -319.373831) (xy 386.964946 -319.356379) (xy 387.013165 -319.346535) (xy 387.06234 -319.344554)
			(xy 387.111195 -319.350486) (xy 387.158466 -319.364178) (xy 387.202928 -319.385276) (xy 387.243431 -319.413232)
			(xy 387.278924 -319.447324) (xy 387.308489 -319.486668) (xy 387.33136 -319.530245) (xy 387.346944 -319.576926)
			(xy 387.354839 -319.625503) (xy 387.355334 -319.65011) (xy 388.644142 -319.65011) (xy 388.648102 -319.601056)
			(xy 388.659879 -319.553272) (xy 388.67917 -319.507996) (xy 388.705473 -319.4664) (xy 388.738108 -319.429563)
			(xy 388.776229 -319.398438) (xy 388.81885 -319.373831) (xy 388.864866 -319.356379) (xy 388.913085 -319.346535)
			(xy 388.96226 -319.344554) (xy 389.011115 -319.350486) (xy 389.058386 -319.364178) (xy 389.102848 -319.385276)
			(xy 389.143351 -319.413232) (xy 389.178844 -319.447324) (xy 389.208409 -319.486668) (xy 389.23128 -319.530245)
			(xy 389.246864 -319.576926) (xy 389.254759 -319.625503) (xy 389.255254 -319.65011) (xy 390.544062 -319.65011)
			(xy 390.548022 -319.601056) (xy 390.559799 -319.553272) (xy 390.57909 -319.507996) (xy 390.605393 -319.4664)
			(xy 390.638028 -319.429563) (xy 390.676149 -319.398438) (xy 390.71877 -319.373831) (xy 390.764786 -319.356379)
			(xy 390.813005 -319.346535) (xy 390.86218 -319.344554) (xy 390.911035 -319.350486) (xy 390.958306 -319.364178)
			(xy 391.002768 -319.385276) (xy 391.043271 -319.413232) (xy 391.078764 -319.447324) (xy 391.108329 -319.486668)
			(xy 391.1312 -319.530245) (xy 391.146784 -319.576926) (xy 391.154679 -319.625503) (xy 391.155174 -319.65011)
			(xy 392.444236 -319.65011) (xy 392.448196 -319.601056) (xy 392.459973 -319.553272) (xy 392.479264 -319.507996)
			(xy 392.505567 -319.4664) (xy 392.538202 -319.429563) (xy 392.576323 -319.398438) (xy 392.618944 -319.373831)
			(xy 392.66496 -319.356379) (xy 392.713179 -319.346535) (xy 392.762354 -319.344554) (xy 392.811209 -319.350486)
			(xy 392.85848 -319.364178) (xy 392.902942 -319.385276) (xy 392.943445 -319.413232) (xy 392.978938 -319.447324)
			(xy 393.008503 -319.486668) (xy 393.031374 -319.530245) (xy 393.046958 -319.576926) (xy 393.054853 -319.625503)
			(xy 393.055348 -319.65011) (xy 393.054853 -319.674717) (xy 393.046958 -319.723294) (xy 393.031374 -319.769975)
			(xy 393.008503 -319.813552) (xy 392.978938 -319.852896) (xy 392.943445 -319.886988) (xy 392.902942 -319.914944)
			(xy 392.85848 -319.936042) (xy 392.811209 -319.949734) (xy 392.762354 -319.955666) (xy 392.713179 -319.953685)
			(xy 392.66496 -319.943841) (xy 392.618944 -319.926389) (xy 392.576323 -319.901782) (xy 392.538202 -319.870657)
			(xy 392.505567 -319.83382) (xy 392.479264 -319.792224) (xy 392.459973 -319.746948) (xy 392.448196 -319.699164)
			(xy 392.444236 -319.65011) (xy 391.155174 -319.65011) (xy 391.154679 -319.674717) (xy 391.146784 -319.723294)
			(xy 391.1312 -319.769975) (xy 391.108329 -319.813552) (xy 391.078764 -319.852896) (xy 391.043271 -319.886988)
			(xy 391.002768 -319.914944) (xy 390.958306 -319.936042) (xy 390.911035 -319.949734) (xy 390.86218 -319.955666)
			(xy 390.813005 -319.953685) (xy 390.764786 -319.943841) (xy 390.71877 -319.926389) (xy 390.676149 -319.901782)
			(xy 390.638028 -319.870657) (xy 390.605393 -319.83382) (xy 390.57909 -319.792224) (xy 390.559799 -319.746948)
			(xy 390.548022 -319.699164) (xy 390.544062 -319.65011) (xy 389.255254 -319.65011) (xy 389.254759 -319.674717)
			(xy 389.246864 -319.723294) (xy 389.23128 -319.769975) (xy 389.208409 -319.813552) (xy 389.178844 -319.852896)
			(xy 389.143351 -319.886988) (xy 389.102848 -319.914944) (xy 389.058386 -319.936042) (xy 389.011115 -319.949734)
			(xy 388.96226 -319.955666) (xy 388.913085 -319.953685) (xy 388.864866 -319.943841) (xy 388.81885 -319.926389)
			(xy 388.776229 -319.901782) (xy 388.738108 -319.870657) (xy 388.705473 -319.83382) (xy 388.67917 -319.792224)
			(xy 388.659879 -319.746948) (xy 388.648102 -319.699164) (xy 388.644142 -319.65011) (xy 387.355334 -319.65011)
			(xy 387.354839 -319.674717) (xy 387.346944 -319.723294) (xy 387.33136 -319.769975) (xy 387.308489 -319.813552)
			(xy 387.278924 -319.852896) (xy 387.243431 -319.886988) (xy 387.202928 -319.914944) (xy 387.158466 -319.936042)
			(xy 387.111195 -319.949734) (xy 387.06234 -319.955666) (xy 387.013165 -319.953685) (xy 386.964946 -319.943841)
			(xy 386.91893 -319.926389) (xy 386.876309 -319.901782) (xy 386.838188 -319.870657) (xy 386.805553 -319.83382)
			(xy 386.77925 -319.792224) (xy 386.759959 -319.746948) (xy 386.748182 -319.699164) (xy 386.744222 -319.65011)
			(xy 382.533339 -319.65011) (xy 382.580102 -319.836041) (xy 382.619881 -320.027038) (xy 382.651785 -320.219508)
			(xy 382.67576 -320.413126) (xy 382.691766 -320.607564) (xy 382.699775 -320.802496) (xy 382.700276 -320.900044)
			(xy 382.699775 -320.997592) (xy 382.691766 -321.192524) (xy 382.67576 -321.386962) (xy 382.651785 -321.58058)
			(xy 382.619881 -321.77305) (xy 382.580102 -321.964047) (xy 382.532516 -322.153251) (xy 382.477201 -322.340341)
			(xy 382.414253 -322.525003) (xy 382.343776 -322.706925) (xy 382.26589 -322.8858) (xy 382.180725 -323.061326)
			(xy 382.088427 -323.233209) (xy 381.989149 -323.401156) (xy 381.88306 -323.564887) (xy 381.770339 -323.724124)
			(xy 381.651175 -323.878598) (xy 381.52577 -324.028051) (xy 381.394334 -324.172229) (xy 381.25709 -324.310889)
			(xy 381.114269 -324.443797) (xy 380.966112 -324.570731) (xy 380.812869 -324.691474) (xy 380.654798 -324.805824)
			(xy 380.492165 -324.913589) (xy 380.325246 -325.014585) (xy 380.15432 -325.108644) (xy 379.979677 -325.195606)
			(xy 379.801611 -325.275324) (xy 379.620423 -325.347665) (xy 379.436417 -325.412506) (xy 379.249904 -325.469738)
			(xy 379.061199 -325.519265) (xy 378.87062 -325.561002) (xy 378.678487 -325.59488) (xy 378.485126 -325.620842)
			(xy 378.290862 -325.638843) (xy 378.096023 -325.648854) (xy 377.900937 -325.650857) (xy 377.705934 -325.644849)
			(xy 377.511341 -325.63084) (xy 377.317488 -325.608854) (xy 377.124701 -325.578928) (xy 376.933304 -325.541112)
			(xy 376.743622 -325.49547) (xy 376.555974 -325.44208) (xy 376.370675 -325.38103) (xy 376.18804 -325.312425)
			(xy 376.008375 -325.236379) (xy 375.831983 -325.153021) (xy 375.659162 -325.062492) (xy 375.490204 -324.964944)
			(xy 375.325393 -324.860541) (xy 375.165007 -324.749461) (xy 375.009317 -324.631889) (xy 374.858585 -324.508025)
			(xy 374.713066 -324.378076) (xy 374.573004 -324.242263) (xy 374.438636 -324.100814) (xy 374.310189 -323.953968)
			(xy 374.187878 -323.801973) (xy 374.071911 -323.645084) (xy 373.962483 -323.483566) (xy 373.859778 -323.317692)
			(xy 373.76397 -323.147741) (xy 373.675219 -322.974) (xy 373.593677 -322.796762) (xy 373.51948 -322.616326)
			(xy 373.452753 -322.432995) (xy 373.393609 -322.24708) (xy 373.342148 -322.058893) (xy 373.298456 -321.868753)
			(xy 373.262607 -321.676978) (xy 373.234662 -321.483894) (xy 373.214667 -321.289825) (xy 373.202657 -321.095099)
			(xy 373.198651 -320.900044) (xy 351.831402 -320.900044) (xy 351.831402 -324.472046) (xy 351.831834 -324.482112)
			(xy 351.83956 -324.500705) (xy 351.846388 -324.508114) (xy 353.116134 -325.77786) (xy 359.257344 -325.77786)
			(xy 359.261415 -325.722238) (xy 359.273541 -325.667801) (xy 359.293464 -325.61571) (xy 359.32076 -325.567075)
			(xy 359.354846 -325.522932) (xy 359.394995 -325.484223) (xy 359.440353 -325.451772) (xy 359.489953 -325.426271)
			(xy 359.542737 -325.408264) (xy 359.59758 -325.398134) (xy 359.653314 -325.396097) (xy 359.708751 -325.402197)
			(xy 359.762708 -325.416303) (xy 359.814037 -325.438115) (xy 359.861643 -325.467169) (xy 359.904511 -325.502844)
			(xy 359.941728 -325.544381) (xy 359.972501 -325.590894) (xy 359.996173 -325.641391) (xy 360.012241 -325.694798)
			(xy 360.020361 -325.749974) (xy 360.02087 -325.77786) (xy 360.020361 -325.805746) (xy 360.012241 -325.860922)
			(xy 359.996173 -325.914329) (xy 359.972501 -325.964826) (xy 359.941728 -326.011339) (xy 359.904511 -326.052876)
			(xy 359.861643 -326.088551) (xy 359.814037 -326.117605) (xy 359.762708 -326.139417) (xy 359.708751 -326.153523)
			(xy 359.653314 -326.159623) (xy 359.59758 -326.157586) (xy 359.542737 -326.147456) (xy 359.489953 -326.129449)
			(xy 359.440353 -326.103948) (xy 359.394995 -326.071497) (xy 359.354846 -326.032788) (xy 359.32076 -325.988645)
			(xy 359.293464 -325.94001) (xy 359.273541 -325.887919) (xy 359.261415 -325.833482) (xy 359.257344 -325.77786)
			(xy 353.116134 -325.77786) (xy 353.801934 -326.46366) (xy 356.238808 -326.46366) (xy 356.242879 -326.408038)
			(xy 356.255005 -326.353601) (xy 356.274928 -326.30151) (xy 356.302224 -326.252875) (xy 356.33631 -326.208732)
			(xy 356.376459 -326.170023) (xy 356.421817 -326.137572) (xy 356.471417 -326.112071) (xy 356.524201 -326.094064)
			(xy 356.579044 -326.083934) (xy 356.634778 -326.081897) (xy 356.690215 -326.087997) (xy 356.744172 -326.102103)
			(xy 356.795501 -326.123915) (xy 356.843107 -326.152969) (xy 356.885975 -326.188644) (xy 356.923192 -326.230181)
			(xy 356.953965 -326.276694) (xy 356.977637 -326.327191) (xy 356.993705 -326.380598) (xy 357.001825 -326.435774)
			(xy 357.002334 -326.46366) (xy 357.001825 -326.491546) (xy 356.993705 -326.546722) (xy 356.977637 -326.600129)
			(xy 356.953965 -326.650626) (xy 356.923192 -326.697139) (xy 356.885975 -326.738676) (xy 356.843107 -326.774351)
			(xy 356.795501 -326.803405) (xy 356.744172 -326.825217) (xy 356.690215 -326.839323) (xy 356.634778 -326.845423)
			(xy 356.579044 -326.843386) (xy 356.524201 -326.833256) (xy 356.471417 -326.815249) (xy 356.421817 -326.789748)
			(xy 356.376459 -326.757297) (xy 356.33631 -326.718588) (xy 356.302224 -326.674445) (xy 356.274928 -326.62581)
			(xy 356.255005 -326.573719) (xy 356.242879 -326.519282) (xy 356.238808 -326.46366) (xy 353.801934 -326.46366)
			(xy 353.88931 -326.551036) (xy 353.896161 -326.558432) (xy 353.903896 -326.577031) (xy 353.904296 -326.587104)
			(xy 353.904296 -329.188318) (xy 353.904723 -329.198387) (xy 353.912441 -329.216987) (xy 353.919282 -329.224386)
			(xy 354.23729 -329.542394) (xy 361.73359 -329.542394) (xy 361.737661 -329.486772) (xy 361.749787 -329.432335)
			(xy 361.76971 -329.380244) (xy 361.797006 -329.331609) (xy 361.831092 -329.287466) (xy 361.871241 -329.248757)
			(xy 361.916599 -329.216306) (xy 361.966199 -329.190805) (xy 362.018983 -329.172798) (xy 362.073826 -329.162668)
			(xy 362.12956 -329.160631) (xy 362.184997 -329.166731) (xy 362.238954 -329.180837) (xy 362.290283 -329.202649)
			(xy 362.337889 -329.231703) (xy 362.380757 -329.267378) (xy 362.417974 -329.308915) (xy 362.448747 -329.355428)
			(xy 362.472419 -329.405925) (xy 362.488487 -329.459332) (xy 362.496607 -329.514508) (xy 362.497116 -329.542394)
			(xy 362.496607 -329.57028) (xy 362.488487 -329.625456) (xy 362.472419 -329.678863) (xy 362.448747 -329.72936)
			(xy 362.417974 -329.775873) (xy 362.380757 -329.81741) (xy 362.337889 -329.853085) (xy 362.290283 -329.882139)
			(xy 362.238954 -329.903951) (xy 362.184997 -329.918057) (xy 362.12956 -329.924157) (xy 362.073826 -329.92212)
			(xy 362.018983 -329.91199) (xy 361.966199 -329.893983) (xy 361.916599 -329.868482) (xy 361.871241 -329.836031)
			(xy 361.831092 -329.797322) (xy 361.797006 -329.753179) (xy 361.76971 -329.704544) (xy 361.749787 -329.652453)
			(xy 361.737661 -329.598016) (xy 361.73359 -329.542394) (xy 354.23729 -329.542394) (xy 354.739956 -330.04506)
			(xy 354.747356 -330.051902) (xy 354.765954 -330.059622) (xy 354.776024 -330.060046)
		)
		(stroke
			(width 0)
			(type solid)
		)
		(fill yes)
		(layer "In5.Cu")
		(net "P0V8_SERDES_VDDA_PEX3")
	)
)
